LOGICAL PART CROSS REFERENCE - 14-Sep-2023 AT 16:11:04

DRAWING: @T6G_MB_LIB.T6G(SCH_1):PAGE10 

GENOA_SP5-SOCKET6096_13568-001,SMLF,IO,DGA^6000030  I200  U25
AR74 M_A_CPU0_ALERT_R_N MA_ALERT_L @T6G_MB_LIB.T6G(SCH_1):M_A_CPU0_ALERT_R_N
AT74 M_A_CPU0_RESET_N MA_RESET_L @T6G_MB_LIB.T6G(SCH_1):M_A_CPU0_RESET_N
CE73 M_A_CPU0_SB_DQS_DN<5> MAB_DQS_L5 @T6G_MB_LIB.T6G(SCH_1):M_A_CPU0_SB_DQS_DN(5)
CK74 M_A_CPU0_SB_DQS_DP<1> MAB_DQS_H1 @T6G_MB_LIB.T6G(SCH_1):M_A_CPU0_SB_DQS_DP(1)
DE73 M_A_CPU0_SB_DQ<29> MAB_DATA29 @T6G_MB_LIB.T6G(SCH_1):M_A_CPU0_SB_DQ(29)
CR74 M_A_CPU0_SB_DQ<18> MAB_DATA18 @T6G_MB_LIB.T6G(SCH_1):M_A_CPU0_SB_DQ(18)
CD72 M_A_CPU0_SB_DQ<3> MAB_DATA3 @T6G_MB_LIB.T6G(SCH_1):M_A_CPU0_SB_DQ(3)
AA73 M_A_CPU0_SA_DQS_DP<7> MAA_DQS_H7 @T6G_MB_LIB.T6G(SCH_1):M_A_CPU0_SA_DQS_DP(7)
 J74 M_A_CPU0_SA_DQ<4> MAA_DATA4 @T6G_MB_LIB.T6G(SCH_1):M_A_CPU0_SA_DQ(4)
AU74     NC MAA1_CS_L0     NC
AW73 M_A_CPU0_SA_CS_N<1> MAA0_CS_L1 @T6G_MB_LIB.T6G(SCH_1):M_A_CPU0_SA_CS_N(1)
CL73 M_A_CPU0_SB_DQS_DN<6> MAB_DQS_L6 @T6G_MB_LIB.T6G(SCH_1):M_A_CPU0_SB_DQS_DN(6)
CT74 M_A_CPU0_SB_DQS_DP<2> MAB_DQS_H2 @T6G_MB_LIB.T6G(SCH_1):M_A_CPU0_SB_DQS_DP(2)
CT72 M_A_CPU0_SB_DQ<19> MAB_DATA19 @T6G_MB_LIB.T6G(SCH_1):M_A_CPU0_SB_DQ(19)
CF74 M_A_CPU0_SB_DQ<4> MAB_DATA4 @T6G_MB_LIB.T6G(SCH_1):M_A_CPU0_SB_DQ(4)
AG73 M_A_CPU0_SA_DQS_DP<8> MAA_DQS_H8 @T6G_MB_LIB.T6G(SCH_1):M_A_CPU0_SA_DQS_DP(8)
AH74 M_A_CPU0_SA_DQ<30> MAA_DATA30 @T6G_MB_LIB.T6G(SCH_1):M_A_CPU0_SA_DQ(30)
 K72 M_A_CPU0_SA_DQ<5> MAA_DATA5 @T6G_MB_LIB.T6G(SCH_1):M_A_CPU0_SA_DQ(5)
AV72     NC MAA1_CS_L1     NC
CU73 M_A_CPU0_SB_DQS_DN<7> MAB_DQS_L7 @T6G_MB_LIB.T6G(SCH_1):M_A_CPU0_SB_DQS_DN(7)
DB74 M_A_CPU0_SB_DQS_DP<3> MAB_DQS_H3 @T6G_MB_LIB.T6G(SCH_1):M_A_CPU0_SB_DQS_DP(3)
CG73 M_A_CPU0_SB_DQ<5> MAB_DATA5 @T6G_MB_LIB.T6G(SCH_1):M_A_CPU0_SB_DQ(5)
AN73 M_A_CPU0_SA_DQS_DP<9> MAA_DQS_H9 @T6G_MB_LIB.T6G(SCH_1):M_A_CPU0_SA_DQS_DP(9)
AJ73 M_A_CPU0_SA_DQ<31> MAA_DATA31 @T6G_MB_LIB.T6G(SCH_1):M_A_CPU0_SA_DQ(31)
AA74 M_A_CPU0_SA_DQ<20> MAA_DATA20 @T6G_MB_LIB.T6G(SCH_1):M_A_CPU0_SA_DQ(20)
 K74 M_A_CPU0_SA_DQ<6> MAA_DATA6 @T6G_MB_LIB.T6G(SCH_1):M_A_CPU0_SA_DQ(6)
AJ74 M_A_CPU0_SA_CB<0> MAA_CHECK0 @T6G_MB_LIB.T6G(SCH_1):M_A_CPU0_SA_CB(0)
DC73 M_A_CPU0_SB_DQS_DN<8> MAB_DQS_L8 @T6G_MB_LIB.T6G(SCH_1):M_A_CPU0_SB_DQS_DN(8)
BY72 M_A_CPU0_SB_DQS_DP<4> MAB_DQS_H4 @T6G_MB_LIB.T6G(SCH_1):M_A_CPU0_SB_DQS_DP(4)
CG74 M_A_CPU0_SB_DQ<6> MAB_DATA6 @T6G_MB_LIB.T6G(SCH_1):M_A_CPU0_SB_DQ(6)
AB72 M_A_CPU0_SA_DQ<21> MAA_DATA21 @T6G_MB_LIB.T6G(SCH_1):M_A_CPU0_SA_DQ(21)
 M74 M_A_CPU0_SA_DQ<10> MAA_DATA10 @T6G_MB_LIB.T6G(SCH_1):M_A_CPU0_SA_DQ(10)
 L73 M_A_CPU0_SA_DQ<7> MAA_DATA7 @T6G_MB_LIB.T6G(SCH_1):M_A_CPU0_SA_DQ(7)
AK72 M_A_CPU0_SA_CB<1> MAA_CHECK1 @T6G_MB_LIB.T6G(SCH_1):M_A_CPU0_SA_CB(1)
BW74 M_A_CPU0_SB_DQS_DN<9> MAB_DQS_L9 @T6G_MB_LIB.T6G(SCH_1):M_A_CPU0_SB_DQS_DN(9)
CF72 M_A_CPU0_SB_DQS_DP<5> MAB_DQS_H5 @T6G_MB_LIB.T6G(SCH_1):M_A_CPU0_SB_DQS_DP(5)
CH72 M_A_CPU0_SB_DQ<7> MAB_DATA7 @T6G_MB_LIB.T6G(SCH_1):M_A_CPU0_SB_DQ(7)
AB74 M_A_CPU0_SA_DQ<22> MAA_DATA22 @T6G_MB_LIB.T6G(SCH_1):M_A_CPU0_SA_DQ(22)
 N73 M_A_CPU0_SA_DQ<11> MAA_DATA11 @T6G_MB_LIB.T6G(SCH_1):M_A_CPU0_SA_DQ(11)
 L74 M_A_CPU0_SA_DQ<8> MAA_DATA8 @T6G_MB_LIB.T6G(SCH_1):M_A_CPU0_SA_DQ(8)
AK74 M_A_CPU0_SA_CB<2> MAA_CHECK2 @T6G_MB_LIB.T6G(SCH_1):M_A_CPU0_SA_CB(2)
CM72 M_A_CPU0_SB_DQS_DP<6> MAB_DQS_H6 @T6G_MB_LIB.T6G(SCH_1):M_A_CPU0_SB_DQS_DP(6)
CH74 M_A_CPU0_SB_DQ<8> MAB_DATA8 @T6G_MB_LIB.T6G(SCH_1):M_A_CPU0_SB_DQ(8)
BM72 M_A_CPU0_SB_CS_N<0> MAB0_CS_L0 @T6G_MB_LIB.T6G(SCH_1):M_A_CPU0_SB_CS_N(0)
AC73 M_A_CPU0_SA_DQ<23> MAA_DATA23 @T6G_MB_LIB.T6G(SCH_1):M_A_CPU0_SA_DQ(23)
 R74 M_A_CPU0_SA_DQ<12> MAA_DATA12 @T6G_MB_LIB.T6G(SCH_1):M_A_CPU0_SA_DQ(12)
 M72 M_A_CPU0_SA_DQ<9> MAA_DATA9 @T6G_MB_LIB.T6G(SCH_1):M_A_CPU0_SA_DQ(9)
AL73 M_A_CPU0_SA_CB<3> MAA_CHECK3 @T6G_MB_LIB.T6G(SCH_1):M_A_CPU0_SA_CB(3)
CV72 M_A_CPU0_SB_DQS_DP<7> MAB_DQS_H7 @T6G_MB_LIB.T6G(SCH_1):M_A_CPU0_SB_DQS_DP(7)
CJ73 M_A_CPU0_SB_DQ<9> MAB_DATA9 @T6G_MB_LIB.T6G(SCH_1):M_A_CPU0_SB_DQ(9)
BL73     NC MAB1_CS_L0     NC
BN74 M_A_CPU0_SB_CS_N<1> MAB0_CS_L1 @T6G_MB_LIB.T6G(SCH_1):M_A_CPU0_SB_CS_N(1)
 H74 M_A_CPU0_SA_DQS_DN<0> MAA_DQS_L0 @T6G_MB_LIB.T6G(SCH_1):M_A_CPU0_SA_DQS_DN(0)
AC74 M_A_CPU0_SA_DQ<24> MAA_DATA24 @T6G_MB_LIB.T6G(SCH_1):M_A_CPU0_SA_DQ(24)
 T72 M_A_CPU0_SA_DQ<13> MAA_DATA13 @T6G_MB_LIB.T6G(SCH_1):M_A_CPU0_SA_DQ(13)
AN74 M_A_CPU0_SA_CB<4> MAA_CHECK4 @T6G_MB_LIB.T6G(SCH_1):M_A_CPU0_SA_CB(4)
DD72 M_A_CPU0_SB_DQS_DP<8> MAB_DQS_H8 @T6G_MB_LIB.T6G(SCH_1):M_A_CPU0_SB_DQS_DP(8)
DE74 M_A_CPU0_SB_DQ<30> MAB_DATA30 @T6G_MB_LIB.T6G(SCH_1):M_A_CPU0_SB_DQ(30)
BM74     NC MAB1_CS_L1     NC
 P74 M_A_CPU0_SA_DQS_DN<1> MAA_DQS_L1 @T6G_MB_LIB.T6G(SCH_1):M_A_CPU0_SA_DQS_DN(1)
AD72 M_A_CPU0_SA_DQ<25> MAA_DATA25 @T6G_MB_LIB.T6G(SCH_1):M_A_CPU0_SA_DQ(25)
 T74 M_A_CPU0_SA_DQ<14> MAA_DATA14 @T6G_MB_LIB.T6G(SCH_1):M_A_CPU0_SA_DQ(14)
AP72 M_A_CPU0_SA_CB<5> MAA_CHECK5 @T6G_MB_LIB.T6G(SCH_1):M_A_CPU0_SA_CB(5)
DF74 M_A_CPU0_SB_DQ<31> MAB_DATA31 @T6G_MB_LIB.T6G(SCH_1):M_A_CPU0_SB_DQ(31)
CV74 M_A_CPU0_SB_DQ<20> MAB_DATA20 @T6G_MB_LIB.T6G(SCH_1):M_A_CPU0_SB_DQ(20)
BY74 M_A_CPU0_SB_CB<0> MAB_CHECK0 @T6G_MB_LIB.T6G(SCH_1):M_A_CPU0_SB_CB(0)
 Y74 M_A_CPU0_SA_DQS_DN<2> MAA_DQS_L2 @T6G_MB_LIB.T6G(SCH_1):M_A_CPU0_SA_DQS_DN(2)
AD74 M_A_CPU0_SA_DQ<26> MAA_DATA26 @T6G_MB_LIB.T6G(SCH_1):M_A_CPU0_SA_DQ(26)
 U73 M_A_CPU0_SA_DQ<15> MAA_DATA15 @T6G_MB_LIB.T6G(SCH_1):M_A_CPU0_SA_DQ(15)
AP74 M_A_CPU0_SA_CB<6> MAA_CHECK6 @T6G_MB_LIB.T6G(SCH_1):M_A_CPU0_SA_CB(6)
BN73 M_A_CPU0_SA_RSP<0> MAA0_RSP_L @T6G_MB_LIB.T6G(SCH_1):M_A_CPU0_SA_RSP(0)
CW73 M_A_CPU0_SB_DQ<21> MAB_DATA21 @T6G_MB_LIB.T6G(SCH_1):M_A_CPU0_SB_DQ(21)
CJ74 M_A_CPU0_SB_DQ<10> MAB_DATA10 @T6G_MB_LIB.T6G(SCH_1):M_A_CPU0_SB_DQ(10)
CA73 M_A_CPU0_SB_CB<1> MAB_CHECK1 @T6G_MB_LIB.T6G(SCH_1):M_A_CPU0_SB_CB(1)
AF74 M_A_CPU0_SA_DQS_DN<3> MAA_DQS_L3 @T6G_MB_LIB.T6G(SCH_1):M_A_CPU0_SA_DQS_DN(3)
AE73 M_A_CPU0_SA_DQ<27> MAA_DATA27 @T6G_MB_LIB.T6G(SCH_1):M_A_CPU0_SA_DQ(27)
 U74 M_A_CPU0_SA_DQ<16> MAA_DATA16 @T6G_MB_LIB.T6G(SCH_1):M_A_CPU0_SA_DQ(16)
AR73 M_A_CPU0_SA_CB<7> MAA_CHECK7 @T6G_MB_LIB.T6G(SCH_1):M_A_CPU0_SA_CB(7)
AW74 M_A_CPU0_SA_CA<0> MAA_CA0 @T6G_MB_LIB.T6G(SCH_1):M_A_CPU0_SA_CA(0)
BP72     NC MAA1_RSP_L     NC
CW74 M_A_CPU0_SB_DQ<22> MAB_DATA22 @T6G_MB_LIB.T6G(SCH_1):M_A_CPU0_SB_DQ(22)
CK72 M_A_CPU0_SB_DQ<11> MAB_DATA11 @T6G_MB_LIB.T6G(SCH_1):M_A_CPU0_SB_DQ(11)
CA74 M_A_CPU0_SB_CB<2> MAB_CHECK2 @T6G_MB_LIB.T6G(SCH_1):M_A_CPU0_SB_CB(2)
BG73 M_A_CPU0_SB_CA<0> MAB_CA0 @T6G_MB_LIB.T6G(SCH_1):M_A_CPU0_SB_CA(0)
AM74 M_A_CPU0_SA_DQS_DN<4> MAA_DQS_L4 @T6G_MB_LIB.T6G(SCH_1):M_A_CPU0_SA_DQS_DN(4)
 G74 M_A_CPU0_SA_DQS_DP<0> MAA_DQS_H0 @T6G_MB_LIB.T6G(SCH_1):M_A_CPU0_SA_DQS_DP(0)
AG74 M_A_CPU0_SA_DQ<28> MAA_DATA28 @T6G_MB_LIB.T6G(SCH_1):M_A_CPU0_SA_DQ(28)
 V72 M_A_CPU0_SA_DQ<17> MAA_DATA17 @T6G_MB_LIB.T6G(SCH_1):M_A_CPU0_SA_DQ(17)
AY74 M_A_CPU0_SA_CA<1> MAA_CA1 @T6G_MB_LIB.T6G(SCH_1):M_A_CPU0_SA_CA(1)
CY72 M_A_CPU0_SB_DQ<23> MAB_DATA23 @T6G_MB_LIB.T6G(SCH_1):M_A_CPU0_SB_DQ(23)
CM74 M_A_CPU0_SB_DQ<12> MAB_DATA12 @T6G_MB_LIB.T6G(SCH_1):M_A_CPU0_SB_DQ(12)
CB72 M_A_CPU0_SB_CB<3> MAB_CHECK3 @T6G_MB_LIB.T6G(SCH_1):M_A_CPU0_SB_CB(3)
BH72 M_A_CPU0_SB_CA<1> MAB_CA1 @T6G_MB_LIB.T6G(SCH_1):M_A_CPU0_SB_CA(1)
 H72 M_A_CPU0_SA_DQS_DN<5> MAA_DQS_L5 @T6G_MB_LIB.T6G(SCH_1):M_A_CPU0_SA_DQS_DN(5)
 N74 M_A_CPU0_SA_DQS_DP<1> MAA_DQS_H1 @T6G_MB_LIB.T6G(SCH_1):M_A_CPU0_SA_DQS_DP(1)
AH72 M_A_CPU0_SA_DQ<29> MAA_DATA29 @T6G_MB_LIB.T6G(SCH_1):M_A_CPU0_SA_DQ(29)
 V74 M_A_CPU0_SA_DQ<18> MAA_DATA18 @T6G_MB_LIB.T6G(SCH_1):M_A_CPU0_SA_DQ(18)
AY72 M_A_CPU0_SA_CA<2> MAA_CA2 @T6G_MB_LIB.T6G(SCH_1):M_A_CPU0_SA_CA(2)
CE74 M_A_CPU0_SB_DQS_DN<0> MAB_DQS_L0 @T6G_MB_LIB.T6G(SCH_1):M_A_CPU0_SB_DQS_DN(0)
CY74 M_A_CPU0_SB_DQ<24> MAB_DATA24 @T6G_MB_LIB.T6G(SCH_1):M_A_CPU0_SB_DQ(24)
CN73 M_A_CPU0_SB_DQ<13> MAB_DATA13 @T6G_MB_LIB.T6G(SCH_1):M_A_CPU0_SB_DQ(13)
BT74 M_A_CPU0_SB_CB<4> MAB_CHECK4 @T6G_MB_LIB.T6G(SCH_1):M_A_CPU0_SB_CB(4)
BH74 M_A_CPU0_SB_CA<2> MAB_CA2 @T6G_MB_LIB.T6G(SCH_1):M_A_CPU0_SB_CA(2)
 P72 M_A_CPU0_SA_DQS_DN<6> MAA_DQS_L6 @T6G_MB_LIB.T6G(SCH_1):M_A_CPU0_SA_DQS_DN(6)
 W74 M_A_CPU0_SA_DQS_DP<2> MAA_DQS_H2 @T6G_MB_LIB.T6G(SCH_1):M_A_CPU0_SA_DQS_DP(2)
 W73 M_A_CPU0_SA_DQ<19> MAA_DATA19 @T6G_MB_LIB.T6G(SCH_1):M_A_CPU0_SA_DQ(19)
BA73 M_A_CPU0_SA_CA<3> MAA_CA3 @T6G_MB_LIB.T6G(SCH_1):M_A_CPU0_SA_CA(3)
CL74 M_A_CPU0_SB_DQS_DN<1> MAB_DQS_L1 @T6G_MB_LIB.T6G(SCH_1):M_A_CPU0_SB_DQS_DN(1)
DA73 M_A_CPU0_SB_DQ<25> MAB_DATA25 @T6G_MB_LIB.T6G(SCH_1):M_A_CPU0_SB_DQ(25)
CN74 M_A_CPU0_SB_DQ<14> MAB_DATA14 @T6G_MB_LIB.T6G(SCH_1):M_A_CPU0_SB_DQ(14)
BU73 M_A_CPU0_SB_CB<5> MAB_CHECK5 @T6G_MB_LIB.T6G(SCH_1):M_A_CPU0_SB_CB(5)
BJ74 M_A_CPU0_SB_CA<3> MAB_CA3 @T6G_MB_LIB.T6G(SCH_1):M_A_CPU0_SB_CA(3)
 Y72 M_A_CPU0_SA_DQS_DN<7> MAA_DQS_L7 @T6G_MB_LIB.T6G(SCH_1):M_A_CPU0_SA_DQS_DN(7)
AE74 M_A_CPU0_SA_DQS_DP<3> MAA_DQS_H3 @T6G_MB_LIB.T6G(SCH_1):M_A_CPU0_SA_DQS_DP(3)
 E74 M_A_CPU0_SA_DQ<0> MAA_DATA0 @T6G_MB_LIB.T6G(SCH_1):M_A_CPU0_SA_DQ(0)
BA74 M_A_CPU0_SA_CA<4> MAA_CA4 @T6G_MB_LIB.T6G(SCH_1):M_A_CPU0_SA_CA(4)
CU74 M_A_CPU0_SB_DQS_DN<2> MAB_DQS_L2 @T6G_MB_LIB.T6G(SCH_1):M_A_CPU0_SB_DQS_DN(2)
DA74 M_A_CPU0_SB_DQ<26> MAB_DATA26 @T6G_MB_LIB.T6G(SCH_1):M_A_CPU0_SB_DQ(26)
CP72 M_A_CPU0_SB_DQ<15> MAB_DATA15 @T6G_MB_LIB.T6G(SCH_1):M_A_CPU0_SB_DQ(15)
CB74 M_A_CPU0_SB_DQ<0> MAB_DATA0 @T6G_MB_LIB.T6G(SCH_1):M_A_CPU0_SB_DQ(0)
BU74 M_A_CPU0_SB_CB<6> MAB_CHECK6 @T6G_MB_LIB.T6G(SCH_1):M_A_CPU0_SB_CB(6)
BJ73 M_A_CPU0_SB_CA<4> MAB_CA4 @T6G_MB_LIB.T6G(SCH_1):M_A_CPU0_SB_CA(4)
BP74 M_A_CPU0_SB_RSP<0> MAB0_RSP_L @T6G_MB_LIB.T6G(SCH_1):M_A_CPU0_SB_RSP(0)
AF72 M_A_CPU0_SA_DQS_DN<8> MAA_DQS_L8 @T6G_MB_LIB.T6G(SCH_1):M_A_CPU0_SA_DQS_DN(8)
AL74 M_A_CPU0_SA_DQS_DP<4> MAA_DQS_H4 @T6G_MB_LIB.T6G(SCH_1):M_A_CPU0_SA_DQS_DP(4)
 F72 M_A_CPU0_SA_DQ<1> MAA_DATA1 @T6G_MB_LIB.T6G(SCH_1):M_A_CPU0_SA_DQ(1)
BB74 M_A_CPU0_SA_CA<5> MAA_CA5 @T6G_MB_LIB.T6G(SCH_1):M_A_CPU0_SA_CA(5)
DC74 M_A_CPU0_SB_DQS_DN<3> MAB_DQS_L3 @T6G_MB_LIB.T6G(SCH_1):M_A_CPU0_SB_DQS_DN(3)
DB72 M_A_CPU0_SB_DQ<27> MAB_DATA27 @T6G_MB_LIB.T6G(SCH_1):M_A_CPU0_SB_DQ(27)
CP74 M_A_CPU0_SB_DQ<16> MAB_DATA16 @T6G_MB_LIB.T6G(SCH_1):M_A_CPU0_SB_DQ(16)
CC73 M_A_CPU0_SB_DQ<1> MAB_DATA1 @T6G_MB_LIB.T6G(SCH_1):M_A_CPU0_SB_DQ(1)
BV72 M_A_CPU0_SB_CB<7> MAB_CHECK7 @T6G_MB_LIB.T6G(SCH_1):M_A_CPU0_SB_CB(7)
BK72 M_A_CPU0_SB_CA<5> MAB_CA5 @T6G_MB_LIB.T6G(SCH_1):M_A_CPU0_SB_CA(5)
BR74     NC MAB1_RSP_L     NC
AM72 M_A_CPU0_SA_DQS_DN<9> MAA_DQS_L9 @T6G_MB_LIB.T6G(SCH_1):M_A_CPU0_SA_DQS_DN(9)
 J73 M_A_CPU0_SA_DQS_DP<5> MAA_DQS_H5 @T6G_MB_LIB.T6G(SCH_1):M_A_CPU0_SA_DQS_DP(5)
 F74 M_A_CPU0_SA_DQ<2> MAA_DATA2 @T6G_MB_LIB.T6G(SCH_1):M_A_CPU0_SA_DQ(2)
BB72 M_A_CPU0_SA_CA<6> MAA_CA6 @T6G_MB_LIB.T6G(SCH_1):M_A_CPU0_SA_CA(6)
BW73 M_A_CPU0_SB_DQS_DN<4> MAB_DQS_L4 @T6G_MB_LIB.T6G(SCH_1):M_A_CPU0_SB_DQS_DN(4)
CD74 M_A_CPU0_SB_DQS_DP<0> MAB_DQS_H0 @T6G_MB_LIB.T6G(SCH_1):M_A_CPU0_SB_DQS_DP(0)
DD74 M_A_CPU0_SB_DQ<28> MAB_DATA28 @T6G_MB_LIB.T6G(SCH_1):M_A_CPU0_SB_DQ(28)
CR73 M_A_CPU0_SB_DQ<17> MAB_DATA17 @T6G_MB_LIB.T6G(SCH_1):M_A_CPU0_SB_DQ(17)
CC74 M_A_CPU0_SB_DQ<2> MAB_DATA2 @T6G_MB_LIB.T6G(SCH_1):M_A_CPU0_SB_DQ(2)
BK74 M_A_CPU0_SB_CA<6> MAB_CA6 @T6G_MB_LIB.T6G(SCH_1):M_A_CPU0_SB_CA(6)
 R73 M_A_CPU0_SA_DQS_DP<6> MAA_DQS_H6 @T6G_MB_LIB.T6G(SCH_1):M_A_CPU0_SA_DQS_DP(6)
 G73 M_A_CPU0_SA_DQ<3> MAA_DATA3 @T6G_MB_LIB.T6G(SCH_1):M_A_CPU0_SA_DQ(3)
AV74 M_A_CPU0_SA_CS_N<0> MAA0_CS_L0 @T6G_MB_LIB.T6G(SCH_1):M_A_CPU0_SA_CS_N(0)
BC73 M_A_CPU0_SA_PAR MAA_PAR @T6G_MB_LIB.T6G(SCH_1):M_A_CPU0_SA_PAR
BL74 M_A_CPU0_SB_PAR MAB_PAR @T6G_MB_LIB.T6G(SCH_1):M_A_CPU0_SB_PAR
BC74 M_A_CPU0_CLK_DP<0> MA0_CLK_H @T6G_MB_LIB.T6G(SCH_1):M_A_CPU0_CLK_DP(0)
BV74 M_A_CPU0_SB_DQS_DP<9> MAB_DQS_H9 @T6G_MB_LIB.T6G(SCH_1):M_A_CPU0_SB_DQS_DP(9)
BF74     NC MA1_CLK_H     NC
BD74 M_A_CPU0_CLK_DN<0> MA0_CLK_L @T6G_MB_LIB.T6G(SCH_1):M_A_CPU0_CLK_DN(0)
BG74     NC MA1_CLK_L     NC
BF72 TP_M_A_CPU0_SA_TEST39A TEST39A @T6G_MB_LIB.T6G(SCH_1):TP_M_A_CPU0_SA_TEST39A
 C60 TP_M_A_CPU0_SA_TEST40 TEST40 @T6G_MB_LIB.T6G(SCH_1):TP_M_A_CPU0_SA_TEST40

Q_RES_0402LF-15,1%,1/16W,CHIP,CS01502FB03  I837  R375
   1 M_A_CPU0_ALERT_N      A @T6G_MB_LIB.T6G(SCH_1):M_A_CPU0_ALERT_N
   2 M_A_CPU0_ALERT_R_N      B @T6G_MB_LIB.T6G(SCH_1):M_A_CPU0_ALERT_R_N


DRAWING: @T6G_MB_LIB.T6G(SCH_1):PAGE11 

GENOA_SP5-SOCKET6096_13568-001,SMLF,IO,DGA^6000030  I171  U25
AT62 M_B_CPU0_ALERT_R_N MB_ALERT_L @T6G_MB_LIB.T6G(SCH_1):M_B_CPU0_ALERT_R_N
AU62 M_B_CPU0_RESET_N MB_RESET_L @T6G_MB_LIB.T6G(SCH_1):M_B_CPU0_RESET_N
BW64 M_B_CPU0_SB_DQS_DN<9> MBB_DQS_L9 @T6G_MB_LIB.T6G(SCH_1):M_B_CPU0_SB_DQS_DN(9)
CF62 M_B_CPU0_SB_DQS_DP<5> MBB_DQS_H5 @T6G_MB_LIB.T6G(SCH_1):M_B_CPU0_SB_DQS_DP(5)
AB63 M_B_CPU0_SA_DQ<22> MBA_DATA22 @T6G_MB_LIB.T6G(SCH_1):M_B_CPU0_SA_DQ(22)
 N62 M_B_CPU0_SA_DQ<11> MBA_DATA11 @T6G_MB_LIB.T6G(SCH_1):M_B_CPU0_SA_DQ(11)
AK63 M_B_CPU0_SA_CB<2> MBA_CHECK2 @T6G_MB_LIB.T6G(SCH_1):M_B_CPU0_SA_CB(2)
CM62 M_B_CPU0_SB_DQS_DP<6> MBB_DQS_H6 @T6G_MB_LIB.T6G(SCH_1):M_B_CPU0_SB_DQS_DP(6)
AC62 M_B_CPU0_SA_DQ<23> MBA_DATA23 @T6G_MB_LIB.T6G(SCH_1):M_B_CPU0_SA_DQ(23)
 R64 M_B_CPU0_SA_DQ<12> MBA_DATA12 @T6G_MB_LIB.T6G(SCH_1):M_B_CPU0_SA_DQ(12)
AL62 M_B_CPU0_SA_CB<3> MBA_CHECK3 @T6G_MB_LIB.T6G(SCH_1):M_B_CPU0_SA_CB(3)
CV62 M_B_CPU0_SB_DQS_DP<7> MBB_DQS_H7 @T6G_MB_LIB.T6G(SCH_1):M_B_CPU0_SB_DQS_DP(7)
BM62 M_B_CPU0_SB_CS_N<0> MBB0_CS_L0 @T6G_MB_LIB.T6G(SCH_1):M_B_CPU0_SB_CS_N(0)
 H63 M_B_CPU0_SA_DQS_DN<0> MBA_DQS_L0 @T6G_MB_LIB.T6G(SCH_1):M_B_CPU0_SA_DQS_DN(0)
 T62 M_B_CPU0_SA_DQ<13> MBA_DATA13 @T6G_MB_LIB.T6G(SCH_1):M_B_CPU0_SA_DQ(13)
 E64 M_B_CPU0_SA_DQ<0> MBA_DATA0 @T6G_MB_LIB.T6G(SCH_1):M_B_CPU0_SA_DQ(0)
AN64 M_B_CPU0_SA_CB<4> MBA_CHECK4 @T6G_MB_LIB.T6G(SCH_1):M_B_CPU0_SA_CB(4)
DD62 M_B_CPU0_SB_DQS_DP<8> MBB_DQS_H8 @T6G_MB_LIB.T6G(SCH_1):M_B_CPU0_SB_DQS_DP(8)
DE64 M_B_CPU0_SB_DQ<30> MBB_DATA30 @T6G_MB_LIB.T6G(SCH_1):M_B_CPU0_SB_DQ(30)
CB63 M_B_CPU0_SB_DQ<0> MBB_DATA0 @T6G_MB_LIB.T6G(SCH_1):M_B_CPU0_SB_DQ(0)
BL62     NC MBB1_CS_L0     NC
BN64 M_B_CPU0_SB_CS_N<1> MBB0_CS_L1 @T6G_MB_LIB.T6G(SCH_1):M_B_CPU0_SB_CS_N(1)
 P63 M_B_CPU0_SA_DQS_DN<1> MBA_DQS_L1 @T6G_MB_LIB.T6G(SCH_1):M_B_CPU0_SA_DQS_DN(1)
AD62 M_B_CPU0_SA_DQ<25> MBA_DATA25 @T6G_MB_LIB.T6G(SCH_1):M_B_CPU0_SA_DQ(25)
 T63 M_B_CPU0_SA_DQ<14> MBA_DATA14 @T6G_MB_LIB.T6G(SCH_1):M_B_CPU0_SA_DQ(14)
 F62 M_B_CPU0_SA_DQ<1> MBA_DATA1 @T6G_MB_LIB.T6G(SCH_1):M_B_CPU0_SA_DQ(1)
AP62 M_B_CPU0_SA_CB<5> MBA_CHECK5 @T6G_MB_LIB.T6G(SCH_1):M_B_CPU0_SA_CB(5)
DF62 M_B_CPU0_SB_DQ<31> MBB_DATA31 @T6G_MB_LIB.T6G(SCH_1):M_B_CPU0_SB_DQ(31)
CC62 M_B_CPU0_SB_DQ<1> MBB_DATA1 @T6G_MB_LIB.T6G(SCH_1):M_B_CPU0_SB_DQ(1)
BY63 M_B_CPU0_SB_CB<0> MBB_CHECK0 @T6G_MB_LIB.T6G(SCH_1):M_B_CPU0_SB_CB(0)
BM63     NC MBB1_CS_L1     NC
 Y63 M_B_CPU0_SA_DQS_DN<2> MBA_DQS_L2 @T6G_MB_LIB.T6G(SCH_1):M_B_CPU0_SA_DQS_DN(2)
AD63 M_B_CPU0_SA_DQ<26> MBA_DATA26 @T6G_MB_LIB.T6G(SCH_1):M_B_CPU0_SA_DQ(26)
 U62 M_B_CPU0_SA_DQ<15> MBA_DATA15 @T6G_MB_LIB.T6G(SCH_1):M_B_CPU0_SA_DQ(15)
 F63 M_B_CPU0_SA_DQ<2> MBA_DATA2 @T6G_MB_LIB.T6G(SCH_1):M_B_CPU0_SA_DQ(2)
AP63 M_B_CPU0_SA_CB<6> MBA_CHECK6 @T6G_MB_LIB.T6G(SCH_1):M_B_CPU0_SA_CB(6)
CW62 M_B_CPU0_SB_DQ<21> MBB_DATA21 @T6G_MB_LIB.T6G(SCH_1):M_B_CPU0_SB_DQ(21)
CJ64 M_B_CPU0_SB_DQ<10> MBB_DATA10 @T6G_MB_LIB.T6G(SCH_1):M_B_CPU0_SB_DQ(10)
CC64 M_B_CPU0_SB_DQ<2> MBB_DATA2 @T6G_MB_LIB.T6G(SCH_1):M_B_CPU0_SB_DQ(2)
CA62 M_B_CPU0_SB_CB<1> MBB_CHECK1 @T6G_MB_LIB.T6G(SCH_1):M_B_CPU0_SB_CB(1)
AF63 M_B_CPU0_SA_DQS_DN<3> MBA_DQS_L3 @T6G_MB_LIB.T6G(SCH_1):M_B_CPU0_SA_DQS_DN(3)
AE62 M_B_CPU0_SA_DQ<27> MBA_DATA27 @T6G_MB_LIB.T6G(SCH_1):M_B_CPU0_SA_DQ(27)
 U64 M_B_CPU0_SA_DQ<16> MBA_DATA16 @T6G_MB_LIB.T6G(SCH_1):M_B_CPU0_SA_DQ(16)
 G62 M_B_CPU0_SA_DQ<3> MBA_DATA3 @T6G_MB_LIB.T6G(SCH_1):M_B_CPU0_SA_DQ(3)
AR62 M_B_CPU0_SA_CB<7> MBA_CHECK7 @T6G_MB_LIB.T6G(SCH_1):M_B_CPU0_SA_CB(7)
BN62 M_B_CPU0_SA_RSP<0> MBA0_RSP_L @T6G_MB_LIB.T6G(SCH_1):M_B_CPU0_SA_RSP(0)
CW64 M_B_CPU0_SB_DQ<22> MBB_DATA22 @T6G_MB_LIB.T6G(SCH_1):M_B_CPU0_SB_DQ(22)
CK62 M_B_CPU0_SB_DQ<11> MBB_DATA11 @T6G_MB_LIB.T6G(SCH_1):M_B_CPU0_SB_DQ(11)
CD62 M_B_CPU0_SB_DQ<3> MBB_DATA3 @T6G_MB_LIB.T6G(SCH_1):M_B_CPU0_SB_DQ(3)
CA64 M_B_CPU0_SB_CB<2> MBB_CHECK2 @T6G_MB_LIB.T6G(SCH_1):M_B_CPU0_SB_CB(2)
AM63 M_B_CPU0_SA_DQS_DN<4> MBA_DQS_L4 @T6G_MB_LIB.T6G(SCH_1):M_B_CPU0_SA_DQS_DN(4)
 G64 M_B_CPU0_SA_DQS_DP<0> MBA_DQS_H0 @T6G_MB_LIB.T6G(SCH_1):M_B_CPU0_SA_DQS_DP(0)
AG64 M_B_CPU0_SA_DQ<28> MBA_DATA28 @T6G_MB_LIB.T6G(SCH_1):M_B_CPU0_SA_DQ(28)
 V62 M_B_CPU0_SA_DQ<17> MBA_DATA17 @T6G_MB_LIB.T6G(SCH_1):M_B_CPU0_SA_DQ(17)
 J64 M_B_CPU0_SA_DQ<4> MBA_DATA4 @T6G_MB_LIB.T6G(SCH_1):M_B_CPU0_SA_DQ(4)
BP62     NC MBA1_RSP_L     NC
CY62 M_B_CPU0_SB_DQ<23> MBB_DATA23 @T6G_MB_LIB.T6G(SCH_1):M_B_CPU0_SB_DQ(23)
CM63 M_B_CPU0_SB_DQ<12> MBB_DATA12 @T6G_MB_LIB.T6G(SCH_1):M_B_CPU0_SB_DQ(12)
CF63 M_B_CPU0_SB_DQ<4> MBB_DATA4 @T6G_MB_LIB.T6G(SCH_1):M_B_CPU0_SB_DQ(4)
CB62 M_B_CPU0_SB_CB<3> MBB_CHECK3 @T6G_MB_LIB.T6G(SCH_1):M_B_CPU0_SB_CB(3)
 H62 M_B_CPU0_SA_DQS_DN<5> MBA_DQS_L5 @T6G_MB_LIB.T6G(SCH_1):M_B_CPU0_SA_DQS_DN(5)
 N64 M_B_CPU0_SA_DQS_DP<1> MBA_DQS_H1 @T6G_MB_LIB.T6G(SCH_1):M_B_CPU0_SA_DQS_DP(1)
AH62 M_B_CPU0_SA_DQ<29> MBA_DATA29 @T6G_MB_LIB.T6G(SCH_1):M_B_CPU0_SA_DQ(29)
 V63 M_B_CPU0_SA_DQ<18> MBA_DATA18 @T6G_MB_LIB.T6G(SCH_1):M_B_CPU0_SA_DQ(18)
 K62 M_B_CPU0_SA_DQ<5> MBA_DATA5 @T6G_MB_LIB.T6G(SCH_1):M_B_CPU0_SA_DQ(5)
CE64 M_B_CPU0_SB_DQS_DN<0> MBB_DQS_L0 @T6G_MB_LIB.T6G(SCH_1):M_B_CPU0_SB_DQS_DN(0)
CY63 M_B_CPU0_SB_DQ<24> MBB_DATA24 @T6G_MB_LIB.T6G(SCH_1):M_B_CPU0_SB_DQ(24)
CN62 M_B_CPU0_SB_DQ<13> MBB_DATA13 @T6G_MB_LIB.T6G(SCH_1):M_B_CPU0_SB_DQ(13)
CG62 M_B_CPU0_SB_DQ<5> MBB_DATA5 @T6G_MB_LIB.T6G(SCH_1):M_B_CPU0_SB_DQ(5)
BT63 M_B_CPU0_SB_CB<4> MBB_CHECK4 @T6G_MB_LIB.T6G(SCH_1):M_B_CPU0_SB_CB(4)
 P62 M_B_CPU0_SA_DQS_DN<6> MBA_DQS_L6 @T6G_MB_LIB.T6G(SCH_1):M_B_CPU0_SA_DQS_DN(6)
 W64 M_B_CPU0_SA_DQS_DP<2> MBA_DQS_H2 @T6G_MB_LIB.T6G(SCH_1):M_B_CPU0_SA_DQS_DP(2)
 W62 M_B_CPU0_SA_DQ<19> MBA_DATA19 @T6G_MB_LIB.T6G(SCH_1):M_B_CPU0_SA_DQ(19)
 K63 M_B_CPU0_SA_DQ<6> MBA_DATA6 @T6G_MB_LIB.T6G(SCH_1):M_B_CPU0_SA_DQ(6)
AW64 M_B_CPU0_SA_CA<0> MBA_CA0 @T6G_MB_LIB.T6G(SCH_1):M_B_CPU0_SA_CA(0)
CL64 M_B_CPU0_SB_DQS_DN<1> MBB_DQS_L1 @T6G_MB_LIB.T6G(SCH_1):M_B_CPU0_SB_DQS_DN(1)
DA62 M_B_CPU0_SB_DQ<25> MBB_DATA25 @T6G_MB_LIB.T6G(SCH_1):M_B_CPU0_SB_DQ(25)
CN64 M_B_CPU0_SB_DQ<14> MBB_DATA14 @T6G_MB_LIB.T6G(SCH_1):M_B_CPU0_SB_DQ(14)
CG64 M_B_CPU0_SB_DQ<6> MBB_DATA6 @T6G_MB_LIB.T6G(SCH_1):M_B_CPU0_SB_DQ(6)
BU62 M_B_CPU0_SB_CB<5> MBB_CHECK5 @T6G_MB_LIB.T6G(SCH_1):M_B_CPU0_SB_CB(5)
BG62 M_B_CPU0_SB_CA<0> MBB_CA0 @T6G_MB_LIB.T6G(SCH_1):M_B_CPU0_SB_CA(0)
 Y62 M_B_CPU0_SA_DQS_DN<7> MBA_DQS_L7 @T6G_MB_LIB.T6G(SCH_1):M_B_CPU0_SA_DQS_DN(7)
AE64 M_B_CPU0_SA_DQS_DP<3> MBA_DQS_H3 @T6G_MB_LIB.T6G(SCH_1):M_B_CPU0_SA_DQS_DP(3)
 L62 M_B_CPU0_SA_DQ<7> MBA_DATA7 @T6G_MB_LIB.T6G(SCH_1):M_B_CPU0_SA_DQ(7)
AY63 M_B_CPU0_SA_CA<1> MBA_CA1 @T6G_MB_LIB.T6G(SCH_1):M_B_CPU0_SA_CA(1)
CU64 M_B_CPU0_SB_DQS_DN<2> MBB_DQS_L2 @T6G_MB_LIB.T6G(SCH_1):M_B_CPU0_SB_DQS_DN(2)
DA64 M_B_CPU0_SB_DQ<26> MBB_DATA26 @T6G_MB_LIB.T6G(SCH_1):M_B_CPU0_SB_DQ(26)
CP62 M_B_CPU0_SB_DQ<15> MBB_DATA15 @T6G_MB_LIB.T6G(SCH_1):M_B_CPU0_SB_DQ(15)
CH62 M_B_CPU0_SB_DQ<7> MBB_DATA7 @T6G_MB_LIB.T6G(SCH_1):M_B_CPU0_SB_DQ(7)
BU64 M_B_CPU0_SB_CB<6> MBB_CHECK6 @T6G_MB_LIB.T6G(SCH_1):M_B_CPU0_SB_CB(6)
BH62 M_B_CPU0_SB_CA<1> MBB_CA1 @T6G_MB_LIB.T6G(SCH_1):M_B_CPU0_SB_CA(1)
AF62 M_B_CPU0_SA_DQS_DN<8> MBA_DQS_L8 @T6G_MB_LIB.T6G(SCH_1):M_B_CPU0_SA_DQS_DN(8)
AL64 M_B_CPU0_SA_DQS_DP<4> MBA_DQS_H4 @T6G_MB_LIB.T6G(SCH_1):M_B_CPU0_SA_DQS_DP(4)
 L64 M_B_CPU0_SA_DQ<8> MBA_DATA8 @T6G_MB_LIB.T6G(SCH_1):M_B_CPU0_SA_DQ(8)
AY62 M_B_CPU0_SA_CA<2> MBA_CA2 @T6G_MB_LIB.T6G(SCH_1):M_B_CPU0_SA_CA(2)
DC64 M_B_CPU0_SB_DQS_DN<3> MBB_DQS_L3 @T6G_MB_LIB.T6G(SCH_1):M_B_CPU0_SB_DQS_DN(3)
DB62 M_B_CPU0_SB_DQ<27> MBB_DATA27 @T6G_MB_LIB.T6G(SCH_1):M_B_CPU0_SB_DQ(27)
CP63 M_B_CPU0_SB_DQ<16> MBB_DATA16 @T6G_MB_LIB.T6G(SCH_1):M_B_CPU0_SB_DQ(16)
CH63 M_B_CPU0_SB_DQ<8> MBB_DATA8 @T6G_MB_LIB.T6G(SCH_1):M_B_CPU0_SB_DQ(8)
BV62 M_B_CPU0_SB_CB<7> MBB_CHECK7 @T6G_MB_LIB.T6G(SCH_1):M_B_CPU0_SB_CB(7)
BH63 M_B_CPU0_SB_CA<2> MBB_CA2 @T6G_MB_LIB.T6G(SCH_1):M_B_CPU0_SB_CA(2)
BP63 M_B_CPU0_SB_RSP<0> MBB0_RSP_L @T6G_MB_LIB.T6G(SCH_1):M_B_CPU0_SB_RSP(0)
AM62 M_B_CPU0_SA_DQS_DN<9> MBA_DQS_L9 @T6G_MB_LIB.T6G(SCH_1):M_B_CPU0_SA_DQS_DN(9)
 J62 M_B_CPU0_SA_DQS_DP<5> MBA_DQS_H5 @T6G_MB_LIB.T6G(SCH_1):M_B_CPU0_SA_DQS_DP(5)
 M62 M_B_CPU0_SA_DQ<9> MBA_DATA9 @T6G_MB_LIB.T6G(SCH_1):M_B_CPU0_SA_DQ(9)
BA62 M_B_CPU0_SA_CA<3> MBA_CA3 @T6G_MB_LIB.T6G(SCH_1):M_B_CPU0_SA_CA(3)
BW62 M_B_CPU0_SB_DQS_DN<4> MBB_DQS_L4 @T6G_MB_LIB.T6G(SCH_1):M_B_CPU0_SB_DQS_DN(4)
CD63 M_B_CPU0_SB_DQS_DP<0> MBB_DQS_H0 @T6G_MB_LIB.T6G(SCH_1):M_B_CPU0_SB_DQS_DP(0)
DD63 M_B_CPU0_SB_DQ<28> MBB_DATA28 @T6G_MB_LIB.T6G(SCH_1):M_B_CPU0_SB_DQ(28)
CR62 M_B_CPU0_SB_DQ<17> MBB_DATA17 @T6G_MB_LIB.T6G(SCH_1):M_B_CPU0_SB_DQ(17)
CJ62 M_B_CPU0_SB_DQ<9> MBB_DATA9 @T6G_MB_LIB.T6G(SCH_1):M_B_CPU0_SB_DQ(9)
BJ64 M_B_CPU0_SB_CA<3> MBB_CA3 @T6G_MB_LIB.T6G(SCH_1):M_B_CPU0_SB_CA(3)
BR64     NC MBB1_RSP_L     NC
 R62 M_B_CPU0_SA_DQS_DP<6> MBA_DQS_H6 @T6G_MB_LIB.T6G(SCH_1):M_B_CPU0_SA_DQS_DP(6)
BA64 M_B_CPU0_SA_CA<4> MBA_CA4 @T6G_MB_LIB.T6G(SCH_1):M_B_CPU0_SA_CA(4)
CE62 M_B_CPU0_SB_DQS_DN<5> MBB_DQS_L5 @T6G_MB_LIB.T6G(SCH_1):M_B_CPU0_SB_DQS_DN(5)
CK63 M_B_CPU0_SB_DQS_DP<1> MBB_DQS_H1 @T6G_MB_LIB.T6G(SCH_1):M_B_CPU0_SB_DQS_DP(1)
DE62 M_B_CPU0_SB_DQ<29> MBB_DATA29 @T6G_MB_LIB.T6G(SCH_1):M_B_CPU0_SB_DQ(29)
CR64 M_B_CPU0_SB_DQ<18> MBB_DATA18 @T6G_MB_LIB.T6G(SCH_1):M_B_CPU0_SB_DQ(18)
BJ62 M_B_CPU0_SB_CA<4> MBB_CA4 @T6G_MB_LIB.T6G(SCH_1):M_B_CPU0_SB_CA(4)
AA62 M_B_CPU0_SA_DQS_DP<7> MBA_DQS_H7 @T6G_MB_LIB.T6G(SCH_1):M_B_CPU0_SA_DQS_DP(7)
BB63 M_B_CPU0_SA_CA<5> MBA_CA5 @T6G_MB_LIB.T6G(SCH_1):M_B_CPU0_SA_CA(5)
AV63 M_B_CPU0_SA_CS_N<0> MBA0_CS_L0 @T6G_MB_LIB.T6G(SCH_1):M_B_CPU0_SA_CS_N(0)
CL62 M_B_CPU0_SB_DQS_DN<6> MBB_DQS_L6 @T6G_MB_LIB.T6G(SCH_1):M_B_CPU0_SB_DQS_DN(6)
CT63 M_B_CPU0_SB_DQS_DP<2> MBB_DQS_H2 @T6G_MB_LIB.T6G(SCH_1):M_B_CPU0_SB_DQS_DP(2)
BK62 M_B_CPU0_SB_CA<5> MBB_CA5 @T6G_MB_LIB.T6G(SCH_1):M_B_CPU0_SB_CA(5)
AG62 M_B_CPU0_SA_DQS_DP<8> MBA_DQS_H8 @T6G_MB_LIB.T6G(SCH_1):M_B_CPU0_SA_DQS_DP(8)
AH63 M_B_CPU0_SA_DQ<30> MBA_DATA30 @T6G_MB_LIB.T6G(SCH_1):M_B_CPU0_SA_DQ(30)
BB62 M_B_CPU0_SA_CA<6> MBA_CA6 @T6G_MB_LIB.T6G(SCH_1):M_B_CPU0_SA_CA(6)
AU64     NC MBA1_CS_L0     NC
AW62 M_B_CPU0_SA_CS_N<1> MBA0_CS_L1 @T6G_MB_LIB.T6G(SCH_1):M_B_CPU0_SA_CS_N(1)
CU62 M_B_CPU0_SB_DQS_DN<7> MBB_DQS_L7 @T6G_MB_LIB.T6G(SCH_1):M_B_CPU0_SB_DQS_DN(7)
DB63 M_B_CPU0_SB_DQS_DP<3> MBB_DQS_H3 @T6G_MB_LIB.T6G(SCH_1):M_B_CPU0_SB_DQS_DP(3)
BK63 M_B_CPU0_SB_CA<6> MBB_CA6 @T6G_MB_LIB.T6G(SCH_1):M_B_CPU0_SB_CA(6)
AN62 M_B_CPU0_SA_DQS_DP<9> MBA_DQS_H9 @T6G_MB_LIB.T6G(SCH_1):M_B_CPU0_SA_DQS_DP(9)
AJ62 M_B_CPU0_SA_DQ<31> MBA_DATA31 @T6G_MB_LIB.T6G(SCH_1):M_B_CPU0_SA_DQ(31)
AA64 M_B_CPU0_SA_DQ<20> MBA_DATA20 @T6G_MB_LIB.T6G(SCH_1):M_B_CPU0_SA_DQ(20)
AJ64 M_B_CPU0_SA_CB<0> MBA_CHECK0 @T6G_MB_LIB.T6G(SCH_1):M_B_CPU0_SA_CB(0)
AV62     NC MBA1_CS_L1     NC
DC62 M_B_CPU0_SB_DQS_DN<8> MBB_DQS_L8 @T6G_MB_LIB.T6G(SCH_1):M_B_CPU0_SB_DQS_DN(8)
BY62 M_B_CPU0_SB_DQS_DP<4> MBB_DQS_H4 @T6G_MB_LIB.T6G(SCH_1):M_B_CPU0_SB_DQS_DP(4)
AB62 M_B_CPU0_SA_DQ<21> MBA_DATA21 @T6G_MB_LIB.T6G(SCH_1):M_B_CPU0_SA_DQ(21)
 M63 M_B_CPU0_SA_DQ<10> MBA_DATA10 @T6G_MB_LIB.T6G(SCH_1):M_B_CPU0_SA_DQ(10)
AK62 M_B_CPU0_SA_CB<1> MBA_CHECK1 @T6G_MB_LIB.T6G(SCH_1):M_B_CPU0_SA_CB(1)
BV63 M_B_CPU0_SB_DQS_DP<9> MBB_DQS_H9 @T6G_MB_LIB.T6G(SCH_1):M_B_CPU0_SB_DQS_DP(9)
BC62 M_B_CPU0_SA_PAR MBA_PAR @T6G_MB_LIB.T6G(SCH_1):M_B_CPU0_SA_PAR
BL64 M_B_CPU0_SB_PAR MBB_PAR @T6G_MB_LIB.T6G(SCH_1):M_B_CPU0_SB_PAR
BC64 M_B_CPU0_CLK_DP<0> MB0_CLK_H @T6G_MB_LIB.T6G(SCH_1):M_B_CPU0_CLK_DP(0)
BD63 M_B_CPU0_CLK_DN<0> MB0_CLK_L @T6G_MB_LIB.T6G(SCH_1):M_B_CPU0_CLK_DN(0)
BF63     NC MB1_CLK_H     NC
BG64     NC MB1_CLK_L     NC
CT62 M_B_CPU0_SB_DQ<19> MBB_DATA19 @T6G_MB_LIB.T6G(SCH_1):M_B_CPU0_SB_DQ(19)
AC64 M_B_CPU0_SA_DQ<24> MBA_DATA24 @T6G_MB_LIB.T6G(SCH_1):M_B_CPU0_SA_DQ(24)
CV63 M_B_CPU0_SB_DQ<20> MBB_DATA20 @T6G_MB_LIB.T6G(SCH_1):M_B_CPU0_SB_DQ(20)
BF62 TP_M_B_CPU0_SA_TEST39B TEST39B @T6G_MB_LIB.T6G(SCH_1):TP_M_B_CPU0_SA_TEST39B

Q_RES_0402LF-15,1%,1/16W,CHIP,CS01502FB03  I327  R376
   1 M_B_CPU0_ALERT_N      A @T6G_MB_LIB.T6G(SCH_1):M_B_CPU0_ALERT_N
   2 M_B_CPU0_ALERT_R_N      B @T6G_MB_LIB.T6G(SCH_1):M_B_CPU0_ALERT_R_N


DRAWING: @T6G_MB_LIB.T6G(SCH_1):PAGE12 

GENOA_SP5-SOCKET6096_13568-001,SMLF,IO,DGA^6000030  I159  U25
AT55 M_C_CPU0_ALERT_R_N MC_ALERT_L @T6G_MB_LIB.T6G(SCH_1):M_C_CPU0_ALERT_R_N
AU55 M_C_CPU0_RESET_N MC_RESET_L @T6G_MB_LIB.T6G(SCH_1):M_C_CPU0_RESET_N
DD55 M_C_CPU0_SB_DQS_DP<8> MCB_DQS_H8 @T6G_MB_LIB.T6G(SCH_1):M_C_CPU0_SB_DQS_DP(8)
DE57 M_C_CPU0_SB_DQ<30> MCB_DATA30 @T6G_MB_LIB.T6G(SCH_1):M_C_CPU0_SB_DQ(30)
CH56 M_C_CPU0_SB_DQ<8> MCB_DATA8 @T6G_MB_LIB.T6G(SCH_1):M_C_CPU0_SB_DQ(8)
BM56     NC MCB1_CS_L1     NC
BN57 M_C_CPU0_SB_CS_N<1> MCB0_CS_L1 @T6G_MB_LIB.T6G(SCH_1):M_C_CPU0_SB_CS_N(1)
 P56 M_C_CPU0_SA_DQS_DN<1> MCA_DQS_L1 @T6G_MB_LIB.T6G(SCH_1):M_C_CPU0_SA_DQS_DN(1)
AD55 M_C_CPU0_SA_DQ<25> MCA_DATA25 @T6G_MB_LIB.T6G(SCH_1):M_C_CPU0_SA_DQ(25)
 T56 M_C_CPU0_SA_DQ<14> MCA_DATA14 @T6G_MB_LIB.T6G(SCH_1):M_C_CPU0_SA_DQ(14)
 M55 M_C_CPU0_SA_DQ<9> MCA_DATA9 @T6G_MB_LIB.T6G(SCH_1):M_C_CPU0_SA_DQ(9)
AP55 M_C_CPU0_SA_CB<5> MCA_CHECK5 @T6G_MB_LIB.T6G(SCH_1):M_C_CPU0_SA_CB(5)
DF55 M_C_CPU0_SB_DQ<31> MCB_DATA31 @T6G_MB_LIB.T6G(SCH_1):M_C_CPU0_SB_DQ(31)
CV56 M_C_CPU0_SB_DQ<20> MCB_DATA20 @T6G_MB_LIB.T6G(SCH_1):M_C_CPU0_SB_DQ(20)
CJ55 M_C_CPU0_SB_DQ<9> MCB_DATA9 @T6G_MB_LIB.T6G(SCH_1):M_C_CPU0_SB_DQ(9)
BY56 M_C_CPU0_SB_CB<0> MCB_CHECK0 @T6G_MB_LIB.T6G(SCH_1):M_C_CPU0_SB_CB(0)
 Y56 M_C_CPU0_SA_DQS_DN<2> MCA_DQS_L2 @T6G_MB_LIB.T6G(SCH_1):M_C_CPU0_SA_DQS_DN(2)
AD56 M_C_CPU0_SA_DQ<26> MCA_DATA26 @T6G_MB_LIB.T6G(SCH_1):M_C_CPU0_SA_DQ(26)
 U55 M_C_CPU0_SA_DQ<15> MCA_DATA15 @T6G_MB_LIB.T6G(SCH_1):M_C_CPU0_SA_DQ(15)
AP56 M_C_CPU0_SA_CB<6> MCA_CHECK6 @T6G_MB_LIB.T6G(SCH_1):M_C_CPU0_SA_CB(6)
BN55 M_C_CPU0_SA_RSP<0> MCA0_RSP_L @T6G_MB_LIB.T6G(SCH_1):M_C_CPU0_SA_RSP(0)
CW55 M_C_CPU0_SB_DQ<21> MCB_DATA21 @T6G_MB_LIB.T6G(SCH_1):M_C_CPU0_SB_DQ(21)
CJ57 M_C_CPU0_SB_DQ<10> MCB_DATA10 @T6G_MB_LIB.T6G(SCH_1):M_C_CPU0_SB_DQ(10)
CA55 M_C_CPU0_SB_CB<1> MCB_CHECK1 @T6G_MB_LIB.T6G(SCH_1):M_C_CPU0_SB_CB(1)
AF56 M_C_CPU0_SA_DQS_DN<3> MCA_DQS_L3 @T6G_MB_LIB.T6G(SCH_1):M_C_CPU0_SA_DQS_DN(3)
AE55 M_C_CPU0_SA_DQ<27> MCA_DATA27 @T6G_MB_LIB.T6G(SCH_1):M_C_CPU0_SA_DQ(27)
 U57 M_C_CPU0_SA_DQ<16> MCA_DATA16 @T6G_MB_LIB.T6G(SCH_1):M_C_CPU0_SA_DQ(16)
AR55 M_C_CPU0_SA_CB<7> MCA_CHECK7 @T6G_MB_LIB.T6G(SCH_1):M_C_CPU0_SA_CB(7)
BP55     NC MCA1_RSP_L     NC
CW57 M_C_CPU0_SB_DQ<22> MCB_DATA22 @T6G_MB_LIB.T6G(SCH_1):M_C_CPU0_SB_DQ(22)
CK55 M_C_CPU0_SB_DQ<11> MCB_DATA11 @T6G_MB_LIB.T6G(SCH_1):M_C_CPU0_SB_DQ(11)
CA57 M_C_CPU0_SB_CB<2> MCB_CHECK2 @T6G_MB_LIB.T6G(SCH_1):M_C_CPU0_SB_CB(2)
AM56 M_C_CPU0_SA_DQS_DN<4> MCA_DQS_L4 @T6G_MB_LIB.T6G(SCH_1):M_C_CPU0_SA_DQS_DN(4)
 G57 M_C_CPU0_SA_DQS_DP<0> MCA_DQS_H0 @T6G_MB_LIB.T6G(SCH_1):M_C_CPU0_SA_DQS_DP(0)
AG57 M_C_CPU0_SA_DQ<28> MCA_DATA28 @T6G_MB_LIB.T6G(SCH_1):M_C_CPU0_SA_DQ(28)
 V55 M_C_CPU0_SA_DQ<17> MCA_DATA17 @T6G_MB_LIB.T6G(SCH_1):M_C_CPU0_SA_DQ(17)
CY55 M_C_CPU0_SB_DQ<23> MCB_DATA23 @T6G_MB_LIB.T6G(SCH_1):M_C_CPU0_SB_DQ(23)
CM56 M_C_CPU0_SB_DQ<12> MCB_DATA12 @T6G_MB_LIB.T6G(SCH_1):M_C_CPU0_SB_DQ(12)
CB55 M_C_CPU0_SB_CB<3> MCB_CHECK3 @T6G_MB_LIB.T6G(SCH_1):M_C_CPU0_SB_CB(3)
 H55 M_C_CPU0_SA_DQS_DN<5> MCA_DQS_L5 @T6G_MB_LIB.T6G(SCH_1):M_C_CPU0_SA_DQS_DN(5)
 N57 M_C_CPU0_SA_DQS_DP<1> MCA_DQS_H1 @T6G_MB_LIB.T6G(SCH_1):M_C_CPU0_SA_DQS_DP(1)
AH55 M_C_CPU0_SA_DQ<29> MCA_DATA29 @T6G_MB_LIB.T6G(SCH_1):M_C_CPU0_SA_DQ(29)
 V56 M_C_CPU0_SA_DQ<18> MCA_DATA18 @T6G_MB_LIB.T6G(SCH_1):M_C_CPU0_SA_DQ(18)
CE57 M_C_CPU0_SB_DQS_DN<0> MCB_DQS_L0 @T6G_MB_LIB.T6G(SCH_1):M_C_CPU0_SB_DQS_DN(0)
CY56 M_C_CPU0_SB_DQ<24> MCB_DATA24 @T6G_MB_LIB.T6G(SCH_1):M_C_CPU0_SB_DQ(24)
CN55 M_C_CPU0_SB_DQ<13> MCB_DATA13 @T6G_MB_LIB.T6G(SCH_1):M_C_CPU0_SB_DQ(13)
BT56 M_C_CPU0_SB_CB<4> MCB_CHECK4 @T6G_MB_LIB.T6G(SCH_1):M_C_CPU0_SB_CB(4)
 P55 M_C_CPU0_SA_DQS_DN<6> MCA_DQS_L6 @T6G_MB_LIB.T6G(SCH_1):M_C_CPU0_SA_DQS_DN(6)
 W57 M_C_CPU0_SA_DQS_DP<2> MCA_DQS_H2 @T6G_MB_LIB.T6G(SCH_1):M_C_CPU0_SA_DQS_DP(2)
 W55 M_C_CPU0_SA_DQ<19> MCA_DATA19 @T6G_MB_LIB.T6G(SCH_1):M_C_CPU0_SA_DQ(19)
CL57 M_C_CPU0_SB_DQS_DN<1> MCB_DQS_L1 @T6G_MB_LIB.T6G(SCH_1):M_C_CPU0_SB_DQS_DN(1)
DA55 M_C_CPU0_SB_DQ<25> MCB_DATA25 @T6G_MB_LIB.T6G(SCH_1):M_C_CPU0_SB_DQ(25)
CN57 M_C_CPU0_SB_DQ<14> MCB_DATA14 @T6G_MB_LIB.T6G(SCH_1):M_C_CPU0_SB_DQ(14)
BU55 M_C_CPU0_SB_CB<5> MCB_CHECK5 @T6G_MB_LIB.T6G(SCH_1):M_C_CPU0_SB_CB(5)
 Y55 M_C_CPU0_SA_DQS_DN<7> MCA_DQS_L7 @T6G_MB_LIB.T6G(SCH_1):M_C_CPU0_SA_DQS_DN(7)
AE57 M_C_CPU0_SA_DQS_DP<3> MCA_DQS_H3 @T6G_MB_LIB.T6G(SCH_1):M_C_CPU0_SA_DQS_DP(3)
CU57 M_C_CPU0_SB_DQS_DN<2> MCB_DQS_L2 @T6G_MB_LIB.T6G(SCH_1):M_C_CPU0_SB_DQS_DN(2)
DA57 M_C_CPU0_SB_DQ<26> MCB_DATA26 @T6G_MB_LIB.T6G(SCH_1):M_C_CPU0_SB_DQ(26)
CP55 M_C_CPU0_SB_DQ<15> MCB_DATA15 @T6G_MB_LIB.T6G(SCH_1):M_C_CPU0_SB_DQ(15)
BU57 M_C_CPU0_SB_CB<6> MCB_CHECK6 @T6G_MB_LIB.T6G(SCH_1):M_C_CPU0_SB_CB(6)
AF55 M_C_CPU0_SA_DQS_DN<8> MCA_DQS_L8 @T6G_MB_LIB.T6G(SCH_1):M_C_CPU0_SA_DQS_DN(8)
AL57 M_C_CPU0_SA_DQS_DP<4> MCA_DQS_H4 @T6G_MB_LIB.T6G(SCH_1):M_C_CPU0_SA_DQS_DP(4)
AW57 M_C_CPU0_SA_CA<0> MCA_CA0 @T6G_MB_LIB.T6G(SCH_1):M_C_CPU0_SA_CA(0)
DC57 M_C_CPU0_SB_DQS_DN<3> MCB_DQS_L3 @T6G_MB_LIB.T6G(SCH_1):M_C_CPU0_SB_DQS_DN(3)
DB55 M_C_CPU0_SB_DQ<27> MCB_DATA27 @T6G_MB_LIB.T6G(SCH_1):M_C_CPU0_SB_DQ(27)
CP56 M_C_CPU0_SB_DQ<16> MCB_DATA16 @T6G_MB_LIB.T6G(SCH_1):M_C_CPU0_SB_DQ(16)
BV55 M_C_CPU0_SB_CB<7> MCB_CHECK7 @T6G_MB_LIB.T6G(SCH_1):M_C_CPU0_SB_CB(7)
BG55 M_C_CPU0_SB_CA<0> MCB_CA0 @T6G_MB_LIB.T6G(SCH_1):M_C_CPU0_SB_CA(0)
BR57     NC MCB1_RSP_L     NC
BP56 M_C_CPU0_SB_RSP<0> MCB0_RSP_L @T6G_MB_LIB.T6G(SCH_1):M_C_CPU0_SB_RSP(0)
AM55 M_C_CPU0_SA_DQS_DN<9> MCA_DQS_L9 @T6G_MB_LIB.T6G(SCH_1):M_C_CPU0_SA_DQS_DN(9)
 J55 M_C_CPU0_SA_DQS_DP<5> MCA_DQS_H5 @T6G_MB_LIB.T6G(SCH_1):M_C_CPU0_SA_DQS_DP(5)
 E57 M_C_CPU0_SA_DQ<0> MCA_DATA0 @T6G_MB_LIB.T6G(SCH_1):M_C_CPU0_SA_DQ(0)
AY56 M_C_CPU0_SA_CA<1> MCA_CA1 @T6G_MB_LIB.T6G(SCH_1):M_C_CPU0_SA_CA(1)
BW55 M_C_CPU0_SB_DQS_DN<4> MCB_DQS_L4 @T6G_MB_LIB.T6G(SCH_1):M_C_CPU0_SB_DQS_DN(4)
CD56 M_C_CPU0_SB_DQS_DP<0> MCB_DQS_H0 @T6G_MB_LIB.T6G(SCH_1):M_C_CPU0_SB_DQS_DP(0)
DD56 M_C_CPU0_SB_DQ<28> MCB_DATA28 @T6G_MB_LIB.T6G(SCH_1):M_C_CPU0_SB_DQ(28)
CR55 M_C_CPU0_SB_DQ<17> MCB_DATA17 @T6G_MB_LIB.T6G(SCH_1):M_C_CPU0_SB_DQ(17)
CB56 M_C_CPU0_SB_DQ<0> MCB_DATA0 @T6G_MB_LIB.T6G(SCH_1):M_C_CPU0_SB_DQ(0)
BH55 M_C_CPU0_SB_CA<1> MCB_CA1 @T6G_MB_LIB.T6G(SCH_1):M_C_CPU0_SB_CA(1)
 R55 M_C_CPU0_SA_DQS_DP<6> MCA_DQS_H6 @T6G_MB_LIB.T6G(SCH_1):M_C_CPU0_SA_DQS_DP(6)
 F55 M_C_CPU0_SA_DQ<1> MCA_DATA1 @T6G_MB_LIB.T6G(SCH_1):M_C_CPU0_SA_DQ(1)
AY55 M_C_CPU0_SA_CA<2> MCA_CA2 @T6G_MB_LIB.T6G(SCH_1):M_C_CPU0_SA_CA(2)
AV56 M_C_CPU0_SA_CS_N<0> MCA0_CS_L0 @T6G_MB_LIB.T6G(SCH_1):M_C_CPU0_SA_CS_N(0)
CE55 M_C_CPU0_SB_DQS_DN<5> MCB_DQS_L5 @T6G_MB_LIB.T6G(SCH_1):M_C_CPU0_SB_DQS_DN(5)
CK56 M_C_CPU0_SB_DQS_DP<1> MCB_DQS_H1 @T6G_MB_LIB.T6G(SCH_1):M_C_CPU0_SB_DQS_DP(1)
DE55 M_C_CPU0_SB_DQ<29> MCB_DATA29 @T6G_MB_LIB.T6G(SCH_1):M_C_CPU0_SB_DQ(29)
CR57 M_C_CPU0_SB_DQ<18> MCB_DATA18 @T6G_MB_LIB.T6G(SCH_1):M_C_CPU0_SB_DQ(18)
CC55 M_C_CPU0_SB_DQ<1> MCB_DATA1 @T6G_MB_LIB.T6G(SCH_1):M_C_CPU0_SB_DQ(1)
BH56 M_C_CPU0_SB_CA<2> MCB_CA2 @T6G_MB_LIB.T6G(SCH_1):M_C_CPU0_SB_CA(2)
AA55 M_C_CPU0_SA_DQS_DP<7> MCA_DQS_H7 @T6G_MB_LIB.T6G(SCH_1):M_C_CPU0_SA_DQS_DP(7)
 F56 M_C_CPU0_SA_DQ<2> MCA_DATA2 @T6G_MB_LIB.T6G(SCH_1):M_C_CPU0_SA_DQ(2)
BA55 M_C_CPU0_SA_CA<3> MCA_CA3 @T6G_MB_LIB.T6G(SCH_1):M_C_CPU0_SA_CA(3)
AU57     NC MCA1_CS_L0     NC
AW55 M_C_CPU0_SA_CS_N<1> MCA0_CS_L1 @T6G_MB_LIB.T6G(SCH_1):M_C_CPU0_SA_CS_N(1)
CL55 M_C_CPU0_SB_DQS_DN<6> MCB_DQS_L6 @T6G_MB_LIB.T6G(SCH_1):M_C_CPU0_SB_DQS_DN(6)
CT56 M_C_CPU0_SB_DQS_DP<2> MCB_DQS_H2 @T6G_MB_LIB.T6G(SCH_1):M_C_CPU0_SB_DQS_DP(2)
CT55 M_C_CPU0_SB_DQ<19> MCB_DATA19 @T6G_MB_LIB.T6G(SCH_1):M_C_CPU0_SB_DQ(19)
CC57 M_C_CPU0_SB_DQ<2> MCB_DATA2 @T6G_MB_LIB.T6G(SCH_1):M_C_CPU0_SB_DQ(2)
BJ57 M_C_CPU0_SB_CA<3> MCB_CA3 @T6G_MB_LIB.T6G(SCH_1):M_C_CPU0_SB_CA(3)
AG55 M_C_CPU0_SA_DQS_DP<8> MCA_DQS_H8 @T6G_MB_LIB.T6G(SCH_1):M_C_CPU0_SA_DQS_DP(8)
AH56 M_C_CPU0_SA_DQ<30> MCA_DATA30 @T6G_MB_LIB.T6G(SCH_1):M_C_CPU0_SA_DQ(30)
 G55 M_C_CPU0_SA_DQ<3> MCA_DATA3 @T6G_MB_LIB.T6G(SCH_1):M_C_CPU0_SA_DQ(3)
BA57 M_C_CPU0_SA_CA<4> MCA_CA4 @T6G_MB_LIB.T6G(SCH_1):M_C_CPU0_SA_CA(4)
AV55     NC MCA1_CS_L1     NC
CU55 M_C_CPU0_SB_DQS_DN<7> MCB_DQS_L7 @T6G_MB_LIB.T6G(SCH_1):M_C_CPU0_SB_DQS_DN(7)
DB56 M_C_CPU0_SB_DQS_DP<3> MCB_DQS_H3 @T6G_MB_LIB.T6G(SCH_1):M_C_CPU0_SB_DQS_DP(3)
CD55 M_C_CPU0_SB_DQ<3> MCB_DATA3 @T6G_MB_LIB.T6G(SCH_1):M_C_CPU0_SB_DQ(3)
BJ55 M_C_CPU0_SB_CA<4> MCB_CA4 @T6G_MB_LIB.T6G(SCH_1):M_C_CPU0_SB_CA(4)
AN55 M_C_CPU0_SA_DQS_DP<9> MCA_DQS_H9 @T6G_MB_LIB.T6G(SCH_1):M_C_CPU0_SA_DQS_DP(9)
AJ55 M_C_CPU0_SA_DQ<31> MCA_DATA31 @T6G_MB_LIB.T6G(SCH_1):M_C_CPU0_SA_DQ(31)
AA57 M_C_CPU0_SA_DQ<20> MCA_DATA20 @T6G_MB_LIB.T6G(SCH_1):M_C_CPU0_SA_DQ(20)
 J57 M_C_CPU0_SA_DQ<4> MCA_DATA4 @T6G_MB_LIB.T6G(SCH_1):M_C_CPU0_SA_DQ(4)
AJ57 M_C_CPU0_SA_CB<0> MCA_CHECK0 @T6G_MB_LIB.T6G(SCH_1):M_C_CPU0_SA_CB(0)
BB56 M_C_CPU0_SA_CA<5> MCA_CA5 @T6G_MB_LIB.T6G(SCH_1):M_C_CPU0_SA_CA(5)
DC55 M_C_CPU0_SB_DQS_DN<8> MCB_DQS_L8 @T6G_MB_LIB.T6G(SCH_1):M_C_CPU0_SB_DQS_DN(8)
BY55 M_C_CPU0_SB_DQS_DP<4> MCB_DQS_H4 @T6G_MB_LIB.T6G(SCH_1):M_C_CPU0_SB_DQS_DP(4)
CF56 M_C_CPU0_SB_DQ<4> MCB_DATA4 @T6G_MB_LIB.T6G(SCH_1):M_C_CPU0_SB_DQ(4)
BK55 M_C_CPU0_SB_CA<5> MCB_CA5 @T6G_MB_LIB.T6G(SCH_1):M_C_CPU0_SB_CA(5)
AB55 M_C_CPU0_SA_DQ<21> MCA_DATA21 @T6G_MB_LIB.T6G(SCH_1):M_C_CPU0_SA_DQ(21)
 M56 M_C_CPU0_SA_DQ<10> MCA_DATA10 @T6G_MB_LIB.T6G(SCH_1):M_C_CPU0_SA_DQ(10)
 K55 M_C_CPU0_SA_DQ<5> MCA_DATA5 @T6G_MB_LIB.T6G(SCH_1):M_C_CPU0_SA_DQ(5)
AK55 M_C_CPU0_SA_CB<1> MCA_CHECK1 @T6G_MB_LIB.T6G(SCH_1):M_C_CPU0_SA_CB(1)
BB55 M_C_CPU0_SA_CA<6> MCA_CA6 @T6G_MB_LIB.T6G(SCH_1):M_C_CPU0_SA_CA(6)
BW57 M_C_CPU0_SB_DQS_DN<9> MCB_DQS_L9 @T6G_MB_LIB.T6G(SCH_1):M_C_CPU0_SB_DQS_DN(9)
CF55 M_C_CPU0_SB_DQS_DP<5> MCB_DQS_H5 @T6G_MB_LIB.T6G(SCH_1):M_C_CPU0_SB_DQS_DP(5)
CG55 M_C_CPU0_SB_DQ<5> MCB_DATA5 @T6G_MB_LIB.T6G(SCH_1):M_C_CPU0_SB_DQ(5)
BK56 M_C_CPU0_SB_CA<6> MCB_CA6 @T6G_MB_LIB.T6G(SCH_1):M_C_CPU0_SB_CA(6)
AB56 M_C_CPU0_SA_DQ<22> MCA_DATA22 @T6G_MB_LIB.T6G(SCH_1):M_C_CPU0_SA_DQ(22)
 N55 M_C_CPU0_SA_DQ<11> MCA_DATA11 @T6G_MB_LIB.T6G(SCH_1):M_C_CPU0_SA_DQ(11)
 K56 M_C_CPU0_SA_DQ<6> MCA_DATA6 @T6G_MB_LIB.T6G(SCH_1):M_C_CPU0_SA_DQ(6)
AK56 M_C_CPU0_SA_CB<2> MCA_CHECK2 @T6G_MB_LIB.T6G(SCH_1):M_C_CPU0_SA_CB(2)
CM55 M_C_CPU0_SB_DQS_DP<6> MCB_DQS_H6 @T6G_MB_LIB.T6G(SCH_1):M_C_CPU0_SB_DQS_DP(6)
CG57 M_C_CPU0_SB_DQ<6> MCB_DATA6 @T6G_MB_LIB.T6G(SCH_1):M_C_CPU0_SB_DQ(6)
AC55 M_C_CPU0_SA_DQ<23> MCA_DATA23 @T6G_MB_LIB.T6G(SCH_1):M_C_CPU0_SA_DQ(23)
 R57 M_C_CPU0_SA_DQ<12> MCA_DATA12 @T6G_MB_LIB.T6G(SCH_1):M_C_CPU0_SA_DQ(12)
 L55 M_C_CPU0_SA_DQ<7> MCA_DATA7 @T6G_MB_LIB.T6G(SCH_1):M_C_CPU0_SA_DQ(7)
AL55 M_C_CPU0_SA_CB<3> MCA_CHECK3 @T6G_MB_LIB.T6G(SCH_1):M_C_CPU0_SA_CB(3)
CV55 M_C_CPU0_SB_DQS_DP<7> MCB_DQS_H7 @T6G_MB_LIB.T6G(SCH_1):M_C_CPU0_SB_DQS_DP(7)
CH55 M_C_CPU0_SB_DQ<7> MCB_DATA7 @T6G_MB_LIB.T6G(SCH_1):M_C_CPU0_SB_DQ(7)
BL55     NC MCB1_CS_L0     NC
BM55 M_C_CPU0_SB_CS_N<0> MCB0_CS_L0 @T6G_MB_LIB.T6G(SCH_1):M_C_CPU0_SB_CS_N(0)
 H56 M_C_CPU0_SA_DQS_DN<0> MCA_DQS_L0 @T6G_MB_LIB.T6G(SCH_1):M_C_CPU0_SA_DQS_DN(0)
AC57 M_C_CPU0_SA_DQ<24> MCA_DATA24 @T6G_MB_LIB.T6G(SCH_1):M_C_CPU0_SA_DQ(24)
 T55 M_C_CPU0_SA_DQ<13> MCA_DATA13 @T6G_MB_LIB.T6G(SCH_1):M_C_CPU0_SA_DQ(13)
 L57 M_C_CPU0_SA_DQ<8> MCA_DATA8 @T6G_MB_LIB.T6G(SCH_1):M_C_CPU0_SA_DQ(8)
AN57 M_C_CPU0_SA_CB<4> MCA_CHECK4 @T6G_MB_LIB.T6G(SCH_1):M_C_CPU0_SA_CB(4)
BV56 M_C_CPU0_SB_DQS_DP<9> MCB_DQS_H9 @T6G_MB_LIB.T6G(SCH_1):M_C_CPU0_SB_DQS_DP(9)
BC55 M_C_CPU0_SA_PAR MCA_PAR @T6G_MB_LIB.T6G(SCH_1):M_C_CPU0_SA_PAR
BL57 M_C_CPU0_SB_PAR MCB_PAR @T6G_MB_LIB.T6G(SCH_1):M_C_CPU0_SB_PAR
BC57 M_C_CPU0_CLK_DP<0> MC0_CLK_H @T6G_MB_LIB.T6G(SCH_1):M_C_CPU0_CLK_DP(0)
BD56 M_C_CPU0_CLK_DN<0> MC0_CLK_L @T6G_MB_LIB.T6G(SCH_1):M_C_CPU0_CLK_DN(0)
BF56     NC MC1_CLK_H     NC
BG57     NC MC1_CLK_L     NC
BF55 TP_M_C_CPU0_SA_TEST39C TEST39C @T6G_MB_LIB.T6G(SCH_1):TP_M_C_CPU0_SA_TEST39C

Q_RES_0402LF-15,1%,1/16W,CHIP,CS01502FB03  I314  R377
   1 M_C_CPU0_ALERT_N      A @T6G_MB_LIB.T6G(SCH_1):M_C_CPU0_ALERT_N
   2 M_C_CPU0_ALERT_R_N      B @T6G_MB_LIB.T6G(SCH_1):M_C_CPU0_ALERT_R_N


DRAWING: @T6G_MB_LIB.T6G(SCH_1):PAGE13 

GENOA_SP5-SOCKET6096_13568-001,SMLF,IO,DGA^6000030  I159  U25
AT58 M_D_CPU0_ALERT_R_N MD_ALERT_L @T6G_MB_LIB.T6G(SCH_1):M_D_CPU0_ALERT_R_N
AU59 M_D_CPU0_RESET_N MD_RESET_L @T6G_MB_LIB.T6G(SCH_1):M_D_CPU0_RESET_N
CY58 M_D_CPU0_SB_DQ<23> MDB_DATA23 @T6G_MB_LIB.T6G(SCH_1):M_D_CPU0_SB_DQ(23)
CM60 M_D_CPU0_SB_DQ<12> MDB_DATA12 @T6G_MB_LIB.T6G(SCH_1):M_D_CPU0_SB_DQ(12)
CC60 M_D_CPU0_SB_DQ<2> MDB_DATA2 @T6G_MB_LIB.T6G(SCH_1):M_D_CPU0_SB_DQ(2)
CB58 M_D_CPU0_SB_CB<3> MDB_CHECK3 @T6G_MB_LIB.T6G(SCH_1):M_D_CPU0_SB_CB(3)
 H58 M_D_CPU0_SA_DQS_DN<5> MDA_DQS_L5 @T6G_MB_LIB.T6G(SCH_1):M_D_CPU0_SA_DQS_DN(5)
 N60 M_D_CPU0_SA_DQS_DP<1> MDA_DQS_H1 @T6G_MB_LIB.T6G(SCH_1):M_D_CPU0_SA_DQS_DP(1)
AH58 M_D_CPU0_SA_DQ<29> MDA_DATA29 @T6G_MB_LIB.T6G(SCH_1):M_D_CPU0_SA_DQ(29)
 V60 M_D_CPU0_SA_DQ<18> MDA_DATA18 @T6G_MB_LIB.T6G(SCH_1):M_D_CPU0_SA_DQ(18)
 G59 M_D_CPU0_SA_DQ<3> MDA_DATA3 @T6G_MB_LIB.T6G(SCH_1):M_D_CPU0_SA_DQ(3)
CE60 M_D_CPU0_SB_DQS_DN<0> MDB_DQS_L0 @T6G_MB_LIB.T6G(SCH_1):M_D_CPU0_SB_DQS_DN(0)
CY60 M_D_CPU0_SB_DQ<24> MDB_DATA24 @T6G_MB_LIB.T6G(SCH_1):M_D_CPU0_SB_DQ(24)
CN59 M_D_CPU0_SB_DQ<13> MDB_DATA13 @T6G_MB_LIB.T6G(SCH_1):M_D_CPU0_SB_DQ(13)
CD58 M_D_CPU0_SB_DQ<3> MDB_DATA3 @T6G_MB_LIB.T6G(SCH_1):M_D_CPU0_SB_DQ(3)
BT60 M_D_CPU0_SB_CB<4> MDB_CHECK4 @T6G_MB_LIB.T6G(SCH_1):M_D_CPU0_SB_CB(4)
 P58 M_D_CPU0_SA_DQS_DN<6> MDA_DQS_L6 @T6G_MB_LIB.T6G(SCH_1):M_D_CPU0_SA_DQS_DN(6)
 W60 M_D_CPU0_SA_DQS_DP<2> MDA_DQS_H2 @T6G_MB_LIB.T6G(SCH_1):M_D_CPU0_SA_DQS_DP(2)
 W59 M_D_CPU0_SA_DQ<19> MDA_DATA19 @T6G_MB_LIB.T6G(SCH_1):M_D_CPU0_SA_DQ(19)
 J60 M_D_CPU0_SA_DQ<4> MDA_DATA4 @T6G_MB_LIB.T6G(SCH_1):M_D_CPU0_SA_DQ(4)
CL60 M_D_CPU0_SB_DQS_DN<1> MDB_DQS_L1 @T6G_MB_LIB.T6G(SCH_1):M_D_CPU0_SB_DQS_DN(1)
DA59 M_D_CPU0_SB_DQ<25> MDB_DATA25 @T6G_MB_LIB.T6G(SCH_1):M_D_CPU0_SB_DQ(25)
CN60 M_D_CPU0_SB_DQ<14> MDB_DATA14 @T6G_MB_LIB.T6G(SCH_1):M_D_CPU0_SB_DQ(14)
CF60 M_D_CPU0_SB_DQ<4> MDB_DATA4 @T6G_MB_LIB.T6G(SCH_1):M_D_CPU0_SB_DQ(4)
BU59 M_D_CPU0_SB_CB<5> MDB_CHECK5 @T6G_MB_LIB.T6G(SCH_1):M_D_CPU0_SB_CB(5)
 Y58 M_D_CPU0_SA_DQS_DN<7> MDA_DQS_L7 @T6G_MB_LIB.T6G(SCH_1):M_D_CPU0_SA_DQS_DN(7)
AE60 M_D_CPU0_SA_DQS_DP<3> MDA_DQS_H3 @T6G_MB_LIB.T6G(SCH_1):M_D_CPU0_SA_DQS_DP(3)
 K58 M_D_CPU0_SA_DQ<5> MDA_DATA5 @T6G_MB_LIB.T6G(SCH_1):M_D_CPU0_SA_DQ(5)
CU60 M_D_CPU0_SB_DQS_DN<2> MDB_DQS_L2 @T6G_MB_LIB.T6G(SCH_1):M_D_CPU0_SB_DQS_DN(2)
DA60 M_D_CPU0_SB_DQ<26> MDB_DATA26 @T6G_MB_LIB.T6G(SCH_1):M_D_CPU0_SB_DQ(26)
CP58 M_D_CPU0_SB_DQ<15> MDB_DATA15 @T6G_MB_LIB.T6G(SCH_1):M_D_CPU0_SB_DQ(15)
CG59 M_D_CPU0_SB_DQ<5> MDB_DATA5 @T6G_MB_LIB.T6G(SCH_1):M_D_CPU0_SB_DQ(5)
BU60 M_D_CPU0_SB_CB<6> MDB_CHECK6 @T6G_MB_LIB.T6G(SCH_1):M_D_CPU0_SB_CB(6)
AF58 M_D_CPU0_SA_DQS_DN<8> MDA_DQS_L8 @T6G_MB_LIB.T6G(SCH_1):M_D_CPU0_SA_DQS_DN(8)
AL60 M_D_CPU0_SA_DQS_DP<4> MDA_DQS_H4 @T6G_MB_LIB.T6G(SCH_1):M_D_CPU0_SA_DQS_DP(4)
 K60 M_D_CPU0_SA_DQ<6> MDA_DATA6 @T6G_MB_LIB.T6G(SCH_1):M_D_CPU0_SA_DQ(6)
DC60 M_D_CPU0_SB_DQS_DN<3> MDB_DQS_L3 @T6G_MB_LIB.T6G(SCH_1):M_D_CPU0_SB_DQS_DN(3)
DB58 M_D_CPU0_SB_DQ<27> MDB_DATA27 @T6G_MB_LIB.T6G(SCH_1):M_D_CPU0_SB_DQ(27)
CP60 M_D_CPU0_SB_DQ<16> MDB_DATA16 @T6G_MB_LIB.T6G(SCH_1):M_D_CPU0_SB_DQ(16)
CG60 M_D_CPU0_SB_DQ<6> MDB_DATA6 @T6G_MB_LIB.T6G(SCH_1):M_D_CPU0_SB_DQ(6)
BV58 M_D_CPU0_SB_CB<7> MDB_CHECK7 @T6G_MB_LIB.T6G(SCH_1):M_D_CPU0_SB_CB(7)
BP60 M_D_CPU0_SB_RSP<0> MDB0_RSP_L @T6G_MB_LIB.T6G(SCH_1):M_D_CPU0_SB_RSP(0)
AM58 M_D_CPU0_SA_DQS_DN<9> MDA_DQS_L9 @T6G_MB_LIB.T6G(SCH_1):M_D_CPU0_SA_DQS_DN(9)
 J59 M_D_CPU0_SA_DQS_DP<5> MDA_DQS_H5 @T6G_MB_LIB.T6G(SCH_1):M_D_CPU0_SA_DQS_DP(5)
 L59 M_D_CPU0_SA_DQ<7> MDA_DATA7 @T6G_MB_LIB.T6G(SCH_1):M_D_CPU0_SA_DQ(7)
BW59 M_D_CPU0_SB_DQS_DN<4> MDB_DQS_L4 @T6G_MB_LIB.T6G(SCH_1):M_D_CPU0_SB_DQS_DN(4)
CD60 M_D_CPU0_SB_DQS_DP<0> MDB_DQS_H0 @T6G_MB_LIB.T6G(SCH_1):M_D_CPU0_SB_DQS_DP(0)
DD60 M_D_CPU0_SB_DQ<28> MDB_DATA28 @T6G_MB_LIB.T6G(SCH_1):M_D_CPU0_SB_DQ(28)
CR59 M_D_CPU0_SB_DQ<17> MDB_DATA17 @T6G_MB_LIB.T6G(SCH_1):M_D_CPU0_SB_DQ(17)
CH58 M_D_CPU0_SB_DQ<7> MDB_DATA7 @T6G_MB_LIB.T6G(SCH_1):M_D_CPU0_SB_DQ(7)
BR60     NC MDB1_RSP_L     NC
 R59 M_D_CPU0_SA_DQS_DP<6> MDA_DQS_H6 @T6G_MB_LIB.T6G(SCH_1):M_D_CPU0_SA_DQS_DP(6)
 L60 M_D_CPU0_SA_DQ<8> MDA_DATA8 @T6G_MB_LIB.T6G(SCH_1):M_D_CPU0_SA_DQ(8)
CE59 M_D_CPU0_SB_DQS_DN<5> MDB_DQS_L5 @T6G_MB_LIB.T6G(SCH_1):M_D_CPU0_SB_DQS_DN(5)
CK60 M_D_CPU0_SB_DQS_DP<1> MDB_DQS_H1 @T6G_MB_LIB.T6G(SCH_1):M_D_CPU0_SB_DQS_DP(1)
DE59 M_D_CPU0_SB_DQ<29> MDB_DATA29 @T6G_MB_LIB.T6G(SCH_1):M_D_CPU0_SB_DQ(29)
CR60 M_D_CPU0_SB_DQ<18> MDB_DATA18 @T6G_MB_LIB.T6G(SCH_1):M_D_CPU0_SB_DQ(18)
CH60 M_D_CPU0_SB_DQ<8> MDB_DATA8 @T6G_MB_LIB.T6G(SCH_1):M_D_CPU0_SB_DQ(8)
AA59 M_D_CPU0_SA_DQS_DP<7> MDA_DQS_H7 @T6G_MB_LIB.T6G(SCH_1):M_D_CPU0_SA_DQS_DP(7)
 M58 M_D_CPU0_SA_DQ<9> MDA_DATA9 @T6G_MB_LIB.T6G(SCH_1):M_D_CPU0_SA_DQ(9)
AW60 M_D_CPU0_SA_CA<0> MDA_CA0 @T6G_MB_LIB.T6G(SCH_1):M_D_CPU0_SA_CA(0)
AV60 M_D_CPU0_SA_CS_N<0> MDA0_CS_L0 @T6G_MB_LIB.T6G(SCH_1):M_D_CPU0_SA_CS_N(0)
CL59 M_D_CPU0_SB_DQS_DN<6> MDB_DQS_L6 @T6G_MB_LIB.T6G(SCH_1):M_D_CPU0_SB_DQS_DN(6)
CT60 M_D_CPU0_SB_DQS_DP<2> MDB_DQS_H2 @T6G_MB_LIB.T6G(SCH_1):M_D_CPU0_SB_DQS_DP(2)
CT58 M_D_CPU0_SB_DQ<19> MDB_DATA19 @T6G_MB_LIB.T6G(SCH_1):M_D_CPU0_SB_DQ(19)
CJ59 M_D_CPU0_SB_DQ<9> MDB_DATA9 @T6G_MB_LIB.T6G(SCH_1):M_D_CPU0_SB_DQ(9)
BG59 M_D_CPU0_SB_CA<0> MDB_CA0 @T6G_MB_LIB.T6G(SCH_1):M_D_CPU0_SB_CA(0)
AG59 M_D_CPU0_SA_DQS_DP<8> MDA_DQS_H8 @T6G_MB_LIB.T6G(SCH_1):M_D_CPU0_SA_DQS_DP(8)
AH60 M_D_CPU0_SA_DQ<30> MDA_DATA30 @T6G_MB_LIB.T6G(SCH_1):M_D_CPU0_SA_DQ(30)
AY60 M_D_CPU0_SA_CA<1> MDA_CA1 @T6G_MB_LIB.T6G(SCH_1):M_D_CPU0_SA_CA(1)
AU60     NC MDA1_CS_L0     NC
AW59 M_D_CPU0_SA_CS_N<1> MDA0_CS_L1 @T6G_MB_LIB.T6G(SCH_1):M_D_CPU0_SA_CS_N(1)
CU59 M_D_CPU0_SB_DQS_DN<7> MDB_DQS_L7 @T6G_MB_LIB.T6G(SCH_1):M_D_CPU0_SB_DQS_DN(7)
DB60 M_D_CPU0_SB_DQS_DP<3> MDB_DQS_H3 @T6G_MB_LIB.T6G(SCH_1):M_D_CPU0_SB_DQS_DP(3)
BH58 M_D_CPU0_SB_CA<1> MDB_CA1 @T6G_MB_LIB.T6G(SCH_1):M_D_CPU0_SB_CA(1)
AN59 M_D_CPU0_SA_DQS_DP<9> MDA_DQS_H9 @T6G_MB_LIB.T6G(SCH_1):M_D_CPU0_SA_DQS_DP(9)
AJ59 M_D_CPU0_SA_DQ<31> MDA_DATA31 @T6G_MB_LIB.T6G(SCH_1):M_D_CPU0_SA_DQ(31)
AA60 M_D_CPU0_SA_DQ<20> MDA_DATA20 @T6G_MB_LIB.T6G(SCH_1):M_D_CPU0_SA_DQ(20)
AJ60 M_D_CPU0_SA_CB<0> MDA_CHECK0 @T6G_MB_LIB.T6G(SCH_1):M_D_CPU0_SA_CB(0)
AY58 M_D_CPU0_SA_CA<2> MDA_CA2 @T6G_MB_LIB.T6G(SCH_1):M_D_CPU0_SA_CA(2)
AV58     NC MDA1_CS_L1     NC
DC59 M_D_CPU0_SB_DQS_DN<8> MDB_DQS_L8 @T6G_MB_LIB.T6G(SCH_1):M_D_CPU0_SB_DQS_DN(8)
BY58 M_D_CPU0_SB_DQS_DP<4> MDB_DQS_H4 @T6G_MB_LIB.T6G(SCH_1):M_D_CPU0_SB_DQS_DP(4)
BH60 M_D_CPU0_SB_CA<2> MDB_CA2 @T6G_MB_LIB.T6G(SCH_1):M_D_CPU0_SB_CA(2)
AB58 M_D_CPU0_SA_DQ<21> MDA_DATA21 @T6G_MB_LIB.T6G(SCH_1):M_D_CPU0_SA_DQ(21)
 M60 M_D_CPU0_SA_DQ<10> MDA_DATA10 @T6G_MB_LIB.T6G(SCH_1):M_D_CPU0_SA_DQ(10)
AK58 M_D_CPU0_SA_CB<1> MDA_CHECK1 @T6G_MB_LIB.T6G(SCH_1):M_D_CPU0_SA_CB(1)
BA59 M_D_CPU0_SA_CA<3> MDA_CA3 @T6G_MB_LIB.T6G(SCH_1):M_D_CPU0_SA_CA(3)
BW60 M_D_CPU0_SB_DQS_DN<9> MDB_DQS_L9 @T6G_MB_LIB.T6G(SCH_1):M_D_CPU0_SB_DQS_DN(9)
CF58 M_D_CPU0_SB_DQS_DP<5> MDB_DQS_H5 @T6G_MB_LIB.T6G(SCH_1):M_D_CPU0_SB_DQS_DP(5)
AB60 M_D_CPU0_SA_DQ<22> MDA_DATA22 @T6G_MB_LIB.T6G(SCH_1):M_D_CPU0_SA_DQ(22)
 N59 M_D_CPU0_SA_DQ<11> MDA_DATA11 @T6G_MB_LIB.T6G(SCH_1):M_D_CPU0_SA_DQ(11)
AK60 M_D_CPU0_SA_CB<2> MDA_CHECK2 @T6G_MB_LIB.T6G(SCH_1):M_D_CPU0_SA_CB(2)
BA60 M_D_CPU0_SA_CA<4> MDA_CA4 @T6G_MB_LIB.T6G(SCH_1):M_D_CPU0_SA_CA(4)
CM58 M_D_CPU0_SB_DQS_DP<6> MDB_DQS_H6 @T6G_MB_LIB.T6G(SCH_1):M_D_CPU0_SB_DQS_DP(6)
BJ59 M_D_CPU0_SB_CA<4> MDB_CA4 @T6G_MB_LIB.T6G(SCH_1):M_D_CPU0_SB_CA(4)
AC59 M_D_CPU0_SA_DQ<23> MDA_DATA23 @T6G_MB_LIB.T6G(SCH_1):M_D_CPU0_SA_DQ(23)
 R60 M_D_CPU0_SA_DQ<12> MDA_DATA12 @T6G_MB_LIB.T6G(SCH_1):M_D_CPU0_SA_DQ(12)
AL59 M_D_CPU0_SA_CB<3> MDA_CHECK3 @T6G_MB_LIB.T6G(SCH_1):M_D_CPU0_SA_CB(3)
BB60 M_D_CPU0_SA_CA<5> MDA_CA5 @T6G_MB_LIB.T6G(SCH_1):M_D_CPU0_SA_CA(5)
CV58 M_D_CPU0_SB_DQS_DP<7> MDB_DQS_H7 @T6G_MB_LIB.T6G(SCH_1):M_D_CPU0_SB_DQS_DP(7)
BK58 M_D_CPU0_SB_CA<5> MDB_CA5 @T6G_MB_LIB.T6G(SCH_1):M_D_CPU0_SB_CA(5)
BM58 M_D_CPU0_SB_CS_N<0> MDB0_CS_L0 @T6G_MB_LIB.T6G(SCH_1):M_D_CPU0_SB_CS_N(0)
 H60 M_D_CPU0_SA_DQS_DN<0> MDA_DQS_L0 @T6G_MB_LIB.T6G(SCH_1):M_D_CPU0_SA_DQS_DN(0)
AC60 M_D_CPU0_SA_DQ<24> MDA_DATA24 @T6G_MB_LIB.T6G(SCH_1):M_D_CPU0_SA_DQ(24)
 T58 M_D_CPU0_SA_DQ<13> MDA_DATA13 @T6G_MB_LIB.T6G(SCH_1):M_D_CPU0_SA_DQ(13)
AN60 M_D_CPU0_SA_CB<4> MDA_CHECK4 @T6G_MB_LIB.T6G(SCH_1):M_D_CPU0_SA_CB(4)
BB58 M_D_CPU0_SA_CA<6> MDA_CA6 @T6G_MB_LIB.T6G(SCH_1):M_D_CPU0_SA_CA(6)
DD58 M_D_CPU0_SB_DQS_DP<8> MDB_DQS_H8 @T6G_MB_LIB.T6G(SCH_1):M_D_CPU0_SB_DQS_DP(8)
DE60 M_D_CPU0_SB_DQ<30> MDB_DATA30 @T6G_MB_LIB.T6G(SCH_1):M_D_CPU0_SB_DQ(30)
BK60 M_D_CPU0_SB_CA<6> MDB_CA6 @T6G_MB_LIB.T6G(SCH_1):M_D_CPU0_SB_CA(6)
BL59     NC MDB1_CS_L0     NC
BN60 M_D_CPU0_SB_CS_N<1> MDB0_CS_L1 @T6G_MB_LIB.T6G(SCH_1):M_D_CPU0_SB_CS_N(1)
 P60 M_D_CPU0_SA_DQS_DN<1> MDA_DQS_L1 @T6G_MB_LIB.T6G(SCH_1):M_D_CPU0_SA_DQS_DN(1)
AD58 M_D_CPU0_SA_DQ<25> MDA_DATA25 @T6G_MB_LIB.T6G(SCH_1):M_D_CPU0_SA_DQ(25)
 T60 M_D_CPU0_SA_DQ<14> MDA_DATA14 @T6G_MB_LIB.T6G(SCH_1):M_D_CPU0_SA_DQ(14)
AP58 M_D_CPU0_SA_CB<5> MDA_CHECK5 @T6G_MB_LIB.T6G(SCH_1):M_D_CPU0_SA_CB(5)
DF60 M_D_CPU0_SB_DQ<31> MDB_DATA31 @T6G_MB_LIB.T6G(SCH_1):M_D_CPU0_SB_DQ(31)
CV60 M_D_CPU0_SB_DQ<20> MDB_DATA20 @T6G_MB_LIB.T6G(SCH_1):M_D_CPU0_SB_DQ(20)
BY60 M_D_CPU0_SB_CB<0> MDB_CHECK0 @T6G_MB_LIB.T6G(SCH_1):M_D_CPU0_SB_CB(0)
BM60     NC MDB1_CS_L1     NC
 Y60 M_D_CPU0_SA_DQS_DN<2> MDA_DQS_L2 @T6G_MB_LIB.T6G(SCH_1):M_D_CPU0_SA_DQS_DN(2)
AD60 M_D_CPU0_SA_DQ<26> MDA_DATA26 @T6G_MB_LIB.T6G(SCH_1):M_D_CPU0_SA_DQ(26)
 U59 M_D_CPU0_SA_DQ<15> MDA_DATA15 @T6G_MB_LIB.T6G(SCH_1):M_D_CPU0_SA_DQ(15)
 E60 M_D_CPU0_SA_DQ<0> MDA_DATA0 @T6G_MB_LIB.T6G(SCH_1):M_D_CPU0_SA_DQ(0)
AP60 M_D_CPU0_SA_CB<6> MDA_CHECK6 @T6G_MB_LIB.T6G(SCH_1):M_D_CPU0_SA_CB(6)
CW59 M_D_CPU0_SB_DQ<21> MDB_DATA21 @T6G_MB_LIB.T6G(SCH_1):M_D_CPU0_SB_DQ(21)
CJ60 M_D_CPU0_SB_DQ<10> MDB_DATA10 @T6G_MB_LIB.T6G(SCH_1):M_D_CPU0_SB_DQ(10)
CB60 M_D_CPU0_SB_DQ<0> MDB_DATA0 @T6G_MB_LIB.T6G(SCH_1):M_D_CPU0_SB_DQ(0)
CA59 M_D_CPU0_SB_CB<1> MDB_CHECK1 @T6G_MB_LIB.T6G(SCH_1):M_D_CPU0_SB_CB(1)
AF60 M_D_CPU0_SA_DQS_DN<3> MDA_DQS_L3 @T6G_MB_LIB.T6G(SCH_1):M_D_CPU0_SA_DQS_DN(3)
AE59 M_D_CPU0_SA_DQ<27> MDA_DATA27 @T6G_MB_LIB.T6G(SCH_1):M_D_CPU0_SA_DQ(27)
 U60 M_D_CPU0_SA_DQ<16> MDA_DATA16 @T6G_MB_LIB.T6G(SCH_1):M_D_CPU0_SA_DQ(16)
 F58 M_D_CPU0_SA_DQ<1> MDA_DATA1 @T6G_MB_LIB.T6G(SCH_1):M_D_CPU0_SA_DQ(1)
AR59 M_D_CPU0_SA_CB<7> MDA_CHECK7 @T6G_MB_LIB.T6G(SCH_1):M_D_CPU0_SA_CB(7)
BN59 M_D_CPU0_SA_RSP<0> MDA0_RSP_L @T6G_MB_LIB.T6G(SCH_1):M_D_CPU0_SA_RSP(0)
CW60 M_D_CPU0_SB_DQ<22> MDB_DATA22 @T6G_MB_LIB.T6G(SCH_1):M_D_CPU0_SB_DQ(22)
CK58 M_D_CPU0_SB_DQ<11> MDB_DATA11 @T6G_MB_LIB.T6G(SCH_1):M_D_CPU0_SB_DQ(11)
CC59 M_D_CPU0_SB_DQ<1> MDB_DATA1 @T6G_MB_LIB.T6G(SCH_1):M_D_CPU0_SB_DQ(1)
CA60 M_D_CPU0_SB_CB<2> MDB_CHECK2 @T6G_MB_LIB.T6G(SCH_1):M_D_CPU0_SB_CB(2)
AM60 M_D_CPU0_SA_DQS_DN<4> MDA_DQS_L4 @T6G_MB_LIB.T6G(SCH_1):M_D_CPU0_SA_DQS_DN(4)
 G60 M_D_CPU0_SA_DQS_DP<0> MDA_DQS_H0 @T6G_MB_LIB.T6G(SCH_1):M_D_CPU0_SA_DQS_DP(0)
AG60 M_D_CPU0_SA_DQ<28> MDA_DATA28 @T6G_MB_LIB.T6G(SCH_1):M_D_CPU0_SA_DQ(28)
 V58 M_D_CPU0_SA_DQ<17> MDA_DATA17 @T6G_MB_LIB.T6G(SCH_1):M_D_CPU0_SA_DQ(17)
 F60 M_D_CPU0_SA_DQ<2> MDA_DATA2 @T6G_MB_LIB.T6G(SCH_1):M_D_CPU0_SA_DQ(2)
BP58     NC MDA1_RSP_L     NC
BC59 M_D_CPU0_SA_PAR MDA_PAR @T6G_MB_LIB.T6G(SCH_1):M_D_CPU0_SA_PAR
BL60 M_D_CPU0_SB_PAR MDB_PAR @T6G_MB_LIB.T6G(SCH_1):M_D_CPU0_SB_PAR
BJ60 M_D_CPU0_SB_CA<3> MDB_CA3 @T6G_MB_LIB.T6G(SCH_1):M_D_CPU0_SB_CA(3)
BV60 M_D_CPU0_SB_DQS_DP<9> MDB_DQS_H9 @T6G_MB_LIB.T6G(SCH_1):M_D_CPU0_SB_DQS_DP(9)
BC60 M_D_CPU0_CLK_DP<0> MD0_CLK_H @T6G_MB_LIB.T6G(SCH_1):M_D_CPU0_CLK_DP(0)
BD60 M_D_CPU0_CLK_DN<0> MD0_CLK_L @T6G_MB_LIB.T6G(SCH_1):M_D_CPU0_CLK_DN(0)
BF60     NC MD1_CLK_H     NC
BG60     NC MD1_CLK_L     NC
BF58 TP_M_D_CPU0_SA_TEST39D TEST39D @T6G_MB_LIB.T6G(SCH_1):TP_M_D_CPU0_SA_TEST39D

Q_RES_0402LF-15,1%,1/16W,CHIP,CS01502FB03  I314  R378
   1 M_D_CPU0_ALERT_N      A @T6G_MB_LIB.T6G(SCH_1):M_D_CPU0_ALERT_N
   2 M_D_CPU0_ALERT_R_N      B @T6G_MB_LIB.T6G(SCH_1):M_D_CPU0_ALERT_R_N


DRAWING: @T6G_MB_LIB.T6G(SCH_1):PAGE14 

GENOA_SP5-SOCKET6096_13568-001,SMLF,IO,DGA^6000030  I159  U25
AT69 M_E_CPU0_ALERT_R_N ME_ALERT_L @T6G_MB_LIB.T6G(SCH_1):M_E_CPU0_ALERT_R_N
AU69 M_E_CPU0_RESET_N ME_RESET_L @T6G_MB_LIB.T6G(SCH_1):M_E_CPU0_RESET_N
CU71 M_E_CPU0_SB_DQS_DN<2> MEB_DQS_L2 @T6G_MB_LIB.T6G(SCH_1):M_E_CPU0_SB_DQS_DN(2)
DA71 M_E_CPU0_SB_DQ<26> MEB_DATA26 @T6G_MB_LIB.T6G(SCH_1):M_E_CPU0_SB_DQ(26)
CP69 M_E_CPU0_SB_DQ<15> MEB_DATA15 @T6G_MB_LIB.T6G(SCH_1):M_E_CPU0_SB_DQ(15)
BU71 M_E_CPU0_SB_CB<6> MEB_CHECK6 @T6G_MB_LIB.T6G(SCH_1):M_E_CPU0_SB_CB(6)
AF69 M_E_CPU0_SA_DQS_DN<8> MEA_DQS_L8 @T6G_MB_LIB.T6G(SCH_1):M_E_CPU0_SA_DQS_DN(8)
AL71 M_E_CPU0_SA_DQS_DP<4> MEA_DQS_H4 @T6G_MB_LIB.T6G(SCH_1):M_E_CPU0_SA_DQS_DP(4)
DC71 M_E_CPU0_SB_DQS_DN<3> MEB_DQS_L3 @T6G_MB_LIB.T6G(SCH_1):M_E_CPU0_SB_DQS_DN(3)
DB69 M_E_CPU0_SB_DQ<27> MEB_DATA27 @T6G_MB_LIB.T6G(SCH_1):M_E_CPU0_SB_DQ(27)
CP70 M_E_CPU0_SB_DQ<16> MEB_DATA16 @T6G_MB_LIB.T6G(SCH_1):M_E_CPU0_SB_DQ(16)
BV69 M_E_CPU0_SB_CB<7> MEB_CHECK7 @T6G_MB_LIB.T6G(SCH_1):M_E_CPU0_SB_CB(7)
BR71     NC MEB1_RSP_L     NC
BP70 M_E_CPU0_SB_RSP<0> MEB0_RSP_L @T6G_MB_LIB.T6G(SCH_1):M_E_CPU0_SB_RSP(0)
AM69 M_E_CPU0_SA_DQS_DN<9> MEA_DQS_L9 @T6G_MB_LIB.T6G(SCH_1):M_E_CPU0_SA_DQS_DN(9)
 J69 M_E_CPU0_SA_DQS_DP<5> MEA_DQS_H5 @T6G_MB_LIB.T6G(SCH_1):M_E_CPU0_SA_DQS_DP(5)
BW69 M_E_CPU0_SB_DQS_DN<4> MEB_DQS_L4 @T6G_MB_LIB.T6G(SCH_1):M_E_CPU0_SB_DQS_DN(4)
CD70 M_E_CPU0_SB_DQS_DP<0> MEB_DQS_H0 @T6G_MB_LIB.T6G(SCH_1):M_E_CPU0_SB_DQS_DP(0)
DD70 M_E_CPU0_SB_DQ<28> MEB_DATA28 @T6G_MB_LIB.T6G(SCH_1):M_E_CPU0_SB_DQ(28)
CR69 M_E_CPU0_SB_DQ<17> MEB_DATA17 @T6G_MB_LIB.T6G(SCH_1):M_E_CPU0_SB_DQ(17)
 R69 M_E_CPU0_SA_DQS_DP<6> MEA_DQS_H6 @T6G_MB_LIB.T6G(SCH_1):M_E_CPU0_SA_DQS_DP(6)
CE69 M_E_CPU0_SB_DQS_DN<5> MEB_DQS_L5 @T6G_MB_LIB.T6G(SCH_1):M_E_CPU0_SB_DQS_DN(5)
CK70 M_E_CPU0_SB_DQS_DP<1> MEB_DQS_H1 @T6G_MB_LIB.T6G(SCH_1):M_E_CPU0_SB_DQS_DP(1)
DE69 M_E_CPU0_SB_DQ<29> MEB_DATA29 @T6G_MB_LIB.T6G(SCH_1):M_E_CPU0_SB_DQ(29)
CR71 M_E_CPU0_SB_DQ<18> MEB_DATA18 @T6G_MB_LIB.T6G(SCH_1):M_E_CPU0_SB_DQ(18)
AA69 M_E_CPU0_SA_DQS_DP<7> MEA_DQS_H7 @T6G_MB_LIB.T6G(SCH_1):M_E_CPU0_SA_DQS_DP(7)
 E71 M_E_CPU0_SA_DQ<0> MEA_DATA0 @T6G_MB_LIB.T6G(SCH_1):M_E_CPU0_SA_DQ(0)
AU71     NC MEA1_CS_L0     NC
AV70 M_E_CPU0_SA_CS_N<0> MEA0_CS_L0 @T6G_MB_LIB.T6G(SCH_1):M_E_CPU0_SA_CS_N(0)
CL69 M_E_CPU0_SB_DQS_DN<6> MEB_DQS_L6 @T6G_MB_LIB.T6G(SCH_1):M_E_CPU0_SB_DQS_DN(6)
CT70 M_E_CPU0_SB_DQS_DP<2> MEB_DQS_H2 @T6G_MB_LIB.T6G(SCH_1):M_E_CPU0_SB_DQS_DP(2)
CT69 M_E_CPU0_SB_DQ<19> MEB_DATA19 @T6G_MB_LIB.T6G(SCH_1):M_E_CPU0_SB_DQ(19)
CB70 M_E_CPU0_SB_DQ<0> MEB_DATA0 @T6G_MB_LIB.T6G(SCH_1):M_E_CPU0_SB_DQ(0)
AG69 M_E_CPU0_SA_DQS_DP<8> MEA_DQS_H8 @T6G_MB_LIB.T6G(SCH_1):M_E_CPU0_SA_DQS_DP(8)
AH70 M_E_CPU0_SA_DQ<30> MEA_DATA30 @T6G_MB_LIB.T6G(SCH_1):M_E_CPU0_SA_DQ(30)
 F69 M_E_CPU0_SA_DQ<1> MEA_DATA1 @T6G_MB_LIB.T6G(SCH_1):M_E_CPU0_SA_DQ(1)
AV69     NC MEA1_CS_L1     NC
AW69 M_E_CPU0_SA_CS_N<1> MEA0_CS_L1 @T6G_MB_LIB.T6G(SCH_1):M_E_CPU0_SA_CS_N(1)
CU69 M_E_CPU0_SB_DQS_DN<7> MEB_DQS_L7 @T6G_MB_LIB.T6G(SCH_1):M_E_CPU0_SB_DQS_DN(7)
DB70 M_E_CPU0_SB_DQS_DP<3> MEB_DQS_H3 @T6G_MB_LIB.T6G(SCH_1):M_E_CPU0_SB_DQS_DP(3)
CC69 M_E_CPU0_SB_DQ<1> MEB_DATA1 @T6G_MB_LIB.T6G(SCH_1):M_E_CPU0_SB_DQ(1)
AN69 M_E_CPU0_SA_DQS_DP<9> MEA_DQS_H9 @T6G_MB_LIB.T6G(SCH_1):M_E_CPU0_SA_DQS_DP(9)
AJ69 M_E_CPU0_SA_DQ<31> MEA_DATA31 @T6G_MB_LIB.T6G(SCH_1):M_E_CPU0_SA_DQ(31)
AA71 M_E_CPU0_SA_DQ<20> MEA_DATA20 @T6G_MB_LIB.T6G(SCH_1):M_E_CPU0_SA_DQ(20)
 F70 M_E_CPU0_SA_DQ<2> MEA_DATA2 @T6G_MB_LIB.T6G(SCH_1):M_E_CPU0_SA_DQ(2)
AJ71 M_E_CPU0_SA_CB<0> MEA_CHECK0 @T6G_MB_LIB.T6G(SCH_1):M_E_CPU0_SA_CB(0)
AW71 M_E_CPU0_SA_CA<0> MEA_CA0 @T6G_MB_LIB.T6G(SCH_1):M_E_CPU0_SA_CA(0)
DC69 M_E_CPU0_SB_DQS_DN<8> MEB_DQS_L8 @T6G_MB_LIB.T6G(SCH_1):M_E_CPU0_SB_DQS_DN(8)
BY69 M_E_CPU0_SB_DQS_DP<4> MEB_DQS_H4 @T6G_MB_LIB.T6G(SCH_1):M_E_CPU0_SB_DQS_DP(4)
CC71 M_E_CPU0_SB_DQ<2> MEB_DATA2 @T6G_MB_LIB.T6G(SCH_1):M_E_CPU0_SB_DQ(2)
BG69 M_E_CPU0_SB_CA<0> MEB_CA0 @T6G_MB_LIB.T6G(SCH_1):M_E_CPU0_SB_CA(0)
AB69 M_E_CPU0_SA_DQ<21> MEA_DATA21 @T6G_MB_LIB.T6G(SCH_1):M_E_CPU0_SA_DQ(21)
 M70 M_E_CPU0_SA_DQ<10> MEA_DATA10 @T6G_MB_LIB.T6G(SCH_1):M_E_CPU0_SA_DQ(10)
 G69 M_E_CPU0_SA_DQ<3> MEA_DATA3 @T6G_MB_LIB.T6G(SCH_1):M_E_CPU0_SA_DQ(3)
AK69 M_E_CPU0_SA_CB<1> MEA_CHECK1 @T6G_MB_LIB.T6G(SCH_1):M_E_CPU0_SA_CB(1)
AY70 M_E_CPU0_SA_CA<1> MEA_CA1 @T6G_MB_LIB.T6G(SCH_1):M_E_CPU0_SA_CA(1)
BW71 M_E_CPU0_SB_DQS_DN<9> MEB_DQS_L9 @T6G_MB_LIB.T6G(SCH_1):M_E_CPU0_SB_DQS_DN(9)
CF69 M_E_CPU0_SB_DQS_DP<5> MEB_DQS_H5 @T6G_MB_LIB.T6G(SCH_1):M_E_CPU0_SB_DQS_DP(5)
CD69 M_E_CPU0_SB_DQ<3> MEB_DATA3 @T6G_MB_LIB.T6G(SCH_1):M_E_CPU0_SB_DQ(3)
BH69 M_E_CPU0_SB_CA<1> MEB_CA1 @T6G_MB_LIB.T6G(SCH_1):M_E_CPU0_SB_CA(1)
AB70 M_E_CPU0_SA_DQ<22> MEA_DATA22 @T6G_MB_LIB.T6G(SCH_1):M_E_CPU0_SA_DQ(22)
 N69 M_E_CPU0_SA_DQ<11> MEA_DATA11 @T6G_MB_LIB.T6G(SCH_1):M_E_CPU0_SA_DQ(11)
 J71 M_E_CPU0_SA_DQ<4> MEA_DATA4 @T6G_MB_LIB.T6G(SCH_1):M_E_CPU0_SA_DQ(4)
AK70 M_E_CPU0_SA_CB<2> MEA_CHECK2 @T6G_MB_LIB.T6G(SCH_1):M_E_CPU0_SA_CB(2)
AY69 M_E_CPU0_SA_CA<2> MEA_CA2 @T6G_MB_LIB.T6G(SCH_1):M_E_CPU0_SA_CA(2)
CM69 M_E_CPU0_SB_DQS_DP<6> MEB_DQS_H6 @T6G_MB_LIB.T6G(SCH_1):M_E_CPU0_SB_DQS_DP(6)
CF70 M_E_CPU0_SB_DQ<4> MEB_DATA4 @T6G_MB_LIB.T6G(SCH_1):M_E_CPU0_SB_DQ(4)
BH70 M_E_CPU0_SB_CA<2> MEB_CA2 @T6G_MB_LIB.T6G(SCH_1):M_E_CPU0_SB_CA(2)
AC69 M_E_CPU0_SA_DQ<23> MEA_DATA23 @T6G_MB_LIB.T6G(SCH_1):M_E_CPU0_SA_DQ(23)
 R71 M_E_CPU0_SA_DQ<12> MEA_DATA12 @T6G_MB_LIB.T6G(SCH_1):M_E_CPU0_SA_DQ(12)
 K69 M_E_CPU0_SA_DQ<5> MEA_DATA5 @T6G_MB_LIB.T6G(SCH_1):M_E_CPU0_SA_DQ(5)
AL69 M_E_CPU0_SA_CB<3> MEA_CHECK3 @T6G_MB_LIB.T6G(SCH_1):M_E_CPU0_SA_CB(3)
BA69 M_E_CPU0_SA_CA<3> MEA_CA3 @T6G_MB_LIB.T6G(SCH_1):M_E_CPU0_SA_CA(3)
CV69 M_E_CPU0_SB_DQS_DP<7> MEB_DQS_H7 @T6G_MB_LIB.T6G(SCH_1):M_E_CPU0_SB_DQS_DP(7)
CG69 M_E_CPU0_SB_DQ<5> MEB_DATA5 @T6G_MB_LIB.T6G(SCH_1):M_E_CPU0_SB_DQ(5)
BJ71 M_E_CPU0_SB_CA<3> MEB_CA3 @T6G_MB_LIB.T6G(SCH_1):M_E_CPU0_SB_CA(3)
BL69     NC MEB1_CS_L0     NC
BM69 M_E_CPU0_SB_CS_N<0> MEB0_CS_L0 @T6G_MB_LIB.T6G(SCH_1):M_E_CPU0_SB_CS_N(0)
 H70 M_E_CPU0_SA_DQS_DN<0> MEA_DQS_L0 @T6G_MB_LIB.T6G(SCH_1):M_E_CPU0_SA_DQS_DN(0)
AC71 M_E_CPU0_SA_DQ<24> MEA_DATA24 @T6G_MB_LIB.T6G(SCH_1):M_E_CPU0_SA_DQ(24)
 T69 M_E_CPU0_SA_DQ<13> MEA_DATA13 @T6G_MB_LIB.T6G(SCH_1):M_E_CPU0_SA_DQ(13)
 K70 M_E_CPU0_SA_DQ<6> MEA_DATA6 @T6G_MB_LIB.T6G(SCH_1):M_E_CPU0_SA_DQ(6)
AN71 M_E_CPU0_SA_CB<4> MEA_CHECK4 @T6G_MB_LIB.T6G(SCH_1):M_E_CPU0_SA_CB(4)
BA71 M_E_CPU0_SA_CA<4> MEA_CA4 @T6G_MB_LIB.T6G(SCH_1):M_E_CPU0_SA_CA(4)
DD69 M_E_CPU0_SB_DQS_DP<8> MEB_DQS_H8 @T6G_MB_LIB.T6G(SCH_1):M_E_CPU0_SB_DQS_DP(8)
DE71 M_E_CPU0_SB_DQ<30> MEB_DATA30 @T6G_MB_LIB.T6G(SCH_1):M_E_CPU0_SB_DQ(30)
CG71 M_E_CPU0_SB_DQ<6> MEB_DATA6 @T6G_MB_LIB.T6G(SCH_1):M_E_CPU0_SB_DQ(6)
BJ69 M_E_CPU0_SB_CA<4> MEB_CA4 @T6G_MB_LIB.T6G(SCH_1):M_E_CPU0_SB_CA(4)
BM70     NC MEB1_CS_L1     NC
BN71 M_E_CPU0_SB_CS_N<1> MEB0_CS_L1 @T6G_MB_LIB.T6G(SCH_1):M_E_CPU0_SB_CS_N(1)
 P70 M_E_CPU0_SA_DQS_DN<1> MEA_DQS_L1 @T6G_MB_LIB.T6G(SCH_1):M_E_CPU0_SA_DQS_DN(1)
AD69 M_E_CPU0_SA_DQ<25> MEA_DATA25 @T6G_MB_LIB.T6G(SCH_1):M_E_CPU0_SA_DQ(25)
 T70 M_E_CPU0_SA_DQ<14> MEA_DATA14 @T6G_MB_LIB.T6G(SCH_1):M_E_CPU0_SA_DQ(14)
 L69 M_E_CPU0_SA_DQ<7> MEA_DATA7 @T6G_MB_LIB.T6G(SCH_1):M_E_CPU0_SA_DQ(7)
AP69 M_E_CPU0_SA_CB<5> MEA_CHECK5 @T6G_MB_LIB.T6G(SCH_1):M_E_CPU0_SA_CB(5)
BB70 M_E_CPU0_SA_CA<5> MEA_CA5 @T6G_MB_LIB.T6G(SCH_1):M_E_CPU0_SA_CA(5)
DF69 M_E_CPU0_SB_DQ<31> MEB_DATA31 @T6G_MB_LIB.T6G(SCH_1):M_E_CPU0_SB_DQ(31)
CV70 M_E_CPU0_SB_DQ<20> MEB_DATA20 @T6G_MB_LIB.T6G(SCH_1):M_E_CPU0_SB_DQ(20)
CH69 M_E_CPU0_SB_DQ<7> MEB_DATA7 @T6G_MB_LIB.T6G(SCH_1):M_E_CPU0_SB_DQ(7)
BY70 M_E_CPU0_SB_CB<0> MEB_CHECK0 @T6G_MB_LIB.T6G(SCH_1):M_E_CPU0_SB_CB(0)
BK69 M_E_CPU0_SB_CA<5> MEB_CA5 @T6G_MB_LIB.T6G(SCH_1):M_E_CPU0_SB_CA(5)
 Y70 M_E_CPU0_SA_DQS_DN<2> MEA_DQS_L2 @T6G_MB_LIB.T6G(SCH_1):M_E_CPU0_SA_DQS_DN(2)
AD70 M_E_CPU0_SA_DQ<26> MEA_DATA26 @T6G_MB_LIB.T6G(SCH_1):M_E_CPU0_SA_DQ(26)
 U69 M_E_CPU0_SA_DQ<15> MEA_DATA15 @T6G_MB_LIB.T6G(SCH_1):M_E_CPU0_SA_DQ(15)
 L71 M_E_CPU0_SA_DQ<8> MEA_DATA8 @T6G_MB_LIB.T6G(SCH_1):M_E_CPU0_SA_DQ(8)
AP70 M_E_CPU0_SA_CB<6> MEA_CHECK6 @T6G_MB_LIB.T6G(SCH_1):M_E_CPU0_SA_CB(6)
BB69 M_E_CPU0_SA_CA<6> MEA_CA6 @T6G_MB_LIB.T6G(SCH_1):M_E_CPU0_SA_CA(6)
CW69 M_E_CPU0_SB_DQ<21> MEB_DATA21 @T6G_MB_LIB.T6G(SCH_1):M_E_CPU0_SB_DQ(21)
CJ71 M_E_CPU0_SB_DQ<10> MEB_DATA10 @T6G_MB_LIB.T6G(SCH_1):M_E_CPU0_SB_DQ(10)
CH70 M_E_CPU0_SB_DQ<8> MEB_DATA8 @T6G_MB_LIB.T6G(SCH_1):M_E_CPU0_SB_DQ(8)
CA69 M_E_CPU0_SB_CB<1> MEB_CHECK1 @T6G_MB_LIB.T6G(SCH_1):M_E_CPU0_SB_CB(1)
BK70 M_E_CPU0_SB_CA<6> MEB_CA6 @T6G_MB_LIB.T6G(SCH_1):M_E_CPU0_SB_CA(6)
AF70 M_E_CPU0_SA_DQS_DN<3> MEA_DQS_L3 @T6G_MB_LIB.T6G(SCH_1):M_E_CPU0_SA_DQS_DN(3)
AE69 M_E_CPU0_SA_DQ<27> MEA_DATA27 @T6G_MB_LIB.T6G(SCH_1):M_E_CPU0_SA_DQ(27)
 U71 M_E_CPU0_SA_DQ<16> MEA_DATA16 @T6G_MB_LIB.T6G(SCH_1):M_E_CPU0_SA_DQ(16)
 M69 M_E_CPU0_SA_DQ<9> MEA_DATA9 @T6G_MB_LIB.T6G(SCH_1):M_E_CPU0_SA_DQ(9)
AR69 M_E_CPU0_SA_CB<7> MEA_CHECK7 @T6G_MB_LIB.T6G(SCH_1):M_E_CPU0_SA_CB(7)
BP69     NC MEA1_RSP_L     NC
BN69 M_E_CPU0_SA_RSP<0> MEA0_RSP_L @T6G_MB_LIB.T6G(SCH_1):M_E_CPU0_SA_RSP(0)
CW71 M_E_CPU0_SB_DQ<22> MEB_DATA22 @T6G_MB_LIB.T6G(SCH_1):M_E_CPU0_SB_DQ(22)
CK69 M_E_CPU0_SB_DQ<11> MEB_DATA11 @T6G_MB_LIB.T6G(SCH_1):M_E_CPU0_SB_DQ(11)
CJ69 M_E_CPU0_SB_DQ<9> MEB_DATA9 @T6G_MB_LIB.T6G(SCH_1):M_E_CPU0_SB_DQ(9)
CA71 M_E_CPU0_SB_CB<2> MEB_CHECK2 @T6G_MB_LIB.T6G(SCH_1):M_E_CPU0_SB_CB(2)
AM70 M_E_CPU0_SA_DQS_DN<4> MEA_DQS_L4 @T6G_MB_LIB.T6G(SCH_1):M_E_CPU0_SA_DQS_DN(4)
 G71 M_E_CPU0_SA_DQS_DP<0> MEA_DQS_H0 @T6G_MB_LIB.T6G(SCH_1):M_E_CPU0_SA_DQS_DP(0)
AG71 M_E_CPU0_SA_DQ<28> MEA_DATA28 @T6G_MB_LIB.T6G(SCH_1):M_E_CPU0_SA_DQ(28)
 V69 M_E_CPU0_SA_DQ<17> MEA_DATA17 @T6G_MB_LIB.T6G(SCH_1):M_E_CPU0_SA_DQ(17)
CY69 M_E_CPU0_SB_DQ<23> MEB_DATA23 @T6G_MB_LIB.T6G(SCH_1):M_E_CPU0_SB_DQ(23)
CM70 M_E_CPU0_SB_DQ<12> MEB_DATA12 @T6G_MB_LIB.T6G(SCH_1):M_E_CPU0_SB_DQ(12)
CB69 M_E_CPU0_SB_CB<3> MEB_CHECK3 @T6G_MB_LIB.T6G(SCH_1):M_E_CPU0_SB_CB(3)
 H69 M_E_CPU0_SA_DQS_DN<5> MEA_DQS_L5 @T6G_MB_LIB.T6G(SCH_1):M_E_CPU0_SA_DQS_DN(5)
 N71 M_E_CPU0_SA_DQS_DP<1> MEA_DQS_H1 @T6G_MB_LIB.T6G(SCH_1):M_E_CPU0_SA_DQS_DP(1)
AH69 M_E_CPU0_SA_DQ<29> MEA_DATA29 @T6G_MB_LIB.T6G(SCH_1):M_E_CPU0_SA_DQ(29)
 V70 M_E_CPU0_SA_DQ<18> MEA_DATA18 @T6G_MB_LIB.T6G(SCH_1):M_E_CPU0_SA_DQ(18)
CE71 M_E_CPU0_SB_DQS_DN<0> MEB_DQS_L0 @T6G_MB_LIB.T6G(SCH_1):M_E_CPU0_SB_DQS_DN(0)
CY70 M_E_CPU0_SB_DQ<24> MEB_DATA24 @T6G_MB_LIB.T6G(SCH_1):M_E_CPU0_SB_DQ(24)
CN69 M_E_CPU0_SB_DQ<13> MEB_DATA13 @T6G_MB_LIB.T6G(SCH_1):M_E_CPU0_SB_DQ(13)
BT70 M_E_CPU0_SB_CB<4> MEB_CHECK4 @T6G_MB_LIB.T6G(SCH_1):M_E_CPU0_SB_CB(4)
 P69 M_E_CPU0_SA_DQS_DN<6> MEA_DQS_L6 @T6G_MB_LIB.T6G(SCH_1):M_E_CPU0_SA_DQS_DN(6)
 W71 M_E_CPU0_SA_DQS_DP<2> MEA_DQS_H2 @T6G_MB_LIB.T6G(SCH_1):M_E_CPU0_SA_DQS_DP(2)
 W69 M_E_CPU0_SA_DQ<19> MEA_DATA19 @T6G_MB_LIB.T6G(SCH_1):M_E_CPU0_SA_DQ(19)
CL71 M_E_CPU0_SB_DQS_DN<1> MEB_DQS_L1 @T6G_MB_LIB.T6G(SCH_1):M_E_CPU0_SB_DQS_DN(1)
DA69 M_E_CPU0_SB_DQ<25> MEB_DATA25 @T6G_MB_LIB.T6G(SCH_1):M_E_CPU0_SB_DQ(25)
CN71 M_E_CPU0_SB_DQ<14> MEB_DATA14 @T6G_MB_LIB.T6G(SCH_1):M_E_CPU0_SB_DQ(14)
BU69 M_E_CPU0_SB_CB<5> MEB_CHECK5 @T6G_MB_LIB.T6G(SCH_1):M_E_CPU0_SB_CB(5)
 Y69 M_E_CPU0_SA_DQS_DN<7> MEA_DQS_L7 @T6G_MB_LIB.T6G(SCH_1):M_E_CPU0_SA_DQS_DN(7)
AE71 M_E_CPU0_SA_DQS_DP<3> MEA_DQS_H3 @T6G_MB_LIB.T6G(SCH_1):M_E_CPU0_SA_DQS_DP(3)
BC69 M_E_CPU0_SA_PAR MEA_PAR @T6G_MB_LIB.T6G(SCH_1):M_E_CPU0_SA_PAR
BL71 M_E_CPU0_SB_PAR MEB_PAR @T6G_MB_LIB.T6G(SCH_1):M_E_CPU0_SB_PAR
BV70 M_E_CPU0_SB_DQS_DP<9> MEB_DQS_H9 @T6G_MB_LIB.T6G(SCH_1):M_E_CPU0_SB_DQS_DP(9)
BC71 M_E_CPU0_CLK_DP<0> ME0_CLK_H @T6G_MB_LIB.T6G(SCH_1):M_E_CPU0_CLK_DP(0)
BD70 M_E_CPU0_CLK_DN<0> ME0_CLK_L @T6G_MB_LIB.T6G(SCH_1):M_E_CPU0_CLK_DN(0)
BF70     NC ME1_CLK_H     NC
BG71     NC ME1_CLK_L     NC
BF69 TP_M_E_CPU0_SA_TEST39E TEST39E @T6G_MB_LIB.T6G(SCH_1):TP_M_E_CPU0_SA_TEST39E

Q_RES_0402LF-15,1%,1/16W,CHIP,CS01502FB03  I315  R379
   1 M_E_CPU0_ALERT_N      A @T6G_MB_LIB.T6G(SCH_1):M_E_CPU0_ALERT_N
   2 M_E_CPU0_ALERT_R_N      B @T6G_MB_LIB.T6G(SCH_1):M_E_CPU0_ALERT_R_N


DRAWING: @T6G_MB_LIB.T6G(SCH_1):PAGE15 

GENOA_SP5-SOCKET6096_13568-001,SMLF,IO,DGA^6000030  I159  U25
AT65 M_F_CPU0_ALERT_R_N MF_ALERT_L @T6G_MB_LIB.T6G(SCH_1):M_F_CPU0_ALERT_R_N
AU66 M_F_CPU0_RESET_N MF_RESET_L @T6G_MB_LIB.T6G(SCH_1):M_F_CPU0_RESET_N
CL66 M_F_CPU0_SB_DQS_DN<6> MFB_DQS_L6 @T6G_MB_LIB.T6G(SCH_1):M_F_CPU0_SB_DQS_DN(6)
CT67 M_F_CPU0_SB_DQS_DP<2> MFB_DQS_H2 @T6G_MB_LIB.T6G(SCH_1):M_F_CPU0_SB_DQS_DP(2)
CT65 M_F_CPU0_SB_DQ<19> MFB_DATA19 @T6G_MB_LIB.T6G(SCH_1):M_F_CPU0_SB_DQ(19)
CH65 M_F_CPU0_SB_DQ<7> MFB_DATA7 @T6G_MB_LIB.T6G(SCH_1):M_F_CPU0_SB_DQ(7)
AG66 M_F_CPU0_SA_DQS_DP<8> MFA_DQS_H8 @T6G_MB_LIB.T6G(SCH_1):M_F_CPU0_SA_DQS_DP(8)
AH67 M_F_CPU0_SA_DQ<30> MFA_DATA30 @T6G_MB_LIB.T6G(SCH_1):M_F_CPU0_SA_DQ(30)
 L67 M_F_CPU0_SA_DQ<8> MFA_DATA8 @T6G_MB_LIB.T6G(SCH_1):M_F_CPU0_SA_DQ(8)
AU67     NC MFA1_CS_L0     NC
AW66 M_F_CPU0_SA_CS_N<1> MFA0_CS_L1 @T6G_MB_LIB.T6G(SCH_1):M_F_CPU0_SA_CS_N(1)
CU66 M_F_CPU0_SB_DQS_DN<7> MFB_DQS_L7 @T6G_MB_LIB.T6G(SCH_1):M_F_CPU0_SB_DQS_DN(7)
DB67 M_F_CPU0_SB_DQS_DP<3> MFB_DQS_H3 @T6G_MB_LIB.T6G(SCH_1):M_F_CPU0_SB_DQS_DP(3)
CH67 M_F_CPU0_SB_DQ<8> MFB_DATA8 @T6G_MB_LIB.T6G(SCH_1):M_F_CPU0_SB_DQ(8)
AN66 M_F_CPU0_SA_DQS_DP<9> MFA_DQS_H9 @T6G_MB_LIB.T6G(SCH_1):M_F_CPU0_SA_DQS_DP(9)
AJ66 M_F_CPU0_SA_DQ<31> MFA_DATA31 @T6G_MB_LIB.T6G(SCH_1):M_F_CPU0_SA_DQ(31)
AA67 M_F_CPU0_SA_DQ<20> MFA_DATA20 @T6G_MB_LIB.T6G(SCH_1):M_F_CPU0_SA_DQ(20)
 M65 M_F_CPU0_SA_DQ<9> MFA_DATA9 @T6G_MB_LIB.T6G(SCH_1):M_F_CPU0_SA_DQ(9)
AJ67 M_F_CPU0_SA_CB<0> MFA_CHECK0 @T6G_MB_LIB.T6G(SCH_1):M_F_CPU0_SA_CB(0)
AV65     NC MFA1_CS_L1     NC
DC66 M_F_CPU0_SB_DQS_DN<8> MFB_DQS_L8 @T6G_MB_LIB.T6G(SCH_1):M_F_CPU0_SB_DQS_DN(8)
BY65 M_F_CPU0_SB_DQS_DP<4> MFB_DQS_H4 @T6G_MB_LIB.T6G(SCH_1):M_F_CPU0_SB_DQS_DP(4)
CJ66 M_F_CPU0_SB_DQ<9> MFB_DATA9 @T6G_MB_LIB.T6G(SCH_1):M_F_CPU0_SB_DQ(9)
AB65 M_F_CPU0_SA_DQ<21> MFA_DATA21 @T6G_MB_LIB.T6G(SCH_1):M_F_CPU0_SA_DQ(21)
 M67 M_F_CPU0_SA_DQ<10> MFA_DATA10 @T6G_MB_LIB.T6G(SCH_1):M_F_CPU0_SA_DQ(10)
AK65 M_F_CPU0_SA_CB<1> MFA_CHECK1 @T6G_MB_LIB.T6G(SCH_1):M_F_CPU0_SA_CB(1)
BW67 M_F_CPU0_SB_DQS_DN<9> MFB_DQS_L9 @T6G_MB_LIB.T6G(SCH_1):M_F_CPU0_SB_DQS_DN(9)
CF65 M_F_CPU0_SB_DQS_DP<5> MFB_DQS_H5 @T6G_MB_LIB.T6G(SCH_1):M_F_CPU0_SB_DQS_DP(5)
AB67 M_F_CPU0_SA_DQ<22> MFA_DATA22 @T6G_MB_LIB.T6G(SCH_1):M_F_CPU0_SA_DQ(22)
 N66 M_F_CPU0_SA_DQ<11> MFA_DATA11 @T6G_MB_LIB.T6G(SCH_1):M_F_CPU0_SA_DQ(11)
AK67 M_F_CPU0_SA_CB<2> MFA_CHECK2 @T6G_MB_LIB.T6G(SCH_1):M_F_CPU0_SA_CB(2)
CM65 M_F_CPU0_SB_DQS_DP<6> MFB_DQS_H6 @T6G_MB_LIB.T6G(SCH_1):M_F_CPU0_SB_DQS_DP(6)
AC66 M_F_CPU0_SA_DQ<23> MFA_DATA23 @T6G_MB_LIB.T6G(SCH_1):M_F_CPU0_SA_DQ(23)
 R67 M_F_CPU0_SA_DQ<12> MFA_DATA12 @T6G_MB_LIB.T6G(SCH_1):M_F_CPU0_SA_DQ(12)
AL66 M_F_CPU0_SA_CB<3> MFA_CHECK3 @T6G_MB_LIB.T6G(SCH_1):M_F_CPU0_SA_CB(3)
AW67 M_F_CPU0_SA_CA<0> MFA_CA0 @T6G_MB_LIB.T6G(SCH_1):M_F_CPU0_SA_CA(0)
CV65 M_F_CPU0_SB_DQS_DP<7> MFB_DQS_H7 @T6G_MB_LIB.T6G(SCH_1):M_F_CPU0_SB_DQS_DP(7)
BG66 M_F_CPU0_SB_CA<0> MFB_CA0 @T6G_MB_LIB.T6G(SCH_1):M_F_CPU0_SB_CA(0)
BM65 M_F_CPU0_SB_CS_N<0> MFB0_CS_L0 @T6G_MB_LIB.T6G(SCH_1):M_F_CPU0_SB_CS_N(0)
 H67 M_F_CPU0_SA_DQS_DN<0> MFA_DQS_L0 @T6G_MB_LIB.T6G(SCH_1):M_F_CPU0_SA_DQS_DN(0)
AC67 M_F_CPU0_SA_DQ<24> MFA_DATA24 @T6G_MB_LIB.T6G(SCH_1):M_F_CPU0_SA_DQ(24)
 T65 M_F_CPU0_SA_DQ<13> MFA_DATA13 @T6G_MB_LIB.T6G(SCH_1):M_F_CPU0_SA_DQ(13)
AN67 M_F_CPU0_SA_CB<4> MFA_CHECK4 @T6G_MB_LIB.T6G(SCH_1):M_F_CPU0_SA_CB(4)
AY67 M_F_CPU0_SA_CA<1> MFA_CA1 @T6G_MB_LIB.T6G(SCH_1):M_F_CPU0_SA_CA(1)
DD65 M_F_CPU0_SB_DQS_DP<8> MFB_DQS_H8 @T6G_MB_LIB.T6G(SCH_1):M_F_CPU0_SB_DQS_DP(8)
DE67 M_F_CPU0_SB_DQ<30> MFB_DATA30 @T6G_MB_LIB.T6G(SCH_1):M_F_CPU0_SB_DQ(30)
BH65 M_F_CPU0_SB_CA<1> MFB_CA1 @T6G_MB_LIB.T6G(SCH_1):M_F_CPU0_SB_CA(1)
BL66     NC MFB1_CS_L0     NC
BN67 M_F_CPU0_SB_CS_N<1> MFB0_CS_L1 @T6G_MB_LIB.T6G(SCH_1):M_F_CPU0_SB_CS_N(1)
 P67 M_F_CPU0_SA_DQS_DN<1> MFA_DQS_L1 @T6G_MB_LIB.T6G(SCH_1):M_F_CPU0_SA_DQS_DN(1)
AD65 M_F_CPU0_SA_DQ<25> MFA_DATA25 @T6G_MB_LIB.T6G(SCH_1):M_F_CPU0_SA_DQ(25)
 T67 M_F_CPU0_SA_DQ<14> MFA_DATA14 @T6G_MB_LIB.T6G(SCH_1):M_F_CPU0_SA_DQ(14)
AP65 M_F_CPU0_SA_CB<5> MFA_CHECK5 @T6G_MB_LIB.T6G(SCH_1):M_F_CPU0_SA_CB(5)
AY65 M_F_CPU0_SA_CA<2> MFA_CA2 @T6G_MB_LIB.T6G(SCH_1):M_F_CPU0_SA_CA(2)
DF67 M_F_CPU0_SB_DQ<31> MFB_DATA31 @T6G_MB_LIB.T6G(SCH_1):M_F_CPU0_SB_DQ(31)
CV67 M_F_CPU0_SB_DQ<20> MFB_DATA20 @T6G_MB_LIB.T6G(SCH_1):M_F_CPU0_SB_DQ(20)
BY67 M_F_CPU0_SB_CB<0> MFB_CHECK0 @T6G_MB_LIB.T6G(SCH_1):M_F_CPU0_SB_CB(0)
BH67 M_F_CPU0_SB_CA<2> MFB_CA2 @T6G_MB_LIB.T6G(SCH_1):M_F_CPU0_SB_CA(2)
BM67     NC MFB1_CS_L1     NC
 Y67 M_F_CPU0_SA_DQS_DN<2> MFA_DQS_L2 @T6G_MB_LIB.T6G(SCH_1):M_F_CPU0_SA_DQS_DN(2)
AD67 M_F_CPU0_SA_DQ<26> MFA_DATA26 @T6G_MB_LIB.T6G(SCH_1):M_F_CPU0_SA_DQ(26)
 U66 M_F_CPU0_SA_DQ<15> MFA_DATA15 @T6G_MB_LIB.T6G(SCH_1):M_F_CPU0_SA_DQ(15)
AP67 M_F_CPU0_SA_CB<6> MFA_CHECK6 @T6G_MB_LIB.T6G(SCH_1):M_F_CPU0_SA_CB(6)
BA66 M_F_CPU0_SA_CA<3> MFA_CA3 @T6G_MB_LIB.T6G(SCH_1):M_F_CPU0_SA_CA(3)
CW66 M_F_CPU0_SB_DQ<21> MFB_DATA21 @T6G_MB_LIB.T6G(SCH_1):M_F_CPU0_SB_DQ(21)
CJ67 M_F_CPU0_SB_DQ<10> MFB_DATA10 @T6G_MB_LIB.T6G(SCH_1):M_F_CPU0_SB_DQ(10)
CA66 M_F_CPU0_SB_CB<1> MFB_CHECK1 @T6G_MB_LIB.T6G(SCH_1):M_F_CPU0_SB_CB(1)
BJ67 M_F_CPU0_SB_CA<3> MFB_CA3 @T6G_MB_LIB.T6G(SCH_1):M_F_CPU0_SB_CA(3)
AF67 M_F_CPU0_SA_DQS_DN<3> MFA_DQS_L3 @T6G_MB_LIB.T6G(SCH_1):M_F_CPU0_SA_DQS_DN(3)
AE66 M_F_CPU0_SA_DQ<27> MFA_DATA27 @T6G_MB_LIB.T6G(SCH_1):M_F_CPU0_SA_DQ(27)
 U67 M_F_CPU0_SA_DQ<16> MFA_DATA16 @T6G_MB_LIB.T6G(SCH_1):M_F_CPU0_SA_DQ(16)
AR66 M_F_CPU0_SA_CB<7> MFA_CHECK7 @T6G_MB_LIB.T6G(SCH_1):M_F_CPU0_SA_CB(7)
BA67 M_F_CPU0_SA_CA<4> MFA_CA4 @T6G_MB_LIB.T6G(SCH_1):M_F_CPU0_SA_CA(4)
BN66 M_F_CPU0_SA_RSP<0> MFA0_RSP_L @T6G_MB_LIB.T6G(SCH_1):M_F_CPU0_SA_RSP(0)
CW67 M_F_CPU0_SB_DQ<22> MFB_DATA22 @T6G_MB_LIB.T6G(SCH_1):M_F_CPU0_SB_DQ(22)
CK65 M_F_CPU0_SB_DQ<11> MFB_DATA11 @T6G_MB_LIB.T6G(SCH_1):M_F_CPU0_SB_DQ(11)
CA67 M_F_CPU0_SB_CB<2> MFB_CHECK2 @T6G_MB_LIB.T6G(SCH_1):M_F_CPU0_SB_CB(2)
BJ66 M_F_CPU0_SB_CA<4> MFB_CA4 @T6G_MB_LIB.T6G(SCH_1):M_F_CPU0_SB_CA(4)
AM67 M_F_CPU0_SA_DQS_DN<4> MFA_DQS_L4 @T6G_MB_LIB.T6G(SCH_1):M_F_CPU0_SA_DQS_DN(4)
 G67 M_F_CPU0_SA_DQS_DP<0> MFA_DQS_H0 @T6G_MB_LIB.T6G(SCH_1):M_F_CPU0_SA_DQS_DP(0)
AG67 M_F_CPU0_SA_DQ<28> MFA_DATA28 @T6G_MB_LIB.T6G(SCH_1):M_F_CPU0_SA_DQ(28)
 V65 M_F_CPU0_SA_DQ<17> MFA_DATA17 @T6G_MB_LIB.T6G(SCH_1):M_F_CPU0_SA_DQ(17)
 E67 M_F_CPU0_SA_DQ<0> MFA_DATA0 @T6G_MB_LIB.T6G(SCH_1):M_F_CPU0_SA_DQ(0)
BB67 M_F_CPU0_SA_CA<5> MFA_CA5 @T6G_MB_LIB.T6G(SCH_1):M_F_CPU0_SA_CA(5)
BP65     NC MFA1_RSP_L     NC
CY65 M_F_CPU0_SB_DQ<23> MFB_DATA23 @T6G_MB_LIB.T6G(SCH_1):M_F_CPU0_SB_DQ(23)
CM67 M_F_CPU0_SB_DQ<12> MFB_DATA12 @T6G_MB_LIB.T6G(SCH_1):M_F_CPU0_SB_DQ(12)
CB67 M_F_CPU0_SB_DQ<0> MFB_DATA0 @T6G_MB_LIB.T6G(SCH_1):M_F_CPU0_SB_DQ(0)
CB65 M_F_CPU0_SB_CB<3> MFB_CHECK3 @T6G_MB_LIB.T6G(SCH_1):M_F_CPU0_SB_CB(3)
BK65 M_F_CPU0_SB_CA<5> MFB_CA5 @T6G_MB_LIB.T6G(SCH_1):M_F_CPU0_SB_CA(5)
 H65 M_F_CPU0_SA_DQS_DN<5> MFA_DQS_L5 @T6G_MB_LIB.T6G(SCH_1):M_F_CPU0_SA_DQS_DN(5)
 N67 M_F_CPU0_SA_DQS_DP<1> MFA_DQS_H1 @T6G_MB_LIB.T6G(SCH_1):M_F_CPU0_SA_DQS_DP(1)
AH65 M_F_CPU0_SA_DQ<29> MFA_DATA29 @T6G_MB_LIB.T6G(SCH_1):M_F_CPU0_SA_DQ(29)
 V67 M_F_CPU0_SA_DQ<18> MFA_DATA18 @T6G_MB_LIB.T6G(SCH_1):M_F_CPU0_SA_DQ(18)
 F65 M_F_CPU0_SA_DQ<1> MFA_DATA1 @T6G_MB_LIB.T6G(SCH_1):M_F_CPU0_SA_DQ(1)
BB65 M_F_CPU0_SA_CA<6> MFA_CA6 @T6G_MB_LIB.T6G(SCH_1):M_F_CPU0_SA_CA(6)
CE67 M_F_CPU0_SB_DQS_DN<0> MFB_DQS_L0 @T6G_MB_LIB.T6G(SCH_1):M_F_CPU0_SB_DQS_DN(0)
CY67 M_F_CPU0_SB_DQ<24> MFB_DATA24 @T6G_MB_LIB.T6G(SCH_1):M_F_CPU0_SB_DQ(24)
CN66 M_F_CPU0_SB_DQ<13> MFB_DATA13 @T6G_MB_LIB.T6G(SCH_1):M_F_CPU0_SB_DQ(13)
CC66 M_F_CPU0_SB_DQ<1> MFB_DATA1 @T6G_MB_LIB.T6G(SCH_1):M_F_CPU0_SB_DQ(1)
BT67 M_F_CPU0_SB_CB<4> MFB_CHECK4 @T6G_MB_LIB.T6G(SCH_1):M_F_CPU0_SB_CB(4)
BK67 M_F_CPU0_SB_CA<6> MFB_CA6 @T6G_MB_LIB.T6G(SCH_1):M_F_CPU0_SB_CA(6)
 P65 M_F_CPU0_SA_DQS_DN<6> MFA_DQS_L6 @T6G_MB_LIB.T6G(SCH_1):M_F_CPU0_SA_DQS_DN(6)
 W67 M_F_CPU0_SA_DQS_DP<2> MFA_DQS_H2 @T6G_MB_LIB.T6G(SCH_1):M_F_CPU0_SA_DQS_DP(2)
 W66 M_F_CPU0_SA_DQ<19> MFA_DATA19 @T6G_MB_LIB.T6G(SCH_1):M_F_CPU0_SA_DQ(19)
 F67 M_F_CPU0_SA_DQ<2> MFA_DATA2 @T6G_MB_LIB.T6G(SCH_1):M_F_CPU0_SA_DQ(2)
CL67 M_F_CPU0_SB_DQS_DN<1> MFB_DQS_L1 @T6G_MB_LIB.T6G(SCH_1):M_F_CPU0_SB_DQS_DN(1)
DA66 M_F_CPU0_SB_DQ<25> MFB_DATA25 @T6G_MB_LIB.T6G(SCH_1):M_F_CPU0_SB_DQ(25)
CN67 M_F_CPU0_SB_DQ<14> MFB_DATA14 @T6G_MB_LIB.T6G(SCH_1):M_F_CPU0_SB_DQ(14)
CC67 M_F_CPU0_SB_DQ<2> MFB_DATA2 @T6G_MB_LIB.T6G(SCH_1):M_F_CPU0_SB_DQ(2)
BU66 M_F_CPU0_SB_CB<5> MFB_CHECK5 @T6G_MB_LIB.T6G(SCH_1):M_F_CPU0_SB_CB(5)
 Y65 M_F_CPU0_SA_DQS_DN<7> MFA_DQS_L7 @T6G_MB_LIB.T6G(SCH_1):M_F_CPU0_SA_DQS_DN(7)
AE67 M_F_CPU0_SA_DQS_DP<3> MFA_DQS_H3 @T6G_MB_LIB.T6G(SCH_1):M_F_CPU0_SA_DQS_DP(3)
 G66 M_F_CPU0_SA_DQ<3> MFA_DATA3 @T6G_MB_LIB.T6G(SCH_1):M_F_CPU0_SA_DQ(3)
CU67 M_F_CPU0_SB_DQS_DN<2> MFB_DQS_L2 @T6G_MB_LIB.T6G(SCH_1):M_F_CPU0_SB_DQS_DN(2)
DA67 M_F_CPU0_SB_DQ<26> MFB_DATA26 @T6G_MB_LIB.T6G(SCH_1):M_F_CPU0_SB_DQ(26)
CP65 M_F_CPU0_SB_DQ<15> MFB_DATA15 @T6G_MB_LIB.T6G(SCH_1):M_F_CPU0_SB_DQ(15)
CD65 M_F_CPU0_SB_DQ<3> MFB_DATA3 @T6G_MB_LIB.T6G(SCH_1):M_F_CPU0_SB_DQ(3)
BU67 M_F_CPU0_SB_CB<6> MFB_CHECK6 @T6G_MB_LIB.T6G(SCH_1):M_F_CPU0_SB_CB(6)
AF65 M_F_CPU0_SA_DQS_DN<8> MFA_DQS_L8 @T6G_MB_LIB.T6G(SCH_1):M_F_CPU0_SA_DQS_DN(8)
AL67 M_F_CPU0_SA_DQS_DP<4> MFA_DQS_H4 @T6G_MB_LIB.T6G(SCH_1):M_F_CPU0_SA_DQS_DP(4)
 J67 M_F_CPU0_SA_DQ<4> MFA_DATA4 @T6G_MB_LIB.T6G(SCH_1):M_F_CPU0_SA_DQ(4)
DC67 M_F_CPU0_SB_DQS_DN<3> MFB_DQS_L3 @T6G_MB_LIB.T6G(SCH_1):M_F_CPU0_SB_DQS_DN(3)
DB65 M_F_CPU0_SB_DQ<27> MFB_DATA27 @T6G_MB_LIB.T6G(SCH_1):M_F_CPU0_SB_DQ(27)
CP67 M_F_CPU0_SB_DQ<16> MFB_DATA16 @T6G_MB_LIB.T6G(SCH_1):M_F_CPU0_SB_DQ(16)
CF67 M_F_CPU0_SB_DQ<4> MFB_DATA4 @T6G_MB_LIB.T6G(SCH_1):M_F_CPU0_SB_DQ(4)
BV65 M_F_CPU0_SB_CB<7> MFB_CHECK7 @T6G_MB_LIB.T6G(SCH_1):M_F_CPU0_SB_CB(7)
BP67 M_F_CPU0_SB_RSP<0> MFB0_RSP_L @T6G_MB_LIB.T6G(SCH_1):M_F_CPU0_SB_RSP(0)
AM65 M_F_CPU0_SA_DQS_DN<9> MFA_DQS_L9 @T6G_MB_LIB.T6G(SCH_1):M_F_CPU0_SA_DQS_DN(9)
 J66 M_F_CPU0_SA_DQS_DP<5> MFA_DQS_H5 @T6G_MB_LIB.T6G(SCH_1):M_F_CPU0_SA_DQS_DP(5)
 K65 M_F_CPU0_SA_DQ<5> MFA_DATA5 @T6G_MB_LIB.T6G(SCH_1):M_F_CPU0_SA_DQ(5)
BW66 M_F_CPU0_SB_DQS_DN<4> MFB_DQS_L4 @T6G_MB_LIB.T6G(SCH_1):M_F_CPU0_SB_DQS_DN(4)
CD67 M_F_CPU0_SB_DQS_DP<0> MFB_DQS_H0 @T6G_MB_LIB.T6G(SCH_1):M_F_CPU0_SB_DQS_DP(0)
DD67 M_F_CPU0_SB_DQ<28> MFB_DATA28 @T6G_MB_LIB.T6G(SCH_1):M_F_CPU0_SB_DQ(28)
CR66 M_F_CPU0_SB_DQ<17> MFB_DATA17 @T6G_MB_LIB.T6G(SCH_1):M_F_CPU0_SB_DQ(17)
CG66 M_F_CPU0_SB_DQ<5> MFB_DATA5 @T6G_MB_LIB.T6G(SCH_1):M_F_CPU0_SB_DQ(5)
BR67     NC MFB1_RSP_L     NC
 R66 M_F_CPU0_SA_DQS_DP<6> MFA_DQS_H6 @T6G_MB_LIB.T6G(SCH_1):M_F_CPU0_SA_DQS_DP(6)
 K67 M_F_CPU0_SA_DQ<6> MFA_DATA6 @T6G_MB_LIB.T6G(SCH_1):M_F_CPU0_SA_DQ(6)
CE66 M_F_CPU0_SB_DQS_DN<5> MFB_DQS_L5 @T6G_MB_LIB.T6G(SCH_1):M_F_CPU0_SB_DQS_DN(5)
CK67 M_F_CPU0_SB_DQS_DP<1> MFB_DQS_H1 @T6G_MB_LIB.T6G(SCH_1):M_F_CPU0_SB_DQS_DP(1)
DE66 M_F_CPU0_SB_DQ<29> MFB_DATA29 @T6G_MB_LIB.T6G(SCH_1):M_F_CPU0_SB_DQ(29)
CR67 M_F_CPU0_SB_DQ<18> MFB_DATA18 @T6G_MB_LIB.T6G(SCH_1):M_F_CPU0_SB_DQ(18)
CG67 M_F_CPU0_SB_DQ<6> MFB_DATA6 @T6G_MB_LIB.T6G(SCH_1):M_F_CPU0_SB_DQ(6)
AA66 M_F_CPU0_SA_DQS_DP<7> MFA_DQS_H7 @T6G_MB_LIB.T6G(SCH_1):M_F_CPU0_SA_DQS_DP(7)
 L66 M_F_CPU0_SA_DQ<7> MFA_DATA7 @T6G_MB_LIB.T6G(SCH_1):M_F_CPU0_SA_DQ(7)
AV67 M_F_CPU0_SA_CS_N<0> MFA0_CS_L0 @T6G_MB_LIB.T6G(SCH_1):M_F_CPU0_SA_CS_N(0)
BC66 M_F_CPU0_SA_PAR MFA_PAR @T6G_MB_LIB.T6G(SCH_1):M_F_CPU0_SA_PAR
BL67 M_F_CPU0_SB_PAR MFB_PAR @T6G_MB_LIB.T6G(SCH_1):M_F_CPU0_SB_PAR
BV67 M_F_CPU0_SB_DQS_DP<9> MFB_DQS_H9 @T6G_MB_LIB.T6G(SCH_1):M_F_CPU0_SB_DQS_DP(9)
BC67 M_F_CPU0_CLK_DP<0> MF0_CLK_H @T6G_MB_LIB.T6G(SCH_1):M_F_CPU0_CLK_DP(0)
BD67 M_F_CPU0_CLK_DN<0> MF0_CLK_L @T6G_MB_LIB.T6G(SCH_1):M_F_CPU0_CLK_DN(0)
BF67     NC MF1_CLK_H     NC
BG67     NC MF1_CLK_L     NC
BF65 TP_M_F_CPU0_SA_TEST39F TEST39F @T6G_MB_LIB.T6G(SCH_1):TP_M_F_CPU0_SA_TEST39F

Q_RES_0402LF-15,1%,1/16W,CHIP,CS01502FB03  I314  R380
   1 M_F_CPU0_ALERT_N      A @T6G_MB_LIB.T6G(SCH_1):M_F_CPU0_ALERT_N
   2 M_F_CPU0_ALERT_R_N      B @T6G_MB_LIB.T6G(SCH_1):M_F_CPU0_ALERT_R_N


DRAWING: @T6G_MB_LIB.T6G(SCH_1):PAGE16 

GENOA_SP5-SOCKET6096_13568-001,SMLF,IO,DGA^6000030  I167  U25
 AR2 M_G_CPU0_ALERT_R_N MG_ALERT_L @T6G_MB_LIB.T6G(SCH_1):M_G_CPU0_ALERT_R_N
 AT2 M_G_CPU0_RESET_N MG_RESET_L @T6G_MB_LIB.T6G(SCH_1):M_G_CPU0_RESET_N
 BW2 M_G_CPU0_SB_DQS_DN<9> MGB_DQS_L9 @T6G_MB_LIB.T6G(SCH_1):M_G_CPU0_SB_DQS_DN(9)
 CF4 M_G_CPU0_SB_DQS_DP<5> MGB_DQS_H5 @T6G_MB_LIB.T6G(SCH_1):M_G_CPU0_SB_DQS_DP(5)
 CC3 M_G_CPU0_SB_DQ<1> MGB_DATA1 @T6G_MB_LIB.T6G(SCH_1):M_G_CPU0_SB_DQ(1)
 AB2 M_G_CPU0_SA_DQ<22> MGA_DATA22 @T6G_MB_LIB.T6G(SCH_1):M_G_CPU0_SA_DQ(22)
  N3 M_G_CPU0_SA_DQ<11> MGA_DATA11 @T6G_MB_LIB.T6G(SCH_1):M_G_CPU0_SA_DQ(11)
  F4 M_G_CPU0_SA_DQ<1> MGA_DATA1 @T6G_MB_LIB.T6G(SCH_1):M_G_CPU0_SA_DQ(1)
 AK2 M_G_CPU0_SA_CB<2> MGA_CHECK2 @T6G_MB_LIB.T6G(SCH_1):M_G_CPU0_SA_CB(2)
 CM4 M_G_CPU0_SB_DQS_DP<6> MGB_DQS_H6 @T6G_MB_LIB.T6G(SCH_1):M_G_CPU0_SB_DQS_DP(6)
 CC2 M_G_CPU0_SB_DQ<2> MGB_DATA2 @T6G_MB_LIB.T6G(SCH_1):M_G_CPU0_SB_DQ(2)
 AC3 M_G_CPU0_SA_DQ<23> MGA_DATA23 @T6G_MB_LIB.T6G(SCH_1):M_G_CPU0_SA_DQ(23)
  R2 M_G_CPU0_SA_DQ<12> MGA_DATA12 @T6G_MB_LIB.T6G(SCH_1):M_G_CPU0_SA_DQ(12)
  F2 M_G_CPU0_SA_DQ<2> MGA_DATA2 @T6G_MB_LIB.T6G(SCH_1):M_G_CPU0_SA_DQ(2)
 AL3 M_G_CPU0_SA_CB<3> MGA_CHECK3 @T6G_MB_LIB.T6G(SCH_1):M_G_CPU0_SA_CB(3)
 CV4 M_G_CPU0_SB_DQS_DP<7> MGB_DQS_H7 @T6G_MB_LIB.T6G(SCH_1):M_G_CPU0_SB_DQS_DP(7)
 CD4 M_G_CPU0_SB_DQ<3> MGB_DATA3 @T6G_MB_LIB.T6G(SCH_1):M_G_CPU0_SB_DQ(3)
 BL2     NC MGB1_CS_L0     NC
 BM4 M_G_CPU0_SB_CS_N<0> MGB0_CS_L0 @T6G_MB_LIB.T6G(SCH_1):M_G_CPU0_SB_CS_N(0)
  H2 M_G_CPU0_SA_DQS_DN<0> MGA_DQS_L0 @T6G_MB_LIB.T6G(SCH_1):M_G_CPU0_SA_DQS_DN(0)
 AC2 M_G_CPU0_SA_DQ<24> MGA_DATA24 @T6G_MB_LIB.T6G(SCH_1):M_G_CPU0_SA_DQ(24)
  T4 M_G_CPU0_SA_DQ<13> MGA_DATA13 @T6G_MB_LIB.T6G(SCH_1):M_G_CPU0_SA_DQ(13)
  G3 M_G_CPU0_SA_DQ<3> MGA_DATA3 @T6G_MB_LIB.T6G(SCH_1):M_G_CPU0_SA_DQ(3)
 AN2 M_G_CPU0_SA_CB<4> MGA_CHECK4 @T6G_MB_LIB.T6G(SCH_1):M_G_CPU0_SA_CB(4)
 DD4 M_G_CPU0_SB_DQS_DP<8> MGB_DQS_H8 @T6G_MB_LIB.T6G(SCH_1):M_G_CPU0_SB_DQS_DP(8)
 DE2 M_G_CPU0_SB_DQ<30> MGB_DATA30 @T6G_MB_LIB.T6G(SCH_1):M_G_CPU0_SB_DQ(30)
 CF2 M_G_CPU0_SB_DQ<4> MGB_DATA4 @T6G_MB_LIB.T6G(SCH_1):M_G_CPU0_SB_DQ(4)
 BM2     NC MGB1_CS_L1     NC
 BN2 M_G_CPU0_SB_CS_N<1> MGB0_CS_L1 @T6G_MB_LIB.T6G(SCH_1):M_G_CPU0_SB_CS_N(1)
  P2 M_G_CPU0_SA_DQS_DN<1> MGA_DQS_L1 @T6G_MB_LIB.T6G(SCH_1):M_G_CPU0_SA_DQS_DN(1)
 AD4 M_G_CPU0_SA_DQ<25> MGA_DATA25 @T6G_MB_LIB.T6G(SCH_1):M_G_CPU0_SA_DQ(25)
  T2 M_G_CPU0_SA_DQ<14> MGA_DATA14 @T6G_MB_LIB.T6G(SCH_1):M_G_CPU0_SA_DQ(14)
  J2 M_G_CPU0_SA_DQ<4> MGA_DATA4 @T6G_MB_LIB.T6G(SCH_1):M_G_CPU0_SA_DQ(4)
 AP4 M_G_CPU0_SA_CB<5> MGA_CHECK5 @T6G_MB_LIB.T6G(SCH_1):M_G_CPU0_SA_CB(5)
 AW2 M_G_CPU0_SA_CA<0> MGA_CA0 @T6G_MB_LIB.T6G(SCH_1):M_G_CPU0_SA_CA(0)
 DF2 M_G_CPU0_SB_DQ<31> MGB_DATA31 @T6G_MB_LIB.T6G(SCH_1):M_G_CPU0_SB_DQ(31)
 CV2 M_G_CPU0_SB_DQ<20> MGB_DATA20 @T6G_MB_LIB.T6G(SCH_1):M_G_CPU0_SB_DQ(20)
 CG3 M_G_CPU0_SB_DQ<5> MGB_DATA5 @T6G_MB_LIB.T6G(SCH_1):M_G_CPU0_SB_DQ(5)
 BY2 M_G_CPU0_SB_CB<0> MGB_CHECK0 @T6G_MB_LIB.T6G(SCH_1):M_G_CPU0_SB_CB(0)
 BG3 M_G_CPU0_SB_CA<0> MGB_CA0 @T6G_MB_LIB.T6G(SCH_1):M_G_CPU0_SB_CA(0)
  Y2 M_G_CPU0_SA_DQS_DN<2> MGA_DQS_L2 @T6G_MB_LIB.T6G(SCH_1):M_G_CPU0_SA_DQS_DN(2)
 AD2 M_G_CPU0_SA_DQ<26> MGA_DATA26 @T6G_MB_LIB.T6G(SCH_1):M_G_CPU0_SA_DQ(26)
  U3 M_G_CPU0_SA_DQ<15> MGA_DATA15 @T6G_MB_LIB.T6G(SCH_1):M_G_CPU0_SA_DQ(15)
  K4 M_G_CPU0_SA_DQ<5> MGA_DATA5 @T6G_MB_LIB.T6G(SCH_1):M_G_CPU0_SA_DQ(5)
 AP2 M_G_CPU0_SA_CB<6> MGA_CHECK6 @T6G_MB_LIB.T6G(SCH_1):M_G_CPU0_SA_CB(6)
 AY2 M_G_CPU0_SA_CA<1> MGA_CA1 @T6G_MB_LIB.T6G(SCH_1):M_G_CPU0_SA_CA(1)
 CW3 M_G_CPU0_SB_DQ<21> MGB_DATA21 @T6G_MB_LIB.T6G(SCH_1):M_G_CPU0_SB_DQ(21)
 CJ2 M_G_CPU0_SB_DQ<10> MGB_DATA10 @T6G_MB_LIB.T6G(SCH_1):M_G_CPU0_SB_DQ(10)
 CG2 M_G_CPU0_SB_DQ<6> MGB_DATA6 @T6G_MB_LIB.T6G(SCH_1):M_G_CPU0_SB_DQ(6)
 CA3 M_G_CPU0_SB_CB<1> MGB_CHECK1 @T6G_MB_LIB.T6G(SCH_1):M_G_CPU0_SB_CB(1)
 BH4 M_G_CPU0_SB_CA<1> MGB_CA1 @T6G_MB_LIB.T6G(SCH_1):M_G_CPU0_SB_CA(1)
 AF2 M_G_CPU0_SA_DQS_DN<3> MGA_DQS_L3 @T6G_MB_LIB.T6G(SCH_1):M_G_CPU0_SA_DQS_DN(3)
 AE3 M_G_CPU0_SA_DQ<27> MGA_DATA27 @T6G_MB_LIB.T6G(SCH_1):M_G_CPU0_SA_DQ(27)
  U2 M_G_CPU0_SA_DQ<16> MGA_DATA16 @T6G_MB_LIB.T6G(SCH_1):M_G_CPU0_SA_DQ(16)
  K2 M_G_CPU0_SA_DQ<6> MGA_DATA6 @T6G_MB_LIB.T6G(SCH_1):M_G_CPU0_SA_DQ(6)
 AR3 M_G_CPU0_SA_CB<7> MGA_CHECK7 @T6G_MB_LIB.T6G(SCH_1):M_G_CPU0_SA_CB(7)
 AY4 M_G_CPU0_SA_CA<2> MGA_CA2 @T6G_MB_LIB.T6G(SCH_1):M_G_CPU0_SA_CA(2)
 BP4     NC MGA1_RSP_L     NC
 BN3 M_G_CPU0_SA_RSP<0> MGA0_RSP_L @T6G_MB_LIB.T6G(SCH_1):M_G_CPU0_SA_RSP(0)
 CW2 M_G_CPU0_SB_DQ<22> MGB_DATA22 @T6G_MB_LIB.T6G(SCH_1):M_G_CPU0_SB_DQ(22)
 CK4 M_G_CPU0_SB_DQ<11> MGB_DATA11 @T6G_MB_LIB.T6G(SCH_1):M_G_CPU0_SB_DQ(11)
 CH4 M_G_CPU0_SB_DQ<7> MGB_DATA7 @T6G_MB_LIB.T6G(SCH_1):M_G_CPU0_SB_DQ(7)
 CA2 M_G_CPU0_SB_CB<2> MGB_CHECK2 @T6G_MB_LIB.T6G(SCH_1):M_G_CPU0_SB_CB(2)
 BH2 M_G_CPU0_SB_CA<2> MGB_CA2 @T6G_MB_LIB.T6G(SCH_1):M_G_CPU0_SB_CA(2)
 AM2 M_G_CPU0_SA_DQS_DN<4> MGA_DQS_L4 @T6G_MB_LIB.T6G(SCH_1):M_G_CPU0_SA_DQS_DN(4)
  G2 M_G_CPU0_SA_DQS_DP<0> MGA_DQS_H0 @T6G_MB_LIB.T6G(SCH_1):M_G_CPU0_SA_DQS_DP(0)
 AG2 M_G_CPU0_SA_DQ<28> MGA_DATA28 @T6G_MB_LIB.T6G(SCH_1):M_G_CPU0_SA_DQ(28)
  V4 M_G_CPU0_SA_DQ<17> MGA_DATA17 @T6G_MB_LIB.T6G(SCH_1):M_G_CPU0_SA_DQ(17)
  L3 M_G_CPU0_SA_DQ<7> MGA_DATA7 @T6G_MB_LIB.T6G(SCH_1):M_G_CPU0_SA_DQ(7)
 BA3 M_G_CPU0_SA_CA<3> MGA_CA3 @T6G_MB_LIB.T6G(SCH_1):M_G_CPU0_SA_CA(3)
 CY4 M_G_CPU0_SB_DQ<23> MGB_DATA23 @T6G_MB_LIB.T6G(SCH_1):M_G_CPU0_SB_DQ(23)
 CM2 M_G_CPU0_SB_DQ<12> MGB_DATA12 @T6G_MB_LIB.T6G(SCH_1):M_G_CPU0_SB_DQ(12)
 CH2 M_G_CPU0_SB_DQ<8> MGB_DATA8 @T6G_MB_LIB.T6G(SCH_1):M_G_CPU0_SB_DQ(8)
 CB4 M_G_CPU0_SB_CB<3> MGB_CHECK3 @T6G_MB_LIB.T6G(SCH_1):M_G_CPU0_SB_CB(3)
 BJ2 M_G_CPU0_SB_CA<3> MGB_CA3 @T6G_MB_LIB.T6G(SCH_1):M_G_CPU0_SB_CA(3)
  H4 M_G_CPU0_SA_DQS_DN<5> MGA_DQS_L5 @T6G_MB_LIB.T6G(SCH_1):M_G_CPU0_SA_DQS_DN(5)
  N2 M_G_CPU0_SA_DQS_DP<1> MGA_DQS_H1 @T6G_MB_LIB.T6G(SCH_1):M_G_CPU0_SA_DQS_DP(1)
 AH4 M_G_CPU0_SA_DQ<29> MGA_DATA29 @T6G_MB_LIB.T6G(SCH_1):M_G_CPU0_SA_DQ(29)
  V2 M_G_CPU0_SA_DQ<18> MGA_DATA18 @T6G_MB_LIB.T6G(SCH_1):M_G_CPU0_SA_DQ(18)
  L2 M_G_CPU0_SA_DQ<8> MGA_DATA8 @T6G_MB_LIB.T6G(SCH_1):M_G_CPU0_SA_DQ(8)
 BA2 M_G_CPU0_SA_CA<4> MGA_CA4 @T6G_MB_LIB.T6G(SCH_1):M_G_CPU0_SA_CA(4)
 CE2 M_G_CPU0_SB_DQS_DN<0> MGB_DQS_L0 @T6G_MB_LIB.T6G(SCH_1):M_G_CPU0_SB_DQS_DN(0)
 CY2 M_G_CPU0_SB_DQ<24> MGB_DATA24 @T6G_MB_LIB.T6G(SCH_1):M_G_CPU0_SB_DQ(24)
 CN3 M_G_CPU0_SB_DQ<13> MGB_DATA13 @T6G_MB_LIB.T6G(SCH_1):M_G_CPU0_SB_DQ(13)
 CJ3 M_G_CPU0_SB_DQ<9> MGB_DATA9 @T6G_MB_LIB.T6G(SCH_1):M_G_CPU0_SB_DQ(9)
 BT2 M_G_CPU0_SB_CB<4> MGB_CHECK4 @T6G_MB_LIB.T6G(SCH_1):M_G_CPU0_SB_CB(4)
 BJ3 M_G_CPU0_SB_CA<4> MGB_CA4 @T6G_MB_LIB.T6G(SCH_1):M_G_CPU0_SB_CA(4)
  P4 M_G_CPU0_SA_DQS_DN<6> MGA_DQS_L6 @T6G_MB_LIB.T6G(SCH_1):M_G_CPU0_SA_DQS_DN(6)
  W2 M_G_CPU0_SA_DQS_DP<2> MGA_DQS_H2 @T6G_MB_LIB.T6G(SCH_1):M_G_CPU0_SA_DQS_DP(2)
  W3 M_G_CPU0_SA_DQ<19> MGA_DATA19 @T6G_MB_LIB.T6G(SCH_1):M_G_CPU0_SA_DQ(19)
  M4 M_G_CPU0_SA_DQ<9> MGA_DATA9 @T6G_MB_LIB.T6G(SCH_1):M_G_CPU0_SA_DQ(9)
 BB2 M_G_CPU0_SA_CA<5> MGA_CA5 @T6G_MB_LIB.T6G(SCH_1):M_G_CPU0_SA_CA(5)
 CL2 M_G_CPU0_SB_DQS_DN<1> MGB_DQS_L1 @T6G_MB_LIB.T6G(SCH_1):M_G_CPU0_SB_DQS_DN(1)
 DA3 M_G_CPU0_SB_DQ<25> MGB_DATA25 @T6G_MB_LIB.T6G(SCH_1):M_G_CPU0_SB_DQ(25)
 CN2 M_G_CPU0_SB_DQ<14> MGB_DATA14 @T6G_MB_LIB.T6G(SCH_1):M_G_CPU0_SB_DQ(14)
 BU3 M_G_CPU0_SB_CB<5> MGB_CHECK5 @T6G_MB_LIB.T6G(SCH_1):M_G_CPU0_SB_CB(5)
 BK4 M_G_CPU0_SB_CA<5> MGB_CA5 @T6G_MB_LIB.T6G(SCH_1):M_G_CPU0_SB_CA(5)
  Y4 M_G_CPU0_SA_DQS_DN<7> MGA_DQS_L7 @T6G_MB_LIB.T6G(SCH_1):M_G_CPU0_SA_DQS_DN(7)
 AE2 M_G_CPU0_SA_DQS_DP<3> MGA_DQS_H3 @T6G_MB_LIB.T6G(SCH_1):M_G_CPU0_SA_DQS_DP(3)
 BB4 M_G_CPU0_SA_CA<6> MGA_CA6 @T6G_MB_LIB.T6G(SCH_1):M_G_CPU0_SA_CA(6)
 CU2 M_G_CPU0_SB_DQS_DN<2> MGB_DQS_L2 @T6G_MB_LIB.T6G(SCH_1):M_G_CPU0_SB_DQS_DN(2)
 DA2 M_G_CPU0_SB_DQ<26> MGB_DATA26 @T6G_MB_LIB.T6G(SCH_1):M_G_CPU0_SB_DQ(26)
 CP4 M_G_CPU0_SB_DQ<15> MGB_DATA15 @T6G_MB_LIB.T6G(SCH_1):M_G_CPU0_SB_DQ(15)
 BU2 M_G_CPU0_SB_CB<6> MGB_CHECK6 @T6G_MB_LIB.T6G(SCH_1):M_G_CPU0_SB_CB(6)
 BK2 M_G_CPU0_SB_CA<6> MGB_CA6 @T6G_MB_LIB.T6G(SCH_1):M_G_CPU0_SB_CA(6)
 AF4 M_G_CPU0_SA_DQS_DN<8> MGA_DQS_L8 @T6G_MB_LIB.T6G(SCH_1):M_G_CPU0_SA_DQS_DN(8)
 AL2 M_G_CPU0_SA_DQS_DP<4> MGA_DQS_H4 @T6G_MB_LIB.T6G(SCH_1):M_G_CPU0_SA_DQS_DP(4)
 DC2 M_G_CPU0_SB_DQS_DN<3> MGB_DQS_L3 @T6G_MB_LIB.T6G(SCH_1):M_G_CPU0_SB_DQS_DN(3)
 DB4 M_G_CPU0_SB_DQ<27> MGB_DATA27 @T6G_MB_LIB.T6G(SCH_1):M_G_CPU0_SB_DQ(27)
 CP2 M_G_CPU0_SB_DQ<16> MGB_DATA16 @T6G_MB_LIB.T6G(SCH_1):M_G_CPU0_SB_DQ(16)
 BV4 M_G_CPU0_SB_CB<7> MGB_CHECK7 @T6G_MB_LIB.T6G(SCH_1):M_G_CPU0_SB_CB(7)
 BR2     NC MGB1_RSP_L     NC
 BP2 M_G_CPU0_SB_RSP<0> MGB0_RSP_L @T6G_MB_LIB.T6G(SCH_1):M_G_CPU0_SB_RSP(0)
 AM4 M_G_CPU0_SA_DQS_DN<9> MGA_DQS_L9 @T6G_MB_LIB.T6G(SCH_1):M_G_CPU0_SA_DQS_DN(9)
  J3 M_G_CPU0_SA_DQS_DP<5> MGA_DQS_H5 @T6G_MB_LIB.T6G(SCH_1):M_G_CPU0_SA_DQS_DP(5)
 BW3 M_G_CPU0_SB_DQS_DN<4> MGB_DQS_L4 @T6G_MB_LIB.T6G(SCH_1):M_G_CPU0_SB_DQS_DN(4)
 CD2 M_G_CPU0_SB_DQS_DP<0> MGB_DQS_H0 @T6G_MB_LIB.T6G(SCH_1):M_G_CPU0_SB_DQS_DP(0)
 DD2 M_G_CPU0_SB_DQ<28> MGB_DATA28 @T6G_MB_LIB.T6G(SCH_1):M_G_CPU0_SB_DQ(28)
 CR3 M_G_CPU0_SB_DQ<17> MGB_DATA17 @T6G_MB_LIB.T6G(SCH_1):M_G_CPU0_SB_DQ(17)
  R3 M_G_CPU0_SA_DQS_DP<6> MGA_DQS_H6 @T6G_MB_LIB.T6G(SCH_1):M_G_CPU0_SA_DQS_DP(6)
 CE3 M_G_CPU0_SB_DQS_DN<5> MGB_DQS_L5 @T6G_MB_LIB.T6G(SCH_1):M_G_CPU0_SB_DQS_DN(5)
 CK2 M_G_CPU0_SB_DQS_DP<1> MGB_DQS_H1 @T6G_MB_LIB.T6G(SCH_1):M_G_CPU0_SB_DQS_DP(1)
 DE3 M_G_CPU0_SB_DQ<29> MGB_DATA29 @T6G_MB_LIB.T6G(SCH_1):M_G_CPU0_SB_DQ(29)
 CR2 M_G_CPU0_SB_DQ<18> MGB_DATA18 @T6G_MB_LIB.T6G(SCH_1):M_G_CPU0_SB_DQ(18)
 AA3 M_G_CPU0_SA_DQS_DP<7> MGA_DQS_H7 @T6G_MB_LIB.T6G(SCH_1):M_G_CPU0_SA_DQS_DP(7)
 AV2     NC MGA1_CS_L0     NC
 AU2 M_G_CPU0_SA_CS_N<0> MGA0_CS_L0 @T6G_MB_LIB.T6G(SCH_1):M_G_CPU0_SA_CS_N(0)
 CL3 M_G_CPU0_SB_DQS_DN<6> MGB_DQS_L6 @T6G_MB_LIB.T6G(SCH_1):M_G_CPU0_SB_DQS_DN(6)
 CT2 M_G_CPU0_SB_DQS_DP<2> MGB_DQS_H2 @T6G_MB_LIB.T6G(SCH_1):M_G_CPU0_SB_DQS_DP(2)
 CT4 M_G_CPU0_SB_DQ<19> MGB_DATA19 @T6G_MB_LIB.T6G(SCH_1):M_G_CPU0_SB_DQ(19)
 AG3 M_G_CPU0_SA_DQS_DP<8> MGA_DQS_H8 @T6G_MB_LIB.T6G(SCH_1):M_G_CPU0_SA_DQS_DP(8)
 AH2 M_G_CPU0_SA_DQ<30> MGA_DATA30 @T6G_MB_LIB.T6G(SCH_1):M_G_CPU0_SA_DQ(30)
 AW3     NC MGA1_CS_L1     NC
 AV4 M_G_CPU0_SA_CS_N<1> MGA0_CS_L1 @T6G_MB_LIB.T6G(SCH_1):M_G_CPU0_SA_CS_N(1)
 CU3 M_G_CPU0_SB_DQS_DN<7> MGB_DQS_L7 @T6G_MB_LIB.T6G(SCH_1):M_G_CPU0_SB_DQS_DN(7)
 DB2 M_G_CPU0_SB_DQS_DP<3> MGB_DQS_H3 @T6G_MB_LIB.T6G(SCH_1):M_G_CPU0_SB_DQS_DP(3)
 AN3 M_G_CPU0_SA_DQS_DP<9> MGA_DQS_H9 @T6G_MB_LIB.T6G(SCH_1):M_G_CPU0_SA_DQS_DP(9)
 AJ3 M_G_CPU0_SA_DQ<31> MGA_DATA31 @T6G_MB_LIB.T6G(SCH_1):M_G_CPU0_SA_DQ(31)
 AA2 M_G_CPU0_SA_DQ<20> MGA_DATA20 @T6G_MB_LIB.T6G(SCH_1):M_G_CPU0_SA_DQ(20)
 AJ2 M_G_CPU0_SA_CB<0> MGA_CHECK0 @T6G_MB_LIB.T6G(SCH_1):M_G_CPU0_SA_CB(0)
 DC3 M_G_CPU0_SB_DQS_DN<8> MGB_DQS_L8 @T6G_MB_LIB.T6G(SCH_1):M_G_CPU0_SB_DQS_DN(8)
 BY4 M_G_CPU0_SB_DQS_DP<4> MGB_DQS_H4 @T6G_MB_LIB.T6G(SCH_1):M_G_CPU0_SB_DQS_DP(4)
 CB2 M_G_CPU0_SB_DQ<0> MGB_DATA0 @T6G_MB_LIB.T6G(SCH_1):M_G_CPU0_SB_DQ(0)
 AB4 M_G_CPU0_SA_DQ<21> MGA_DATA21 @T6G_MB_LIB.T6G(SCH_1):M_G_CPU0_SA_DQ(21)
  M2 M_G_CPU0_SA_DQ<10> MGA_DATA10 @T6G_MB_LIB.T6G(SCH_1):M_G_CPU0_SA_DQ(10)
  E2 M_G_CPU0_SA_DQ<0> MGA_DATA0 @T6G_MB_LIB.T6G(SCH_1):M_G_CPU0_SA_DQ(0)
 AK4 M_G_CPU0_SA_CB<1> MGA_CHECK1 @T6G_MB_LIB.T6G(SCH_1):M_G_CPU0_SA_CB(1)
 BL3 M_G_CPU0_SB_PAR MGB_PAR @T6G_MB_LIB.T6G(SCH_1):M_G_CPU0_SB_PAR
 BV2 M_G_CPU0_SB_DQS_DP<9> MGB_DQS_H9 @T6G_MB_LIB.T6G(SCH_1):M_G_CPU0_SB_DQS_DP(9)
 BC3 M_G_CPU0_SA_PAR MGA_PAR @T6G_MB_LIB.T6G(SCH_1):M_G_CPU0_SA_PAR
 BC2 M_G_CPU0_CLK_DP<0> MG0_CLK_H @T6G_MB_LIB.T6G(SCH_1):M_G_CPU0_CLK_DP(0)
 BD2 M_G_CPU0_CLK_DN<0> MG0_CLK_L @T6G_MB_LIB.T6G(SCH_1):M_G_CPU0_CLK_DN(0)
 BF2     NC MG1_CLK_H     NC
 BG2     NC MG1_CLK_L     NC
 BF4 TP_M_G_CPU0_SA_TEST39G TEST39G @T6G_MB_LIB.T6G(SCH_1):TP_M_G_CPU0_SA_TEST39G

Q_RES_0402LF-15,1%,1/16W,CHIP,CS01502FB03  I323  R381
   1 M_G_CPU0_ALERT_N      A @T6G_MB_LIB.T6G(SCH_1):M_G_CPU0_ALERT_N
   2 M_G_CPU0_ALERT_R_N      B @T6G_MB_LIB.T6G(SCH_1):M_G_CPU0_ALERT_R_N


DRAWING: @T6G_MB_LIB.T6G(SCH_1):PAGE17 

GENOA_SP5-SOCKET6096_13568-001,SMLF,IO,DGA^6000030  I159  U25
AT14 M_H_CPU0_ALERT_R_N MH_ALERT_L @T6G_MB_LIB.T6G(SCH_1):M_H_CPU0_ALERT_R_N
AU14 M_H_CPU0_RESET_N MH_RESET_L @T6G_MB_LIB.T6G(SCH_1):M_H_CPU0_RESET_N
DF14 M_H_CPU0_SB_DQ<31> MHB_DATA31 @T6G_MB_LIB.T6G(SCH_1):M_H_CPU0_SB_DQ(31)
CV13 M_H_CPU0_SB_DQ<20> MHB_DATA20 @T6G_MB_LIB.T6G(SCH_1):M_H_CPU0_SB_DQ(20)
BY13 M_H_CPU0_SB_CB<0> MHB_CHECK0 @T6G_MB_LIB.T6G(SCH_1):M_H_CPU0_SB_CB(0)
BM13     NC MHB1_CS_L1     NC
 Y13 M_H_CPU0_SA_DQS_DN<2> MHA_DQS_L2 @T6G_MB_LIB.T6G(SCH_1):M_H_CPU0_SA_DQS_DN(2)
AD13 M_H_CPU0_SA_DQ<26> MHA_DATA26 @T6G_MB_LIB.T6G(SCH_1):M_H_CPU0_SA_DQ(26)
 U14 M_H_CPU0_SA_DQ<15> MHA_DATA15 @T6G_MB_LIB.T6G(SCH_1):M_H_CPU0_SA_DQ(15)
AP13 M_H_CPU0_SA_CB<6> MHA_CHECK6 @T6G_MB_LIB.T6G(SCH_1):M_H_CPU0_SA_CB(6)
CW14 M_H_CPU0_SB_DQ<21> MHB_DATA21 @T6G_MB_LIB.T6G(SCH_1):M_H_CPU0_SB_DQ(21)
CJ12 M_H_CPU0_SB_DQ<10> MHB_DATA10 @T6G_MB_LIB.T6G(SCH_1):M_H_CPU0_SB_DQ(10)
CA14 M_H_CPU0_SB_CB<1> MHB_CHECK1 @T6G_MB_LIB.T6G(SCH_1):M_H_CPU0_SB_CB(1)
AF13 M_H_CPU0_SA_DQS_DN<3> MHA_DQS_L3 @T6G_MB_LIB.T6G(SCH_1):M_H_CPU0_SA_DQS_DN(3)
AE14 M_H_CPU0_SA_DQ<27> MHA_DATA27 @T6G_MB_LIB.T6G(SCH_1):M_H_CPU0_SA_DQ(27)
 U12 M_H_CPU0_SA_DQ<16> MHA_DATA16 @T6G_MB_LIB.T6G(SCH_1):M_H_CPU0_SA_DQ(16)
AR14 M_H_CPU0_SA_CB<7> MHA_CHECK7 @T6G_MB_LIB.T6G(SCH_1):M_H_CPU0_SA_CB(7)
BN14 M_H_CPU0_SA_RSP<0> MHA0_RSP_L @T6G_MB_LIB.T6G(SCH_1):M_H_CPU0_SA_RSP(0)
CW12 M_H_CPU0_SB_DQ<22> MHB_DATA22 @T6G_MB_LIB.T6G(SCH_1):M_H_CPU0_SB_DQ(22)
CK14 M_H_CPU0_SB_DQ<11> MHB_DATA11 @T6G_MB_LIB.T6G(SCH_1):M_H_CPU0_SB_DQ(11)
CA12 M_H_CPU0_SB_CB<2> MHB_CHECK2 @T6G_MB_LIB.T6G(SCH_1):M_H_CPU0_SB_CB(2)
AM13 M_H_CPU0_SA_DQS_DN<4> MHA_DQS_L4 @T6G_MB_LIB.T6G(SCH_1):M_H_CPU0_SA_DQS_DN(4)
 G12 M_H_CPU0_SA_DQS_DP<0> MHA_DQS_H0 @T6G_MB_LIB.T6G(SCH_1):M_H_CPU0_SA_DQS_DP(0)
AG12 M_H_CPU0_SA_DQ<28> MHA_DATA28 @T6G_MB_LIB.T6G(SCH_1):M_H_CPU0_SA_DQ(28)
 V14 M_H_CPU0_SA_DQ<17> MHA_DATA17 @T6G_MB_LIB.T6G(SCH_1):M_H_CPU0_SA_DQ(17)
AW12 M_H_CPU0_SA_CA<0> MHA_CA0 @T6G_MB_LIB.T6G(SCH_1):M_H_CPU0_SA_CA(0)
BP14     NC MHA1_RSP_L     NC
CY14 M_H_CPU0_SB_DQ<23> MHB_DATA23 @T6G_MB_LIB.T6G(SCH_1):M_H_CPU0_SB_DQ(23)
CM13 M_H_CPU0_SB_DQ<12> MHB_DATA12 @T6G_MB_LIB.T6G(SCH_1):M_H_CPU0_SB_DQ(12)
CB14 M_H_CPU0_SB_CB<3> MHB_CHECK3 @T6G_MB_LIB.T6G(SCH_1):M_H_CPU0_SB_CB(3)
BG14 M_H_CPU0_SB_CA<0> MHB_CA0 @T6G_MB_LIB.T6G(SCH_1):M_H_CPU0_SB_CA(0)
 H14 M_H_CPU0_SA_DQS_DN<5> MHA_DQS_L5 @T6G_MB_LIB.T6G(SCH_1):M_H_CPU0_SA_DQS_DN(5)
 N12 M_H_CPU0_SA_DQS_DP<1> MHA_DQS_H1 @T6G_MB_LIB.T6G(SCH_1):M_H_CPU0_SA_DQS_DP(1)
AH14 M_H_CPU0_SA_DQ<29> MHA_DATA29 @T6G_MB_LIB.T6G(SCH_1):M_H_CPU0_SA_DQ(29)
 V13 M_H_CPU0_SA_DQ<18> MHA_DATA18 @T6G_MB_LIB.T6G(SCH_1):M_H_CPU0_SA_DQ(18)
AY13 M_H_CPU0_SA_CA<1> MHA_CA1 @T6G_MB_LIB.T6G(SCH_1):M_H_CPU0_SA_CA(1)
CE12 M_H_CPU0_SB_DQS_DN<0> MHB_DQS_L0 @T6G_MB_LIB.T6G(SCH_1):M_H_CPU0_SB_DQS_DN(0)
CY13 M_H_CPU0_SB_DQ<24> MHB_DATA24 @T6G_MB_LIB.T6G(SCH_1):M_H_CPU0_SB_DQ(24)
CN14 M_H_CPU0_SB_DQ<13> MHB_DATA13 @T6G_MB_LIB.T6G(SCH_1):M_H_CPU0_SB_DQ(13)
BT13 M_H_CPU0_SB_CB<4> MHB_CHECK4 @T6G_MB_LIB.T6G(SCH_1):M_H_CPU0_SB_CB(4)
BH14 M_H_CPU0_SB_CA<1> MHB_CA1 @T6G_MB_LIB.T6G(SCH_1):M_H_CPU0_SB_CA(1)
 P14 M_H_CPU0_SA_DQS_DN<6> MHA_DQS_L6 @T6G_MB_LIB.T6G(SCH_1):M_H_CPU0_SA_DQS_DN(6)
 W12 M_H_CPU0_SA_DQS_DP<2> MHA_DQS_H2 @T6G_MB_LIB.T6G(SCH_1):M_H_CPU0_SA_DQS_DP(2)
 W14 M_H_CPU0_SA_DQ<19> MHA_DATA19 @T6G_MB_LIB.T6G(SCH_1):M_H_CPU0_SA_DQ(19)
AY14 M_H_CPU0_SA_CA<2> MHA_CA2 @T6G_MB_LIB.T6G(SCH_1):M_H_CPU0_SA_CA(2)
CL12 M_H_CPU0_SB_DQS_DN<1> MHB_DQS_L1 @T6G_MB_LIB.T6G(SCH_1):M_H_CPU0_SB_DQS_DN(1)
DA14 M_H_CPU0_SB_DQ<25> MHB_DATA25 @T6G_MB_LIB.T6G(SCH_1):M_H_CPU0_SB_DQ(25)
CN12 M_H_CPU0_SB_DQ<14> MHB_DATA14 @T6G_MB_LIB.T6G(SCH_1):M_H_CPU0_SB_DQ(14)
CB13 M_H_CPU0_SB_DQ<0> MHB_DATA0 @T6G_MB_LIB.T6G(SCH_1):M_H_CPU0_SB_DQ(0)
BU14 M_H_CPU0_SB_CB<5> MHB_CHECK5 @T6G_MB_LIB.T6G(SCH_1):M_H_CPU0_SB_CB(5)
BH13 M_H_CPU0_SB_CA<2> MHB_CA2 @T6G_MB_LIB.T6G(SCH_1):M_H_CPU0_SB_CA(2)
 Y14 M_H_CPU0_SA_DQS_DN<7> MHA_DQS_L7 @T6G_MB_LIB.T6G(SCH_1):M_H_CPU0_SA_DQS_DN(7)
AE12 M_H_CPU0_SA_DQS_DP<3> MHA_DQS_H3 @T6G_MB_LIB.T6G(SCH_1):M_H_CPU0_SA_DQS_DP(3)
 E12 M_H_CPU0_SA_DQ<0> MHA_DATA0 @T6G_MB_LIB.T6G(SCH_1):M_H_CPU0_SA_DQ(0)
BA14 M_H_CPU0_SA_CA<3> MHA_CA3 @T6G_MB_LIB.T6G(SCH_1):M_H_CPU0_SA_CA(3)
CU12 M_H_CPU0_SB_DQS_DN<2> MHB_DQS_L2 @T6G_MB_LIB.T6G(SCH_1):M_H_CPU0_SB_DQS_DN(2)
DA12 M_H_CPU0_SB_DQ<26> MHB_DATA26 @T6G_MB_LIB.T6G(SCH_1):M_H_CPU0_SB_DQ(26)
CP14 M_H_CPU0_SB_DQ<15> MHB_DATA15 @T6G_MB_LIB.T6G(SCH_1):M_H_CPU0_SB_DQ(15)
CC14 M_H_CPU0_SB_DQ<1> MHB_DATA1 @T6G_MB_LIB.T6G(SCH_1):M_H_CPU0_SB_DQ(1)
BU12 M_H_CPU0_SB_CB<6> MHB_CHECK6 @T6G_MB_LIB.T6G(SCH_1):M_H_CPU0_SB_CB(6)
BJ12 M_H_CPU0_SB_CA<3> MHB_CA3 @T6G_MB_LIB.T6G(SCH_1):M_H_CPU0_SB_CA(3)
AF14 M_H_CPU0_SA_DQS_DN<8> MHA_DQS_L8 @T6G_MB_LIB.T6G(SCH_1):M_H_CPU0_SA_DQS_DN(8)
AL12 M_H_CPU0_SA_DQS_DP<4> MHA_DQS_H4 @T6G_MB_LIB.T6G(SCH_1):M_H_CPU0_SA_DQS_DP(4)
 F14 M_H_CPU0_SA_DQ<1> MHA_DATA1 @T6G_MB_LIB.T6G(SCH_1):M_H_CPU0_SA_DQ(1)
BA12 M_H_CPU0_SA_CA<4> MHA_CA4 @T6G_MB_LIB.T6G(SCH_1):M_H_CPU0_SA_CA(4)
DC12 M_H_CPU0_SB_DQS_DN<3> MHB_DQS_L3 @T6G_MB_LIB.T6G(SCH_1):M_H_CPU0_SB_DQS_DN(3)
DB14 M_H_CPU0_SB_DQ<27> MHB_DATA27 @T6G_MB_LIB.T6G(SCH_1):M_H_CPU0_SB_DQ(27)
CP13 M_H_CPU0_SB_DQ<16> MHB_DATA16 @T6G_MB_LIB.T6G(SCH_1):M_H_CPU0_SB_DQ(16)
CC12 M_H_CPU0_SB_DQ<2> MHB_DATA2 @T6G_MB_LIB.T6G(SCH_1):M_H_CPU0_SB_DQ(2)
BV14 M_H_CPU0_SB_CB<7> MHB_CHECK7 @T6G_MB_LIB.T6G(SCH_1):M_H_CPU0_SB_CB(7)
BJ14 M_H_CPU0_SB_CA<4> MHB_CA4 @T6G_MB_LIB.T6G(SCH_1):M_H_CPU0_SB_CA(4)
BP13 M_H_CPU0_SB_RSP<0> MHB0_RSP_L @T6G_MB_LIB.T6G(SCH_1):M_H_CPU0_SB_RSP(0)
AM14 M_H_CPU0_SA_DQS_DN<9> MHA_DQS_L9 @T6G_MB_LIB.T6G(SCH_1):M_H_CPU0_SA_DQS_DN(9)
 J14 M_H_CPU0_SA_DQS_DP<5> MHA_DQS_H5 @T6G_MB_LIB.T6G(SCH_1):M_H_CPU0_SA_DQS_DP(5)
 F13 M_H_CPU0_SA_DQ<2> MHA_DATA2 @T6G_MB_LIB.T6G(SCH_1):M_H_CPU0_SA_DQ(2)
BB13 M_H_CPU0_SA_CA<5> MHA_CA5 @T6G_MB_LIB.T6G(SCH_1):M_H_CPU0_SA_CA(5)
BW14 M_H_CPU0_SB_DQS_DN<4> MHB_DQS_L4 @T6G_MB_LIB.T6G(SCH_1):M_H_CPU0_SB_DQS_DN(4)
CD13 M_H_CPU0_SB_DQS_DP<0> MHB_DQS_H0 @T6G_MB_LIB.T6G(SCH_1):M_H_CPU0_SB_DQS_DP(0)
DD13 M_H_CPU0_SB_DQ<28> MHB_DATA28 @T6G_MB_LIB.T6G(SCH_1):M_H_CPU0_SB_DQ(28)
CR14 M_H_CPU0_SB_DQ<17> MHB_DATA17 @T6G_MB_LIB.T6G(SCH_1):M_H_CPU0_SB_DQ(17)
CD14 M_H_CPU0_SB_DQ<3> MHB_DATA3 @T6G_MB_LIB.T6G(SCH_1):M_H_CPU0_SB_DQ(3)
BK14 M_H_CPU0_SB_CA<5> MHB_CA5 @T6G_MB_LIB.T6G(SCH_1):M_H_CPU0_SB_CA(5)
BR12     NC MHB1_RSP_L     NC
 R14 M_H_CPU0_SA_DQS_DP<6> MHA_DQS_H6 @T6G_MB_LIB.T6G(SCH_1):M_H_CPU0_SA_DQS_DP(6)
 G14 M_H_CPU0_SA_DQ<3> MHA_DATA3 @T6G_MB_LIB.T6G(SCH_1):M_H_CPU0_SA_DQ(3)
BB14 M_H_CPU0_SA_CA<6> MHA_CA6 @T6G_MB_LIB.T6G(SCH_1):M_H_CPU0_SA_CA(6)
CE14 M_H_CPU0_SB_DQS_DN<5> MHB_DQS_L5 @T6G_MB_LIB.T6G(SCH_1):M_H_CPU0_SB_DQS_DN(5)
CK13 M_H_CPU0_SB_DQS_DP<1> MHB_DQS_H1 @T6G_MB_LIB.T6G(SCH_1):M_H_CPU0_SB_DQS_DP(1)
DE14 M_H_CPU0_SB_DQ<29> MHB_DATA29 @T6G_MB_LIB.T6G(SCH_1):M_H_CPU0_SB_DQ(29)
CR12 M_H_CPU0_SB_DQ<18> MHB_DATA18 @T6G_MB_LIB.T6G(SCH_1):M_H_CPU0_SB_DQ(18)
CF13 M_H_CPU0_SB_DQ<4> MHB_DATA4 @T6G_MB_LIB.T6G(SCH_1):M_H_CPU0_SB_DQ(4)
BK13 M_H_CPU0_SB_CA<6> MHB_CA6 @T6G_MB_LIB.T6G(SCH_1):M_H_CPU0_SB_CA(6)
AA14 M_H_CPU0_SA_DQS_DP<7> MHA_DQS_H7 @T6G_MB_LIB.T6G(SCH_1):M_H_CPU0_SA_DQS_DP(7)
 J12 M_H_CPU0_SA_DQ<4> MHA_DATA4 @T6G_MB_LIB.T6G(SCH_1):M_H_CPU0_SA_DQ(4)
AU12 M_H_CPU0_SA_CS_N<0> MHA0_CS_L0 @T6G_MB_LIB.T6G(SCH_1):M_H_CPU0_SA_CS_N(0)
CL14 M_H_CPU0_SB_DQS_DN<6> MHB_DQS_L6 @T6G_MB_LIB.T6G(SCH_1):M_H_CPU0_SB_DQS_DN(6)
CT13 M_H_CPU0_SB_DQS_DP<2> MHB_DQS_H2 @T6G_MB_LIB.T6G(SCH_1):M_H_CPU0_SB_DQS_DP(2)
CT14 M_H_CPU0_SB_DQ<19> MHB_DATA19 @T6G_MB_LIB.T6G(SCH_1):M_H_CPU0_SB_DQ(19)
CG14 M_H_CPU0_SB_DQ<5> MHB_DATA5 @T6G_MB_LIB.T6G(SCH_1):M_H_CPU0_SB_DQ(5)
AG14 M_H_CPU0_SA_DQS_DP<8> MHA_DQS_H8 @T6G_MB_LIB.T6G(SCH_1):M_H_CPU0_SA_DQS_DP(8)
AH13 M_H_CPU0_SA_DQ<30> MHA_DATA30 @T6G_MB_LIB.T6G(SCH_1):M_H_CPU0_SA_DQ(30)
 K14 M_H_CPU0_SA_DQ<5> MHA_DATA5 @T6G_MB_LIB.T6G(SCH_1):M_H_CPU0_SA_DQ(5)
AV13     NC MHA1_CS_L0     NC
AV14 M_H_CPU0_SA_CS_N<1> MHA0_CS_L1 @T6G_MB_LIB.T6G(SCH_1):M_H_CPU0_SA_CS_N(1)
CU14 M_H_CPU0_SB_DQS_DN<7> MHB_DQS_L7 @T6G_MB_LIB.T6G(SCH_1):M_H_CPU0_SB_DQS_DN(7)
DB13 M_H_CPU0_SB_DQS_DP<3> MHB_DQS_H3 @T6G_MB_LIB.T6G(SCH_1):M_H_CPU0_SB_DQS_DP(3)
CG12 M_H_CPU0_SB_DQ<6> MHB_DATA6 @T6G_MB_LIB.T6G(SCH_1):M_H_CPU0_SB_DQ(6)
AN14 M_H_CPU0_SA_DQS_DP<9> MHA_DQS_H9 @T6G_MB_LIB.T6G(SCH_1):M_H_CPU0_SA_DQS_DP(9)
AJ14 M_H_CPU0_SA_DQ<31> MHA_DATA31 @T6G_MB_LIB.T6G(SCH_1):M_H_CPU0_SA_DQ(31)
AA12 M_H_CPU0_SA_DQ<20> MHA_DATA20 @T6G_MB_LIB.T6G(SCH_1):M_H_CPU0_SA_DQ(20)
 K13 M_H_CPU0_SA_DQ<6> MHA_DATA6 @T6G_MB_LIB.T6G(SCH_1):M_H_CPU0_SA_DQ(6)
AJ12 M_H_CPU0_SA_CB<0> MHA_CHECK0 @T6G_MB_LIB.T6G(SCH_1):M_H_CPU0_SA_CB(0)
AW14     NC MHA1_CS_L1     NC
DC14 M_H_CPU0_SB_DQS_DN<8> MHB_DQS_L8 @T6G_MB_LIB.T6G(SCH_1):M_H_CPU0_SB_DQS_DN(8)
BY14 M_H_CPU0_SB_DQS_DP<4> MHB_DQS_H4 @T6G_MB_LIB.T6G(SCH_1):M_H_CPU0_SB_DQS_DP(4)
CH14 M_H_CPU0_SB_DQ<7> MHB_DATA7 @T6G_MB_LIB.T6G(SCH_1):M_H_CPU0_SB_DQ(7)
AB14 M_H_CPU0_SA_DQ<21> MHA_DATA21 @T6G_MB_LIB.T6G(SCH_1):M_H_CPU0_SA_DQ(21)
 M13 M_H_CPU0_SA_DQ<10> MHA_DATA10 @T6G_MB_LIB.T6G(SCH_1):M_H_CPU0_SA_DQ(10)
 L14 M_H_CPU0_SA_DQ<7> MHA_DATA7 @T6G_MB_LIB.T6G(SCH_1):M_H_CPU0_SA_DQ(7)
AK14 M_H_CPU0_SA_CB<1> MHA_CHECK1 @T6G_MB_LIB.T6G(SCH_1):M_H_CPU0_SA_CB(1)
BW12 M_H_CPU0_SB_DQS_DN<9> MHB_DQS_L9 @T6G_MB_LIB.T6G(SCH_1):M_H_CPU0_SB_DQS_DN(9)
CF14 M_H_CPU0_SB_DQS_DP<5> MHB_DQS_H5 @T6G_MB_LIB.T6G(SCH_1):M_H_CPU0_SB_DQS_DP(5)
CH13 M_H_CPU0_SB_DQ<8> MHB_DATA8 @T6G_MB_LIB.T6G(SCH_1):M_H_CPU0_SB_DQ(8)
AB13 M_H_CPU0_SA_DQ<22> MHA_DATA22 @T6G_MB_LIB.T6G(SCH_1):M_H_CPU0_SA_DQ(22)
 N14 M_H_CPU0_SA_DQ<11> MHA_DATA11 @T6G_MB_LIB.T6G(SCH_1):M_H_CPU0_SA_DQ(11)
 L12 M_H_CPU0_SA_DQ<8> MHA_DATA8 @T6G_MB_LIB.T6G(SCH_1):M_H_CPU0_SA_DQ(8)
AK13 M_H_CPU0_SA_CB<2> MHA_CHECK2 @T6G_MB_LIB.T6G(SCH_1):M_H_CPU0_SA_CB(2)
CM14 M_H_CPU0_SB_DQS_DP<6> MHB_DQS_H6 @T6G_MB_LIB.T6G(SCH_1):M_H_CPU0_SB_DQS_DP(6)
CJ14 M_H_CPU0_SB_DQ<9> MHB_DATA9 @T6G_MB_LIB.T6G(SCH_1):M_H_CPU0_SB_DQ(9)
AC14 M_H_CPU0_SA_DQ<23> MHA_DATA23 @T6G_MB_LIB.T6G(SCH_1):M_H_CPU0_SA_DQ(23)
 R12 M_H_CPU0_SA_DQ<12> MHA_DATA12 @T6G_MB_LIB.T6G(SCH_1):M_H_CPU0_SA_DQ(12)
 M14 M_H_CPU0_SA_DQ<9> MHA_DATA9 @T6G_MB_LIB.T6G(SCH_1):M_H_CPU0_SA_DQ(9)
AL14 M_H_CPU0_SA_CB<3> MHA_CHECK3 @T6G_MB_LIB.T6G(SCH_1):M_H_CPU0_SA_CB(3)
CV14 M_H_CPU0_SB_DQS_DP<7> MHB_DQS_H7 @T6G_MB_LIB.T6G(SCH_1):M_H_CPU0_SB_DQS_DP(7)
BM14 M_H_CPU0_SB_CS_N<0> MHB0_CS_L0 @T6G_MB_LIB.T6G(SCH_1):M_H_CPU0_SB_CS_N(0)
 H13 M_H_CPU0_SA_DQS_DN<0> MHA_DQS_L0 @T6G_MB_LIB.T6G(SCH_1):M_H_CPU0_SA_DQS_DN(0)
AC12 M_H_CPU0_SA_DQ<24> MHA_DATA24 @T6G_MB_LIB.T6G(SCH_1):M_H_CPU0_SA_DQ(24)
 T14 M_H_CPU0_SA_DQ<13> MHA_DATA13 @T6G_MB_LIB.T6G(SCH_1):M_H_CPU0_SA_DQ(13)
AN12 M_H_CPU0_SA_CB<4> MHA_CHECK4 @T6G_MB_LIB.T6G(SCH_1):M_H_CPU0_SA_CB(4)
DD14 M_H_CPU0_SB_DQS_DP<8> MHB_DQS_H8 @T6G_MB_LIB.T6G(SCH_1):M_H_CPU0_SB_DQS_DP(8)
DE12 M_H_CPU0_SB_DQ<30> MHB_DATA30 @T6G_MB_LIB.T6G(SCH_1):M_H_CPU0_SB_DQ(30)
BL12     NC MHB1_CS_L0     NC
BN12 M_H_CPU0_SB_CS_N<1> MHB0_CS_L1 @T6G_MB_LIB.T6G(SCH_1):M_H_CPU0_SB_CS_N(1)
 P13 M_H_CPU0_SA_DQS_DN<1> MHA_DQS_L1 @T6G_MB_LIB.T6G(SCH_1):M_H_CPU0_SA_DQS_DN(1)
AD14 M_H_CPU0_SA_DQ<25> MHA_DATA25 @T6G_MB_LIB.T6G(SCH_1):M_H_CPU0_SA_DQ(25)
 T13 M_H_CPU0_SA_DQ<14> MHA_DATA14 @T6G_MB_LIB.T6G(SCH_1):M_H_CPU0_SA_DQ(14)
AP14 M_H_CPU0_SA_CB<5> MHA_CHECK5 @T6G_MB_LIB.T6G(SCH_1):M_H_CPU0_SA_CB(5)
BV13 M_H_CPU0_SB_DQS_DP<9> MHB_DQS_H9 @T6G_MB_LIB.T6G(SCH_1):M_H_CPU0_SB_DQS_DP(9)
BC14 M_H_CPU0_SA_PAR MHA_PAR @T6G_MB_LIB.T6G(SCH_1):M_H_CPU0_SA_PAR
BL14 M_H_CPU0_SB_PAR MHB_PAR @T6G_MB_LIB.T6G(SCH_1):M_H_CPU0_SB_PAR
BC12 M_H_CPU0_CLK_DP<0> MH0_CLK_H @T6G_MB_LIB.T6G(SCH_1):M_H_CPU0_CLK_DP(0)
BD13 M_H_CPU0_CLK_DN<0> MH0_CLK_L @T6G_MB_LIB.T6G(SCH_1):M_H_CPU0_CLK_DN(0)
BF13     NC MH1_CLK_H     NC
BG12     NC MH1_CLK_L     NC
BF14 TP_M_H_CPU0_SA_TEST39H TEST39H @T6G_MB_LIB.T6G(SCH_1):TP_M_H_CPU0_SA_TEST39H

Q_RES_0402LF-15,1%,1/16W,CHIP,CS01502FB03  I314  R382
   1 M_H_CPU0_ALERT_N      A @T6G_MB_LIB.T6G(SCH_1):M_H_CPU0_ALERT_N
   2 M_H_CPU0_ALERT_R_N      B @T6G_MB_LIB.T6G(SCH_1):M_H_CPU0_ALERT_R_N


DRAWING: @T6G_MB_LIB.T6G(SCH_1):PAGE18 

GENOA_SP5-SOCKET6096_13568-001,SMLF,IO,DGA^6000030  I159  U25
CY21 M_I_CPU0_SB_DQ<23> MIB_DATA23 @T6G_MB_LIB.T6G(SCH_1):M_I_CPU0_SB_DQ(23)
CM20 M_I_CPU0_SB_DQ<12> MIB_DATA12 @T6G_MB_LIB.T6G(SCH_1):M_I_CPU0_SB_DQ(12)
CG19 M_I_CPU0_SB_DQ<6> MIB_DATA6 @T6G_MB_LIB.T6G(SCH_1):M_I_CPU0_SB_DQ(6)
CB21 M_I_CPU0_SB_CB<3> MIB_CHECK3 @T6G_MB_LIB.T6G(SCH_1):M_I_CPU0_SB_CB(3)
 H21 M_I_CPU0_SA_DQS_DN<5> MIA_DQS_L5 @T6G_MB_LIB.T6G(SCH_1):M_I_CPU0_SA_DQS_DN(5)
 N19 M_I_CPU0_SA_DQS_DP<1> MIA_DQS_H1 @T6G_MB_LIB.T6G(SCH_1):M_I_CPU0_SA_DQS_DP(1)
AH21 M_I_CPU0_SA_DQ<29> MIA_DATA29 @T6G_MB_LIB.T6G(SCH_1):M_I_CPU0_SA_DQ(29)
 V20 M_I_CPU0_SA_DQ<18> MIA_DATA18 @T6G_MB_LIB.T6G(SCH_1):M_I_CPU0_SA_DQ(18)
 K20 M_I_CPU0_SA_DQ<6> MIA_DATA6 @T6G_MB_LIB.T6G(SCH_1):M_I_CPU0_SA_DQ(6)
CE19 M_I_CPU0_SB_DQS_DN<0> MIB_DQS_L0 @T6G_MB_LIB.T6G(SCH_1):M_I_CPU0_SB_DQS_DN(0)
CY20 M_I_CPU0_SB_DQ<24> MIB_DATA24 @T6G_MB_LIB.T6G(SCH_1):M_I_CPU0_SB_DQ(24)
CN21 M_I_CPU0_SB_DQ<13> MIB_DATA13 @T6G_MB_LIB.T6G(SCH_1):M_I_CPU0_SB_DQ(13)
CH21 M_I_CPU0_SB_DQ<7> MIB_DATA7 @T6G_MB_LIB.T6G(SCH_1):M_I_CPU0_SB_DQ(7)
BT20 M_I_CPU0_SB_CB<4> MIB_CHECK4 @T6G_MB_LIB.T6G(SCH_1):M_I_CPU0_SB_CB(4)
 P21 M_I_CPU0_SA_DQS_DN<6> MIA_DQS_L6 @T6G_MB_LIB.T6G(SCH_1):M_I_CPU0_SA_DQS_DN(6)
 W19 M_I_CPU0_SA_DQS_DP<2> MIA_DQS_H2 @T6G_MB_LIB.T6G(SCH_1):M_I_CPU0_SA_DQS_DP(2)
 W21 M_I_CPU0_SA_DQ<19> MIA_DATA19 @T6G_MB_LIB.T6G(SCH_1):M_I_CPU0_SA_DQ(19)
 L21 M_I_CPU0_SA_DQ<7> MIA_DATA7 @T6G_MB_LIB.T6G(SCH_1):M_I_CPU0_SA_DQ(7)
AW19 M_I_CPU0_SA_CA<0> MIA_CA0 @T6G_MB_LIB.T6G(SCH_1):M_I_CPU0_SA_CA(0)
CL19 M_I_CPU0_SB_DQS_DN<1> MIB_DQS_L1 @T6G_MB_LIB.T6G(SCH_1):M_I_CPU0_SB_DQS_DN(1)
DA21 M_I_CPU0_SB_DQ<25> MIB_DATA25 @T6G_MB_LIB.T6G(SCH_1):M_I_CPU0_SB_DQ(25)
CN19 M_I_CPU0_SB_DQ<14> MIB_DATA14 @T6G_MB_LIB.T6G(SCH_1):M_I_CPU0_SB_DQ(14)
CH20 M_I_CPU0_SB_DQ<8> MIB_DATA8 @T6G_MB_LIB.T6G(SCH_1):M_I_CPU0_SB_DQ(8)
BU21 M_I_CPU0_SB_CB<5> MIB_CHECK5 @T6G_MB_LIB.T6G(SCH_1):M_I_CPU0_SB_CB(5)
BG21 M_I_CPU0_SB_CA<0> MIB_CA0 @T6G_MB_LIB.T6G(SCH_1):M_I_CPU0_SB_CA(0)
 Y21 M_I_CPU0_SA_DQS_DN<7> MIA_DQS_L7 @T6G_MB_LIB.T6G(SCH_1):M_I_CPU0_SA_DQS_DN(7)
AE19 M_I_CPU0_SA_DQS_DP<3> MIA_DQS_H3 @T6G_MB_LIB.T6G(SCH_1):M_I_CPU0_SA_DQS_DP(3)
 L19 M_I_CPU0_SA_DQ<8> MIA_DATA8 @T6G_MB_LIB.T6G(SCH_1):M_I_CPU0_SA_DQ(8)
AY20 M_I_CPU0_SA_CA<1> MIA_CA1 @T6G_MB_LIB.T6G(SCH_1):M_I_CPU0_SA_CA(1)
CU19 M_I_CPU0_SB_DQS_DN<2> MIB_DQS_L2 @T6G_MB_LIB.T6G(SCH_1):M_I_CPU0_SB_DQS_DN(2)
DA19 M_I_CPU0_SB_DQ<26> MIB_DATA26 @T6G_MB_LIB.T6G(SCH_1):M_I_CPU0_SB_DQ(26)
CP21 M_I_CPU0_SB_DQ<15> MIB_DATA15 @T6G_MB_LIB.T6G(SCH_1):M_I_CPU0_SB_DQ(15)
CJ21 M_I_CPU0_SB_DQ<9> MIB_DATA9 @T6G_MB_LIB.T6G(SCH_1):M_I_CPU0_SB_DQ(9)
BU19 M_I_CPU0_SB_CB<6> MIB_CHECK6 @T6G_MB_LIB.T6G(SCH_1):M_I_CPU0_SB_CB(6)
BH21 M_I_CPU0_SB_CA<1> MIB_CA1 @T6G_MB_LIB.T6G(SCH_1):M_I_CPU0_SB_CA(1)
AF21 M_I_CPU0_SA_DQS_DN<8> MIA_DQS_L8 @T6G_MB_LIB.T6G(SCH_1):M_I_CPU0_SA_DQS_DN(8)
AL19 M_I_CPU0_SA_DQS_DP<4> MIA_DQS_H4 @T6G_MB_LIB.T6G(SCH_1):M_I_CPU0_SA_DQS_DP(4)
 M21 M_I_CPU0_SA_DQ<9> MIA_DATA9 @T6G_MB_LIB.T6G(SCH_1):M_I_CPU0_SA_DQ(9)
AY21 M_I_CPU0_SA_CA<2> MIA_CA2 @T6G_MB_LIB.T6G(SCH_1):M_I_CPU0_SA_CA(2)
DC19 M_I_CPU0_SB_DQS_DN<3> MIB_DQS_L3 @T6G_MB_LIB.T6G(SCH_1):M_I_CPU0_SB_DQS_DN(3)
DB21 M_I_CPU0_SB_DQ<27> MIB_DATA27 @T6G_MB_LIB.T6G(SCH_1):M_I_CPU0_SB_DQ(27)
CP20 M_I_CPU0_SB_DQ<16> MIB_DATA16 @T6G_MB_LIB.T6G(SCH_1):M_I_CPU0_SB_DQ(16)
BV21 M_I_CPU0_SB_CB<7> MIB_CHECK7 @T6G_MB_LIB.T6G(SCH_1):M_I_CPU0_SB_CB(7)
BH20 M_I_CPU0_SB_CA<2> MIB_CA2 @T6G_MB_LIB.T6G(SCH_1):M_I_CPU0_SB_CA(2)
BP20 M_I_CPU0_SB_RSP<0> MIB0_RSP_L @T6G_MB_LIB.T6G(SCH_1):M_I_CPU0_SB_RSP(0)
AM21 M_I_CPU0_SA_DQS_DN<9> MIA_DQS_L9 @T6G_MB_LIB.T6G(SCH_1):M_I_CPU0_SA_DQS_DN(9)
 J21 M_I_CPU0_SA_DQS_DP<5> MIA_DQS_H5 @T6G_MB_LIB.T6G(SCH_1):M_I_CPU0_SA_DQS_DP(5)
BA21 M_I_CPU0_SA_CA<3> MIA_CA3 @T6G_MB_LIB.T6G(SCH_1):M_I_CPU0_SA_CA(3)
BW21 M_I_CPU0_SB_DQS_DN<4> MIB_DQS_L4 @T6G_MB_LIB.T6G(SCH_1):M_I_CPU0_SB_DQS_DN(4)
CD20 M_I_CPU0_SB_DQS_DP<0> MIB_DQS_H0 @T6G_MB_LIB.T6G(SCH_1):M_I_CPU0_SB_DQS_DP(0)
DD20 M_I_CPU0_SB_DQ<28> MIB_DATA28 @T6G_MB_LIB.T6G(SCH_1):M_I_CPU0_SB_DQ(28)
CR21 M_I_CPU0_SB_DQ<17> MIB_DATA17 @T6G_MB_LIB.T6G(SCH_1):M_I_CPU0_SB_DQ(17)
BJ19 M_I_CPU0_SB_CA<3> MIB_CA3 @T6G_MB_LIB.T6G(SCH_1):M_I_CPU0_SB_CA(3)
BR19     NC MIB1_RSP_L     NC
 R21 M_I_CPU0_SA_DQS_DP<6> MIA_DQS_H6 @T6G_MB_LIB.T6G(SCH_1):M_I_CPU0_SA_DQS_DP(6)
BA19 M_I_CPU0_SA_CA<4> MIA_CA4 @T6G_MB_LIB.T6G(SCH_1):M_I_CPU0_SA_CA(4)
CE21 M_I_CPU0_SB_DQS_DN<5> MIB_DQS_L5 @T6G_MB_LIB.T6G(SCH_1):M_I_CPU0_SB_DQS_DN(5)
CK20 M_I_CPU0_SB_DQS_DP<1> MIB_DQS_H1 @T6G_MB_LIB.T6G(SCH_1):M_I_CPU0_SB_DQS_DP(1)
DE21 M_I_CPU0_SB_DQ<29> MIB_DATA29 @T6G_MB_LIB.T6G(SCH_1):M_I_CPU0_SB_DQ(29)
CR19 M_I_CPU0_SB_DQ<18> MIB_DATA18 @T6G_MB_LIB.T6G(SCH_1):M_I_CPU0_SB_DQ(18)
BJ21 M_I_CPU0_SB_CA<4> MIB_CA4 @T6G_MB_LIB.T6G(SCH_1):M_I_CPU0_SB_CA(4)
AA21 M_I_CPU0_SA_DQS_DP<7> MIA_DQS_H7 @T6G_MB_LIB.T6G(SCH_1):M_I_CPU0_SA_DQS_DP(7)
BB20 M_I_CPU0_SA_CA<5> MIA_CA5 @T6G_MB_LIB.T6G(SCH_1):M_I_CPU0_SA_CA(5)
AV20     NC MIA1_CS_L0     NC
AU19 M_I_CPU0_SA_CS_N<0> MIA0_CS_L0 @T6G_MB_LIB.T6G(SCH_1):M_I_CPU0_SA_CS_N(0)
BF20     NC MI1_CLK_H     NC
BC19 M_I_CPU0_CLK_DP<0> MI0_CLK_H @T6G_MB_LIB.T6G(SCH_1):M_I_CPU0_CLK_DP(0)
CL21 M_I_CPU0_SB_DQS_DN<6> MIB_DQS_L6 @T6G_MB_LIB.T6G(SCH_1):M_I_CPU0_SB_DQS_DN(6)
CT20 M_I_CPU0_SB_DQS_DP<2> MIB_DQS_H2 @T6G_MB_LIB.T6G(SCH_1):M_I_CPU0_SB_DQS_DP(2)
CT21 M_I_CPU0_SB_DQ<19> MIB_DATA19 @T6G_MB_LIB.T6G(SCH_1):M_I_CPU0_SB_DQ(19)
BK21 M_I_CPU0_SB_CA<5> MIB_CA5 @T6G_MB_LIB.T6G(SCH_1):M_I_CPU0_SB_CA(5)
AG21 M_I_CPU0_SA_DQS_DP<8> MIA_DQS_H8 @T6G_MB_LIB.T6G(SCH_1):M_I_CPU0_SA_DQS_DP(8)
AH20 M_I_CPU0_SA_DQ<30> MIA_DATA30 @T6G_MB_LIB.T6G(SCH_1):M_I_CPU0_SA_DQ(30)
BB21 M_I_CPU0_SA_CA<6> MIA_CA6 @T6G_MB_LIB.T6G(SCH_1):M_I_CPU0_SA_CA(6)
AW21     NC MIA1_CS_L1     NC
AV21 M_I_CPU0_SA_CS_N<1> MIA0_CS_L1 @T6G_MB_LIB.T6G(SCH_1):M_I_CPU0_SA_CS_N(1)
CU21 M_I_CPU0_SB_DQS_DN<7> MIB_DQS_L7 @T6G_MB_LIB.T6G(SCH_1):M_I_CPU0_SB_DQS_DN(7)
DB20 M_I_CPU0_SB_DQS_DP<3> MIB_DQS_H3 @T6G_MB_LIB.T6G(SCH_1):M_I_CPU0_SB_DQS_DP(3)
BK20 M_I_CPU0_SB_CA<6> MIB_CA6 @T6G_MB_LIB.T6G(SCH_1):M_I_CPU0_SB_CA(6)
AN21 M_I_CPU0_SA_DQS_DP<9> MIA_DQS_H9 @T6G_MB_LIB.T6G(SCH_1):M_I_CPU0_SA_DQS_DP(9)
AJ21 M_I_CPU0_SA_DQ<31> MIA_DATA31 @T6G_MB_LIB.T6G(SCH_1):M_I_CPU0_SA_DQ(31)
AA19 M_I_CPU0_SA_DQ<20> MIA_DATA20 @T6G_MB_LIB.T6G(SCH_1):M_I_CPU0_SA_DQ(20)
AJ19 M_I_CPU0_SA_CB<0> MIA_CHECK0 @T6G_MB_LIB.T6G(SCH_1):M_I_CPU0_SA_CB(0)
DC21 M_I_CPU0_SB_DQS_DN<8> MIB_DQS_L8 @T6G_MB_LIB.T6G(SCH_1):M_I_CPU0_SB_DQS_DN(8)
BY21 M_I_CPU0_SB_DQS_DP<4> MIB_DQS_H4 @T6G_MB_LIB.T6G(SCH_1):M_I_CPU0_SB_DQS_DP(4)
AB21 M_I_CPU0_SA_DQ<21> MIA_DATA21 @T6G_MB_LIB.T6G(SCH_1):M_I_CPU0_SA_DQ(21)
 M20 M_I_CPU0_SA_DQ<10> MIA_DATA10 @T6G_MB_LIB.T6G(SCH_1):M_I_CPU0_SA_DQ(10)
AK21 M_I_CPU0_SA_CB<1> MIA_CHECK1 @T6G_MB_LIB.T6G(SCH_1):M_I_CPU0_SA_CB(1)
BW19 M_I_CPU0_SB_DQS_DN<9> MIB_DQS_L9 @T6G_MB_LIB.T6G(SCH_1):M_I_CPU0_SB_DQS_DN(9)
CF21 M_I_CPU0_SB_DQS_DP<5> MIB_DQS_H5 @T6G_MB_LIB.T6G(SCH_1):M_I_CPU0_SB_DQS_DP(5)
AB20 M_I_CPU0_SA_DQ<22> MIA_DATA22 @T6G_MB_LIB.T6G(SCH_1):M_I_CPU0_SA_DQ(22)
 N21 M_I_CPU0_SA_DQ<11> MIA_DATA11 @T6G_MB_LIB.T6G(SCH_1):M_I_CPU0_SA_DQ(11)
AK20 M_I_CPU0_SA_CB<2> MIA_CHECK2 @T6G_MB_LIB.T6G(SCH_1):M_I_CPU0_SA_CB(2)
BG19     NC MI1_CLK_L     NC
BD20 M_I_CPU0_CLK_DN<0> MI0_CLK_L @T6G_MB_LIB.T6G(SCH_1):M_I_CPU0_CLK_DN(0)
AU21 M_I_CPU0_RESET_N MI_RESET_L @T6G_MB_LIB.T6G(SCH_1):M_I_CPU0_RESET_N
CM21 M_I_CPU0_SB_DQS_DP<6> MIB_DQS_H6 @T6G_MB_LIB.T6G(SCH_1):M_I_CPU0_SB_DQS_DP(6)
CB20 M_I_CPU0_SB_DQ<0> MIB_DATA0 @T6G_MB_LIB.T6G(SCH_1):M_I_CPU0_SB_DQ(0)
AC21 M_I_CPU0_SA_DQ<23> MIA_DATA23 @T6G_MB_LIB.T6G(SCH_1):M_I_CPU0_SA_DQ(23)
 R19 M_I_CPU0_SA_DQ<12> MIA_DATA12 @T6G_MB_LIB.T6G(SCH_1):M_I_CPU0_SA_DQ(12)
 E19 M_I_CPU0_SA_DQ<0> MIA_DATA0 @T6G_MB_LIB.T6G(SCH_1):M_I_CPU0_SA_DQ(0)
AL21 M_I_CPU0_SA_CB<3> MIA_CHECK3 @T6G_MB_LIB.T6G(SCH_1):M_I_CPU0_SA_CB(3)
CV21 M_I_CPU0_SB_DQS_DP<7> MIB_DQS_H7 @T6G_MB_LIB.T6G(SCH_1):M_I_CPU0_SB_DQS_DP(7)
CC21 M_I_CPU0_SB_DQ<1> MIB_DATA1 @T6G_MB_LIB.T6G(SCH_1):M_I_CPU0_SB_DQ(1)
BM21 M_I_CPU0_SB_CS_N<0> MIB0_CS_L0 @T6G_MB_LIB.T6G(SCH_1):M_I_CPU0_SB_CS_N(0)
 H20 M_I_CPU0_SA_DQS_DN<0> MIA_DQS_L0 @T6G_MB_LIB.T6G(SCH_1):M_I_CPU0_SA_DQS_DN(0)
AC19 M_I_CPU0_SA_DQ<24> MIA_DATA24 @T6G_MB_LIB.T6G(SCH_1):M_I_CPU0_SA_DQ(24)
 T21 M_I_CPU0_SA_DQ<13> MIA_DATA13 @T6G_MB_LIB.T6G(SCH_1):M_I_CPU0_SA_DQ(13)
 F21 M_I_CPU0_SA_DQ<1> MIA_DATA1 @T6G_MB_LIB.T6G(SCH_1):M_I_CPU0_SA_DQ(1)
AN19 M_I_CPU0_SA_CB<4> MIA_CHECK4 @T6G_MB_LIB.T6G(SCH_1):M_I_CPU0_SA_CB(4)
DD21 M_I_CPU0_SB_DQS_DP<8> MIB_DQS_H8 @T6G_MB_LIB.T6G(SCH_1):M_I_CPU0_SB_DQS_DP(8)
DE19 M_I_CPU0_SB_DQ<30> MIB_DATA30 @T6G_MB_LIB.T6G(SCH_1):M_I_CPU0_SB_DQ(30)
CC19 M_I_CPU0_SB_DQ<2> MIB_DATA2 @T6G_MB_LIB.T6G(SCH_1):M_I_CPU0_SB_DQ(2)
BL19     NC MIB1_CS_L0     NC
BN19 M_I_CPU0_SB_CS_N<1> MIB0_CS_L1 @T6G_MB_LIB.T6G(SCH_1):M_I_CPU0_SB_CS_N(1)
 P20 M_I_CPU0_SA_DQS_DN<1> MIA_DQS_L1 @T6G_MB_LIB.T6G(SCH_1):M_I_CPU0_SA_DQS_DN(1)
AD21 M_I_CPU0_SA_DQ<25> MIA_DATA25 @T6G_MB_LIB.T6G(SCH_1):M_I_CPU0_SA_DQ(25)
 T20 M_I_CPU0_SA_DQ<14> MIA_DATA14 @T6G_MB_LIB.T6G(SCH_1):M_I_CPU0_SA_DQ(14)
 F20 M_I_CPU0_SA_DQ<2> MIA_DATA2 @T6G_MB_LIB.T6G(SCH_1):M_I_CPU0_SA_DQ(2)
AP21 M_I_CPU0_SA_CB<5> MIA_CHECK5 @T6G_MB_LIB.T6G(SCH_1):M_I_CPU0_SA_CB(5)
BV20 M_I_CPU0_SB_DQS_DP<9> MIB_DQS_H9 @T6G_MB_LIB.T6G(SCH_1):M_I_CPU0_SB_DQS_DP(9)
DF21 M_I_CPU0_SB_DQ<31> MIB_DATA31 @T6G_MB_LIB.T6G(SCH_1):M_I_CPU0_SB_DQ(31)
CV20 M_I_CPU0_SB_DQ<20> MIB_DATA20 @T6G_MB_LIB.T6G(SCH_1):M_I_CPU0_SB_DQ(20)
CD21 M_I_CPU0_SB_DQ<3> MIB_DATA3 @T6G_MB_LIB.T6G(SCH_1):M_I_CPU0_SB_DQ(3)
BY20 M_I_CPU0_SB_CB<0> MIB_CHECK0 @T6G_MB_LIB.T6G(SCH_1):M_I_CPU0_SB_CB(0)
BM20     NC MIB1_CS_L1     NC
BC21 M_I_CPU0_SA_PAR MIA_PAR @T6G_MB_LIB.T6G(SCH_1):M_I_CPU0_SA_PAR
 Y20 M_I_CPU0_SA_DQS_DN<2> MIA_DQS_L2 @T6G_MB_LIB.T6G(SCH_1):M_I_CPU0_SA_DQS_DN(2)
AD20 M_I_CPU0_SA_DQ<26> MIA_DATA26 @T6G_MB_LIB.T6G(SCH_1):M_I_CPU0_SA_DQ(26)
 U21 M_I_CPU0_SA_DQ<15> MIA_DATA15 @T6G_MB_LIB.T6G(SCH_1):M_I_CPU0_SA_DQ(15)
 G21 M_I_CPU0_SA_DQ<3> MIA_DATA3 @T6G_MB_LIB.T6G(SCH_1):M_I_CPU0_SA_DQ(3)
AP20 M_I_CPU0_SA_CB<6> MIA_CHECK6 @T6G_MB_LIB.T6G(SCH_1):M_I_CPU0_SA_CB(6)
BL21 M_I_CPU0_SB_PAR MIB_PAR @T6G_MB_LIB.T6G(SCH_1):M_I_CPU0_SB_PAR
CW21 M_I_CPU0_SB_DQ<21> MIB_DATA21 @T6G_MB_LIB.T6G(SCH_1):M_I_CPU0_SB_DQ(21)
CJ19 M_I_CPU0_SB_DQ<10> MIB_DATA10 @T6G_MB_LIB.T6G(SCH_1):M_I_CPU0_SB_DQ(10)
CF20 M_I_CPU0_SB_DQ<4> MIB_DATA4 @T6G_MB_LIB.T6G(SCH_1):M_I_CPU0_SB_DQ(4)
CA21 M_I_CPU0_SB_CB<1> MIB_CHECK1 @T6G_MB_LIB.T6G(SCH_1):M_I_CPU0_SB_CB(1)
AF20 M_I_CPU0_SA_DQS_DN<3> MIA_DQS_L3 @T6G_MB_LIB.T6G(SCH_1):M_I_CPU0_SA_DQS_DN(3)
AE21 M_I_CPU0_SA_DQ<27> MIA_DATA27 @T6G_MB_LIB.T6G(SCH_1):M_I_CPU0_SA_DQ(27)
 U19 M_I_CPU0_SA_DQ<16> MIA_DATA16 @T6G_MB_LIB.T6G(SCH_1):M_I_CPU0_SA_DQ(16)
 J19 M_I_CPU0_SA_DQ<4> MIA_DATA4 @T6G_MB_LIB.T6G(SCH_1):M_I_CPU0_SA_DQ(4)
AR21 M_I_CPU0_SA_CB<7> MIA_CHECK7 @T6G_MB_LIB.T6G(SCH_1):M_I_CPU0_SA_CB(7)
BP21     NC MIA1_RSP_L     NC
BN21 M_I_CPU0_SA_RSP<0> MIA0_RSP_L @T6G_MB_LIB.T6G(SCH_1):M_I_CPU0_SA_RSP(0)
AT21 M_I_CPU0_ALERT_R_N MI_ALERT_L @T6G_MB_LIB.T6G(SCH_1):M_I_CPU0_ALERT_R_N
CW19 M_I_CPU0_SB_DQ<22> MIB_DATA22 @T6G_MB_LIB.T6G(SCH_1):M_I_CPU0_SB_DQ(22)
CK21 M_I_CPU0_SB_DQ<11> MIB_DATA11 @T6G_MB_LIB.T6G(SCH_1):M_I_CPU0_SB_DQ(11)
CG21 M_I_CPU0_SB_DQ<5> MIB_DATA5 @T6G_MB_LIB.T6G(SCH_1):M_I_CPU0_SB_DQ(5)
CA19 M_I_CPU0_SB_CB<2> MIB_CHECK2 @T6G_MB_LIB.T6G(SCH_1):M_I_CPU0_SB_CB(2)
AM20 M_I_CPU0_SA_DQS_DN<4> MIA_DQS_L4 @T6G_MB_LIB.T6G(SCH_1):M_I_CPU0_SA_DQS_DN(4)
 G19 M_I_CPU0_SA_DQS_DP<0> MIA_DQS_H0 @T6G_MB_LIB.T6G(SCH_1):M_I_CPU0_SA_DQS_DP(0)
AG19 M_I_CPU0_SA_DQ<28> MIA_DATA28 @T6G_MB_LIB.T6G(SCH_1):M_I_CPU0_SA_DQ(28)
 V21 M_I_CPU0_SA_DQ<17> MIA_DATA17 @T6G_MB_LIB.T6G(SCH_1):M_I_CPU0_SA_DQ(17)
 K21 M_I_CPU0_SA_DQ<5> MIA_DATA5 @T6G_MB_LIB.T6G(SCH_1):M_I_CPU0_SA_DQ(5)
BF21 TP_M_I_CPU0_SA_TEST39I TEST39I @T6G_MB_LIB.T6G(SCH_1):TP_M_I_CPU0_SA_TEST39I

Q_RES_0402LF-15,1%,1/16W,CHIP,CS01502FB03  I314  R383
   1 M_I_CPU0_ALERT_N      A @T6G_MB_LIB.T6G(SCH_1):M_I_CPU0_ALERT_N
   2 M_I_CPU0_ALERT_R_N      B @T6G_MB_LIB.T6G(SCH_1):M_I_CPU0_ALERT_R_N


DRAWING: @T6G_MB_LIB.T6G(SCH_1):PAGE19 

GENOA_SP5-SOCKET6096_13568-001,SMLF,IO,DGA^6000030  I159  U25
AU17 M_J_CPU0_RESET_N MJ_RESET_L @T6G_MB_LIB.T6G(SCH_1):M_J_CPU0_RESET_N
AT18 M_J_CPU0_ALERT_R_N MJ_ALERT_L @T6G_MB_LIB.T6G(SCH_1):M_J_CPU0_ALERT_R_N
BL17 M_J_CPU0_SB_PAR MJB_PAR @T6G_MB_LIB.T6G(SCH_1):M_J_CPU0_SB_PAR
BW16 M_J_CPU0_SB_DQS_DN<9> MJB_DQS_L9 @T6G_MB_LIB.T6G(SCH_1):M_J_CPU0_SB_DQS_DN(9)
DC17 M_J_CPU0_SB_DQS_DN<8> MJB_DQS_L8 @T6G_MB_LIB.T6G(SCH_1):M_J_CPU0_SB_DQS_DN(8)
CU17 M_J_CPU0_SB_DQS_DN<7> MJB_DQS_L7 @T6G_MB_LIB.T6G(SCH_1):M_J_CPU0_SB_DQS_DN(7)
CL17 M_J_CPU0_SB_DQS_DN<6> MJB_DQS_L6 @T6G_MB_LIB.T6G(SCH_1):M_J_CPU0_SB_DQS_DN(6)
CE17 M_J_CPU0_SB_DQS_DN<5> MJB_DQS_L5 @T6G_MB_LIB.T6G(SCH_1):M_J_CPU0_SB_DQS_DN(5)
DC16 M_J_CPU0_SB_DQS_DN<3> MJB_DQS_L3 @T6G_MB_LIB.T6G(SCH_1):M_J_CPU0_SB_DQS_DN(3)
CU16 M_J_CPU0_SB_DQS_DN<2> MJB_DQS_L2 @T6G_MB_LIB.T6G(SCH_1):M_J_CPU0_SB_DQS_DN(2)
CL16 M_J_CPU0_SB_DQS_DN<1> MJB_DQS_L1 @T6G_MB_LIB.T6G(SCH_1):M_J_CPU0_SB_DQS_DN(1)
BV16 M_J_CPU0_SB_DQS_DP<9> MJB_DQS_H9 @T6G_MB_LIB.T6G(SCH_1):M_J_CPU0_SB_DQS_DP(9)
DD18 M_J_CPU0_SB_DQS_DP<8> MJB_DQS_H8 @T6G_MB_LIB.T6G(SCH_1):M_J_CPU0_SB_DQS_DP(8)
CV18 M_J_CPU0_SB_DQS_DP<7> MJB_DQS_H7 @T6G_MB_LIB.T6G(SCH_1):M_J_CPU0_SB_DQS_DP(7)
CM18 M_J_CPU0_SB_DQS_DP<6> MJB_DQS_H6 @T6G_MB_LIB.T6G(SCH_1):M_J_CPU0_SB_DQS_DP(6)
BY18 M_J_CPU0_SB_DQS_DP<4> MJB_DQS_H4 @T6G_MB_LIB.T6G(SCH_1):M_J_CPU0_SB_DQS_DP(4)
DB16 M_J_CPU0_SB_DQS_DP<3> MJB_DQS_H3 @T6G_MB_LIB.T6G(SCH_1):M_J_CPU0_SB_DQS_DP(3)
CT16 M_J_CPU0_SB_DQS_DP<2> MJB_DQS_H2 @T6G_MB_LIB.T6G(SCH_1):M_J_CPU0_SB_DQS_DP(2)
CK16 M_J_CPU0_SB_DQS_DP<1> MJB_DQS_H1 @T6G_MB_LIB.T6G(SCH_1):M_J_CPU0_SB_DQS_DP(1)
CD16 M_J_CPU0_SB_DQS_DP<0> MJB_DQS_H0 @T6G_MB_LIB.T6G(SCH_1):M_J_CPU0_SB_DQS_DP(0)
DF16 M_J_CPU0_SB_DQ<31> MJB_DATA31 @T6G_MB_LIB.T6G(SCH_1):M_J_CPU0_SB_DQ(31)
DE16 M_J_CPU0_SB_DQ<30> MJB_DATA30 @T6G_MB_LIB.T6G(SCH_1):M_J_CPU0_SB_DQ(30)
DE17 M_J_CPU0_SB_DQ<29> MJB_DATA29 @T6G_MB_LIB.T6G(SCH_1):M_J_CPU0_SB_DQ(29)
DD16 M_J_CPU0_SB_DQ<28> MJB_DATA28 @T6G_MB_LIB.T6G(SCH_1):M_J_CPU0_SB_DQ(28)
DB18 M_J_CPU0_SB_DQ<27> MJB_DATA27 @T6G_MB_LIB.T6G(SCH_1):M_J_CPU0_SB_DQ(27)
DA16 M_J_CPU0_SB_DQ<26> MJB_DATA26 @T6G_MB_LIB.T6G(SCH_1):M_J_CPU0_SB_DQ(26)
DA17 M_J_CPU0_SB_DQ<25> MJB_DATA25 @T6G_MB_LIB.T6G(SCH_1):M_J_CPU0_SB_DQ(25)
CY16 M_J_CPU0_SB_DQ<24> MJB_DATA24 @T6G_MB_LIB.T6G(SCH_1):M_J_CPU0_SB_DQ(24)
CY18 M_J_CPU0_SB_DQ<23> MJB_DATA23 @T6G_MB_LIB.T6G(SCH_1):M_J_CPU0_SB_DQ(23)
CW16 M_J_CPU0_SB_DQ<22> MJB_DATA22 @T6G_MB_LIB.T6G(SCH_1):M_J_CPU0_SB_DQ(22)
CW17 M_J_CPU0_SB_DQ<21> MJB_DATA21 @T6G_MB_LIB.T6G(SCH_1):M_J_CPU0_SB_DQ(21)
CV16 M_J_CPU0_SB_DQ<20> MJB_DATA20 @T6G_MB_LIB.T6G(SCH_1):M_J_CPU0_SB_DQ(20)
CT18 M_J_CPU0_SB_DQ<19> MJB_DATA19 @T6G_MB_LIB.T6G(SCH_1):M_J_CPU0_SB_DQ(19)
CR16 M_J_CPU0_SB_DQ<18> MJB_DATA18 @T6G_MB_LIB.T6G(SCH_1):M_J_CPU0_SB_DQ(18)
CR17 M_J_CPU0_SB_DQ<17> MJB_DATA17 @T6G_MB_LIB.T6G(SCH_1):M_J_CPU0_SB_DQ(17)
CP16 M_J_CPU0_SB_DQ<16> MJB_DATA16 @T6G_MB_LIB.T6G(SCH_1):M_J_CPU0_SB_DQ(16)
CP18 M_J_CPU0_SB_DQ<15> MJB_DATA15 @T6G_MB_LIB.T6G(SCH_1):M_J_CPU0_SB_DQ(15)
CN16 M_J_CPU0_SB_DQ<14> MJB_DATA14 @T6G_MB_LIB.T6G(SCH_1):M_J_CPU0_SB_DQ(14)
CN17 M_J_CPU0_SB_DQ<13> MJB_DATA13 @T6G_MB_LIB.T6G(SCH_1):M_J_CPU0_SB_DQ(13)
CM16 M_J_CPU0_SB_DQ<12> MJB_DATA12 @T6G_MB_LIB.T6G(SCH_1):M_J_CPU0_SB_DQ(12)
CK18 M_J_CPU0_SB_DQ<11> MJB_DATA11 @T6G_MB_LIB.T6G(SCH_1):M_J_CPU0_SB_DQ(11)
CJ16 M_J_CPU0_SB_DQ<10> MJB_DATA10 @T6G_MB_LIB.T6G(SCH_1):M_J_CPU0_SB_DQ(10)
CJ17 M_J_CPU0_SB_DQ<9> MJB_DATA9 @T6G_MB_LIB.T6G(SCH_1):M_J_CPU0_SB_DQ(9)
CH16 M_J_CPU0_SB_DQ<8> MJB_DATA8 @T6G_MB_LIB.T6G(SCH_1):M_J_CPU0_SB_DQ(8)
CC16 M_J_CPU0_SB_DQ<2> MJB_DATA2 @T6G_MB_LIB.T6G(SCH_1):M_J_CPU0_SB_DQ(2)
CC17 M_J_CPU0_SB_DQ<1> MJB_DATA1 @T6G_MB_LIB.T6G(SCH_1):M_J_CPU0_SB_DQ(1)
BV18 M_J_CPU0_SB_CB<7> MJB_CHECK7 @T6G_MB_LIB.T6G(SCH_1):M_J_CPU0_SB_CB(7)
BU16 M_J_CPU0_SB_CB<6> MJB_CHECK6 @T6G_MB_LIB.T6G(SCH_1):M_J_CPU0_SB_CB(6)
BU17 M_J_CPU0_SB_CB<5> MJB_CHECK5 @T6G_MB_LIB.T6G(SCH_1):M_J_CPU0_SB_CB(5)
BT16 M_J_CPU0_SB_CB<4> MJB_CHECK4 @T6G_MB_LIB.T6G(SCH_1):M_J_CPU0_SB_CB(4)
CB18 M_J_CPU0_SB_CB<3> MJB_CHECK3 @T6G_MB_LIB.T6G(SCH_1):M_J_CPU0_SB_CB(3)
CA16 M_J_CPU0_SB_CB<2> MJB_CHECK2 @T6G_MB_LIB.T6G(SCH_1):M_J_CPU0_SB_CB(2)
CA17 M_J_CPU0_SB_CB<1> MJB_CHECK1 @T6G_MB_LIB.T6G(SCH_1):M_J_CPU0_SB_CB(1)
BY16 M_J_CPU0_SB_CB<0> MJB_CHECK0 @T6G_MB_LIB.T6G(SCH_1):M_J_CPU0_SB_CB(0)
BK16 M_J_CPU0_SB_CA<6> MJB_CA6 @T6G_MB_LIB.T6G(SCH_1):M_J_CPU0_SB_CA(6)
BK18 M_J_CPU0_SB_CA<5> MJB_CA5 @T6G_MB_LIB.T6G(SCH_1):M_J_CPU0_SB_CA(5)
BJ17 M_J_CPU0_SB_CA<4> MJB_CA4 @T6G_MB_LIB.T6G(SCH_1):M_J_CPU0_SB_CA(4)
BJ16 M_J_CPU0_SB_CA<3> MJB_CA3 @T6G_MB_LIB.T6G(SCH_1):M_J_CPU0_SB_CA(3)
BH16 M_J_CPU0_SB_CA<2> MJB_CA2 @T6G_MB_LIB.T6G(SCH_1):M_J_CPU0_SB_CA(2)
BH18 M_J_CPU0_SB_CA<1> MJB_CA1 @T6G_MB_LIB.T6G(SCH_1):M_J_CPU0_SB_CA(1)
BG17 M_J_CPU0_SB_CA<0> MJB_CA0 @T6G_MB_LIB.T6G(SCH_1):M_J_CPU0_SB_CA(0)
BR16     NC MJB1_RSP_L     NC
BM16     NC MJB1_CS_L1     NC
BL16     NC MJB1_CS_L0     NC
BP16 M_J_CPU0_SB_RSP<0> MJB0_RSP_L @T6G_MB_LIB.T6G(SCH_1):M_J_CPU0_SB_RSP(0)
BN16 M_J_CPU0_SB_CS_N<1> MJB0_CS_L1 @T6G_MB_LIB.T6G(SCH_1):M_J_CPU0_SB_CS_N(1)
BM18 M_J_CPU0_SB_CS_N<0> MJB0_CS_L0 @T6G_MB_LIB.T6G(SCH_1):M_J_CPU0_SB_CS_N(0)
BC17 M_J_CPU0_SA_PAR MJA_PAR @T6G_MB_LIB.T6G(SCH_1):M_J_CPU0_SA_PAR
AM18 M_J_CPU0_SA_DQS_DN<9> MJA_DQS_L9 @T6G_MB_LIB.T6G(SCH_1):M_J_CPU0_SA_DQS_DN(9)
AF18 M_J_CPU0_SA_DQS_DN<8> MJA_DQS_L8 @T6G_MB_LIB.T6G(SCH_1):M_J_CPU0_SA_DQS_DN(8)
 P18 M_J_CPU0_SA_DQS_DN<6> MJA_DQS_L6 @T6G_MB_LIB.T6G(SCH_1):M_J_CPU0_SA_DQS_DN(6)
AF16 M_J_CPU0_SA_DQS_DN<3> MJA_DQS_L3 @T6G_MB_LIB.T6G(SCH_1):M_J_CPU0_SA_DQS_DN(3)
 Y16 M_J_CPU0_SA_DQS_DN<2> MJA_DQS_L2 @T6G_MB_LIB.T6G(SCH_1):M_J_CPU0_SA_DQS_DN(2)
 P16 M_J_CPU0_SA_DQS_DN<1> MJA_DQS_L1 @T6G_MB_LIB.T6G(SCH_1):M_J_CPU0_SA_DQS_DN(1)
 H16 M_J_CPU0_SA_DQS_DN<0> MJA_DQS_L0 @T6G_MB_LIB.T6G(SCH_1):M_J_CPU0_SA_DQS_DN(0)
AN17 M_J_CPU0_SA_DQS_DP<9> MJA_DQS_H9 @T6G_MB_LIB.T6G(SCH_1):M_J_CPU0_SA_DQS_DP(9)
AA17 M_J_CPU0_SA_DQS_DP<7> MJA_DQS_H7 @T6G_MB_LIB.T6G(SCH_1):M_J_CPU0_SA_DQS_DP(7)
 R17 M_J_CPU0_SA_DQS_DP<6> MJA_DQS_H6 @T6G_MB_LIB.T6G(SCH_1):M_J_CPU0_SA_DQS_DP(6)
 J17 M_J_CPU0_SA_DQS_DP<5> MJA_DQS_H5 @T6G_MB_LIB.T6G(SCH_1):M_J_CPU0_SA_DQS_DP(5)
AE16 M_J_CPU0_SA_DQS_DP<3> MJA_DQS_H3 @T6G_MB_LIB.T6G(SCH_1):M_J_CPU0_SA_DQS_DP(3)
 W16 M_J_CPU0_SA_DQS_DP<2> MJA_DQS_H2 @T6G_MB_LIB.T6G(SCH_1):M_J_CPU0_SA_DQS_DP(2)
 N16 M_J_CPU0_SA_DQS_DP<1> MJA_DQS_H1 @T6G_MB_LIB.T6G(SCH_1):M_J_CPU0_SA_DQS_DP(1)
 G16 M_J_CPU0_SA_DQS_DP<0> MJA_DQS_H0 @T6G_MB_LIB.T6G(SCH_1):M_J_CPU0_SA_DQS_DP(0)
AH16 M_J_CPU0_SA_DQ<30> MJA_DATA30 @T6G_MB_LIB.T6G(SCH_1):M_J_CPU0_SA_DQ(30)
AH18 M_J_CPU0_SA_DQ<29> MJA_DATA29 @T6G_MB_LIB.T6G(SCH_1):M_J_CPU0_SA_DQ(29)
AG16 M_J_CPU0_SA_DQ<28> MJA_DATA28 @T6G_MB_LIB.T6G(SCH_1):M_J_CPU0_SA_DQ(28)
AE17 M_J_CPU0_SA_DQ<27> MJA_DATA27 @T6G_MB_LIB.T6G(SCH_1):M_J_CPU0_SA_DQ(27)
AD16 M_J_CPU0_SA_DQ<26> MJA_DATA26 @T6G_MB_LIB.T6G(SCH_1):M_J_CPU0_SA_DQ(26)
AD18 M_J_CPU0_SA_DQ<25> MJA_DATA25 @T6G_MB_LIB.T6G(SCH_1):M_J_CPU0_SA_DQ(25)
AC16 M_J_CPU0_SA_DQ<24> MJA_DATA24 @T6G_MB_LIB.T6G(SCH_1):M_J_CPU0_SA_DQ(24)
AC17 M_J_CPU0_SA_DQ<23> MJA_DATA23 @T6G_MB_LIB.T6G(SCH_1):M_J_CPU0_SA_DQ(23)
AB18 M_J_CPU0_SA_DQ<21> MJA_DATA21 @T6G_MB_LIB.T6G(SCH_1):M_J_CPU0_SA_DQ(21)
AA16 M_J_CPU0_SA_DQ<20> MJA_DATA20 @T6G_MB_LIB.T6G(SCH_1):M_J_CPU0_SA_DQ(20)
 W17 M_J_CPU0_SA_DQ<19> MJA_DATA19 @T6G_MB_LIB.T6G(SCH_1):M_J_CPU0_SA_DQ(19)
 V16 M_J_CPU0_SA_DQ<18> MJA_DATA18 @T6G_MB_LIB.T6G(SCH_1):M_J_CPU0_SA_DQ(18)
 V18 M_J_CPU0_SA_DQ<17> MJA_DATA17 @T6G_MB_LIB.T6G(SCH_1):M_J_CPU0_SA_DQ(17)
 U16 M_J_CPU0_SA_DQ<16> MJA_DATA16 @T6G_MB_LIB.T6G(SCH_1):M_J_CPU0_SA_DQ(16)
 U17 M_J_CPU0_SA_DQ<15> MJA_DATA15 @T6G_MB_LIB.T6G(SCH_1):M_J_CPU0_SA_DQ(15)
 T16 M_J_CPU0_SA_DQ<14> MJA_DATA14 @T6G_MB_LIB.T6G(SCH_1):M_J_CPU0_SA_DQ(14)
 T18 M_J_CPU0_SA_DQ<13> MJA_DATA13 @T6G_MB_LIB.T6G(SCH_1):M_J_CPU0_SA_DQ(13)
 R16 M_J_CPU0_SA_DQ<12> MJA_DATA12 @T6G_MB_LIB.T6G(SCH_1):M_J_CPU0_SA_DQ(12)
 N17 M_J_CPU0_SA_DQ<11> MJA_DATA11 @T6G_MB_LIB.T6G(SCH_1):M_J_CPU0_SA_DQ(11)
 M16 M_J_CPU0_SA_DQ<10> MJA_DATA10 @T6G_MB_LIB.T6G(SCH_1):M_J_CPU0_SA_DQ(10)
 M18 M_J_CPU0_SA_DQ<9> MJA_DATA9 @T6G_MB_LIB.T6G(SCH_1):M_J_CPU0_SA_DQ(9)
 L16 M_J_CPU0_SA_DQ<8> MJA_DATA8 @T6G_MB_LIB.T6G(SCH_1):M_J_CPU0_SA_DQ(8)
 L17 M_J_CPU0_SA_DQ<7> MJA_DATA7 @T6G_MB_LIB.T6G(SCH_1):M_J_CPU0_SA_DQ(7)
 K16 M_J_CPU0_SA_DQ<6> MJA_DATA6 @T6G_MB_LIB.T6G(SCH_1):M_J_CPU0_SA_DQ(6)
 K18 M_J_CPU0_SA_DQ<5> MJA_DATA5 @T6G_MB_LIB.T6G(SCH_1):M_J_CPU0_SA_DQ(5)
 J16 M_J_CPU0_SA_DQ<4> MJA_DATA4 @T6G_MB_LIB.T6G(SCH_1):M_J_CPU0_SA_DQ(4)
 G17 M_J_CPU0_SA_DQ<3> MJA_DATA3 @T6G_MB_LIB.T6G(SCH_1):M_J_CPU0_SA_DQ(3)
 F16 M_J_CPU0_SA_DQ<2> MJA_DATA2 @T6G_MB_LIB.T6G(SCH_1):M_J_CPU0_SA_DQ(2)
 F18 M_J_CPU0_SA_DQ<1> MJA_DATA1 @T6G_MB_LIB.T6G(SCH_1):M_J_CPU0_SA_DQ(1)
 E16 M_J_CPU0_SA_DQ<0> MJA_DATA0 @T6G_MB_LIB.T6G(SCH_1):M_J_CPU0_SA_DQ(0)
AR17 M_J_CPU0_SA_CB<7> MJA_CHECK7 @T6G_MB_LIB.T6G(SCH_1):M_J_CPU0_SA_CB(7)
AP16 M_J_CPU0_SA_CB<6> MJA_CHECK6 @T6G_MB_LIB.T6G(SCH_1):M_J_CPU0_SA_CB(6)
AP18 M_J_CPU0_SA_CB<5> MJA_CHECK5 @T6G_MB_LIB.T6G(SCH_1):M_J_CPU0_SA_CB(5)
AN16 M_J_CPU0_SA_CB<4> MJA_CHECK4 @T6G_MB_LIB.T6G(SCH_1):M_J_CPU0_SA_CB(4)
AL17 M_J_CPU0_SA_CB<3> MJA_CHECK3 @T6G_MB_LIB.T6G(SCH_1):M_J_CPU0_SA_CB(3)
AK16 M_J_CPU0_SA_CB<2> MJA_CHECK2 @T6G_MB_LIB.T6G(SCH_1):M_J_CPU0_SA_CB(2)
AK18 M_J_CPU0_SA_CB<1> MJA_CHECK1 @T6G_MB_LIB.T6G(SCH_1):M_J_CPU0_SA_CB(1)
AJ16 M_J_CPU0_SA_CB<0> MJA_CHECK0 @T6G_MB_LIB.T6G(SCH_1):M_J_CPU0_SA_CB(0)
BA16 M_J_CPU0_SA_CA<4> MJA_CA4 @T6G_MB_LIB.T6G(SCH_1):M_J_CPU0_SA_CA(4)
BA17 M_J_CPU0_SA_CA<3> MJA_CA3 @T6G_MB_LIB.T6G(SCH_1):M_J_CPU0_SA_CA(3)
AY18 M_J_CPU0_SA_CA<2> MJA_CA2 @T6G_MB_LIB.T6G(SCH_1):M_J_CPU0_SA_CA(2)
AY16 M_J_CPU0_SA_CA<1> MJA_CA1 @T6G_MB_LIB.T6G(SCH_1):M_J_CPU0_SA_CA(1)
AW16 M_J_CPU0_SA_CA<0> MJA_CA0 @T6G_MB_LIB.T6G(SCH_1):M_J_CPU0_SA_CA(0)
BP18     NC MJA1_RSP_L     NC
AW17     NC MJA1_CS_L1     NC
AV16     NC MJA1_CS_L0     NC
BN17 M_J_CPU0_SA_RSP<0> MJA0_RSP_L @T6G_MB_LIB.T6G(SCH_1):M_J_CPU0_SA_RSP(0)
AV18 M_J_CPU0_SA_CS_N<1> MJA0_CS_L1 @T6G_MB_LIB.T6G(SCH_1):M_J_CPU0_SA_CS_N(1)
AU16 M_J_CPU0_SA_CS_N<0> MJA0_CS_L0 @T6G_MB_LIB.T6G(SCH_1):M_J_CPU0_SA_CS_N(0)
BG16     NC MJ1_CLK_L     NC
BF16     NC MJ1_CLK_H     NC
BD16 M_J_CPU0_CLK_DN<0> MJ0_CLK_L @T6G_MB_LIB.T6G(SCH_1):M_J_CPU0_CLK_DN(0)
BC16 M_J_CPU0_CLK_DP<0> MJ0_CLK_H @T6G_MB_LIB.T6G(SCH_1):M_J_CPU0_CLK_DP(0)
BB18 M_J_CPU0_SA_CA<6> MJA_CA6 @T6G_MB_LIB.T6G(SCH_1):M_J_CPU0_SA_CA(6)
BB16 M_J_CPU0_SA_CA<5> MJA_CA5 @T6G_MB_LIB.T6G(SCH_1):M_J_CPU0_SA_CA(5)
AB16 M_J_CPU0_SA_DQ<22> MJA_DATA22 @T6G_MB_LIB.T6G(SCH_1):M_J_CPU0_SA_DQ(22)
 Y18 M_J_CPU0_SA_DQS_DN<7> MJA_DQS_L7 @T6G_MB_LIB.T6G(SCH_1):M_J_CPU0_SA_DQS_DN(7)
 H18 M_J_CPU0_SA_DQS_DN<5> MJA_DQS_L5 @T6G_MB_LIB.T6G(SCH_1):M_J_CPU0_SA_DQS_DN(5)
AM16 M_J_CPU0_SA_DQS_DN<4> MJA_DQS_L4 @T6G_MB_LIB.T6G(SCH_1):M_J_CPU0_SA_DQS_DN(4)
AG17 M_J_CPU0_SA_DQS_DP<8> MJA_DQS_H8 @T6G_MB_LIB.T6G(SCH_1):M_J_CPU0_SA_DQS_DP(8)
AL16 M_J_CPU0_SA_DQS_DP<4> MJA_DQS_H4 @T6G_MB_LIB.T6G(SCH_1):M_J_CPU0_SA_DQS_DP(4)
CF16 M_J_CPU0_SB_DQ<4> MJB_DATA4 @T6G_MB_LIB.T6G(SCH_1):M_J_CPU0_SB_DQ(4)
CD18 M_J_CPU0_SB_DQ<3> MJB_DATA3 @T6G_MB_LIB.T6G(SCH_1):M_J_CPU0_SB_DQ(3)
CB16 M_J_CPU0_SB_DQ<0> MJB_DATA0 @T6G_MB_LIB.T6G(SCH_1):M_J_CPU0_SB_DQ(0)
AJ17 M_J_CPU0_SA_DQ<31> MJA_DATA31 @T6G_MB_LIB.T6G(SCH_1):M_J_CPU0_SA_DQ(31)
CE16 M_J_CPU0_SB_DQS_DN<0> MJB_DQS_L0 @T6G_MB_LIB.T6G(SCH_1):M_J_CPU0_SB_DQS_DN(0)
BW17 M_J_CPU0_SB_DQS_DN<4> MJB_DQS_L4 @T6G_MB_LIB.T6G(SCH_1):M_J_CPU0_SB_DQS_DN(4)
CF18 M_J_CPU0_SB_DQS_DP<5> MJB_DQS_H5 @T6G_MB_LIB.T6G(SCH_1):M_J_CPU0_SB_DQS_DP(5)
CG17 M_J_CPU0_SB_DQ<5> MJB_DATA5 @T6G_MB_LIB.T6G(SCH_1):M_J_CPU0_SB_DQ(5)
CG16 M_J_CPU0_SB_DQ<6> MJB_DATA6 @T6G_MB_LIB.T6G(SCH_1):M_J_CPU0_SB_DQ(6)
CH18 M_J_CPU0_SB_DQ<7> MJB_DATA7 @T6G_MB_LIB.T6G(SCH_1):M_J_CPU0_SB_DQ(7)
BF18 TP_M_J_CPU0_SA_TEST39J TEST39J @T6G_MB_LIB.T6G(SCH_1):TP_M_J_CPU0_SA_TEST39J

Q_RES_0402LF-15,1%,1/16W,CHIP,CS01502FB03  I314  R384
   1 M_J_CPU0_ALERT_N      A @T6G_MB_LIB.T6G(SCH_1):M_J_CPU0_ALERT_N
   2 M_J_CPU0_ALERT_R_N      B @T6G_MB_LIB.T6G(SCH_1):M_J_CPU0_ALERT_R_N


DRAWING: @T6G_MB_LIB.T6G(SCH_1):PAGE20 

GENOA_SP5-SOCKET6096_13568-001,SMLF,IO,DGA^6000030  I159  U25
 CL7 M_K_CPU0_SB_DQS_DN<6> MKB_DQS_L6 @T6G_MB_LIB.T6G(SCH_1):M_K_CPU0_SB_DQS_DN(6)
 CT6 M_K_CPU0_SB_DQS_DP<2> MKB_DQS_H2 @T6G_MB_LIB.T6G(SCH_1):M_K_CPU0_SB_DQS_DP(2)
 CT7 M_K_CPU0_SB_DQ<19> MKB_DATA19 @T6G_MB_LIB.T6G(SCH_1):M_K_CPU0_SB_DQ(19)
 BG7 M_K_CPU0_SB_CA<0> MKB_CA0 @T6G_MB_LIB.T6G(SCH_1):M_K_CPU0_SB_CA(0)
 AG7 M_K_CPU0_SA_DQS_DP<8> MKA_DQS_H8 @T6G_MB_LIB.T6G(SCH_1):M_K_CPU0_SA_DQS_DP(8)
 AH6 M_K_CPU0_SA_DQ<30> MKA_DATA30 @T6G_MB_LIB.T6G(SCH_1):M_K_CPU0_SA_DQ(30)
 AY6 M_K_CPU0_SA_CA<1> MKA_CA1 @T6G_MB_LIB.T6G(SCH_1):M_K_CPU0_SA_CA(1)
 AV6     NC MKA1_CS_L0     NC
 AV7 M_K_CPU0_SA_CS_N<1> MKA0_CS_L1 @T6G_MB_LIB.T6G(SCH_1):M_K_CPU0_SA_CS_N(1)
 CU7 M_K_CPU0_SB_DQS_DN<7> MKB_DQS_L7 @T6G_MB_LIB.T6G(SCH_1):M_K_CPU0_SB_DQS_DN(7)
 DB6 M_K_CPU0_SB_DQS_DP<3> MKB_DQS_H3 @T6G_MB_LIB.T6G(SCH_1):M_K_CPU0_SB_DQS_DP(3)
 BH7 M_K_CPU0_SB_CA<1> MKB_CA1 @T6G_MB_LIB.T6G(SCH_1):M_K_CPU0_SB_CA(1)
 AN7 M_K_CPU0_SA_DQS_DP<9> MKA_DQS_H9 @T6G_MB_LIB.T6G(SCH_1):M_K_CPU0_SA_DQS_DP(9)
 AJ7 M_K_CPU0_SA_DQ<31> MKA_DATA31 @T6G_MB_LIB.T6G(SCH_1):M_K_CPU0_SA_DQ(31)
 AA5 M_K_CPU0_SA_DQ<20> MKA_DATA20 @T6G_MB_LIB.T6G(SCH_1):M_K_CPU0_SA_DQ(20)
 AJ5 M_K_CPU0_SA_CB<0> MKA_CHECK0 @T6G_MB_LIB.T6G(SCH_1):M_K_CPU0_SA_CB(0)
 AY7 M_K_CPU0_SA_CA<2> MKA_CA2 @T6G_MB_LIB.T6G(SCH_1):M_K_CPU0_SA_CA(2)
 AW7     NC MKA1_CS_L1     NC
 BC5 M_K_CPU0_CLK_DP<0> MK0_CLK_H @T6G_MB_LIB.T6G(SCH_1):M_K_CPU0_CLK_DP(0)
 DC7 M_K_CPU0_SB_DQS_DN<8> MKB_DQS_L8 @T6G_MB_LIB.T6G(SCH_1):M_K_CPU0_SB_DQS_DN(8)
 BY7 M_K_CPU0_SB_DQS_DP<4> MKB_DQS_H4 @T6G_MB_LIB.T6G(SCH_1):M_K_CPU0_SB_DQS_DP(4)
 BH6 M_K_CPU0_SB_CA<2> MKB_CA2 @T6G_MB_LIB.T6G(SCH_1):M_K_CPU0_SB_CA(2)
 AB7 M_K_CPU0_SA_DQ<21> MKA_DATA21 @T6G_MB_LIB.T6G(SCH_1):M_K_CPU0_SA_DQ(21)
  M6 M_K_CPU0_SA_DQ<10> MKA_DATA10 @T6G_MB_LIB.T6G(SCH_1):M_K_CPU0_SA_DQ(10)
 AK7 M_K_CPU0_SA_CB<1> MKA_CHECK1 @T6G_MB_LIB.T6G(SCH_1):M_K_CPU0_SA_CB(1)
 BA7 M_K_CPU0_SA_CA<3> MKA_CA3 @T6G_MB_LIB.T6G(SCH_1):M_K_CPU0_SA_CA(3)
 BF6     NC MK1_CLK_H     NC
 BW5 M_K_CPU0_SB_DQS_DN<9> MKB_DQS_L9 @T6G_MB_LIB.T6G(SCH_1):M_K_CPU0_SB_DQS_DN(9)
 CF7 M_K_CPU0_SB_DQS_DP<5> MKB_DQS_H5 @T6G_MB_LIB.T6G(SCH_1):M_K_CPU0_SB_DQS_DP(5)
 BJ5 M_K_CPU0_SB_CA<3> MKB_CA3 @T6G_MB_LIB.T6G(SCH_1):M_K_CPU0_SB_CA(3)
 AB6 M_K_CPU0_SA_DQ<22> MKA_DATA22 @T6G_MB_LIB.T6G(SCH_1):M_K_CPU0_SA_DQ(22)
  N7 M_K_CPU0_SA_DQ<11> MKA_DATA11 @T6G_MB_LIB.T6G(SCH_1):M_K_CPU0_SA_DQ(11)
 AK6 M_K_CPU0_SA_CB<2> MKA_CHECK2 @T6G_MB_LIB.T6G(SCH_1):M_K_CPU0_SA_CB(2)
 BA5 M_K_CPU0_SA_CA<4> MKA_CA4 @T6G_MB_LIB.T6G(SCH_1):M_K_CPU0_SA_CA(4)
 AU7 M_K_CPU0_RESET_N MK_RESET_L @T6G_MB_LIB.T6G(SCH_1):M_K_CPU0_RESET_N
 CM7 M_K_CPU0_SB_DQS_DP<6> MKB_DQS_H6 @T6G_MB_LIB.T6G(SCH_1):M_K_CPU0_SB_DQS_DP(6)
 BJ7 M_K_CPU0_SB_CA<4> MKB_CA4 @T6G_MB_LIB.T6G(SCH_1):M_K_CPU0_SB_CA(4)
 AC7 M_K_CPU0_SA_DQ<23> MKA_DATA23 @T6G_MB_LIB.T6G(SCH_1):M_K_CPU0_SA_DQ(23)
  R5 M_K_CPU0_SA_DQ<12> MKA_DATA12 @T6G_MB_LIB.T6G(SCH_1):M_K_CPU0_SA_DQ(12)
 AL7 M_K_CPU0_SA_CB<3> MKA_CHECK3 @T6G_MB_LIB.T6G(SCH_1):M_K_CPU0_SA_CB(3)
 BB6 M_K_CPU0_SA_CA<5> MKA_CA5 @T6G_MB_LIB.T6G(SCH_1):M_K_CPU0_SA_CA(5)
 CV7 M_K_CPU0_SB_DQS_DP<7> MKB_DQS_H7 @T6G_MB_LIB.T6G(SCH_1):M_K_CPU0_SB_DQS_DP(7)
 BK7 M_K_CPU0_SB_CA<5> MKB_CA5 @T6G_MB_LIB.T6G(SCH_1):M_K_CPU0_SB_CA(5)
 BM7 M_K_CPU0_SB_CS_N<0> MKB0_CS_L0 @T6G_MB_LIB.T6G(SCH_1):M_K_CPU0_SB_CS_N(0)
  H6 M_K_CPU0_SA_DQS_DN<0> MKA_DQS_L0 @T6G_MB_LIB.T6G(SCH_1):M_K_CPU0_SA_DQS_DN(0)
 AC5 M_K_CPU0_SA_DQ<24> MKA_DATA24 @T6G_MB_LIB.T6G(SCH_1):M_K_CPU0_SA_DQ(24)
  T7 M_K_CPU0_SA_DQ<13> MKA_DATA13 @T6G_MB_LIB.T6G(SCH_1):M_K_CPU0_SA_DQ(13)
 AN5 M_K_CPU0_SA_CB<4> MKA_CHECK4 @T6G_MB_LIB.T6G(SCH_1):M_K_CPU0_SA_CB(4)
 BB7 M_K_CPU0_SA_CA<6> MKA_CA6 @T6G_MB_LIB.T6G(SCH_1):M_K_CPU0_SA_CA(6)
 BD6 M_K_CPU0_CLK_DN<0> MK0_CLK_L @T6G_MB_LIB.T6G(SCH_1):M_K_CPU0_CLK_DN(0)
 DD7 M_K_CPU0_SB_DQS_DP<8> MKB_DQS_H8 @T6G_MB_LIB.T6G(SCH_1):M_K_CPU0_SB_DQS_DP(8)
 DE5 M_K_CPU0_SB_DQ<30> MKB_DATA30 @T6G_MB_LIB.T6G(SCH_1):M_K_CPU0_SB_DQ(30)
 BK6 M_K_CPU0_SB_CA<6> MKB_CA6 @T6G_MB_LIB.T6G(SCH_1):M_K_CPU0_SB_CA(6)
 BL5     NC MKB1_CS_L0     NC
 BN5 M_K_CPU0_SB_CS_N<1> MKB0_CS_L1 @T6G_MB_LIB.T6G(SCH_1):M_K_CPU0_SB_CS_N(1)
  P6 M_K_CPU0_SA_DQS_DN<1> MKA_DQS_L1 @T6G_MB_LIB.T6G(SCH_1):M_K_CPU0_SA_DQS_DN(1)
 AD7 M_K_CPU0_SA_DQ<25> MKA_DATA25 @T6G_MB_LIB.T6G(SCH_1):M_K_CPU0_SA_DQ(25)
  T6 M_K_CPU0_SA_DQ<14> MKA_DATA14 @T6G_MB_LIB.T6G(SCH_1):M_K_CPU0_SA_DQ(14)
  E5 M_K_CPU0_SA_DQ<0> MKA_DATA0 @T6G_MB_LIB.T6G(SCH_1):M_K_CPU0_SA_DQ(0)
 AP7 M_K_CPU0_SA_CB<5> MKA_CHECK5 @T6G_MB_LIB.T6G(SCH_1):M_K_CPU0_SA_CB(5)
 BG5     NC MK1_CLK_L     NC
 BV6 M_K_CPU0_SB_DQS_DP<9> MKB_DQS_H9 @T6G_MB_LIB.T6G(SCH_1):M_K_CPU0_SB_DQS_DP(9)
 DF7 M_K_CPU0_SB_DQ<31> MKB_DATA31 @T6G_MB_LIB.T6G(SCH_1):M_K_CPU0_SB_DQ(31)
 CV6 M_K_CPU0_SB_DQ<20> MKB_DATA20 @T6G_MB_LIB.T6G(SCH_1):M_K_CPU0_SB_DQ(20)
 CB6 M_K_CPU0_SB_DQ<0> MKB_DATA0 @T6G_MB_LIB.T6G(SCH_1):M_K_CPU0_SB_DQ(0)
 BY6 M_K_CPU0_SB_CB<0> MKB_CHECK0 @T6G_MB_LIB.T6G(SCH_1):M_K_CPU0_SB_CB(0)
 BM6     NC MKB1_CS_L1     NC
  Y6 M_K_CPU0_SA_DQS_DN<2> MKA_DQS_L2 @T6G_MB_LIB.T6G(SCH_1):M_K_CPU0_SA_DQS_DN(2)
 AD6 M_K_CPU0_SA_DQ<26> MKA_DATA26 @T6G_MB_LIB.T6G(SCH_1):M_K_CPU0_SA_DQ(26)
  U7 M_K_CPU0_SA_DQ<15> MKA_DATA15 @T6G_MB_LIB.T6G(SCH_1):M_K_CPU0_SA_DQ(15)
  F7 M_K_CPU0_SA_DQ<1> MKA_DATA1 @T6G_MB_LIB.T6G(SCH_1):M_K_CPU0_SA_DQ(1)
 AP6 M_K_CPU0_SA_CB<6> MKA_CHECK6 @T6G_MB_LIB.T6G(SCH_1):M_K_CPU0_SA_CB(6)
 CW7 M_K_CPU0_SB_DQ<21> MKB_DATA21 @T6G_MB_LIB.T6G(SCH_1):M_K_CPU0_SB_DQ(21)
 CJ5 M_K_CPU0_SB_DQ<10> MKB_DATA10 @T6G_MB_LIB.T6G(SCH_1):M_K_CPU0_SB_DQ(10)
 CC7 M_K_CPU0_SB_DQ<1> MKB_DATA1 @T6G_MB_LIB.T6G(SCH_1):M_K_CPU0_SB_DQ(1)
 CA7 M_K_CPU0_SB_CB<1> MKB_CHECK1 @T6G_MB_LIB.T6G(SCH_1):M_K_CPU0_SB_CB(1)
 AF6 M_K_CPU0_SA_DQS_DN<3> MKA_DQS_L3 @T6G_MB_LIB.T6G(SCH_1):M_K_CPU0_SA_DQS_DN(3)
 AE7 M_K_CPU0_SA_DQ<27> MKA_DATA27 @T6G_MB_LIB.T6G(SCH_1):M_K_CPU0_SA_DQ(27)
  U5 M_K_CPU0_SA_DQ<16> MKA_DATA16 @T6G_MB_LIB.T6G(SCH_1):M_K_CPU0_SA_DQ(16)
  F6 M_K_CPU0_SA_DQ<2> MKA_DATA2 @T6G_MB_LIB.T6G(SCH_1):M_K_CPU0_SA_DQ(2)
 AR7 M_K_CPU0_SA_CB<7> MKA_CHECK7 @T6G_MB_LIB.T6G(SCH_1):M_K_CPU0_SA_CB(7)
 BN7 M_K_CPU0_SA_RSP<0> MKA0_RSP_L @T6G_MB_LIB.T6G(SCH_1):M_K_CPU0_SA_RSP(0)
 AT7 M_K_CPU0_ALERT_R_N MK_ALERT_L @T6G_MB_LIB.T6G(SCH_1):M_K_CPU0_ALERT_R_N
 CW5 M_K_CPU0_SB_DQ<22> MKB_DATA22 @T6G_MB_LIB.T6G(SCH_1):M_K_CPU0_SB_DQ(22)
 CK7 M_K_CPU0_SB_DQ<11> MKB_DATA11 @T6G_MB_LIB.T6G(SCH_1):M_K_CPU0_SB_DQ(11)
 CC5 M_K_CPU0_SB_DQ<2> MKB_DATA2 @T6G_MB_LIB.T6G(SCH_1):M_K_CPU0_SB_DQ(2)
 CA5 M_K_CPU0_SB_CB<2> MKB_CHECK2 @T6G_MB_LIB.T6G(SCH_1):M_K_CPU0_SB_CB(2)
 AM6 M_K_CPU0_SA_DQS_DN<4> MKA_DQS_L4 @T6G_MB_LIB.T6G(SCH_1):M_K_CPU0_SA_DQS_DN(4)
  G5 M_K_CPU0_SA_DQS_DP<0> MKA_DQS_H0 @T6G_MB_LIB.T6G(SCH_1):M_K_CPU0_SA_DQS_DP(0)
 AG5 M_K_CPU0_SA_DQ<28> MKA_DATA28 @T6G_MB_LIB.T6G(SCH_1):M_K_CPU0_SA_DQ(28)
  V7 M_K_CPU0_SA_DQ<17> MKA_DATA17 @T6G_MB_LIB.T6G(SCH_1):M_K_CPU0_SA_DQ(17)
  G7 M_K_CPU0_SA_DQ<3> MKA_DATA3 @T6G_MB_LIB.T6G(SCH_1):M_K_CPU0_SA_DQ(3)
 BP7     NC MKA1_RSP_L     NC
 CY7 M_K_CPU0_SB_DQ<23> MKB_DATA23 @T6G_MB_LIB.T6G(SCH_1):M_K_CPU0_SB_DQ(23)
 CM6 M_K_CPU0_SB_DQ<12> MKB_DATA12 @T6G_MB_LIB.T6G(SCH_1):M_K_CPU0_SB_DQ(12)
 CD7 M_K_CPU0_SB_DQ<3> MKB_DATA3 @T6G_MB_LIB.T6G(SCH_1):M_K_CPU0_SB_DQ(3)
 CB7 M_K_CPU0_SB_CB<3> MKB_CHECK3 @T6G_MB_LIB.T6G(SCH_1):M_K_CPU0_SB_CB(3)
  H7 M_K_CPU0_SA_DQS_DN<5> MKA_DQS_L5 @T6G_MB_LIB.T6G(SCH_1):M_K_CPU0_SA_DQS_DN(5)
  N5 M_K_CPU0_SA_DQS_DP<1> MKA_DQS_H1 @T6G_MB_LIB.T6G(SCH_1):M_K_CPU0_SA_DQS_DP(1)
 AH7 M_K_CPU0_SA_DQ<29> MKA_DATA29 @T6G_MB_LIB.T6G(SCH_1):M_K_CPU0_SA_DQ(29)
  V6 M_K_CPU0_SA_DQ<18> MKA_DATA18 @T6G_MB_LIB.T6G(SCH_1):M_K_CPU0_SA_DQ(18)
  J5 M_K_CPU0_SA_DQ<4> MKA_DATA4 @T6G_MB_LIB.T6G(SCH_1):M_K_CPU0_SA_DQ(4)
 CE5 M_K_CPU0_SB_DQS_DN<0> MKB_DQS_L0 @T6G_MB_LIB.T6G(SCH_1):M_K_CPU0_SB_DQS_DN(0)
 CY6 M_K_CPU0_SB_DQ<24> MKB_DATA24 @T6G_MB_LIB.T6G(SCH_1):M_K_CPU0_SB_DQ(24)
 CN7 M_K_CPU0_SB_DQ<13> MKB_DATA13 @T6G_MB_LIB.T6G(SCH_1):M_K_CPU0_SB_DQ(13)
 CF6 M_K_CPU0_SB_DQ<4> MKB_DATA4 @T6G_MB_LIB.T6G(SCH_1):M_K_CPU0_SB_DQ(4)
 BT6 M_K_CPU0_SB_CB<4> MKB_CHECK4 @T6G_MB_LIB.T6G(SCH_1):M_K_CPU0_SB_CB(4)
  P7 M_K_CPU0_SA_DQS_DN<6> MKA_DQS_L6 @T6G_MB_LIB.T6G(SCH_1):M_K_CPU0_SA_DQS_DN(6)
  W5 M_K_CPU0_SA_DQS_DP<2> MKA_DQS_H2 @T6G_MB_LIB.T6G(SCH_1):M_K_CPU0_SA_DQS_DP(2)
  W7 M_K_CPU0_SA_DQ<19> MKA_DATA19 @T6G_MB_LIB.T6G(SCH_1):M_K_CPU0_SA_DQ(19)
  K7 M_K_CPU0_SA_DQ<5> MKA_DATA5 @T6G_MB_LIB.T6G(SCH_1):M_K_CPU0_SA_DQ(5)
 CL5 M_K_CPU0_SB_DQS_DN<1> MKB_DQS_L1 @T6G_MB_LIB.T6G(SCH_1):M_K_CPU0_SB_DQS_DN(1)
 DA7 M_K_CPU0_SB_DQ<25> MKB_DATA25 @T6G_MB_LIB.T6G(SCH_1):M_K_CPU0_SB_DQ(25)
 CN5 M_K_CPU0_SB_DQ<14> MKB_DATA14 @T6G_MB_LIB.T6G(SCH_1):M_K_CPU0_SB_DQ(14)
 CG7 M_K_CPU0_SB_DQ<5> MKB_DATA5 @T6G_MB_LIB.T6G(SCH_1):M_K_CPU0_SB_DQ(5)
 BU7 M_K_CPU0_SB_CB<5> MKB_CHECK5 @T6G_MB_LIB.T6G(SCH_1):M_K_CPU0_SB_CB(5)
 BC7 M_K_CPU0_SA_PAR MKA_PAR @T6G_MB_LIB.T6G(SCH_1):M_K_CPU0_SA_PAR
  Y7 M_K_CPU0_SA_DQS_DN<7> MKA_DQS_L7 @T6G_MB_LIB.T6G(SCH_1):M_K_CPU0_SA_DQS_DN(7)
 AE5 M_K_CPU0_SA_DQS_DP<3> MKA_DQS_H3 @T6G_MB_LIB.T6G(SCH_1):M_K_CPU0_SA_DQS_DP(3)
  K6 M_K_CPU0_SA_DQ<6> MKA_DATA6 @T6G_MB_LIB.T6G(SCH_1):M_K_CPU0_SA_DQ(6)
 BL7 M_K_CPU0_SB_PAR MKB_PAR @T6G_MB_LIB.T6G(SCH_1):M_K_CPU0_SB_PAR
 CU5 M_K_CPU0_SB_DQS_DN<2> MKB_DQS_L2 @T6G_MB_LIB.T6G(SCH_1):M_K_CPU0_SB_DQS_DN(2)
 DA5 M_K_CPU0_SB_DQ<26> MKB_DATA26 @T6G_MB_LIB.T6G(SCH_1):M_K_CPU0_SB_DQ(26)
 CP7 M_K_CPU0_SB_DQ<15> MKB_DATA15 @T6G_MB_LIB.T6G(SCH_1):M_K_CPU0_SB_DQ(15)
 CG5 M_K_CPU0_SB_DQ<6> MKB_DATA6 @T6G_MB_LIB.T6G(SCH_1):M_K_CPU0_SB_DQ(6)
 BU5 M_K_CPU0_SB_CB<6> MKB_CHECK6 @T6G_MB_LIB.T6G(SCH_1):M_K_CPU0_SB_CB(6)
 AF7 M_K_CPU0_SA_DQS_DN<8> MKA_DQS_L8 @T6G_MB_LIB.T6G(SCH_1):M_K_CPU0_SA_DQS_DN(8)
 AL5 M_K_CPU0_SA_DQS_DP<4> MKA_DQS_H4 @T6G_MB_LIB.T6G(SCH_1):M_K_CPU0_SA_DQS_DP(4)
  L7 M_K_CPU0_SA_DQ<7> MKA_DATA7 @T6G_MB_LIB.T6G(SCH_1):M_K_CPU0_SA_DQ(7)
 DC5 M_K_CPU0_SB_DQS_DN<3> MKB_DQS_L3 @T6G_MB_LIB.T6G(SCH_1):M_K_CPU0_SB_DQS_DN(3)
 DB7 M_K_CPU0_SB_DQ<27> MKB_DATA27 @T6G_MB_LIB.T6G(SCH_1):M_K_CPU0_SB_DQ(27)
 CP6 M_K_CPU0_SB_DQ<16> MKB_DATA16 @T6G_MB_LIB.T6G(SCH_1):M_K_CPU0_SB_DQ(16)
 CH7 M_K_CPU0_SB_DQ<7> MKB_DATA7 @T6G_MB_LIB.T6G(SCH_1):M_K_CPU0_SB_DQ(7)
 BV7 M_K_CPU0_SB_CB<7> MKB_CHECK7 @T6G_MB_LIB.T6G(SCH_1):M_K_CPU0_SB_CB(7)
 BP6 M_K_CPU0_SB_RSP<0> MKB0_RSP_L @T6G_MB_LIB.T6G(SCH_1):M_K_CPU0_SB_RSP(0)
 AM7 M_K_CPU0_SA_DQS_DN<9> MKA_DQS_L9 @T6G_MB_LIB.T6G(SCH_1):M_K_CPU0_SA_DQS_DN(9)
  J7 M_K_CPU0_SA_DQS_DP<5> MKA_DQS_H5 @T6G_MB_LIB.T6G(SCH_1):M_K_CPU0_SA_DQS_DP(5)
  L5 M_K_CPU0_SA_DQ<8> MKA_DATA8 @T6G_MB_LIB.T6G(SCH_1):M_K_CPU0_SA_DQ(8)
 BW7 M_K_CPU0_SB_DQS_DN<4> MKB_DQS_L4 @T6G_MB_LIB.T6G(SCH_1):M_K_CPU0_SB_DQS_DN(4)
 CD6 M_K_CPU0_SB_DQS_DP<0> MKB_DQS_H0 @T6G_MB_LIB.T6G(SCH_1):M_K_CPU0_SB_DQS_DP(0)
 DD6 M_K_CPU0_SB_DQ<28> MKB_DATA28 @T6G_MB_LIB.T6G(SCH_1):M_K_CPU0_SB_DQ(28)
 CR7 M_K_CPU0_SB_DQ<17> MKB_DATA17 @T6G_MB_LIB.T6G(SCH_1):M_K_CPU0_SB_DQ(17)
 CH6 M_K_CPU0_SB_DQ<8> MKB_DATA8 @T6G_MB_LIB.T6G(SCH_1):M_K_CPU0_SB_DQ(8)
 BR5     NC MKB1_RSP_L     NC
  R7 M_K_CPU0_SA_DQS_DP<6> MKA_DQS_H6 @T6G_MB_LIB.T6G(SCH_1):M_K_CPU0_SA_DQS_DP(6)
  M7 M_K_CPU0_SA_DQ<9> MKA_DATA9 @T6G_MB_LIB.T6G(SCH_1):M_K_CPU0_SA_DQ(9)
 CE7 M_K_CPU0_SB_DQS_DN<5> MKB_DQS_L5 @T6G_MB_LIB.T6G(SCH_1):M_K_CPU0_SB_DQS_DN(5)
 CK6 M_K_CPU0_SB_DQS_DP<1> MKB_DQS_H1 @T6G_MB_LIB.T6G(SCH_1):M_K_CPU0_SB_DQS_DP(1)
 DE7 M_K_CPU0_SB_DQ<29> MKB_DATA29 @T6G_MB_LIB.T6G(SCH_1):M_K_CPU0_SB_DQ(29)
 CR5 M_K_CPU0_SB_DQ<18> MKB_DATA18 @T6G_MB_LIB.T6G(SCH_1):M_K_CPU0_SB_DQ(18)
 CJ7 M_K_CPU0_SB_DQ<9> MKB_DATA9 @T6G_MB_LIB.T6G(SCH_1):M_K_CPU0_SB_DQ(9)
 AA7 M_K_CPU0_SA_DQS_DP<7> MKA_DQS_H7 @T6G_MB_LIB.T6G(SCH_1):M_K_CPU0_SA_DQS_DP(7)
 AW5 M_K_CPU0_SA_CA<0> MKA_CA0 @T6G_MB_LIB.T6G(SCH_1):M_K_CPU0_SA_CA(0)
 AU5 M_K_CPU0_SA_CS_N<0> MKA0_CS_L0 @T6G_MB_LIB.T6G(SCH_1):M_K_CPU0_SA_CS_N(0)
 BF7 TP_M_K_CPU0_SA_TEST39K TEST39K @T6G_MB_LIB.T6G(SCH_1):TP_M_K_CPU0_SA_TEST39K

Q_RES_0402LF-15,1%,1/16W,CHIP,CS01502FB03  I314  R385
   1 M_K_CPU0_ALERT_N      A @T6G_MB_LIB.T6G(SCH_1):M_K_CPU0_ALERT_N
   2 M_K_CPU0_ALERT_R_N      B @T6G_MB_LIB.T6G(SCH_1):M_K_CPU0_ALERT_R_N


DRAWING: @T6G_MB_LIB.T6G(SCH_1):PAGE21 

GENOA_SP5-SOCKET6096_13568-001,SMLF,IO,DGA^6000030  I159  U25
 BW9 M_L_CPU0_SB_DQS_DN<9> MLB_DQS_L9 @T6G_MB_LIB.T6G(SCH_1):M_L_CPU0_SB_DQS_DN(9)
CF11 M_L_CPU0_SB_DQS_DP<5> MLB_DQS_H5 @T6G_MB_LIB.T6G(SCH_1):M_L_CPU0_SB_DQS_DP(5)
 CF9 M_L_CPU0_SB_DQ<4> MLB_DATA4 @T6G_MB_LIB.T6G(SCH_1):M_L_CPU0_SB_DQ(4)
BH11 M_L_CPU0_SB_CA<1> MLB_CA1 @T6G_MB_LIB.T6G(SCH_1):M_L_CPU0_SB_CA(1)
 AB9 M_L_CPU0_SA_DQ<22> MLA_DATA22 @T6G_MB_LIB.T6G(SCH_1):M_L_CPU0_SA_DQ(22)
 N10 M_L_CPU0_SA_DQ<11> MLA_DATA11 @T6G_MB_LIB.T6G(SCH_1):M_L_CPU0_SA_DQ(11)
 K11 M_L_CPU0_SA_DQ<5> MLA_DATA5 @T6G_MB_LIB.T6G(SCH_1):M_L_CPU0_SA_DQ(5)
 AK9 M_L_CPU0_SA_CB<2> MLA_CHECK2 @T6G_MB_LIB.T6G(SCH_1):M_L_CPU0_SA_CB(2)
AY11 M_L_CPU0_SA_CA<2> MLA_CA2 @T6G_MB_LIB.T6G(SCH_1):M_L_CPU0_SA_CA(2)
AU10 M_L_CPU0_RESET_N ML_RESET_L @T6G_MB_LIB.T6G(SCH_1):M_L_CPU0_RESET_N
CM11 M_L_CPU0_SB_DQS_DP<6> MLB_DQS_H6 @T6G_MB_LIB.T6G(SCH_1):M_L_CPU0_SB_DQS_DP(6)
CG10 M_L_CPU0_SB_DQ<5> MLB_DATA5 @T6G_MB_LIB.T6G(SCH_1):M_L_CPU0_SB_DQ(5)
 BH9 M_L_CPU0_SB_CA<2> MLB_CA2 @T6G_MB_LIB.T6G(SCH_1):M_L_CPU0_SB_CA(2)
BM11 M_L_CPU0_SB_CS_N<0> MLB0_CS_L0 @T6G_MB_LIB.T6G(SCH_1):M_L_CPU0_SB_CS_N(0)
AC10 M_L_CPU0_SA_DQ<23> MLA_DATA23 @T6G_MB_LIB.T6G(SCH_1):M_L_CPU0_SA_DQ(23)
  R9 M_L_CPU0_SA_DQ<12> MLA_DATA12 @T6G_MB_LIB.T6G(SCH_1):M_L_CPU0_SA_DQ(12)
  K9 M_L_CPU0_SA_DQ<6> MLA_DATA6 @T6G_MB_LIB.T6G(SCH_1):M_L_CPU0_SA_DQ(6)
AL10 M_L_CPU0_SA_CB<3> MLA_CHECK3 @T6G_MB_LIB.T6G(SCH_1):M_L_CPU0_SA_CB(3)
BA10 M_L_CPU0_SA_CA<3> MLA_CA3 @T6G_MB_LIB.T6G(SCH_1):M_L_CPU0_SA_CA(3)
CV11 M_L_CPU0_SB_DQS_DP<7> MLB_DQS_H7 @T6G_MB_LIB.T6G(SCH_1):M_L_CPU0_SB_DQS_DP(7)
 CG9 M_L_CPU0_SB_DQ<6> MLB_DATA6 @T6G_MB_LIB.T6G(SCH_1):M_L_CPU0_SB_DQ(6)
 BJ9 M_L_CPU0_SB_CA<3> MLB_CA3 @T6G_MB_LIB.T6G(SCH_1):M_L_CPU0_SB_CA(3)
 BL9     NC MLB1_CS_L0     NC
 BN9 M_L_CPU0_SB_CS_N<1> MLB0_CS_L1 @T6G_MB_LIB.T6G(SCH_1):M_L_CPU0_SB_CS_N(1)
  H9 M_L_CPU0_SA_DQS_DN<0> MLA_DQS_L0 @T6G_MB_LIB.T6G(SCH_1):M_L_CPU0_SA_DQS_DN(0)
 AC9 M_L_CPU0_SA_DQ<24> MLA_DATA24 @T6G_MB_LIB.T6G(SCH_1):M_L_CPU0_SA_DQ(24)
 T11 M_L_CPU0_SA_DQ<13> MLA_DATA13 @T6G_MB_LIB.T6G(SCH_1):M_L_CPU0_SA_DQ(13)
 L10 M_L_CPU0_SA_DQ<7> MLA_DATA7 @T6G_MB_LIB.T6G(SCH_1):M_L_CPU0_SA_DQ(7)
 AN9 M_L_CPU0_SA_CB<4> MLA_CHECK4 @T6G_MB_LIB.T6G(SCH_1):M_L_CPU0_SA_CB(4)
 BA9 M_L_CPU0_SA_CA<4> MLA_CA4 @T6G_MB_LIB.T6G(SCH_1):M_L_CPU0_SA_CA(4)
DD11 M_L_CPU0_SB_DQS_DP<8> MLB_DQS_H8 @T6G_MB_LIB.T6G(SCH_1):M_L_CPU0_SB_DQS_DP(8)
 DE9 M_L_CPU0_SB_DQ<30> MLB_DATA30 @T6G_MB_LIB.T6G(SCH_1):M_L_CPU0_SB_DQ(30)
CH11 M_L_CPU0_SB_DQ<7> MLB_DATA7 @T6G_MB_LIB.T6G(SCH_1):M_L_CPU0_SB_DQ(7)
BJ10 M_L_CPU0_SB_CA<4> MLB_CA4 @T6G_MB_LIB.T6G(SCH_1):M_L_CPU0_SB_CA(4)
 BM9     NC MLB1_CS_L1     NC
  P9 M_L_CPU0_SA_DQS_DN<1> MLA_DQS_L1 @T6G_MB_LIB.T6G(SCH_1):M_L_CPU0_SA_DQS_DN(1)
AD11 M_L_CPU0_SA_DQ<25> MLA_DATA25 @T6G_MB_LIB.T6G(SCH_1):M_L_CPU0_SA_DQ(25)
  T9 M_L_CPU0_SA_DQ<14> MLA_DATA14 @T6G_MB_LIB.T6G(SCH_1):M_L_CPU0_SA_DQ(14)
  L9 M_L_CPU0_SA_DQ<8> MLA_DATA8 @T6G_MB_LIB.T6G(SCH_1):M_L_CPU0_SA_DQ(8)
AP11 M_L_CPU0_SA_CB<5> MLA_CHECK5 @T6G_MB_LIB.T6G(SCH_1):M_L_CPU0_SA_CB(5)
 BB9 M_L_CPU0_SA_CA<5> MLA_CA5 @T6G_MB_LIB.T6G(SCH_1):M_L_CPU0_SA_CA(5)
 BV9 M_L_CPU0_SB_DQS_DP<9> MLB_DQS_H9 @T6G_MB_LIB.T6G(SCH_1):M_L_CPU0_SB_DQS_DP(9)
 DF9 M_L_CPU0_SB_DQ<31> MLB_DATA31 @T6G_MB_LIB.T6G(SCH_1):M_L_CPU0_SB_DQ(31)
 CV9 M_L_CPU0_SB_DQ<20> MLB_DATA20 @T6G_MB_LIB.T6G(SCH_1):M_L_CPU0_SB_DQ(20)
 CH9 M_L_CPU0_SB_DQ<8> MLB_DATA8 @T6G_MB_LIB.T6G(SCH_1):M_L_CPU0_SB_DQ(8)
 BY9 M_L_CPU0_SB_CB<0> MLB_CHECK0 @T6G_MB_LIB.T6G(SCH_1):M_L_CPU0_SB_CB(0)
BK11 M_L_CPU0_SB_CA<5> MLB_CA5 @T6G_MB_LIB.T6G(SCH_1):M_L_CPU0_SB_CA(5)
  Y9 M_L_CPU0_SA_DQS_DN<2> MLA_DQS_L2 @T6G_MB_LIB.T6G(SCH_1):M_L_CPU0_SA_DQS_DN(2)
 AD9 M_L_CPU0_SA_DQ<26> MLA_DATA26 @T6G_MB_LIB.T6G(SCH_1):M_L_CPU0_SA_DQ(26)
 U10 M_L_CPU0_SA_DQ<15> MLA_DATA15 @T6G_MB_LIB.T6G(SCH_1):M_L_CPU0_SA_DQ(15)
 M11 M_L_CPU0_SA_DQ<9> MLA_DATA9 @T6G_MB_LIB.T6G(SCH_1):M_L_CPU0_SA_DQ(9)
 AP9 M_L_CPU0_SA_CB<6> MLA_CHECK6 @T6G_MB_LIB.T6G(SCH_1):M_L_CPU0_SA_CB(6)
BB11 M_L_CPU0_SA_CA<6> MLA_CA6 @T6G_MB_LIB.T6G(SCH_1):M_L_CPU0_SA_CA(6)
BN10 M_L_CPU0_SA_RSP<0> MLA0_RSP_L @T6G_MB_LIB.T6G(SCH_1):M_L_CPU0_SA_RSP(0)
CW10 M_L_CPU0_SB_DQ<21> MLB_DATA21 @T6G_MB_LIB.T6G(SCH_1):M_L_CPU0_SB_DQ(21)
 CJ9 M_L_CPU0_SB_DQ<10> MLB_DATA10 @T6G_MB_LIB.T6G(SCH_1):M_L_CPU0_SB_DQ(10)
CJ10 M_L_CPU0_SB_DQ<9> MLB_DATA9 @T6G_MB_LIB.T6G(SCH_1):M_L_CPU0_SB_DQ(9)
CA10 M_L_CPU0_SB_CB<1> MLB_CHECK1 @T6G_MB_LIB.T6G(SCH_1):M_L_CPU0_SB_CB(1)
 BK9 M_L_CPU0_SB_CA<6> MLB_CA6 @T6G_MB_LIB.T6G(SCH_1):M_L_CPU0_SB_CA(6)
 AF9 M_L_CPU0_SA_DQS_DN<3> MLA_DQS_L3 @T6G_MB_LIB.T6G(SCH_1):M_L_CPU0_SA_DQS_DN(3)
AE10 M_L_CPU0_SA_DQ<27> MLA_DATA27 @T6G_MB_LIB.T6G(SCH_1):M_L_CPU0_SA_DQ(27)
  U9 M_L_CPU0_SA_DQ<16> MLA_DATA16 @T6G_MB_LIB.T6G(SCH_1):M_L_CPU0_SA_DQ(16)
AR10 M_L_CPU0_SA_CB<7> MLA_CHECK7 @T6G_MB_LIB.T6G(SCH_1):M_L_CPU0_SA_CB(7)
BP11     NC MLA1_RSP_L     NC
AT11 M_L_CPU0_ALERT_R_N ML_ALERT_L @T6G_MB_LIB.T6G(SCH_1):M_L_CPU0_ALERT_R_N
 CW9 M_L_CPU0_SB_DQ<22> MLB_DATA22 @T6G_MB_LIB.T6G(SCH_1):M_L_CPU0_SB_DQ(22)
CK11 M_L_CPU0_SB_DQ<11> MLB_DATA11 @T6G_MB_LIB.T6G(SCH_1):M_L_CPU0_SB_DQ(11)
 CA9 M_L_CPU0_SB_CB<2> MLB_CHECK2 @T6G_MB_LIB.T6G(SCH_1):M_L_CPU0_SB_CB(2)
 AM9 M_L_CPU0_SA_DQS_DN<4> MLA_DQS_L4 @T6G_MB_LIB.T6G(SCH_1):M_L_CPU0_SA_DQS_DN(4)
  G9 M_L_CPU0_SA_DQS_DP<0> MLA_DQS_H0 @T6G_MB_LIB.T6G(SCH_1):M_L_CPU0_SA_DQS_DP(0)
 AG9 M_L_CPU0_SA_DQ<28> MLA_DATA28 @T6G_MB_LIB.T6G(SCH_1):M_L_CPU0_SA_DQ(28)
 V11 M_L_CPU0_SA_DQ<17> MLA_DATA17 @T6G_MB_LIB.T6G(SCH_1):M_L_CPU0_SA_DQ(17)
CY11 M_L_CPU0_SB_DQ<23> MLB_DATA23 @T6G_MB_LIB.T6G(SCH_1):M_L_CPU0_SB_DQ(23)
 CM9 M_L_CPU0_SB_DQ<12> MLB_DATA12 @T6G_MB_LIB.T6G(SCH_1):M_L_CPU0_SB_DQ(12)
CB11 M_L_CPU0_SB_CB<3> MLB_CHECK3 @T6G_MB_LIB.T6G(SCH_1):M_L_CPU0_SB_CB(3)
 H11 M_L_CPU0_SA_DQS_DN<5> MLA_DQS_L5 @T6G_MB_LIB.T6G(SCH_1):M_L_CPU0_SA_DQS_DN(5)
  N9 M_L_CPU0_SA_DQS_DP<1> MLA_DQS_H1 @T6G_MB_LIB.T6G(SCH_1):M_L_CPU0_SA_DQS_DP(1)
AH11 M_L_CPU0_SA_DQ<29> MLA_DATA29 @T6G_MB_LIB.T6G(SCH_1):M_L_CPU0_SA_DQ(29)
  V9 M_L_CPU0_SA_DQ<18> MLA_DATA18 @T6G_MB_LIB.T6G(SCH_1):M_L_CPU0_SA_DQ(18)
 BC9 M_L_CPU0_CLK_DP<0> ML0_CLK_H @T6G_MB_LIB.T6G(SCH_1):M_L_CPU0_CLK_DP(0)
 CE9 M_L_CPU0_SB_DQS_DN<0> MLB_DQS_L0 @T6G_MB_LIB.T6G(SCH_1):M_L_CPU0_SB_DQS_DN(0)
 CY9 M_L_CPU0_SB_DQ<24> MLB_DATA24 @T6G_MB_LIB.T6G(SCH_1):M_L_CPU0_SB_DQ(24)
CN10 M_L_CPU0_SB_DQ<13> MLB_DATA13 @T6G_MB_LIB.T6G(SCH_1):M_L_CPU0_SB_DQ(13)
 BT9 M_L_CPU0_SB_CB<4> MLB_CHECK4 @T6G_MB_LIB.T6G(SCH_1):M_L_CPU0_SB_CB(4)
 P11 M_L_CPU0_SA_DQS_DN<6> MLA_DQS_L6 @T6G_MB_LIB.T6G(SCH_1):M_L_CPU0_SA_DQS_DN(6)
  W9 M_L_CPU0_SA_DQS_DP<2> MLA_DQS_H2 @T6G_MB_LIB.T6G(SCH_1):M_L_CPU0_SA_DQS_DP(2)
 W10 M_L_CPU0_SA_DQ<19> MLA_DATA19 @T6G_MB_LIB.T6G(SCH_1):M_L_CPU0_SA_DQ(19)
 BF9     NC ML1_CLK_H     NC
 CL9 M_L_CPU0_SB_DQS_DN<1> MLB_DQS_L1 @T6G_MB_LIB.T6G(SCH_1):M_L_CPU0_SB_DQS_DN(1)
DA10 M_L_CPU0_SB_DQ<25> MLB_DATA25 @T6G_MB_LIB.T6G(SCH_1):M_L_CPU0_SB_DQ(25)
 CN9 M_L_CPU0_SB_DQ<14> MLB_DATA14 @T6G_MB_LIB.T6G(SCH_1):M_L_CPU0_SB_DQ(14)
BU10 M_L_CPU0_SB_CB<5> MLB_CHECK5 @T6G_MB_LIB.T6G(SCH_1):M_L_CPU0_SB_CB(5)
 Y11 M_L_CPU0_SA_DQS_DN<7> MLA_DQS_L7 @T6G_MB_LIB.T6G(SCH_1):M_L_CPU0_SA_DQS_DN(7)
 AE9 M_L_CPU0_SA_DQS_DP<3> MLA_DQS_H3 @T6G_MB_LIB.T6G(SCH_1):M_L_CPU0_SA_DQS_DP(3)
 CU9 M_L_CPU0_SB_DQS_DN<2> MLB_DQS_L2 @T6G_MB_LIB.T6G(SCH_1):M_L_CPU0_SB_DQS_DN(2)
 DA9 M_L_CPU0_SB_DQ<26> MLB_DATA26 @T6G_MB_LIB.T6G(SCH_1):M_L_CPU0_SB_DQ(26)
CP11 M_L_CPU0_SB_DQ<15> MLB_DATA15 @T6G_MB_LIB.T6G(SCH_1):M_L_CPU0_SB_DQ(15)
 BU9 M_L_CPU0_SB_CB<6> MLB_CHECK6 @T6G_MB_LIB.T6G(SCH_1):M_L_CPU0_SB_CB(6)
 BP9 M_L_CPU0_SB_RSP<0> MLB0_RSP_L @T6G_MB_LIB.T6G(SCH_1):M_L_CPU0_SB_RSP(0)
AF11 M_L_CPU0_SA_DQS_DN<8> MLA_DQS_L8 @T6G_MB_LIB.T6G(SCH_1):M_L_CPU0_SA_DQS_DN(8)
 AL9 M_L_CPU0_SA_DQS_DP<4> MLA_DQS_H4 @T6G_MB_LIB.T6G(SCH_1):M_L_CPU0_SA_DQS_DP(4)
 DC9 M_L_CPU0_SB_DQS_DN<3> MLB_DQS_L3 @T6G_MB_LIB.T6G(SCH_1):M_L_CPU0_SB_DQS_DN(3)
DB11 M_L_CPU0_SB_DQ<27> MLB_DATA27 @T6G_MB_LIB.T6G(SCH_1):M_L_CPU0_SB_DQ(27)
 CP9 M_L_CPU0_SB_DQ<16> MLB_DATA16 @T6G_MB_LIB.T6G(SCH_1):M_L_CPU0_SB_DQ(16)
BV11 M_L_CPU0_SB_CB<7> MLB_CHECK7 @T6G_MB_LIB.T6G(SCH_1):M_L_CPU0_SB_CB(7)
 BR9     NC MLB1_RSP_L     NC
BC10 M_L_CPU0_SA_PAR MLA_PAR @T6G_MB_LIB.T6G(SCH_1):M_L_CPU0_SA_PAR
AM11 M_L_CPU0_SA_DQS_DN<9> MLA_DQS_L9 @T6G_MB_LIB.T6G(SCH_1):M_L_CPU0_SA_DQS_DN(9)
 J10 M_L_CPU0_SA_DQS_DP<5> MLA_DQS_H5 @T6G_MB_LIB.T6G(SCH_1):M_L_CPU0_SA_DQS_DP(5)
 BD9 M_L_CPU0_CLK_DN<0> ML0_CLK_L @T6G_MB_LIB.T6G(SCH_1):M_L_CPU0_CLK_DN(0)
BL10 M_L_CPU0_SB_PAR MLB_PAR @T6G_MB_LIB.T6G(SCH_1):M_L_CPU0_SB_PAR
BW10 M_L_CPU0_SB_DQS_DN<4> MLB_DQS_L4 @T6G_MB_LIB.T6G(SCH_1):M_L_CPU0_SB_DQS_DN(4)
 CD9 M_L_CPU0_SB_DQS_DP<0> MLB_DQS_H0 @T6G_MB_LIB.T6G(SCH_1):M_L_CPU0_SB_DQS_DP(0)
 DD9 M_L_CPU0_SB_DQ<28> MLB_DATA28 @T6G_MB_LIB.T6G(SCH_1):M_L_CPU0_SB_DQ(28)
CR10 M_L_CPU0_SB_DQ<17> MLB_DATA17 @T6G_MB_LIB.T6G(SCH_1):M_L_CPU0_SB_DQ(17)
 R10 M_L_CPU0_SA_DQS_DP<6> MLA_DQS_H6 @T6G_MB_LIB.T6G(SCH_1):M_L_CPU0_SA_DQS_DP(6)
  E9 M_L_CPU0_SA_DQ<0> MLA_DATA0 @T6G_MB_LIB.T6G(SCH_1):M_L_CPU0_SA_DQ(0)
 AU9 M_L_CPU0_SA_CS_N<0> MLA0_CS_L0 @T6G_MB_LIB.T6G(SCH_1):M_L_CPU0_SA_CS_N(0)
 BG9     NC ML1_CLK_L     NC
CE10 M_L_CPU0_SB_DQS_DN<5> MLB_DQS_L5 @T6G_MB_LIB.T6G(SCH_1):M_L_CPU0_SB_DQS_DN(5)
 CK9 M_L_CPU0_SB_DQS_DP<1> MLB_DQS_H1 @T6G_MB_LIB.T6G(SCH_1):M_L_CPU0_SB_DQS_DP(1)
DE10 M_L_CPU0_SB_DQ<29> MLB_DATA29 @T6G_MB_LIB.T6G(SCH_1):M_L_CPU0_SB_DQ(29)
 CR9 M_L_CPU0_SB_DQ<18> MLB_DATA18 @T6G_MB_LIB.T6G(SCH_1):M_L_CPU0_SB_DQ(18)
 CB9 M_L_CPU0_SB_DQ<0> MLB_DATA0 @T6G_MB_LIB.T6G(SCH_1):M_L_CPU0_SB_DQ(0)
AA10 M_L_CPU0_SA_DQS_DP<7> MLA_DQS_H7 @T6G_MB_LIB.T6G(SCH_1):M_L_CPU0_SA_DQS_DP(7)
 F11 M_L_CPU0_SA_DQ<1> MLA_DATA1 @T6G_MB_LIB.T6G(SCH_1):M_L_CPU0_SA_DQ(1)
 AV9     NC MLA1_CS_L0     NC
AV11 M_L_CPU0_SA_CS_N<1> MLA0_CS_L1 @T6G_MB_LIB.T6G(SCH_1):M_L_CPU0_SA_CS_N(1)
CL10 M_L_CPU0_SB_DQS_DN<6> MLB_DQS_L6 @T6G_MB_LIB.T6G(SCH_1):M_L_CPU0_SB_DQS_DN(6)
 CT9 M_L_CPU0_SB_DQS_DP<2> MLB_DQS_H2 @T6G_MB_LIB.T6G(SCH_1):M_L_CPU0_SB_DQS_DP(2)
CT11 M_L_CPU0_SB_DQ<19> MLB_DATA19 @T6G_MB_LIB.T6G(SCH_1):M_L_CPU0_SB_DQ(19)
CC10 M_L_CPU0_SB_DQ<1> MLB_DATA1 @T6G_MB_LIB.T6G(SCH_1):M_L_CPU0_SB_DQ(1)
AG10 M_L_CPU0_SA_DQS_DP<8> MLA_DQS_H8 @T6G_MB_LIB.T6G(SCH_1):M_L_CPU0_SA_DQS_DP(8)
 AH9 M_L_CPU0_SA_DQ<30> MLA_DATA30 @T6G_MB_LIB.T6G(SCH_1):M_L_CPU0_SA_DQ(30)
  F9 M_L_CPU0_SA_DQ<2> MLA_DATA2 @T6G_MB_LIB.T6G(SCH_1):M_L_CPU0_SA_DQ(2)
AW10     NC MLA1_CS_L1     NC
CU10 M_L_CPU0_SB_DQS_DN<7> MLB_DQS_L7 @T6G_MB_LIB.T6G(SCH_1):M_L_CPU0_SB_DQS_DN(7)
 DB9 M_L_CPU0_SB_DQS_DP<3> MLB_DQS_H3 @T6G_MB_LIB.T6G(SCH_1):M_L_CPU0_SB_DQS_DP(3)
 CC9 M_L_CPU0_SB_DQ<2> MLB_DATA2 @T6G_MB_LIB.T6G(SCH_1):M_L_CPU0_SB_DQ(2)
AN10 M_L_CPU0_SA_DQS_DP<9> MLA_DQS_H9 @T6G_MB_LIB.T6G(SCH_1):M_L_CPU0_SA_DQS_DP(9)
AJ10 M_L_CPU0_SA_DQ<31> MLA_DATA31 @T6G_MB_LIB.T6G(SCH_1):M_L_CPU0_SA_DQ(31)
 AA9 M_L_CPU0_SA_DQ<20> MLA_DATA20 @T6G_MB_LIB.T6G(SCH_1):M_L_CPU0_SA_DQ(20)
 G10 M_L_CPU0_SA_DQ<3> MLA_DATA3 @T6G_MB_LIB.T6G(SCH_1):M_L_CPU0_SA_DQ(3)
 AJ9 M_L_CPU0_SA_CB<0> MLA_CHECK0 @T6G_MB_LIB.T6G(SCH_1):M_L_CPU0_SA_CB(0)
 AW9 M_L_CPU0_SA_CA<0> MLA_CA0 @T6G_MB_LIB.T6G(SCH_1):M_L_CPU0_SA_CA(0)
DC10 M_L_CPU0_SB_DQS_DN<8> MLB_DQS_L8 @T6G_MB_LIB.T6G(SCH_1):M_L_CPU0_SB_DQS_DN(8)
BY11 M_L_CPU0_SB_DQS_DP<4> MLB_DQS_H4 @T6G_MB_LIB.T6G(SCH_1):M_L_CPU0_SB_DQS_DP(4)
CD11 M_L_CPU0_SB_DQ<3> MLB_DATA3 @T6G_MB_LIB.T6G(SCH_1):M_L_CPU0_SB_DQ(3)
BG10 M_L_CPU0_SB_CA<0> MLB_CA0 @T6G_MB_LIB.T6G(SCH_1):M_L_CPU0_SB_CA(0)
AB11 M_L_CPU0_SA_DQ<21> MLA_DATA21 @T6G_MB_LIB.T6G(SCH_1):M_L_CPU0_SA_DQ(21)
  M9 M_L_CPU0_SA_DQ<10> MLA_DATA10 @T6G_MB_LIB.T6G(SCH_1):M_L_CPU0_SA_DQ(10)
  J9 M_L_CPU0_SA_DQ<4> MLA_DATA4 @T6G_MB_LIB.T6G(SCH_1):M_L_CPU0_SA_DQ(4)
AK11 M_L_CPU0_SA_CB<1> MLA_CHECK1 @T6G_MB_LIB.T6G(SCH_1):M_L_CPU0_SA_CB(1)
 AY9 M_L_CPU0_SA_CA<1> MLA_CA1 @T6G_MB_LIB.T6G(SCH_1):M_L_CPU0_SA_CA(1)
BF11 TP_M_L_CPU0_SA_TEST39L TEST39L @T6G_MB_LIB.T6G(SCH_1):TP_M_L_CPU0_SA_TEST39L

Q_RES_0402LF-15,1%,1/16W,CHIP,CS01502FB03  I314  R386
   1 M_L_CPU0_ALERT_N      A @T6G_MB_LIB.T6G(SCH_1):M_L_CPU0_ALERT_N
   2 M_L_CPU0_ALERT_R_N      B @T6G_MB_LIB.T6G(SCH_1):M_L_CPU0_ALERT_R_N


DRAWING: @T6G_MB_LIB.T6G(SCH_1):PAGE22 

GENOA_SP5-SOCKET6096_13568-001,SMLF,IO,DGA^6000030  I207  U25
 M40 GMI_CPU1_G2_CPU0_G0_TX_DN<0> G0_RXN0 @T6G_MB_LIB.T6G(SCH_1):GMI_CPU1_G2_CPU0_G0_TX_DN(0)
 K40 GMI_CPU1_G2_CPU0_G0_TX_DN<1> G0_RXN1 @T6G_MB_LIB.T6G(SCH_1):GMI_CPU1_G2_CPU0_G0_TX_DN(1)
 H40 GMI_CPU1_G2_CPU0_G0_TX_DN<2> G0_RXN2 @T6G_MB_LIB.T6G(SCH_1):GMI_CPU1_G2_CPU0_G0_TX_DN(2)
 L43 GMI_CPU1_G2_CPU0_G0_TX_DN<3> G0_RXN3 @T6G_MB_LIB.T6G(SCH_1):GMI_CPU1_G2_CPU0_G0_TX_DN(3)
 G43 GMI_CPU1_G2_CPU0_G0_TX_DN<4> G0_RXN4 @T6G_MB_LIB.T6G(SCH_1):GMI_CPU1_G2_CPU0_G0_TX_DN(4)
 J43 GMI_CPU1_G2_CPU0_G0_TX_DN<5> G0_RXN5 @T6G_MB_LIB.T6G(SCH_1):GMI_CPU1_G2_CPU0_G0_TX_DN(5)
 L46 GMI_CPU1_G2_CPU0_G0_TX_DN<6> G0_RXN6 @T6G_MB_LIB.T6G(SCH_1):GMI_CPU1_G2_CPU0_G0_TX_DN(6)
 G46 GMI_CPU1_G2_CPU0_G0_TX_DN<7> G0_RXN7 @T6G_MB_LIB.T6G(SCH_1):GMI_CPU1_G2_CPU0_G0_TX_DN(7)
 J46 GMI_CPU1_G2_CPU0_G0_TX_DN<8> G0_RXN8 @T6G_MB_LIB.T6G(SCH_1):GMI_CPU1_G2_CPU0_G0_TX_DN(8)
 L49 GMI_CPU1_G2_CPU0_G0_TX_DN<9> G0_RXN9 @T6G_MB_LIB.T6G(SCH_1):GMI_CPU1_G2_CPU0_G0_TX_DN(9)
 G49 GMI_CPU1_G2_CPU0_G0_TX_DN<10> G0_RXN10 @T6G_MB_LIB.T6G(SCH_1):GMI_CPU1_G2_CPU0_G0_TX_DN(10)
 J49 GMI_CPU1_G2_CPU0_G0_TX_DN<11> G0_RXN11 @T6G_MB_LIB.T6G(SCH_1):GMI_CPU1_G2_CPU0_G0_TX_DN(11)
 L52 GMI_CPU1_G2_CPU0_G0_TX_DN<12> G0_RXN12 @T6G_MB_LIB.T6G(SCH_1):GMI_CPU1_G2_CPU0_G0_TX_DN(12)
 G52 GMI_CPU1_G2_CPU0_G0_TX_DN<13> G0_RXN13 @T6G_MB_LIB.T6G(SCH_1):GMI_CPU1_G2_CPU0_G0_TX_DN(13)
 J52 GMI_CPU1_G2_CPU0_G0_TX_DN<14> G0_RXN14 @T6G_MB_LIB.T6G(SCH_1):GMI_CPU1_G2_CPU0_G0_TX_DN(14)
 N52 GMI_CPU1_G2_CPU0_G0_TX_DN<15> G0_RXN15 @T6G_MB_LIB.T6G(SCH_1):GMI_CPU1_G2_CPU0_G0_TX_DN(15)
 M41 GMI_CPU1_G2_CPU0_G0_TX_DP<0> G0_RXP0 @T6G_MB_LIB.T6G(SCH_1):GMI_CPU1_G2_CPU0_G0_TX_DP(0)
 K41 GMI_CPU1_G2_CPU0_G0_TX_DP<1> G0_RXP1 @T6G_MB_LIB.T6G(SCH_1):GMI_CPU1_G2_CPU0_G0_TX_DP(1)
 H41 GMI_CPU1_G2_CPU0_G0_TX_DP<2> G0_RXP2 @T6G_MB_LIB.T6G(SCH_1):GMI_CPU1_G2_CPU0_G0_TX_DP(2)
 L44 GMI_CPU1_G2_CPU0_G0_TX_DP<3> G0_RXP3 @T6G_MB_LIB.T6G(SCH_1):GMI_CPU1_G2_CPU0_G0_TX_DP(3)
 G44 GMI_CPU1_G2_CPU0_G0_TX_DP<4> G0_RXP4 @T6G_MB_LIB.T6G(SCH_1):GMI_CPU1_G2_CPU0_G0_TX_DP(4)
 J44 GMI_CPU1_G2_CPU0_G0_TX_DP<5> G0_RXP5 @T6G_MB_LIB.T6G(SCH_1):GMI_CPU1_G2_CPU0_G0_TX_DP(5)
 L47 GMI_CPU1_G2_CPU0_G0_TX_DP<6> G0_RXP6 @T6G_MB_LIB.T6G(SCH_1):GMI_CPU1_G2_CPU0_G0_TX_DP(6)
 G47 GMI_CPU1_G2_CPU0_G0_TX_DP<7> G0_RXP7 @T6G_MB_LIB.T6G(SCH_1):GMI_CPU1_G2_CPU0_G0_TX_DP(7)
 J47 GMI_CPU1_G2_CPU0_G0_TX_DP<8> G0_RXP8 @T6G_MB_LIB.T6G(SCH_1):GMI_CPU1_G2_CPU0_G0_TX_DP(8)
 L50 GMI_CPU1_G2_CPU0_G0_TX_DP<9> G0_RXP9 @T6G_MB_LIB.T6G(SCH_1):GMI_CPU1_G2_CPU0_G0_TX_DP(9)
 G50 GMI_CPU1_G2_CPU0_G0_TX_DP<10> G0_RXP10 @T6G_MB_LIB.T6G(SCH_1):GMI_CPU1_G2_CPU0_G0_TX_DP(10)
 J50 GMI_CPU1_G2_CPU0_G0_TX_DP<11> G0_RXP11 @T6G_MB_LIB.T6G(SCH_1):GMI_CPU1_G2_CPU0_G0_TX_DP(11)
 L53 GMI_CPU1_G2_CPU0_G0_TX_DP<12> G0_RXP12 @T6G_MB_LIB.T6G(SCH_1):GMI_CPU1_G2_CPU0_G0_TX_DP(12)
 G53 GMI_CPU1_G2_CPU0_G0_TX_DP<13> G0_RXP13 @T6G_MB_LIB.T6G(SCH_1):GMI_CPU1_G2_CPU0_G0_TX_DP(13)
 J53 GMI_CPU1_G2_CPU0_G0_TX_DP<14> G0_RXP14 @T6G_MB_LIB.T6G(SCH_1):GMI_CPU1_G2_CPU0_G0_TX_DP(14)
 N53 GMI_CPU1_G2_CPU0_G0_TX_DP<15> G0_RXP15 @T6G_MB_LIB.T6G(SCH_1):GMI_CPU1_G2_CPU0_G0_TX_DP(15)
AF41 GMI_CPU0_G0_CPU1_G2_TX_DN<0> G0_TXN0 @T6G_MB_LIB.T6G(SCH_1):GMI_CPU0_G0_CPU1_G2_TX_DN(0)
AD41 GMI_CPU0_G0_CPU1_G2_TX_DN<1> G0_TXN1 @T6G_MB_LIB.T6G(SCH_1):GMI_CPU0_G0_CPU1_G2_TX_DN(1)
AB41 GMI_CPU0_G0_CPU1_G2_TX_DN<2> G0_TXN2 @T6G_MB_LIB.T6G(SCH_1):GMI_CPU0_G0_CPU1_G2_TX_DN(2)
AG44 GMI_CPU0_G0_CPU1_G2_TX_DN<3> G0_TXN3 @T6G_MB_LIB.T6G(SCH_1):GMI_CPU0_G0_CPU1_G2_TX_DN(3)
AA44 GMI_CPU0_G0_CPU1_G2_TX_DN<4> G0_TXN4 @T6G_MB_LIB.T6G(SCH_1):GMI_CPU0_G0_CPU1_G2_TX_DN(4)
AC44 GMI_CPU0_G0_CPU1_G2_TX_DN<5> G0_TXN5 @T6G_MB_LIB.T6G(SCH_1):GMI_CPU0_G0_CPU1_G2_TX_DN(5)
AE44 GMI_CPU0_G0_CPU1_G2_TX_DN<6> G0_TXN6 @T6G_MB_LIB.T6G(SCH_1):GMI_CPU0_G0_CPU1_G2_TX_DN(6)
AG47 GMI_CPU0_G0_CPU1_G2_TX_DN<7> G0_TXN7 @T6G_MB_LIB.T6G(SCH_1):GMI_CPU0_G0_CPU1_G2_TX_DN(7)
AC47 GMI_CPU0_G0_CPU1_G2_TX_DN<8> G0_TXN8 @T6G_MB_LIB.T6G(SCH_1):GMI_CPU0_G0_CPU1_G2_TX_DN(8)
AE47 GMI_CPU0_G0_CPU1_G2_TX_DN<9> G0_TXN9 @T6G_MB_LIB.T6G(SCH_1):GMI_CPU0_G0_CPU1_G2_TX_DN(9)
AG50 GMI_CPU0_G0_CPU1_G2_TX_DN<10> G0_TXN10 @T6G_MB_LIB.T6G(SCH_1):GMI_CPU0_G0_CPU1_G2_TX_DN(10)
AC50 GMI_CPU0_G0_CPU1_G2_TX_DN<11> G0_TXN11 @T6G_MB_LIB.T6G(SCH_1):GMI_CPU0_G0_CPU1_G2_TX_DN(11)
AE50 GMI_CPU0_G0_CPU1_G2_TX_DN<12> G0_TXN12 @T6G_MB_LIB.T6G(SCH_1):GMI_CPU0_G0_CPU1_G2_TX_DN(12)
AG53 GMI_CPU0_G0_CPU1_G2_TX_DN<13> G0_TXN13 @T6G_MB_LIB.T6G(SCH_1):GMI_CPU0_G0_CPU1_G2_TX_DN(13)
AC53 GMI_CPU0_G0_CPU1_G2_TX_DN<14> G0_TXN14 @T6G_MB_LIB.T6G(SCH_1):GMI_CPU0_G0_CPU1_G2_TX_DN(14)
AE53 GMI_CPU0_G0_CPU1_G2_TX_DN<15> G0_TXN15 @T6G_MB_LIB.T6G(SCH_1):GMI_CPU0_G0_CPU1_G2_TX_DN(15)
AF40 GMI_CPU0_G0_CPU1_G2_TX_DP<0> G0_TXP0 @T6G_MB_LIB.T6G(SCH_1):GMI_CPU0_G0_CPU1_G2_TX_DP(0)
AD40 GMI_CPU0_G0_CPU1_G2_TX_DP<1> G0_TXP1 @T6G_MB_LIB.T6G(SCH_1):GMI_CPU0_G0_CPU1_G2_TX_DP(1)
AB40 GMI_CPU0_G0_CPU1_G2_TX_DP<2> G0_TXP2 @T6G_MB_LIB.T6G(SCH_1):GMI_CPU0_G0_CPU1_G2_TX_DP(2)
AG43 GMI_CPU0_G0_CPU1_G2_TX_DP<3> G0_TXP3 @T6G_MB_LIB.T6G(SCH_1):GMI_CPU0_G0_CPU1_G2_TX_DP(3)
AA43 GMI_CPU0_G0_CPU1_G2_TX_DP<4> G0_TXP4 @T6G_MB_LIB.T6G(SCH_1):GMI_CPU0_G0_CPU1_G2_TX_DP(4)
AC43 GMI_CPU0_G0_CPU1_G2_TX_DP<5> G0_TXP5 @T6G_MB_LIB.T6G(SCH_1):GMI_CPU0_G0_CPU1_G2_TX_DP(5)
AE43 GMI_CPU0_G0_CPU1_G2_TX_DP<6> G0_TXP6 @T6G_MB_LIB.T6G(SCH_1):GMI_CPU0_G0_CPU1_G2_TX_DP(6)
AG46 GMI_CPU0_G0_CPU1_G2_TX_DP<7> G0_TXP7 @T6G_MB_LIB.T6G(SCH_1):GMI_CPU0_G0_CPU1_G2_TX_DP(7)
AC46 GMI_CPU0_G0_CPU1_G2_TX_DP<8> G0_TXP8 @T6G_MB_LIB.T6G(SCH_1):GMI_CPU0_G0_CPU1_G2_TX_DP(8)
AE46 GMI_CPU0_G0_CPU1_G2_TX_DP<9> G0_TXP9 @T6G_MB_LIB.T6G(SCH_1):GMI_CPU0_G0_CPU1_G2_TX_DP(9)
AG49 GMI_CPU0_G0_CPU1_G2_TX_DP<10> G0_TXP10 @T6G_MB_LIB.T6G(SCH_1):GMI_CPU0_G0_CPU1_G2_TX_DP(10)
AC49 GMI_CPU0_G0_CPU1_G2_TX_DP<11> G0_TXP11 @T6G_MB_LIB.T6G(SCH_1):GMI_CPU0_G0_CPU1_G2_TX_DP(11)
AE49 GMI_CPU0_G0_CPU1_G2_TX_DP<12> G0_TXP12 @T6G_MB_LIB.T6G(SCH_1):GMI_CPU0_G0_CPU1_G2_TX_DP(12)
AG52 GMI_CPU0_G0_CPU1_G2_TX_DP<13> G0_TXP13 @T6G_MB_LIB.T6G(SCH_1):GMI_CPU0_G0_CPU1_G2_TX_DP(13)
AC52 GMI_CPU0_G0_CPU1_G2_TX_DP<14> G0_TXP14 @T6G_MB_LIB.T6G(SCH_1):GMI_CPU0_G0_CPU1_G2_TX_DP(14)
AE52 GMI_CPU0_G0_CPU1_G2_TX_DP<15> G0_TXP15 @T6G_MB_LIB.T6G(SCH_1):GMI_CPU0_G0_CPU1_G2_TX_DP(15)

GENOA_SP5-SOCKET6096_13568-001,SMLF,IO,DGA^6000030  I208  U25
AL52 GMI_CPU0_G1_CPU1_G3_TX_DP<15> G1_TXP15 @T6G_MB_LIB.T6G(SCH_1):GMI_CPU0_G1_CPU1_G3_TX_DP(15)
AJ52 GMI_CPU0_G1_CPU1_G3_TX_DP<14> G1_TXP14 @T6G_MB_LIB.T6G(SCH_1):GMI_CPU0_G1_CPU1_G3_TX_DP(14)
AN52 GMI_CPU0_G1_CPU1_G3_TX_DP<13> G1_TXP13 @T6G_MB_LIB.T6G(SCH_1):GMI_CPU0_G1_CPU1_G3_TX_DP(13)
AL49 GMI_CPU0_G1_CPU1_G3_TX_DP<12> G1_TXP12 @T6G_MB_LIB.T6G(SCH_1):GMI_CPU0_G1_CPU1_G3_TX_DP(12)
AJ49 GMI_CPU0_G1_CPU1_G3_TX_DP<11> G1_TXP11 @T6G_MB_LIB.T6G(SCH_1):GMI_CPU0_G1_CPU1_G3_TX_DP(11)
AN49 GMI_CPU0_G1_CPU1_G3_TX_DP<10> G1_TXP10 @T6G_MB_LIB.T6G(SCH_1):GMI_CPU0_G1_CPU1_G3_TX_DP(10)
AL46 GMI_CPU0_G1_CPU1_G3_TX_DP<9> G1_TXP9 @T6G_MB_LIB.T6G(SCH_1):GMI_CPU0_G1_CPU1_G3_TX_DP(9)
AJ46 GMI_CPU0_G1_CPU1_G3_TX_DP<8> G1_TXP8 @T6G_MB_LIB.T6G(SCH_1):GMI_CPU0_G1_CPU1_G3_TX_DP(8)
AL53 GMI_CPU0_G1_CPU1_G3_TX_DN<15> G1_TXN15 @T6G_MB_LIB.T6G(SCH_1):GMI_CPU0_G1_CPU1_G3_TX_DN(15)
AJ53 GMI_CPU0_G1_CPU1_G3_TX_DN<14> G1_TXN14 @T6G_MB_LIB.T6G(SCH_1):GMI_CPU0_G1_CPU1_G3_TX_DN(14)
AN53 GMI_CPU0_G1_CPU1_G3_TX_DN<13> G1_TXN13 @T6G_MB_LIB.T6G(SCH_1):GMI_CPU0_G1_CPU1_G3_TX_DN(13)
AL50 GMI_CPU0_G1_CPU1_G3_TX_DN<12> G1_TXN12 @T6G_MB_LIB.T6G(SCH_1):GMI_CPU0_G1_CPU1_G3_TX_DN(12)
AJ50 GMI_CPU0_G1_CPU1_G3_TX_DN<11> G1_TXN11 @T6G_MB_LIB.T6G(SCH_1):GMI_CPU0_G1_CPU1_G3_TX_DN(11)
AN50 GMI_CPU0_G1_CPU1_G3_TX_DN<10> G1_TXN10 @T6G_MB_LIB.T6G(SCH_1):GMI_CPU0_G1_CPU1_G3_TX_DN(10)
AL47 GMI_CPU0_G1_CPU1_G3_TX_DN<9> G1_TXN9 @T6G_MB_LIB.T6G(SCH_1):GMI_CPU0_G1_CPU1_G3_TX_DN(9)
AJ47 GMI_CPU0_G1_CPU1_G3_TX_DN<8> G1_TXN8 @T6G_MB_LIB.T6G(SCH_1):GMI_CPU0_G1_CPU1_G3_TX_DN(8)
 U53 GMI_CPU1_G3_CPU0_G1_TX_DP<15> G1_RXP15 @T6G_MB_LIB.T6G(SCH_1):GMI_CPU1_G3_CPU0_G1_TX_DP(15)
 R53 GMI_CPU1_G3_CPU0_G1_TX_DP<14> G1_RXP14 @T6G_MB_LIB.T6G(SCH_1):GMI_CPU1_G3_CPU0_G1_TX_DP(14)
 W53 GMI_CPU1_G3_CPU0_G1_TX_DP<13> G1_RXP13 @T6G_MB_LIB.T6G(SCH_1):GMI_CPU1_G3_CPU0_G1_TX_DP(13)
 U50 GMI_CPU1_G3_CPU0_G1_TX_DP<12> G1_RXP12 @T6G_MB_LIB.T6G(SCH_1):GMI_CPU1_G3_CPU0_G1_TX_DP(12)
 R50 GMI_CPU1_G3_CPU0_G1_TX_DP<11> G1_RXP11 @T6G_MB_LIB.T6G(SCH_1):GMI_CPU1_G3_CPU0_G1_TX_DP(11)
 N50 GMI_CPU1_G3_CPU0_G1_TX_DP<10> G1_RXP10 @T6G_MB_LIB.T6G(SCH_1):GMI_CPU1_G3_CPU0_G1_TX_DP(10)
 W50 GMI_CPU1_G3_CPU0_G1_TX_DP<9> G1_RXP9 @T6G_MB_LIB.T6G(SCH_1):GMI_CPU1_G3_CPU0_G1_TX_DP(9)
 R47 GMI_CPU1_G3_CPU0_G1_TX_DP<8> G1_RXP8 @T6G_MB_LIB.T6G(SCH_1):GMI_CPU1_G3_CPU0_G1_TX_DP(8)
 U52 GMI_CPU1_G3_CPU0_G1_TX_DN<15> G1_RXN15 @T6G_MB_LIB.T6G(SCH_1):GMI_CPU1_G3_CPU0_G1_TX_DN(15)
 R52 GMI_CPU1_G3_CPU0_G1_TX_DN<14> G1_RXN14 @T6G_MB_LIB.T6G(SCH_1):GMI_CPU1_G3_CPU0_G1_TX_DN(14)
 W52 GMI_CPU1_G3_CPU0_G1_TX_DN<13> G1_RXN13 @T6G_MB_LIB.T6G(SCH_1):GMI_CPU1_G3_CPU0_G1_TX_DN(13)
 U49 GMI_CPU1_G3_CPU0_G1_TX_DN<12> G1_RXN12 @T6G_MB_LIB.T6G(SCH_1):GMI_CPU1_G3_CPU0_G1_TX_DN(12)
 R49 GMI_CPU1_G3_CPU0_G1_TX_DN<11> G1_RXN11 @T6G_MB_LIB.T6G(SCH_1):GMI_CPU1_G3_CPU0_G1_TX_DN(11)
 N49 GMI_CPU1_G3_CPU0_G1_TX_DN<10> G1_RXN10 @T6G_MB_LIB.T6G(SCH_1):GMI_CPU1_G3_CPU0_G1_TX_DN(10)
 W49 GMI_CPU1_G3_CPU0_G1_TX_DN<9> G1_RXN9 @T6G_MB_LIB.T6G(SCH_1):GMI_CPU1_G3_CPU0_G1_TX_DN(9)
 R46 GMI_CPU1_G3_CPU0_G1_TX_DN<8> G1_RXN8 @T6G_MB_LIB.T6G(SCH_1):GMI_CPU1_G3_CPU0_G1_TX_DN(8)
AP40 GMI_CPU0_G1_CPU1_G3_TX_DP<0> G1_TXP0 @T6G_MB_LIB.T6G(SCH_1):GMI_CPU0_G1_CPU1_G3_TX_DP(0)
AM40 GMI_CPU0_G1_CPU1_G3_TX_DP<1> G1_TXP1 @T6G_MB_LIB.T6G(SCH_1):GMI_CPU0_G1_CPU1_G3_TX_DP(1)
AH40 GMI_CPU0_G1_CPU1_G3_TX_DP<2> G1_TXP2 @T6G_MB_LIB.T6G(SCH_1):GMI_CPU0_G1_CPU1_G3_TX_DP(2)
AP41 GMI_CPU0_G1_CPU1_G3_TX_DN<0> G1_TXN0 @T6G_MB_LIB.T6G(SCH_1):GMI_CPU0_G1_CPU1_G3_TX_DN(0)
 V41 GMI_CPU1_G3_CPU0_G1_TX_DP<0> G1_RXP0 @T6G_MB_LIB.T6G(SCH_1):GMI_CPU1_G3_CPU0_G1_TX_DP(0)
AK40 GMI_CPU0_G1_CPU1_G3_TX_DP<3> G1_TXP3 @T6G_MB_LIB.T6G(SCH_1):GMI_CPU0_G1_CPU1_G3_TX_DP(3)
AM41 GMI_CPU0_G1_CPU1_G3_TX_DN<1> G1_TXN1 @T6G_MB_LIB.T6G(SCH_1):GMI_CPU0_G1_CPU1_G3_TX_DN(1)
 T41 GMI_CPU1_G3_CPU0_G1_TX_DP<1> G1_RXP1 @T6G_MB_LIB.T6G(SCH_1):GMI_CPU1_G3_CPU0_G1_TX_DP(1)
AN43 GMI_CPU0_G1_CPU1_G3_TX_DP<4> G1_TXP4 @T6G_MB_LIB.T6G(SCH_1):GMI_CPU0_G1_CPU1_G3_TX_DP(4)
AH41 GMI_CPU0_G1_CPU1_G3_TX_DN<2> G1_TXN2 @T6G_MB_LIB.T6G(SCH_1):GMI_CPU0_G1_CPU1_G3_TX_DN(2)
 P41 GMI_CPU1_G3_CPU0_G1_TX_DP<2> G1_RXP2 @T6G_MB_LIB.T6G(SCH_1):GMI_CPU1_G3_CPU0_G1_TX_DP(2)
 V40 GMI_CPU1_G3_CPU0_G1_TX_DN<0> G1_RXN0 @T6G_MB_LIB.T6G(SCH_1):GMI_CPU1_G3_CPU0_G1_TX_DN(0)
AJ43 GMI_CPU0_G1_CPU1_G3_TX_DP<5> G1_TXP5 @T6G_MB_LIB.T6G(SCH_1):GMI_CPU0_G1_CPU1_G3_TX_DP(5)
AK41 GMI_CPU0_G1_CPU1_G3_TX_DN<3> G1_TXN3 @T6G_MB_LIB.T6G(SCH_1):GMI_CPU0_G1_CPU1_G3_TX_DN(3)
 U44 GMI_CPU1_G3_CPU0_G1_TX_DP<3> G1_RXP3 @T6G_MB_LIB.T6G(SCH_1):GMI_CPU1_G3_CPU0_G1_TX_DP(3)
 T40 GMI_CPU1_G3_CPU0_G1_TX_DN<1> G1_RXN1 @T6G_MB_LIB.T6G(SCH_1):GMI_CPU1_G3_CPU0_G1_TX_DN(1)
AL43 GMI_CPU0_G1_CPU1_G3_TX_DP<6> G1_TXP6 @T6G_MB_LIB.T6G(SCH_1):GMI_CPU0_G1_CPU1_G3_TX_DP(6)
AN44 GMI_CPU0_G1_CPU1_G3_TX_DN<4> G1_TXN4 @T6G_MB_LIB.T6G(SCH_1):GMI_CPU0_G1_CPU1_G3_TX_DN(4)
 N44 GMI_CPU1_G3_CPU0_G1_TX_DP<4> G1_RXP4 @T6G_MB_LIB.T6G(SCH_1):GMI_CPU1_G3_CPU0_G1_TX_DP(4)
 P40 GMI_CPU1_G3_CPU0_G1_TX_DN<2> G1_RXN2 @T6G_MB_LIB.T6G(SCH_1):GMI_CPU1_G3_CPU0_G1_TX_DN(2)
AN46 GMI_CPU0_G1_CPU1_G3_TX_DP<7> G1_TXP7 @T6G_MB_LIB.T6G(SCH_1):GMI_CPU0_G1_CPU1_G3_TX_DP(7)
AJ44 GMI_CPU0_G1_CPU1_G3_TX_DN<5> G1_TXN5 @T6G_MB_LIB.T6G(SCH_1):GMI_CPU0_G1_CPU1_G3_TX_DN(5)
 R44 GMI_CPU1_G3_CPU0_G1_TX_DP<5> G1_RXP5 @T6G_MB_LIB.T6G(SCH_1):GMI_CPU1_G3_CPU0_G1_TX_DP(5)
 U43 GMI_CPU1_G3_CPU0_G1_TX_DN<3> G1_RXN3 @T6G_MB_LIB.T6G(SCH_1):GMI_CPU1_G3_CPU0_G1_TX_DN(3)
AL44 GMI_CPU0_G1_CPU1_G3_TX_DN<6> G1_TXN6 @T6G_MB_LIB.T6G(SCH_1):GMI_CPU0_G1_CPU1_G3_TX_DN(6)
 U47 GMI_CPU1_G3_CPU0_G1_TX_DP<6> G1_RXP6 @T6G_MB_LIB.T6G(SCH_1):GMI_CPU1_G3_CPU0_G1_TX_DP(6)
 N43 GMI_CPU1_G3_CPU0_G1_TX_DN<4> G1_RXN4 @T6G_MB_LIB.T6G(SCH_1):GMI_CPU1_G3_CPU0_G1_TX_DN(4)
AN47 GMI_CPU0_G1_CPU1_G3_TX_DN<7> G1_TXN7 @T6G_MB_LIB.T6G(SCH_1):GMI_CPU0_G1_CPU1_G3_TX_DN(7)
 N47 GMI_CPU1_G3_CPU0_G1_TX_DP<7> G1_RXP7 @T6G_MB_LIB.T6G(SCH_1):GMI_CPU1_G3_CPU0_G1_TX_DP(7)
 R43 GMI_CPU1_G3_CPU0_G1_TX_DN<5> G1_RXN5 @T6G_MB_LIB.T6G(SCH_1):GMI_CPU1_G3_CPU0_G1_TX_DN(5)
 U46 GMI_CPU1_G3_CPU0_G1_TX_DN<6> G1_RXN6 @T6G_MB_LIB.T6G(SCH_1):GMI_CPU1_G3_CPU0_G1_TX_DN(6)
 N46 GMI_CPU1_G3_CPU0_G1_TX_DN<7> G1_RXN7 @T6G_MB_LIB.T6G(SCH_1):GMI_CPU1_G3_CPU0_G1_TX_DN(7)


DRAWING: @T6G_MB_LIB.T6G(SCH_1):PAGE23 

GENOA_SP5-SOCKET6096_13568-001,SMLF,IO,DGA^6000030  I215  U25
 G29 GMI_CPU0_G2_CPU1_G0_TX_DP<8> G2_TXP8 @T6G_MB_LIB.T6G(SCH_1):GMI_CPU0_G2_CPU1_G0_TX_DP(8)
 G30 GMI_CPU0_G2_CPU1_G0_TX_DN<8> G2_TXN8 @T6G_MB_LIB.T6G(SCH_1):GMI_CPU0_G2_CPU1_G0_TX_DN(8)
 J32 GMI_CPU0_G2_CPU1_G0_TX_DP<10> G2_TXP10 @T6G_MB_LIB.T6G(SCH_1):GMI_CPU0_G2_CPU1_G0_TX_DP(10)
 J33 GMI_CPU0_G2_CPU1_G0_TX_DN<10> G2_TXN10 @T6G_MB_LIB.T6G(SCH_1):GMI_CPU0_G2_CPU1_G0_TX_DN(10)
 L32 GMI_CPU0_G2_CPU1_G0_TX_DP<12> G2_TXP12 @T6G_MB_LIB.T6G(SCH_1):GMI_CPU0_G2_CPU1_G0_TX_DP(12)
 L33 GMI_CPU0_G2_CPU1_G0_TX_DN<12> G2_TXN12 @T6G_MB_LIB.T6G(SCH_1):GMI_CPU0_G2_CPU1_G0_TX_DN(12)
 K35 GMI_CPU0_G2_CPU1_G0_TX_DP<14> G2_TXP14 @T6G_MB_LIB.T6G(SCH_1):GMI_CPU0_G2_CPU1_G0_TX_DP(14)
 K36 GMI_CPU0_G2_CPU1_G0_TX_DN<14> G2_TXN14 @T6G_MB_LIB.T6G(SCH_1):GMI_CPU0_G2_CPU1_G0_TX_DN(14)
 L29 GMI_CPU0_G2_CPU1_G0_TX_DP<9> G2_TXP9 @T6G_MB_LIB.T6G(SCH_1):GMI_CPU0_G2_CPU1_G0_TX_DP(9)
 L30 GMI_CPU0_G2_CPU1_G0_TX_DN<9> G2_TXN9 @T6G_MB_LIB.T6G(SCH_1):GMI_CPU0_G2_CPU1_G0_TX_DN(9)
 G32 GMI_CPU0_G2_CPU1_G0_TX_DP<11> G2_TXP11 @T6G_MB_LIB.T6G(SCH_1):GMI_CPU0_G2_CPU1_G0_TX_DP(11)
 G33 GMI_CPU0_G2_CPU1_G0_TX_DN<11> G2_TXN11 @T6G_MB_LIB.T6G(SCH_1):GMI_CPU0_G2_CPU1_G0_TX_DN(11)
 H35 GMI_CPU0_G2_CPU1_G0_TX_DP<13> G2_TXP13 @T6G_MB_LIB.T6G(SCH_1):GMI_CPU0_G2_CPU1_G0_TX_DP(13)
 H36 GMI_CPU0_G2_CPU1_G0_TX_DN<13> G2_TXN13 @T6G_MB_LIB.T6G(SCH_1):GMI_CPU0_G2_CPU1_G0_TX_DN(13)
 M35 GMI_CPU0_G2_CPU1_G0_TX_DP<15> G2_TXP15 @T6G_MB_LIB.T6G(SCH_1):GMI_CPU0_G2_CPU1_G0_TX_DP(15)
 M36 GMI_CPU0_G2_CPU1_G0_TX_DN<15> G2_TXN15 @T6G_MB_LIB.T6G(SCH_1):GMI_CPU0_G2_CPU1_G0_TX_DN(15)
AG30 GMI_CPU1_G0_CPU0_G2_TX_DP<8> G2_RXP8 @T6G_MB_LIB.T6G(SCH_1):GMI_CPU1_G0_CPU0_G2_TX_DP(8)
AG29 GMI_CPU1_G0_CPU0_G2_TX_DN<8> G2_RXN8 @T6G_MB_LIB.T6G(SCH_1):GMI_CPU1_G0_CPU0_G2_TX_DN(8)
AC33 GMI_CPU1_G0_CPU0_G2_TX_DP<10> G2_RXP10 @T6G_MB_LIB.T6G(SCH_1):GMI_CPU1_G0_CPU0_G2_TX_DP(10)
AC32 GMI_CPU1_G0_CPU0_G2_TX_DN<10> G2_RXN10 @T6G_MB_LIB.T6G(SCH_1):GMI_CPU1_G0_CPU0_G2_TX_DN(10)
AG33 GMI_CPU1_G0_CPU0_G2_TX_DP<12> G2_RXP12 @T6G_MB_LIB.T6G(SCH_1):GMI_CPU1_G0_CPU0_G2_TX_DP(12)
AG32 GMI_CPU1_G0_CPU0_G2_TX_DN<12> G2_RXN12 @T6G_MB_LIB.T6G(SCH_1):GMI_CPU1_G0_CPU0_G2_TX_DN(12)
AD36 GMI_CPU1_G0_CPU0_G2_TX_DP<14> G2_RXP14 @T6G_MB_LIB.T6G(SCH_1):GMI_CPU1_G0_CPU0_G2_TX_DP(14)
AD35 GMI_CPU1_G0_CPU0_G2_TX_DN<14> G2_RXN14 @T6G_MB_LIB.T6G(SCH_1):GMI_CPU1_G0_CPU0_G2_TX_DN(14)
AE33 GMI_CPU1_G0_CPU0_G2_TX_DP<9> G2_RXP9 @T6G_MB_LIB.T6G(SCH_1):GMI_CPU1_G0_CPU0_G2_TX_DP(9)
AE32 GMI_CPU1_G0_CPU0_G2_TX_DN<9> G2_RXN9 @T6G_MB_LIB.T6G(SCH_1):GMI_CPU1_G0_CPU0_G2_TX_DN(9)
AA33 GMI_CPU1_G0_CPU0_G2_TX_DP<11> G2_RXP11 @T6G_MB_LIB.T6G(SCH_1):GMI_CPU1_G0_CPU0_G2_TX_DP(11)
AA32 GMI_CPU1_G0_CPU0_G2_TX_DN<11> G2_RXN11 @T6G_MB_LIB.T6G(SCH_1):GMI_CPU1_G0_CPU0_G2_TX_DN(11)
AB36 GMI_CPU1_G0_CPU0_G2_TX_DP<13> G2_RXP13 @T6G_MB_LIB.T6G(SCH_1):GMI_CPU1_G0_CPU0_G2_TX_DP(13)
AB35 GMI_CPU1_G0_CPU0_G2_TX_DN<13> G2_RXN13 @T6G_MB_LIB.T6G(SCH_1):GMI_CPU1_G0_CPU0_G2_TX_DN(13)
AF36 GMI_CPU1_G0_CPU0_G2_TX_DP<15> G2_RXP15 @T6G_MB_LIB.T6G(SCH_1):GMI_CPU1_G0_CPU0_G2_TX_DP(15)
AF35 GMI_CPU1_G0_CPU0_G2_TX_DN<15> G2_RXN15 @T6G_MB_LIB.T6G(SCH_1):GMI_CPU1_G0_CPU0_G2_TX_DN(15)
 J23 GMI_CPU0_G2_CPU1_G0_TX_DP<1> G2_TXP1 @T6G_MB_LIB.T6G(SCH_1):GMI_CPU0_G2_CPU1_G0_TX_DP(1)
 G23 GMI_CPU0_G2_CPU1_G0_TX_DP<2> G2_TXP2 @T6G_MB_LIB.T6G(SCH_1):GMI_CPU0_G2_CPU1_G0_TX_DP(2)
 N24 GMI_CPU0_G2_CPU1_G0_TX_DN<0> G2_TXN0 @T6G_MB_LIB.T6G(SCH_1):GMI_CPU0_G2_CPU1_G0_TX_DN(0)
AE24 GMI_CPU1_G0_CPU0_G2_TX_DP<0> G2_RXP0 @T6G_MB_LIB.T6G(SCH_1):GMI_CPU1_G0_CPU0_G2_TX_DP(0)
 L23 GMI_CPU0_G2_CPU1_G0_TX_DP<3> G2_TXP3 @T6G_MB_LIB.T6G(SCH_1):GMI_CPU0_G2_CPU1_G0_TX_DP(3)
 J24 GMI_CPU0_G2_CPU1_G0_TX_DN<1> G2_TXN1 @T6G_MB_LIB.T6G(SCH_1):GMI_CPU0_G2_CPU1_G0_TX_DN(1)
AC24 GMI_CPU1_G0_CPU0_G2_TX_DP<1> G2_RXP1 @T6G_MB_LIB.T6G(SCH_1):GMI_CPU1_G0_CPU0_G2_TX_DP(1)
 J26 GMI_CPU0_G2_CPU1_G0_TX_DP<4> G2_TXP4 @T6G_MB_LIB.T6G(SCH_1):GMI_CPU0_G2_CPU1_G0_TX_DP(4)
 G24 GMI_CPU0_G2_CPU1_G0_TX_DN<2> G2_TXN2 @T6G_MB_LIB.T6G(SCH_1):GMI_CPU0_G2_CPU1_G0_TX_DN(2)
AG24 GMI_CPU1_G0_CPU0_G2_TX_DP<2> G2_RXP2 @T6G_MB_LIB.T6G(SCH_1):GMI_CPU1_G0_CPU0_G2_TX_DP(2)
AE23 GMI_CPU1_G0_CPU0_G2_TX_DN<0> G2_RXN0 @T6G_MB_LIB.T6G(SCH_1):GMI_CPU1_G0_CPU0_G2_TX_DN(0)
 G26 GMI_CPU0_G2_CPU1_G0_TX_DP<5> G2_TXP5 @T6G_MB_LIB.T6G(SCH_1):GMI_CPU0_G2_CPU1_G0_TX_DP(5)
 L24 GMI_CPU0_G2_CPU1_G0_TX_DN<3> G2_TXN3 @T6G_MB_LIB.T6G(SCH_1):GMI_CPU0_G2_CPU1_G0_TX_DN(3)
AE27 GMI_CPU1_G0_CPU0_G2_TX_DP<3> G2_RXP3 @T6G_MB_LIB.T6G(SCH_1):GMI_CPU1_G0_CPU0_G2_TX_DP(3)
AC23 GMI_CPU1_G0_CPU0_G2_TX_DN<1> G2_RXN1 @T6G_MB_LIB.T6G(SCH_1):GMI_CPU1_G0_CPU0_G2_TX_DN(1)
 L26 GMI_CPU0_G2_CPU1_G0_TX_DP<6> G2_TXP6 @T6G_MB_LIB.T6G(SCH_1):GMI_CPU0_G2_CPU1_G0_TX_DP(6)
 J27 GMI_CPU0_G2_CPU1_G0_TX_DN<4> G2_TXN4 @T6G_MB_LIB.T6G(SCH_1):GMI_CPU0_G2_CPU1_G0_TX_DN(4)
AC27 GMI_CPU1_G0_CPU0_G2_TX_DP<4> G2_RXP4 @T6G_MB_LIB.T6G(SCH_1):GMI_CPU1_G0_CPU0_G2_TX_DP(4)
AG23 GMI_CPU1_G0_CPU0_G2_TX_DN<2> G2_RXN2 @T6G_MB_LIB.T6G(SCH_1):GMI_CPU1_G0_CPU0_G2_TX_DN(2)
 J29 GMI_CPU0_G2_CPU1_G0_TX_DP<7> G2_TXP7 @T6G_MB_LIB.T6G(SCH_1):GMI_CPU0_G2_CPU1_G0_TX_DP(7)
 G27 GMI_CPU0_G2_CPU1_G0_TX_DN<5> G2_TXN5 @T6G_MB_LIB.T6G(SCH_1):GMI_CPU0_G2_CPU1_G0_TX_DN(5)
AG27 GMI_CPU1_G0_CPU0_G2_TX_DP<5> G2_RXP5 @T6G_MB_LIB.T6G(SCH_1):GMI_CPU1_G0_CPU0_G2_TX_DP(5)
AE26 GMI_CPU1_G0_CPU0_G2_TX_DN<3> G2_RXN3 @T6G_MB_LIB.T6G(SCH_1):GMI_CPU1_G0_CPU0_G2_TX_DN(3)
 L27 GMI_CPU0_G2_CPU1_G0_TX_DN<6> G2_TXN6 @T6G_MB_LIB.T6G(SCH_1):GMI_CPU0_G2_CPU1_G0_TX_DN(6)
AE30 GMI_CPU1_G0_CPU0_G2_TX_DP<6> G2_RXP6 @T6G_MB_LIB.T6G(SCH_1):GMI_CPU1_G0_CPU0_G2_TX_DP(6)
AC26 GMI_CPU1_G0_CPU0_G2_TX_DN<4> G2_RXN4 @T6G_MB_LIB.T6G(SCH_1):GMI_CPU1_G0_CPU0_G2_TX_DN(4)
 J30 GMI_CPU0_G2_CPU1_G0_TX_DN<7> G2_TXN7 @T6G_MB_LIB.T6G(SCH_1):GMI_CPU0_G2_CPU1_G0_TX_DN(7)
AC30 GMI_CPU1_G0_CPU0_G2_TX_DP<7> G2_RXP7 @T6G_MB_LIB.T6G(SCH_1):GMI_CPU1_G0_CPU0_G2_TX_DP(7)
AG26 GMI_CPU1_G0_CPU0_G2_TX_DN<5> G2_RXN5 @T6G_MB_LIB.T6G(SCH_1):GMI_CPU1_G0_CPU0_G2_TX_DN(5)
AE29 GMI_CPU1_G0_CPU0_G2_TX_DN<6> G2_RXN6 @T6G_MB_LIB.T6G(SCH_1):GMI_CPU1_G0_CPU0_G2_TX_DN(6)
AC29 GMI_CPU1_G0_CPU0_G2_TX_DN<7> G2_RXN7 @T6G_MB_LIB.T6G(SCH_1):GMI_CPU1_G0_CPU0_G2_TX_DN(7)
 N23 GMI_CPU0_G2_CPU1_G0_TX_DP<0> G2_TXP0 @T6G_MB_LIB.T6G(SCH_1):GMI_CPU0_G2_CPU1_G0_TX_DP(0)

GENOA_SP5-SOCKET6096_13568-001,SMLF,IO,DGA^6000030  I216  U25
 P35 P5E_CPU0_G3_TX_DP<13> G3_TXP13||SATA35_TXP @T6G_MB_LIB.T6G(SCH_1):P5E_CPU0_G3_TX_DP(13)
 R32 P5E_CPU0_G3_TX_DP<10> G3_TXP10||SATA32_TXP @T6G_MB_LIB.T6G(SCH_1):P5E_CPU0_G3_TX_DP(10)
AN26 P5E_CPU0_G3_RX_DN<5> G3_RXN5||SATA25_RXN @T6G_MB_LIB.T6G(SCH_1):P5E_CPU0_G3_RX_DN(5)
 W24 P5E_CPU0_G3_TX_DN<2> G3_TXN2||SATA22_TXN @T6G_MB_LIB.T6G(SCH_1):P5E_CPU0_G3_TX_DN(2)
AK36 P5E_CPU0_G3_RX_DP<12> G3_RXP12||SATA34_RXP @T6G_MB_LIB.T6G(SCH_1):P5E_CPU0_G3_RX_DP(12)
AL24 P5E_CPU0_G3_RX_DP<0> G3_RXP0||SATA20_RXP @T6G_MB_LIB.T6G(SCH_1):P5E_CPU0_G3_RX_DP(0)
 T36 P5E_CPU0_G3_TX_DN<14> G3_TXN14||SATA36_TXN @T6G_MB_LIB.T6G(SCH_1):P5E_CPU0_G3_TX_DN(14)
 N33 P5E_CPU0_G3_TX_DN<11> G3_TXN11||SATA33_TXN @T6G_MB_LIB.T6G(SCH_1):P5E_CPU0_G3_TX_DN(11)
 N27 P5E_CPU0_G3_TX_DN<5> G3_TXN5||SATA25_TXN @T6G_MB_LIB.T6G(SCH_1):P5E_CPU0_G3_TX_DN(5)
AP36 P5E_CPU0_G3_RX_DP<15> G3_RXP15||SATA37_RXP @T6G_MB_LIB.T6G(SCH_1):P5E_CPU0_G3_RX_DP(15)
AL30 P5E_CPU0_G3_RX_DP<6> G3_RXP6||SATA26_RXP @T6G_MB_LIB.T6G(SCH_1):P5E_CPU0_G3_RX_DP(6)
AL27 P5E_CPU0_G3_RX_DP<3> G3_RXP3||SATA23_RXP @T6G_MB_LIB.T6G(SCH_1):P5E_CPU0_G3_RX_DP(3)
 U26 P5E_CPU0_G3_TX_DP<3> G3_TXP3||SATA23_TXP @T6G_MB_LIB.T6G(SCH_1):P5E_CPU0_G3_TX_DP(3)
 U23 P5E_CPU0_G3_TX_DP<0> G3_TXP0||SATA20_TXP @T6G_MB_LIB.T6G(SCH_1):P5E_CPU0_G3_TX_DP(0)
AJ32 P5E_CPU0_G3_RX_DN<10> G3_RXN10||SATA32_RXN @T6G_MB_LIB.T6G(SCH_1):P5E_CPU0_G3_RX_DN(10)
 W26 P5E_CPU0_G3_TX_DP<6> G3_TXP6||SATA26_TXP @T6G_MB_LIB.T6G(SCH_1):P5E_CPU0_G3_TX_DP(6)
AH35 P5E_CPU0_G3_RX_DN<13> G3_RXN13||SATA35_RXN @T6G_MB_LIB.T6G(SCH_1):P5E_CPU0_G3_RX_DN(13)
 N32 P5E_CPU0_G3_TX_DP<11> G3_TXP11||SATA33_TXP @T6G_MB_LIB.T6G(SCH_1):P5E_CPU0_G3_TX_DP(11)
AN30 P5E_CPU0_G3_RX_DP<8> G3_RXP8||SATA30_RXP @T6G_MB_LIB.T6G(SCH_1):P5E_CPU0_G3_RX_DP(8)
AL26 P5E_CPU0_G3_RX_DN<3> G3_RXN3||SATA23_RXN @T6G_MB_LIB.T6G(SCH_1):P5E_CPU0_G3_RX_DN(3)
AL23 P5E_CPU0_G3_RX_DN<0> G3_RXN0||SATA20_RXN @T6G_MB_LIB.T6G(SCH_1):P5E_CPU0_G3_RX_DN(0)
 T35 P5E_CPU0_G3_TX_DP<14> G3_TXP14||SATA36_TXP @T6G_MB_LIB.T6G(SCH_1):P5E_CPU0_G3_TX_DP(14)
 N29 P5E_CPU0_G3_TX_DP<8> G3_TXP8||SATA30_TXP @T6G_MB_LIB.T6G(SCH_1):P5E_CPU0_G3_TX_DP(8)
 U24 P5E_CPU0_G3_TX_DN<0> G3_TXN0||SATA20_TXN @T6G_MB_LIB.T6G(SCH_1):P5E_CPU0_G3_TX_DN(0)
AL29 P5E_CPU0_G3_RX_DN<6> G3_RXN6||SATA26_RXN @T6G_MB_LIB.T6G(SCH_1):P5E_CPU0_G3_RX_DN(6)
 W27 P5E_CPU0_G3_TX_DN<6> G3_TXN6||SATA26_TXN @T6G_MB_LIB.T6G(SCH_1):P5E_CPU0_G3_TX_DN(6)
 U27 P5E_CPU0_G3_TX_DN<3> G3_TXN3||SATA23_TXN @T6G_MB_LIB.T6G(SCH_1):P5E_CPU0_G3_TX_DN(3)
AH36 P5E_CPU0_G3_RX_DP<13> G3_RXP13||SATA35_RXP @T6G_MB_LIB.T6G(SCH_1):P5E_CPU0_G3_RX_DP(13)
AJ33 P5E_CPU0_G3_RX_DP<10> G3_RXP10||SATA32_RXP @T6G_MB_LIB.T6G(SCH_1):P5E_CPU0_G3_RX_DP(10)
AJ27 P5E_CPU0_G3_RX_DP<4> G3_RXP4||SATA24_RXP @T6G_MB_LIB.T6G(SCH_1):P5E_CPU0_G3_RX_DP(4)
AJ24 P5E_CPU0_G3_RX_DP<1> G3_RXP1||SATA21_RXP @T6G_MB_LIB.T6G(SCH_1):P5E_CPU0_G3_RX_DP(1)
 V36 P5E_CPU0_G3_TX_DN<15> G3_TXN15||SATA37_TXN @T6G_MB_LIB.T6G(SCH_1):P5E_CPU0_G3_TX_DN(15)
 U33 P5E_CPU0_G3_TX_DN<12> G3_TXN12||SATA34_TXN @T6G_MB_LIB.T6G(SCH_1):P5E_CPU0_G3_TX_DN(12)
AN29 P5E_CPU0_G3_RX_DN<8> G3_RXN8||SATA30_RXN @T6G_MB_LIB.T6G(SCH_1):P5E_CPU0_G3_RX_DN(8)
AJ30 P5E_CPU0_G3_RX_DP<7> G3_RXP7||SATA27_RXP @T6G_MB_LIB.T6G(SCH_1):P5E_CPU0_G3_RX_DP(7)
 R26 P5E_CPU0_G3_TX_DP<4> G3_TXP4||SATA24_TXP @T6G_MB_LIB.T6G(SCH_1):P5E_CPU0_G3_TX_DP(4)
 R23 P5E_CPU0_G3_TX_DP<1> G3_TXP1||SATA21_TXP @T6G_MB_LIB.T6G(SCH_1):P5E_CPU0_G3_TX_DP(1)
AM35 P5E_CPU0_G3_RX_DN<14> G3_RXN14||SATA36_RXN @T6G_MB_LIB.T6G(SCH_1):P5E_CPU0_G3_RX_DN(14)
AN32 P5E_CPU0_G3_RX_DN<11> G3_RXN11||SATA33_RXN @T6G_MB_LIB.T6G(SCH_1):P5E_CPU0_G3_RX_DN(11)
 N30 P5E_CPU0_G3_TX_DN<8> G3_TXN8||SATA30_TXN @T6G_MB_LIB.T6G(SCH_1):P5E_CPU0_G3_TX_DN(8)
 R29 P5E_CPU0_G3_TX_DP<7> G3_TXP7||SATA27_TXP @T6G_MB_LIB.T6G(SCH_1):P5E_CPU0_G3_TX_DP(7)
AL33 P5E_CPU0_G3_RX_DP<9> G3_RXP9||SATA31_RXP @T6G_MB_LIB.T6G(SCH_1):P5E_CPU0_G3_RX_DP(9)
 U32 P5E_CPU0_G3_TX_DP<12> G3_TXP12||SATA34_TXP @T6G_MB_LIB.T6G(SCH_1):P5E_CPU0_G3_TX_DP(12)
AJ29 P5E_CPU0_G3_RX_DN<7> G3_RXN7||SATA27_RXN @T6G_MB_LIB.T6G(SCH_1):P5E_CPU0_G3_RX_DN(7)
AJ26 P5E_CPU0_G3_RX_DN<4> G3_RXN4||SATA24_RXN @T6G_MB_LIB.T6G(SCH_1):P5E_CPU0_G3_RX_DN(4)
AJ23 P5E_CPU0_G3_RX_DN<1> G3_RXN1||SATA21_RXN @T6G_MB_LIB.T6G(SCH_1):P5E_CPU0_G3_RX_DN(1)
 V35 P5E_CPU0_G3_TX_DP<15> G3_TXP15||SATA37_TXP @T6G_MB_LIB.T6G(SCH_1):P5E_CPU0_G3_TX_DP(15)
 U29 P5E_CPU0_G3_TX_DP<9> G3_TXP9||SATA31_TXP @T6G_MB_LIB.T6G(SCH_1):P5E_CPU0_G3_TX_DP(9)
 R24 P5E_CPU0_G3_TX_DN<1> G3_TXN1||SATA21_TXN @T6G_MB_LIB.T6G(SCH_1):P5E_CPU0_G3_TX_DN(1)
AN33 P5E_CPU0_G3_RX_DP<11> G3_RXP11||SATA33_RXP @T6G_MB_LIB.T6G(SCH_1):P5E_CPU0_G3_RX_DP(11)
 P36 P5E_CPU0_G3_TX_DN<13> G3_TXN13||SATA35_TXN @T6G_MB_LIB.T6G(SCH_1):P5E_CPU0_G3_TX_DN(13)
 R33 P5E_CPU0_G3_TX_DN<10> G3_TXN10||SATA32_TXN @T6G_MB_LIB.T6G(SCH_1):P5E_CPU0_G3_TX_DN(10)
 R30 P5E_CPU0_G3_TX_DN<7> G3_TXN7||SATA27_TXN @T6G_MB_LIB.T6G(SCH_1):P5E_CPU0_G3_TX_DN(7)
 R27 P5E_CPU0_G3_TX_DN<4> G3_TXN4||SATA24_TXN @T6G_MB_LIB.T6G(SCH_1):P5E_CPU0_G3_TX_DN(4)
AM36 P5E_CPU0_G3_RX_DP<14> G3_RXP14||SATA36_RXP @T6G_MB_LIB.T6G(SCH_1):P5E_CPU0_G3_RX_DP(14)
AN27 P5E_CPU0_G3_RX_DP<5> G3_RXP5||SATA25_RXP @T6G_MB_LIB.T6G(SCH_1):P5E_CPU0_G3_RX_DP(5)
AN24 P5E_CPU0_G3_RX_DP<2> G3_RXP2||SATA22_RXP @T6G_MB_LIB.T6G(SCH_1):P5E_CPU0_G3_RX_DP(2)
 W23 P5E_CPU0_G3_TX_DP<2> G3_TXP2||SATA22_TXP @T6G_MB_LIB.T6G(SCH_1):P5E_CPU0_G3_TX_DP(2)
AL32 P5E_CPU0_G3_RX_DN<9> G3_RXN9||SATA31_RXN @T6G_MB_LIB.T6G(SCH_1):P5E_CPU0_G3_RX_DN(9)
 N26 P5E_CPU0_G3_TX_DP<5> G3_TXP5||SATA25_TXP @T6G_MB_LIB.T6G(SCH_1):P5E_CPU0_G3_TX_DP(5)
AP35 P5E_CPU0_G3_RX_DN<15> G3_RXN15||SATA37_RXN @T6G_MB_LIB.T6G(SCH_1):P5E_CPU0_G3_RX_DN(15)
AK35 P5E_CPU0_G3_RX_DN<12> G3_RXN12||SATA34_RXN @T6G_MB_LIB.T6G(SCH_1):P5E_CPU0_G3_RX_DN(12)
 U30 P5E_CPU0_G3_TX_DN<9> G3_TXN9||SATA31_TXN @T6G_MB_LIB.T6G(SCH_1):P5E_CPU0_G3_TX_DN(9)
AN23 P5E_CPU0_G3_RX_DN<2> G3_RXN2||SATA22_RXN @T6G_MB_LIB.T6G(SCH_1):P5E_CPU0_G3_RX_DN(2)


DRAWING: @T6G_MB_LIB.T6G(SCH_1):PAGE24 

GENOA_SP5-SOCKET6096_13568-001,SMLF,IO,DGA^6000030  I148  U25
BW53 P5E_CPU0_P0_RX_DN<0> P0_RXN0||SATA00_RXN @T6G_MB_LIB.T6G(SCH_1):P5E_CPU0_P0_RX_DN(0)
BW47 P5E_CPU0_P0_RX_DN<6> P0_RXN6||SATA06_RXN @T6G_MB_LIB.T6G(SCH_1):P5E_CPU0_P0_RX_DN(6)
BW50 P5E_CPU0_P0_RX_DN<3> P0_RXN3||SATA03_RXN @T6G_MB_LIB.T6G(SCH_1):P5E_CPU0_P0_RX_DN(3)
CN49 P5E_CPU0_P0_TX_DN<3> P0_TXN3||SATA03_TXN @T6G_MB_LIB.T6G(SCH_1):P5E_CPU0_P0_TX_DN(3)
CN52 P5E_CPU0_P0_TX_DN<0> P0_TXN0||SATA00_TXN @T6G_MB_LIB.T6G(SCH_1):P5E_CPU0_P0_TX_DN(0)
CA52 P5E_CPU0_P0_RX_DP<1> P0_RXP1||SATA01_RXP @T6G_MB_LIB.T6G(SCH_1):P5E_CPU0_P0_RX_DP(1)
CL49 P5E_CPU0_P0_TX_DN<6> P0_TXN6||SATA06_TXN @T6G_MB_LIB.T6G(SCH_1):P5E_CPU0_P0_TX_DN(6)
CA46 P5E_CPU0_P0_RX_DP<7> P0_RXP7||SATA07_RXP @T6G_MB_LIB.T6G(SCH_1):P5E_CPU0_P0_RX_DP(7)
CA49 P5E_CPU0_P0_RX_DP<4> P0_RXP4||SATA04_RXP @T6G_MB_LIB.T6G(SCH_1):P5E_CPU0_P0_RX_DP(4)
CR50 P5E_CPU0_P0_TX_DP<4> P0_TXP4||SATA04_TXP @T6G_MB_LIB.T6G(SCH_1):P5E_CPU0_P0_TX_DP(4)
CR53 P5E_CPU0_P0_TX_DP<1> P0_TXP1||SATA01_TXP @T6G_MB_LIB.T6G(SCH_1):P5E_CPU0_P0_TX_DP(1)
CR47 P5E_CPU0_P0_TX_DP<7> P0_TXP7||SATA07_TXP @T6G_MB_LIB.T6G(SCH_1):P5E_CPU0_P0_TX_DP(7)
CA50 P5E_CPU0_P0_RX_DN<4> P0_RXN4||SATA04_RXN @T6G_MB_LIB.T6G(SCH_1):P5E_CPU0_P0_RX_DN(4)
CA53 P5E_CPU0_P0_RX_DN<1> P0_RXN1||SATA01_RXN @T6G_MB_LIB.T6G(SCH_1):P5E_CPU0_P0_RX_DN(1)
CA47 P5E_CPU0_P0_RX_DN<7> P0_RXN7||SATA07_RXN @T6G_MB_LIB.T6G(SCH_1):P5E_CPU0_P0_RX_DN(7)
CR49 P5E_CPU0_P0_TX_DN<4> P0_TXN4||SATA04_TXN @T6G_MB_LIB.T6G(SCH_1):P5E_CPU0_P0_TX_DN(4)
CR46 P5E_CPU0_P0_TX_DN<7> P0_TXN7||SATA07_TXN @T6G_MB_LIB.T6G(SCH_1):P5E_CPU0_P0_TX_DN(7)
CR52 P5E_CPU0_P0_TX_DN<1> P0_TXN1||SATA01_TXN @T6G_MB_LIB.T6G(SCH_1):P5E_CPU0_P0_TX_DN(1)
BU52 P5E_CPU0_P0_RX_DP<2> P0_RXP2||SATA02_RXP @T6G_MB_LIB.T6G(SCH_1):P5E_CPU0_P0_RX_DP(2)
BU49 P5E_CPU0_P0_RX_DP<5> P0_RXP5||SATA05_RXP @T6G_MB_LIB.T6G(SCH_1):P5E_CPU0_P0_RX_DP(5)
CU50 P5E_CPU0_P0_TX_DP<5> P0_TXP5||SATA05_TXP @T6G_MB_LIB.T6G(SCH_1):P5E_CPU0_P0_TX_DP(5)
CL53 P5E_CPU0_P0_TX_DP<2> P0_TXP2||SATA02_TXP @T6G_MB_LIB.T6G(SCH_1):P5E_CPU0_P0_TX_DP(2)
BU50 P5E_CPU0_P0_RX_DN<5> P0_RXN5||SATA05_RXN @T6G_MB_LIB.T6G(SCH_1):P5E_CPU0_P0_RX_DN(5)
BU53 P5E_CPU0_P0_RX_DN<2> P0_RXN2||SATA02_RXN @T6G_MB_LIB.T6G(SCH_1):P5E_CPU0_P0_RX_DN(2)
CL52 P5E_CPU0_P0_TX_DN<2> P0_TXN2||SATA02_TXN @T6G_MB_LIB.T6G(SCH_1):P5E_CPU0_P0_TX_DN(2)
BW52 P5E_CPU0_P0_RX_DP<0> P0_RXP0||SATA00_RXP @T6G_MB_LIB.T6G(SCH_1):P5E_CPU0_P0_RX_DP(0)
CU49 P5E_CPU0_P0_TX_DN<5> P0_TXN5||SATA05_TXN @T6G_MB_LIB.T6G(SCH_1):P5E_CPU0_P0_TX_DN(5)
BW46 P5E_CPU0_P0_RX_DP<6> P0_RXP6||SATA06_RXP @T6G_MB_LIB.T6G(SCH_1):P5E_CPU0_P0_RX_DP(6)
BW49 P5E_CPU0_P0_RX_DP<3> P0_RXP3||SATA03_RXP @T6G_MB_LIB.T6G(SCH_1):P5E_CPU0_P0_RX_DP(3)
CN53 P5E_CPU0_P0_TX_DP<0> P0_TXP0||SATA00_TXP @T6G_MB_LIB.T6G(SCH_1):P5E_CPU0_P0_TX_DP(0)
CL50 P5E_CPU0_P0_TX_DP<6> P0_TXP6||SATA06_TXP @T6G_MB_LIB.T6G(SCH_1):P5E_CPU0_P0_TX_DP(6)
CN50 P5E_CPU0_P0_TX_DP<3> P0_TXP3||SATA03_TXP @T6G_MB_LIB.T6G(SCH_1):P5E_CPU0_P0_TX_DP(3)
CT40 P5E_CPU0_P0_TX_DN<13> P0_TXN13||SATA15_TXN @T6G_MB_LIB.T6G(SCH_1):P5E_CPU0_P0_TX_DN(13)
CR43 P5E_CPU0_P0_TX_DN<10> P0_TXN10||SATA12_TXN @T6G_MB_LIB.T6G(SCH_1):P5E_CPU0_P0_TX_DN(10)
BV40 P5E_CPU0_P0_RX_DP<14> P0_RXP14||SATA16_RXP @T6G_MB_LIB.T6G(SCH_1):P5E_CPU0_P0_RX_DP(14)
BU46 P5E_CPU0_P0_RX_DP<8> P0_RXP8||SATA10_RXP @T6G_MB_LIB.T6G(SCH_1):P5E_CPU0_P0_RX_DP(8)
BY41 P5E_CPU0_P0_RX_DN<12> P0_RXN12||SATA14_RXN @T6G_MB_LIB.T6G(SCH_1):P5E_CPU0_P0_RX_DN(12)
CU47 P5E_CPU0_P0_TX_DP<8> P0_TXP8||SATA10_TXP @T6G_MB_LIB.T6G(SCH_1):P5E_CPU0_P0_TX_DP(8)
BT41 P5E_CPU0_P0_RX_DN<15> P0_RXN15||SATA17_RXN @T6G_MB_LIB.T6G(SCH_1):P5E_CPU0_P0_RX_DN(15)
CR44 P5E_CPU0_P0_TX_DP<10> P0_TXP10||SATA12_TXP @T6G_MB_LIB.T6G(SCH_1):P5E_CPU0_P0_TX_DP(10)
CT41 P5E_CPU0_P0_TX_DP<13> P0_TXP13||SATA15_TXP @T6G_MB_LIB.T6G(SCH_1):P5E_CPU0_P0_TX_DP(13)
BU47 P5E_CPU0_P0_RX_DN<8> P0_RXN8||SATA10_RXN @T6G_MB_LIB.T6G(SCH_1):P5E_CPU0_P0_RX_DN(8)
CU43 P5E_CPU0_P0_TX_DN<11> P0_TXN11||SATA13_TXN @T6G_MB_LIB.T6G(SCH_1):P5E_CPU0_P0_TX_DN(11)
CU46 P5E_CPU0_P0_TX_DN<8> P0_TXN8||SATA10_TXN @T6G_MB_LIB.T6G(SCH_1):P5E_CPU0_P0_TX_DN(8)
BT40 P5E_CPU0_P0_RX_DP<15> P0_RXP15||SATA17_RXP @T6G_MB_LIB.T6G(SCH_1):P5E_CPU0_P0_RX_DP(15)
BY40 P5E_CPU0_P0_RX_DP<12> P0_RXP12||SATA14_RXP @T6G_MB_LIB.T6G(SCH_1):P5E_CPU0_P0_RX_DP(12)
CP40 P5E_CPU0_P0_TX_DN<14> P0_TXN14||SATA16_TXN @T6G_MB_LIB.T6G(SCH_1):P5E_CPU0_P0_TX_DN(14)
BW43 P5E_CPU0_P0_RX_DP<9> P0_RXP9||SATA11_RXP @T6G_MB_LIB.T6G(SCH_1):P5E_CPU0_P0_RX_DP(9)
CN47 P5E_CPU0_P0_TX_DP<9> P0_TXP9||SATA11_TXP @T6G_MB_LIB.T6G(SCH_1):P5E_CPU0_P0_TX_DP(9)
CB41 P5E_CPU0_P0_RX_DN<13> P0_RXN13||SATA15_RXN @T6G_MB_LIB.T6G(SCH_1):P5E_CPU0_P0_RX_DN(13)
CA44 P5E_CPU0_P0_RX_DN<10> P0_RXN10||SATA12_RXN @T6G_MB_LIB.T6G(SCH_1):P5E_CPU0_P0_RX_DN(10)
CP41 P5E_CPU0_P0_TX_DP<14> P0_TXP14||SATA16_TXP @T6G_MB_LIB.T6G(SCH_1):P5E_CPU0_P0_TX_DP(14)
CU44 P5E_CPU0_P0_TX_DP<11> P0_TXP11||SATA13_TXP @T6G_MB_LIB.T6G(SCH_1):P5E_CPU0_P0_TX_DP(11)
BW44 P5E_CPU0_P0_RX_DN<9> P0_RXN9||SATA11_RXN @T6G_MB_LIB.T6G(SCH_1):P5E_CPU0_P0_RX_DN(9)
CA43 P5E_CPU0_P0_RX_DP<10> P0_RXP10||SATA12_RXP @T6G_MB_LIB.T6G(SCH_1):P5E_CPU0_P0_RX_DP(10)
CN43 P5E_CPU0_P0_TX_DN<12> P0_TXN12||SATA14_TXN @T6G_MB_LIB.T6G(SCH_1):P5E_CPU0_P0_TX_DN(12)
CN46 P5E_CPU0_P0_TX_DN<9> P0_TXN9||SATA11_TXN @T6G_MB_LIB.T6G(SCH_1):P5E_CPU0_P0_TX_DN(9)
CB40 P5E_CPU0_P0_RX_DP<13> P0_RXP13||SATA15_RXP @T6G_MB_LIB.T6G(SCH_1):P5E_CPU0_P0_RX_DP(13)
CM40 P5E_CPU0_P0_TX_DN<15> P0_TXN15||SATA17_TXN @T6G_MB_LIB.T6G(SCH_1):P5E_CPU0_P0_TX_DN(15)
BV41 P5E_CPU0_P0_RX_DN<14> P0_RXN14||SATA16_RXN @T6G_MB_LIB.T6G(SCH_1):P5E_CPU0_P0_RX_DN(14)
BU44 P5E_CPU0_P0_RX_DN<11> P0_RXN11||SATA13_RXN @T6G_MB_LIB.T6G(SCH_1):P5E_CPU0_P0_RX_DN(11)
CM41 P5E_CPU0_P0_TX_DP<15> P0_TXP15||SATA17_TXP @T6G_MB_LIB.T6G(SCH_1):P5E_CPU0_P0_TX_DP(15)
CN44 P5E_CPU0_P0_TX_DP<12> P0_TXP12||SATA14_TXP @T6G_MB_LIB.T6G(SCH_1):P5E_CPU0_P0_TX_DP(12)
BU43 P5E_CPU0_P0_RX_DP<11> P0_RXP11||SATA13_RXP @T6G_MB_LIB.T6G(SCH_1):P5E_CPU0_P0_RX_DP(11)

GENOA_SP5-SOCKET6096_13568-001,SMLF,IO,DGA^6000030  I149  U25
CC46 P5E_CPU0_P1_RX_DP<8> P1_RXP8 @T6G_MB_LIB.T6G(SCH_1):P5E_CPU0_P1_RX_DP(8)
CC47 P5E_CPU0_P1_RX_DN<8> P1_RXN8 @T6G_MB_LIB.T6G(SCH_1):P5E_CPU0_P1_RX_DN(8)
CE43 P5E_CPU0_P1_RX_DP<9> P1_RXP9 @T6G_MB_LIB.T6G(SCH_1):P5E_CPU0_P1_RX_DP(9)
CE44 P5E_CPU0_P1_RX_DN<9> P1_RXN9 @T6G_MB_LIB.T6G(SCH_1):P5E_CPU0_P1_RX_DN(9)
CG43 P5E_CPU0_P1_RX_DP<10> P1_RXP10 @T6G_MB_LIB.T6G(SCH_1):P5E_CPU0_P1_RX_DP(10)
CG44 P5E_CPU0_P1_RX_DN<10> P1_RXN10 @T6G_MB_LIB.T6G(SCH_1):P5E_CPU0_P1_RX_DN(10)
CJ43 P5E_CPU0_P1_RX_DP<11> P1_RXP11 @T6G_MB_LIB.T6G(SCH_1):P5E_CPU0_P1_RX_DP(11)
CJ44 P5E_CPU0_P1_RX_DN<11> P1_RXN11 @T6G_MB_LIB.T6G(SCH_1):P5E_CPU0_P1_RX_DN(11)
CC43 P5E_CPU0_P1_RX_DP<12> P1_RXP12 @T6G_MB_LIB.T6G(SCH_1):P5E_CPU0_P1_RX_DP(12)
CC44 P5E_CPU0_P1_RX_DN<12> P1_RXN12 @T6G_MB_LIB.T6G(SCH_1):P5E_CPU0_P1_RX_DN(12)
CH40 P5E_CPU0_P1_RX_DP<13> P1_RXP13 @T6G_MB_LIB.T6G(SCH_1):P5E_CPU0_P1_RX_DP(13)
CH41 P5E_CPU0_P1_RX_DN<13> P1_RXN13 @T6G_MB_LIB.T6G(SCH_1):P5E_CPU0_P1_RX_DN(13)
CF40 P5E_CPU0_P1_RX_DP<14> P1_RXP14 @T6G_MB_LIB.T6G(SCH_1):P5E_CPU0_P1_RX_DP(14)
CF41 P5E_CPU0_P1_RX_DN<14> P1_RXN14 @T6G_MB_LIB.T6G(SCH_1):P5E_CPU0_P1_RX_DN(14)
CD40 P5E_CPU0_P1_RX_DP<15> P1_RXP15 @T6G_MB_LIB.T6G(SCH_1):P5E_CPU0_P1_RX_DP(15)
CD41 P5E_CPU0_P1_RX_DN<15> P1_RXN15 @T6G_MB_LIB.T6G(SCH_1):P5E_CPU0_P1_RX_DN(15)
DC47 P5E_CPU0_P1_TX_DP<8> P1_TXP8 @T6G_MB_LIB.T6G(SCH_1):P5E_CPU0_P1_TX_DP(8)
DC46 P5E_CPU0_P1_TX_DN<8> P1_TXN8 @T6G_MB_LIB.T6G(SCH_1):P5E_CPU0_P1_TX_DN(8)
CW47 P5E_CPU0_P1_TX_DP<9> P1_TXP9 @T6G_MB_LIB.T6G(SCH_1):P5E_CPU0_P1_TX_DP(9)
CW46 P5E_CPU0_P1_TX_DN<9> P1_TXN9 @T6G_MB_LIB.T6G(SCH_1):P5E_CPU0_P1_TX_DN(9)
DA44 P5E_CPU0_P1_TX_DP<10> P1_TXP10 @T6G_MB_LIB.T6G(SCH_1):P5E_CPU0_P1_TX_DP(10)
DA43 P5E_CPU0_P1_TX_DN<10> P1_TXN10 @T6G_MB_LIB.T6G(SCH_1):P5E_CPU0_P1_TX_DN(10)
DC44 P5E_CPU0_P1_TX_DP<11> P1_TXP11 @T6G_MB_LIB.T6G(SCH_1):P5E_CPU0_P1_TX_DP(11)
DC43 P5E_CPU0_P1_TX_DN<11> P1_TXN11 @T6G_MB_LIB.T6G(SCH_1):P5E_CPU0_P1_TX_DN(11)
CW44 P5E_CPU0_P1_TX_DP<12> P1_TXP12 @T6G_MB_LIB.T6G(SCH_1):P5E_CPU0_P1_TX_DP(12)
CW43 P5E_CPU0_P1_TX_DN<12> P1_TXN12 @T6G_MB_LIB.T6G(SCH_1):P5E_CPU0_P1_TX_DN(12)
DB41 P5E_CPU0_P1_TX_DP<13> P1_TXP13 @T6G_MB_LIB.T6G(SCH_1):P5E_CPU0_P1_TX_DP(13)
DB40 P5E_CPU0_P1_TX_DN<13> P1_TXN13 @T6G_MB_LIB.T6G(SCH_1):P5E_CPU0_P1_TX_DN(13)
CY41 P5E_CPU0_P1_TX_DP<14> P1_TXP14 @T6G_MB_LIB.T6G(SCH_1):P5E_CPU0_P1_TX_DP(14)
CY40 P5E_CPU0_P1_TX_DN<14> P1_TXN14 @T6G_MB_LIB.T6G(SCH_1):P5E_CPU0_P1_TX_DN(14)
CV41 P5E_CPU0_P1_TX_DP<15> P1_TXP15 @T6G_MB_LIB.T6G(SCH_1):P5E_CPU0_P1_TX_DP(15)
CV40 P5E_CPU0_P1_TX_DN<15> P1_TXN15 @T6G_MB_LIB.T6G(SCH_1):P5E_CPU0_P1_TX_DN(15)
CG47 P5E_CPU0_P1_RX_DN<7> P1_RXN7 @T6G_MB_LIB.T6G(SCH_1):P5E_CPU0_P1_RX_DN(7)
CU53 P5E_CPU0_P1_TX_DP<0> P1_TXP0 @T6G_MB_LIB.T6G(SCH_1):P5E_CPU0_P1_TX_DP(0)
DA53 P5E_CPU0_P1_TX_DP<1> P1_TXP1 @T6G_MB_LIB.T6G(SCH_1):P5E_CPU0_P1_TX_DP(1)
DC53 P5E_CPU0_P1_TX_DP<2> P1_TXP2 @T6G_MB_LIB.T6G(SCH_1):P5E_CPU0_P1_TX_DP(2)
CU52 P5E_CPU0_P1_TX_DN<0> P1_TXN0 @T6G_MB_LIB.T6G(SCH_1):P5E_CPU0_P1_TX_DN(0)
CE52 P5E_CPU0_P1_RX_DP<0> P1_RXP0 @T6G_MB_LIB.T6G(SCH_1):P5E_CPU0_P1_RX_DP(0)
CW53 P5E_CPU0_P1_TX_DP<3> P1_TXP3 @T6G_MB_LIB.T6G(SCH_1):P5E_CPU0_P1_TX_DP(3)
DA52 P5E_CPU0_P1_TX_DN<1> P1_TXN1 @T6G_MB_LIB.T6G(SCH_1):P5E_CPU0_P1_TX_DN(1)
CG52 P5E_CPU0_P1_RX_DP<1> P1_RXP1 @T6G_MB_LIB.T6G(SCH_1):P5E_CPU0_P1_RX_DP(1)
DA50 P5E_CPU0_P1_TX_DP<4> P1_TXP4 @T6G_MB_LIB.T6G(SCH_1):P5E_CPU0_P1_TX_DP(4)
DC52 P5E_CPU0_P1_TX_DN<2> P1_TXN2 @T6G_MB_LIB.T6G(SCH_1):P5E_CPU0_P1_TX_DN(2)
CC52 P5E_CPU0_P1_RX_DP<2> P1_RXP2 @T6G_MB_LIB.T6G(SCH_1):P5E_CPU0_P1_RX_DP(2)
CE53 P5E_CPU0_P1_RX_DN<0> P1_RXN0 @T6G_MB_LIB.T6G(SCH_1):P5E_CPU0_P1_RX_DN(0)
DC50 P5E_CPU0_P1_TX_DP<5> P1_TXP5 @T6G_MB_LIB.T6G(SCH_1):P5E_CPU0_P1_TX_DP(5)
CW52 P5E_CPU0_P1_TX_DN<3> P1_TXN3 @T6G_MB_LIB.T6G(SCH_1):P5E_CPU0_P1_TX_DN(3)
CE49 P5E_CPU0_P1_RX_DP<3> P1_RXP3 @T6G_MB_LIB.T6G(SCH_1):P5E_CPU0_P1_RX_DP(3)
CG53 P5E_CPU0_P1_RX_DN<1> P1_RXN1 @T6G_MB_LIB.T6G(SCH_1):P5E_CPU0_P1_RX_DN(1)
CW50 P5E_CPU0_P1_TX_DP<6> P1_TXP6 @T6G_MB_LIB.T6G(SCH_1):P5E_CPU0_P1_TX_DP(6)
DA49 P5E_CPU0_P1_TX_DN<4> P1_TXN4 @T6G_MB_LIB.T6G(SCH_1):P5E_CPU0_P1_TX_DN(4)
CG49 P5E_CPU0_P1_RX_DP<4> P1_RXP4 @T6G_MB_LIB.T6G(SCH_1):P5E_CPU0_P1_RX_DP(4)
CC53 P5E_CPU0_P1_RX_DN<2> P1_RXN2 @T6G_MB_LIB.T6G(SCH_1):P5E_CPU0_P1_RX_DN(2)
DA47 P5E_CPU0_P1_TX_DP<7> P1_TXP7 @T6G_MB_LIB.T6G(SCH_1):P5E_CPU0_P1_TX_DP(7)
DC49 P5E_CPU0_P1_TX_DN<5> P1_TXN5 @T6G_MB_LIB.T6G(SCH_1):P5E_CPU0_P1_TX_DN(5)
CC49 P5E_CPU0_P1_RX_DP<5> P1_RXP5 @T6G_MB_LIB.T6G(SCH_1):P5E_CPU0_P1_RX_DP(5)
CE50 P5E_CPU0_P1_RX_DN<3> P1_RXN3 @T6G_MB_LIB.T6G(SCH_1):P5E_CPU0_P1_RX_DN(3)
CW49 P5E_CPU0_P1_TX_DN<6> P1_TXN6 @T6G_MB_LIB.T6G(SCH_1):P5E_CPU0_P1_TX_DN(6)
CE46 P5E_CPU0_P1_RX_DP<6> P1_RXP6 @T6G_MB_LIB.T6G(SCH_1):P5E_CPU0_P1_RX_DP(6)
CG50 P5E_CPU0_P1_RX_DN<4> P1_RXN4 @T6G_MB_LIB.T6G(SCH_1):P5E_CPU0_P1_RX_DN(4)
DA46 P5E_CPU0_P1_TX_DN<7> P1_TXN7 @T6G_MB_LIB.T6G(SCH_1):P5E_CPU0_P1_TX_DN(7)
CG46 P5E_CPU0_P1_RX_DP<7> P1_RXP7 @T6G_MB_LIB.T6G(SCH_1):P5E_CPU0_P1_RX_DP(7)
CC50 P5E_CPU0_P1_RX_DN<5> P1_RXN5 @T6G_MB_LIB.T6G(SCH_1):P5E_CPU0_P1_RX_DN(5)
CE47 P5E_CPU0_P1_RX_DN<6> P1_RXN6 @T6G_MB_LIB.T6G(SCH_1):P5E_CPU0_P1_RX_DN(6)


DRAWING: @T6G_MB_LIB.T6G(SCH_1):PAGE25 

GENOA_SP5-SOCKET6096_13568-001,SMLF,IO,DGA^6000030  I147  U25
CR29 P5E_CPU0_P2_RX_DP<8> P2_RXP8 @T6G_MB_LIB.T6G(SCH_1):P5E_CPU0_P2_RX_DP(8)
CR30 P5E_CPU0_P2_RX_DN<8> P2_RXN8 @T6G_MB_LIB.T6G(SCH_1):P5E_CPU0_P2_RX_DN(8)
CL26 P5E_CPU0_P2_RX_DP<9> P2_RXP9 @T6G_MB_LIB.T6G(SCH_1):P5E_CPU0_P2_RX_DP(9)
CL27 P5E_CPU0_P2_RX_DN<9> P2_RXN9 @T6G_MB_LIB.T6G(SCH_1):P5E_CPU0_P2_RX_DN(9)
CU26 P5E_CPU0_P2_RX_DP<10> P2_RXP10 @T6G_MB_LIB.T6G(SCH_1):P5E_CPU0_P2_RX_DP(10)
CU27 P5E_CPU0_P2_RX_DN<10> P2_RXN10 @T6G_MB_LIB.T6G(SCH_1):P5E_CPU0_P2_RX_DN(10)
CR26 P5E_CPU0_P2_RX_DP<11> P2_RXP11 @T6G_MB_LIB.T6G(SCH_1):P5E_CPU0_P2_RX_DP(11)
CR27 P5E_CPU0_P2_RX_DN<11> P2_RXN11 @T6G_MB_LIB.T6G(SCH_1):P5E_CPU0_P2_RX_DN(11)
CN26 P5E_CPU0_P2_RX_DP<12> P2_RXP12 @T6G_MB_LIB.T6G(SCH_1):P5E_CPU0_P2_RX_DP(12)
CN27 P5E_CPU0_P2_RX_DN<12> P2_RXN12 @T6G_MB_LIB.T6G(SCH_1):P5E_CPU0_P2_RX_DN(12)
CL23 P5E_CPU0_P2_RX_DP<13> P2_RXP13 @T6G_MB_LIB.T6G(SCH_1):P5E_CPU0_P2_RX_DP(13)
CL24 P5E_CPU0_P2_RX_DN<13> P2_RXN13 @T6G_MB_LIB.T6G(SCH_1):P5E_CPU0_P2_RX_DN(13)
CR23 P5E_CPU0_P2_RX_DP<14> P2_RXP14 @T6G_MB_LIB.T6G(SCH_1):P5E_CPU0_P2_RX_DP(14)
CR24 P5E_CPU0_P2_RX_DN<14> P2_RXN14 @T6G_MB_LIB.T6G(SCH_1):P5E_CPU0_P2_RX_DN(14)
CN23 P5E_CPU0_P2_RX_DP<15> P2_RXP15 @T6G_MB_LIB.T6G(SCH_1):P5E_CPU0_P2_RX_DP(15)
CN24 P5E_CPU0_P2_RX_DN<15> P2_RXN15 @T6G_MB_LIB.T6G(SCH_1):P5E_CPU0_P2_RX_DN(15)
CA30 P5E_CPU0_P2_TX_DP<8> P2_TXP8 @T6G_MB_LIB.T6G(SCH_1):P5E_CPU0_P2_TX_DP(8)
CA29 P5E_CPU0_P2_TX_DN<8> P2_TXN8 @T6G_MB_LIB.T6G(SCH_1):P5E_CPU0_P2_TX_DN(8)
BW30 P5E_CPU0_P2_TX_DP<9> P2_TXP9 @T6G_MB_LIB.T6G(SCH_1):P5E_CPU0_P2_TX_DP(9)
BW29 P5E_CPU0_P2_TX_DN<9> P2_TXN9 @T6G_MB_LIB.T6G(SCH_1):P5E_CPU0_P2_TX_DN(9)
BU27 P5E_CPU0_P2_TX_DP<10> P2_TXP10 @T6G_MB_LIB.T6G(SCH_1):P5E_CPU0_P2_TX_DP(10)
BU26 P5E_CPU0_P2_TX_DN<10> P2_TXN10 @T6G_MB_LIB.T6G(SCH_1):P5E_CPU0_P2_TX_DN(10)
CA27 P5E_CPU0_P2_TX_DP<11> P2_TXP11 @T6G_MB_LIB.T6G(SCH_1):P5E_CPU0_P2_TX_DP(11)
CA26 P5E_CPU0_P2_TX_DN<11> P2_TXN11 @T6G_MB_LIB.T6G(SCH_1):P5E_CPU0_P2_TX_DN(11)
BW27 P5E_CPU0_P2_TX_DP<12> P2_TXP12 @T6G_MB_LIB.T6G(SCH_1):P5E_CPU0_P2_TX_DP(12)
BW26 P5E_CPU0_P2_TX_DN<12> P2_TXN12 @T6G_MB_LIB.T6G(SCH_1):P5E_CPU0_P2_TX_DN(12)
BU24 P5E_CPU0_P2_TX_DP<13> P2_TXP13 @T6G_MB_LIB.T6G(SCH_1):P5E_CPU0_P2_TX_DP(13)
BU23 P5E_CPU0_P2_TX_DN<13> P2_TXN13 @T6G_MB_LIB.T6G(SCH_1):P5E_CPU0_P2_TX_DN(13)
CA24 P5E_CPU0_P2_TX_DP<14> P2_TXP14 @T6G_MB_LIB.T6G(SCH_1):P5E_CPU0_P2_TX_DP(14)
CA23 P5E_CPU0_P2_TX_DN<14> P2_TXN14 @T6G_MB_LIB.T6G(SCH_1):P5E_CPU0_P2_TX_DN(14)
BW24 P5E_CPU0_P2_TX_DP<15> P2_TXP15 @T6G_MB_LIB.T6G(SCH_1):P5E_CPU0_P2_TX_DP(15)
BW23 P5E_CPU0_P2_TX_DN<15> P2_TXN15 @T6G_MB_LIB.T6G(SCH_1):P5E_CPU0_P2_TX_DN(15)
BT36 P5E_CPU0_P2_TX_DP<0> P2_TXP0 @T6G_MB_LIB.T6G(SCH_1):P5E_CPU0_P2_TX_DP(0)
BV36 P5E_CPU0_P2_TX_DP<1> P2_TXP1 @T6G_MB_LIB.T6G(SCH_1):P5E_CPU0_P2_TX_DP(1)
CB36 P5E_CPU0_P2_TX_DP<2> P2_TXP2 @T6G_MB_LIB.T6G(SCH_1):P5E_CPU0_P2_TX_DP(2)
BT35 P5E_CPU0_P2_TX_DN<0> P2_TXN0 @T6G_MB_LIB.T6G(SCH_1):P5E_CPU0_P2_TX_DN(0)
CM35 P5E_CPU0_P2_RX_DP<0> P2_RXP0 @T6G_MB_LIB.T6G(SCH_1):P5E_CPU0_P2_RX_DP(0)
BY36 P5E_CPU0_P2_TX_DP<3> P2_TXP3 @T6G_MB_LIB.T6G(SCH_1):P5E_CPU0_P2_TX_DP(3)
BV35 P5E_CPU0_P2_TX_DN<1> P2_TXN1 @T6G_MB_LIB.T6G(SCH_1):P5E_CPU0_P2_TX_DN(1)
CP35 P5E_CPU0_P2_RX_DP<1> P2_RXP1 @T6G_MB_LIB.T6G(SCH_1):P5E_CPU0_P2_RX_DP(1)
BU33 P5E_CPU0_P2_TX_DP<4> P2_TXP4 @T6G_MB_LIB.T6G(SCH_1):P5E_CPU0_P2_TX_DP(4)
CB35 P5E_CPU0_P2_TX_DN<2> P2_TXN2 @T6G_MB_LIB.T6G(SCH_1):P5E_CPU0_P2_TX_DN(2)
CT35 P5E_CPU0_P2_RX_DP<2> P2_RXP2 @T6G_MB_LIB.T6G(SCH_1):P5E_CPU0_P2_RX_DP(2)
CM36 P5E_CPU0_P2_RX_DN<0> P2_RXN0 @T6G_MB_LIB.T6G(SCH_1):P5E_CPU0_P2_RX_DN(0)
CA33 P5E_CPU0_P2_TX_DP<5> P2_TXP5 @T6G_MB_LIB.T6G(SCH_1):P5E_CPU0_P2_TX_DP(5)
BY35 P5E_CPU0_P2_TX_DN<3> P2_TXN3 @T6G_MB_LIB.T6G(SCH_1):P5E_CPU0_P2_TX_DN(3)
CN32 P5E_CPU0_P2_RX_DP<3> P2_RXP3 @T6G_MB_LIB.T6G(SCH_1):P5E_CPU0_P2_RX_DP(3)
CP36 P5E_CPU0_P2_RX_DN<1> P2_RXN1 @T6G_MB_LIB.T6G(SCH_1):P5E_CPU0_P2_RX_DN(1)
BW33 P5E_CPU0_P2_TX_DP<6> P2_TXP6 @T6G_MB_LIB.T6G(SCH_1):P5E_CPU0_P2_TX_DP(6)
BU32 P5E_CPU0_P2_TX_DN<4> P2_TXN4 @T6G_MB_LIB.T6G(SCH_1):P5E_CPU0_P2_TX_DN(4)
CU32 P5E_CPU0_P2_RX_DP<4> P2_RXP4 @T6G_MB_LIB.T6G(SCH_1):P5E_CPU0_P2_RX_DP(4)
CT36 P5E_CPU0_P2_RX_DN<2> P2_RXN2 @T6G_MB_LIB.T6G(SCH_1):P5E_CPU0_P2_RX_DN(2)
BU30 P5E_CPU0_P2_TX_DP<7> P2_TXP7 @T6G_MB_LIB.T6G(SCH_1):P5E_CPU0_P2_TX_DP(7)
CA32 P5E_CPU0_P2_TX_DN<5> P2_TXN5 @T6G_MB_LIB.T6G(SCH_1):P5E_CPU0_P2_TX_DN(5)
CR32 P5E_CPU0_P2_RX_DP<5> P2_RXP5 @T6G_MB_LIB.T6G(SCH_1):P5E_CPU0_P2_RX_DP(5)
CN33 P5E_CPU0_P2_RX_DN<3> P2_RXN3 @T6G_MB_LIB.T6G(SCH_1):P5E_CPU0_P2_RX_DN(3)
BW32 P5E_CPU0_P2_TX_DN<6> P2_TXN6 @T6G_MB_LIB.T6G(SCH_1):P5E_CPU0_P2_TX_DN(6)
CN29 P5E_CPU0_P2_RX_DP<6> P2_RXP6 @T6G_MB_LIB.T6G(SCH_1):P5E_CPU0_P2_RX_DP(6)
CU33 P5E_CPU0_P2_RX_DN<4> P2_RXN4 @T6G_MB_LIB.T6G(SCH_1):P5E_CPU0_P2_RX_DN(4)
BU29 P5E_CPU0_P2_TX_DN<7> P2_TXN7 @T6G_MB_LIB.T6G(SCH_1):P5E_CPU0_P2_TX_DN(7)
CU29 P5E_CPU0_P2_RX_DP<7> P2_RXP7 @T6G_MB_LIB.T6G(SCH_1):P5E_CPU0_P2_RX_DP(7)
CR33 P5E_CPU0_P2_RX_DN<5> P2_RXN5 @T6G_MB_LIB.T6G(SCH_1):P5E_CPU0_P2_RX_DN(5)
CN30 P5E_CPU0_P2_RX_DN<6> P2_RXN6 @T6G_MB_LIB.T6G(SCH_1):P5E_CPU0_P2_RX_DN(6)
CU30 P5E_CPU0_P2_RX_DN<7> P2_RXN7 @T6G_MB_LIB.T6G(SCH_1):P5E_CPU0_P2_RX_DN(7)

GENOA_SP5-SOCKET6096_13568-001,SMLF,IO,DGA^6000030  I148  U25
CV35 P5E_CPU0_P3_RX_DP<0> P3_RXP0 @T6G_MB_LIB.T6G(SCH_1):P5E_CPU0_P3_RX_DP(0)
CV36 P5E_CPU0_P3_RX_DN<0> P3_RXN0 @T6G_MB_LIB.T6G(SCH_1):P5E_CPU0_P3_RX_DN(0)
CY35 P5E_CPU0_P3_RX_DP<1> P3_RXP1 @T6G_MB_LIB.T6G(SCH_1):P5E_CPU0_P3_RX_DP(1)
CY36 P5E_CPU0_P3_RX_DN<1> P3_RXN1 @T6G_MB_LIB.T6G(SCH_1):P5E_CPU0_P3_RX_DN(1)
DB35 P5E_CPU0_P3_RX_DP<2> P3_RXP2 @T6G_MB_LIB.T6G(SCH_1):P5E_CPU0_P3_RX_DP(2)
DB36 P5E_CPU0_P3_RX_DN<2> P3_RXN2 @T6G_MB_LIB.T6G(SCH_1):P5E_CPU0_P3_RX_DN(2)
CW32 P5E_CPU0_P3_RX_DP<3> P3_RXP3 @T6G_MB_LIB.T6G(SCH_1):P5E_CPU0_P3_RX_DP(3)
CW33 P5E_CPU0_P3_RX_DN<3> P3_RXN3 @T6G_MB_LIB.T6G(SCH_1):P5E_CPU0_P3_RX_DN(3)
DC32 P5E_CPU0_P3_RX_DP<4> P3_RXP4 @T6G_MB_LIB.T6G(SCH_1):P5E_CPU0_P3_RX_DP(4)
DC33 P5E_CPU0_P3_RX_DN<4> P3_RXN4 @T6G_MB_LIB.T6G(SCH_1):P5E_CPU0_P3_RX_DN(4)
DA32 P5E_CPU0_P3_RX_DP<5> P3_RXP5 @T6G_MB_LIB.T6G(SCH_1):P5E_CPU0_P3_RX_DP(5)
DA33 P5E_CPU0_P3_RX_DN<5> P3_RXN5 @T6G_MB_LIB.T6G(SCH_1):P5E_CPU0_P3_RX_DN(5)
CW29 P5E_CPU0_P3_RX_DP<6> P3_RXP6 @T6G_MB_LIB.T6G(SCH_1):P5E_CPU0_P3_RX_DP(6)
CW30 P5E_CPU0_P3_RX_DN<6> P3_RXN6 @T6G_MB_LIB.T6G(SCH_1):P5E_CPU0_P3_RX_DN(6)
DC29 P5E_CPU0_P3_RX_DP<7> P3_RXP7 @T6G_MB_LIB.T6G(SCH_1):P5E_CPU0_P3_RX_DP(7)
DC30 P5E_CPU0_P3_RX_DN<7> P3_RXN7 @T6G_MB_LIB.T6G(SCH_1):P5E_CPU0_P3_RX_DN(7)
DA29 P5E_CPU0_P3_RX_DP<8> P3_RXP8 @T6G_MB_LIB.T6G(SCH_1):P5E_CPU0_P3_RX_DP(8)
DA30 P5E_CPU0_P3_RX_DN<8> P3_RXN8 @T6G_MB_LIB.T6G(SCH_1):P5E_CPU0_P3_RX_DN(8)
CW26 P5E_CPU0_P3_RX_DP<9> P3_RXP9 @T6G_MB_LIB.T6G(SCH_1):P5E_CPU0_P3_RX_DP(9)
CW27 P5E_CPU0_P3_RX_DN<9> P3_RXN9 @T6G_MB_LIB.T6G(SCH_1):P5E_CPU0_P3_RX_DN(9)
DC26 P5E_CPU0_P3_RX_DP<10> P3_RXP10 @T6G_MB_LIB.T6G(SCH_1):P5E_CPU0_P3_RX_DP(10)
DC27 P5E_CPU0_P3_RX_DN<10> P3_RXN10 @T6G_MB_LIB.T6G(SCH_1):P5E_CPU0_P3_RX_DN(10)
DA26 P5E_CPU0_P3_RX_DP<11> P3_RXP11 @T6G_MB_LIB.T6G(SCH_1):P5E_CPU0_P3_RX_DP(11)
DA27 P5E_CPU0_P3_RX_DN<11> P3_RXN11 @T6G_MB_LIB.T6G(SCH_1):P5E_CPU0_P3_RX_DN(11)
CW23 P5E_CPU0_P3_RX_DP<12> P3_RXP12 @T6G_MB_LIB.T6G(SCH_1):P5E_CPU0_P3_RX_DP(12)
CW24 P5E_CPU0_P3_RX_DN<12> P3_RXN12 @T6G_MB_LIB.T6G(SCH_1):P5E_CPU0_P3_RX_DN(12)
DC23 P5E_CPU0_P3_RX_DP<13> P3_RXP13 @T6G_MB_LIB.T6G(SCH_1):P5E_CPU0_P3_RX_DP(13)
DC24 P5E_CPU0_P3_RX_DN<13> P3_RXN13 @T6G_MB_LIB.T6G(SCH_1):P5E_CPU0_P3_RX_DN(13)
DA23 P5E_CPU0_P3_RX_DP<14> P3_RXP14 @T6G_MB_LIB.T6G(SCH_1):P5E_CPU0_P3_RX_DP(14)
DA24 P5E_CPU0_P3_RX_DN<14> P3_RXN14 @T6G_MB_LIB.T6G(SCH_1):P5E_CPU0_P3_RX_DN(14)
CU23 P5E_CPU0_P3_RX_DP<15> P3_RXP15 @T6G_MB_LIB.T6G(SCH_1):P5E_CPU0_P3_RX_DP(15)
CU24 P5E_CPU0_P3_RX_DN<15> P3_RXN15 @T6G_MB_LIB.T6G(SCH_1):P5E_CPU0_P3_RX_DN(15)
CD36 P5E_CPU0_P3_TX_DP<0> P3_TXP0 @T6G_MB_LIB.T6G(SCH_1):P5E_CPU0_P3_TX_DP(0)
CD35 P5E_CPU0_P3_TX_DN<0> P3_TXN0 @T6G_MB_LIB.T6G(SCH_1):P5E_CPU0_P3_TX_DN(0)
CF36 P5E_CPU0_P3_TX_DP<1> P3_TXP1 @T6G_MB_LIB.T6G(SCH_1):P5E_CPU0_P3_TX_DP(1)
CF35 P5E_CPU0_P3_TX_DN<1> P3_TXN1 @T6G_MB_LIB.T6G(SCH_1):P5E_CPU0_P3_TX_DN(1)
CH36 P5E_CPU0_P3_TX_DP<2> P3_TXP2 @T6G_MB_LIB.T6G(SCH_1):P5E_CPU0_P3_TX_DP(2)
CH35 P5E_CPU0_P3_TX_DN<2> P3_TXN2 @T6G_MB_LIB.T6G(SCH_1):P5E_CPU0_P3_TX_DN(2)
CC33 P5E_CPU0_P3_TX_DP<3> P3_TXP3 @T6G_MB_LIB.T6G(SCH_1):P5E_CPU0_P3_TX_DP(3)
CC32 P5E_CPU0_P3_TX_DN<3> P3_TXN3 @T6G_MB_LIB.T6G(SCH_1):P5E_CPU0_P3_TX_DN(3)
CJ33 P5E_CPU0_P3_TX_DP<4> P3_TXP4 @T6G_MB_LIB.T6G(SCH_1):P5E_CPU0_P3_TX_DP(4)
CJ32 P5E_CPU0_P3_TX_DN<4> P3_TXN4 @T6G_MB_LIB.T6G(SCH_1):P5E_CPU0_P3_TX_DN(4)
CG33 P5E_CPU0_P3_TX_DP<5> P3_TXP5 @T6G_MB_LIB.T6G(SCH_1):P5E_CPU0_P3_TX_DP(5)
CG32 P5E_CPU0_P3_TX_DN<5> P3_TXN5 @T6G_MB_LIB.T6G(SCH_1):P5E_CPU0_P3_TX_DN(5)
CE33 P5E_CPU0_P3_TX_DP<6> P3_TXP6 @T6G_MB_LIB.T6G(SCH_1):P5E_CPU0_P3_TX_DP(6)
CE32 P5E_CPU0_P3_TX_DN<6> P3_TXN6 @T6G_MB_LIB.T6G(SCH_1):P5E_CPU0_P3_TX_DN(6)
CC30 P5E_CPU0_P3_TX_DP<7> P3_TXP7 @T6G_MB_LIB.T6G(SCH_1):P5E_CPU0_P3_TX_DP(7)
CC29 P5E_CPU0_P3_TX_DN<7> P3_TXN7 @T6G_MB_LIB.T6G(SCH_1):P5E_CPU0_P3_TX_DN(7)
CG30 P5E_CPU0_P3_TX_DP<8> P3_TXP8 @T6G_MB_LIB.T6G(SCH_1):P5E_CPU0_P3_TX_DP(8)
CG29 P5E_CPU0_P3_TX_DN<8> P3_TXN8 @T6G_MB_LIB.T6G(SCH_1):P5E_CPU0_P3_TX_DN(8)
CE30 P5E_CPU0_P3_TX_DP<9> P3_TXP9 @T6G_MB_LIB.T6G(SCH_1):P5E_CPU0_P3_TX_DP(9)
CE29 P5E_CPU0_P3_TX_DN<9> P3_TXN9 @T6G_MB_LIB.T6G(SCH_1):P5E_CPU0_P3_TX_DN(9)
CC27 P5E_CPU0_P3_TX_DP<10> P3_TXP10 @T6G_MB_LIB.T6G(SCH_1):P5E_CPU0_P3_TX_DP(10)
CC26 P5E_CPU0_P3_TX_DN<10> P3_TXN10 @T6G_MB_LIB.T6G(SCH_1):P5E_CPU0_P3_TX_DN(10)
CG27 P5E_CPU0_P3_TX_DP<11> P3_TXP11 @T6G_MB_LIB.T6G(SCH_1):P5E_CPU0_P3_TX_DP(11)
CG26 P5E_CPU0_P3_TX_DN<11> P3_TXN11 @T6G_MB_LIB.T6G(SCH_1):P5E_CPU0_P3_TX_DN(11)
CE27 P5E_CPU0_P3_TX_DP<12> P3_TXP12 @T6G_MB_LIB.T6G(SCH_1):P5E_CPU0_P3_TX_DP(12)
CE26 P5E_CPU0_P3_TX_DN<12> P3_TXN12 @T6G_MB_LIB.T6G(SCH_1):P5E_CPU0_P3_TX_DN(12)
CC24 P5E_CPU0_P3_TX_DP<13> P3_TXP13 @T6G_MB_LIB.T6G(SCH_1):P5E_CPU0_P3_TX_DP(13)
CC23 P5E_CPU0_P3_TX_DN<13> P3_TXN13 @T6G_MB_LIB.T6G(SCH_1):P5E_CPU0_P3_TX_DN(13)
CG24 P5E_CPU0_P3_TX_DP<14> P3_TXP14 @T6G_MB_LIB.T6G(SCH_1):P5E_CPU0_P3_TX_DP(14)
CG23 P5E_CPU0_P3_TX_DN<14> P3_TXN14 @T6G_MB_LIB.T6G(SCH_1):P5E_CPU0_P3_TX_DN(14)
CE24 P5E_CPU0_P3_TX_DP<15> P3_TXP15 @T6G_MB_LIB.T6G(SCH_1):P5E_CPU0_P3_TX_DP(15)
CE23 P5E_CPU0_P3_TX_DN<15> P3_TXN15 @T6G_MB_LIB.T6G(SCH_1):P5E_CPU0_P3_TX_DN(15)


DRAWING: @T6G_MB_LIB.T6G(SCH_1):PAGE26 

GENOA_SP5-SOCKET6096_13568-001,SMLF,IO,DGA^6000030  I59  U25
DG47 P3E_CPU0_P4_RX_DN<2> P4_RXN2 @T6G_MB_LIB.T6G(SCH_1):P3E_CPU0_P4_RX_DN(2)
DG44 P3E_CPU0_P4_RX_DN<3> P4_RXN3 @T6G_MB_LIB.T6G(SCH_1):P3E_CPU0_P4_RX_DN(3)
DG48 P3E_CPU0_P4_RX_DP<2> P4_RXP2 @T6G_MB_LIB.T6G(SCH_1):P3E_CPU0_P4_RX_DP(2)
DG45 P3E_CPU0_P4_RX_DP<3> P4_RXP3 @T6G_MB_LIB.T6G(SCH_1):P3E_CPU0_P4_RX_DP(3)
DE46 P3E_CPU0_P4_TX_DN<2> P4_TXN2 @T6G_MB_LIB.T6G(SCH_1):P3E_CPU0_P4_TX_DN(2)
DE43 P3E_CPU0_P4_TX_DN<3> P4_TXN3 @T6G_MB_LIB.T6G(SCH_1):P3E_CPU0_P4_TX_DN(3)
DE47 P3E_CPU0_P4_TX_DP<2> P4_TXP2 @T6G_MB_LIB.T6G(SCH_1):P3E_CPU0_P4_TX_DP(2)
DE44 P3E_CPU0_P4_TX_DP<3> P4_TXP3 @T6G_MB_LIB.T6G(SCH_1):P3E_CPU0_P4_TX_DP(3)
 E44 P2E_CPU0_P5_RX_DN P5_RXN2 @T6G_MB_LIB.T6G(SCH_1):P2E_CPU0_P5_RX_DN
 E41     NC P5_RXN3     NC
 E43 P2E_CPU0_P5_RX_DP P5_RXP2 @T6G_MB_LIB.T6G(SCH_1):P2E_CPU0_P5_RX_DP
 E40     NC P5_RXP3     NC
 C45 P2E_CPU0_P5_TX_DN P5_TXN2 @T6G_MB_LIB.T6G(SCH_1):P2E_CPU0_P5_TX_DN
 C42     NC P5_TXN3     NC
 C44 P2E_CPU0_P5_TX_DP P5_TXP2 @T6G_MB_LIB.T6G(SCH_1):P2E_CPU0_P5_TX_DP
 C41     NC P5_TXP3     NC
DE53 P3E_CPU0_P4_TX_DP<0> P4_TXP0 @T6G_MB_LIB.T6G(SCH_1):P3E_CPU0_P4_TX_DP(0)
DE50 P3E_CPU0_P4_TX_DP<1> P4_TXP1 @T6G_MB_LIB.T6G(SCH_1):P3E_CPU0_P4_TX_DP(1)
DE52 P3E_CPU0_P4_TX_DN<0> P4_TXN0 @T6G_MB_LIB.T6G(SCH_1):P3E_CPU0_P4_TX_DN(0)
DG54 P3E_CPU0_P4_RX_DP<0> P4_RXP0 @T6G_MB_LIB.T6G(SCH_1):P3E_CPU0_P4_RX_DP(0)
DE49 P3E_CPU0_P4_TX_DN<1> P4_TXN1 @T6G_MB_LIB.T6G(SCH_1):P3E_CPU0_P4_TX_DN(1)
DG51 P3E_CPU0_P4_RX_DP<1> P4_RXP1 @T6G_MB_LIB.T6G(SCH_1):P3E_CPU0_P4_RX_DP(1)
DG53 P3E_CPU0_P4_RX_DN<0> P4_RXN0 @T6G_MB_LIB.T6G(SCH_1):P3E_CPU0_P4_RX_DN(0)
DG50 P3E_CPU0_P4_RX_DN<1> P4_RXN1 @T6G_MB_LIB.T6G(SCH_1):P3E_CPU0_P4_RX_DN(1)
 E50 WAFL_CPU1_TX1_CPU0_RX0_DN WAFL_RXN0||P5_RXN0 @T6G_MB_LIB.T6G(SCH_1):WAFL_CPU1_TX1_CPU0_RX0_DN
 E49 WAFL_CPU1_TX1_CPU0_RX0_DP WAFL_RXP0||P5_RXP0 @T6G_MB_LIB.T6G(SCH_1):WAFL_CPU1_TX1_CPU0_RX0_DP
 E47     NC WAFL_RXN1||P5_RXN1     NC
 E46     NC WAFL_RXP1||P5_RXP1     NC
 C51 WAFL_CPU0_TX0_CPU1_RX1_DN WAFL_TXN0||P5_TXN0 @T6G_MB_LIB.T6G(SCH_1):WAFL_CPU0_TX0_CPU1_RX1_DN
 C50 WAFL_CPU0_TX0_CPU1_RX1_DP WAFL_TXP0||P5_TXP0 @T6G_MB_LIB.T6G(SCH_1):WAFL_CPU0_TX0_CPU1_RX1_DP
 C48     NC WAFL_TXN1||P5_TXN1     NC
 C47     NC WAFL_TXP1||P5_TXP1     NC

Q_CAP_DIFFBUS_C0201-DIFF BUS_0.22UF,6.3V,20%,X6S,SA  I156  C2077
   1 P2E_CPU0_P5_TX_DP      1 @T6G_MB_LIB.T6G(SCH_1):P2E_CPU0_P5_TX_DP
   2 P2E_CPU0_P5_TX_C_DP      2 @T6G_MB_LIB.T6G(SCH_1):P2E_CPU0_P5_TX_C_DP

Q_CAP_DIFFBUS_C0201-DIFF BUS_0.22UF,6.3V,20%,X6S,SA  I157  C2078
   1 P2E_CPU0_P5_TX_DN      1 @T6G_MB_LIB.T6G(SCH_1):P2E_CPU0_P5_TX_DN
   2 P2E_CPU0_P5_TX_C_DN      2 @T6G_MB_LIB.T6G(SCH_1):P2E_CPU0_P5_TX_C_DN


DRAWING: @T6G_MB_LIB.T6G(SCH_1):PAGE27 

Q_RES_0402LF-0,5%,1/16W,CHIP,CS00002JB13  I170  R404
   1 JTAG_CPU0_R_TDO      A @T6G_MB_LIB.T6G(SCH_1):JTAG_CPU0_R_TDO
   2 JTAG_CPU0_TDO      B @T6G_MB_LIB.T6G(SCH_1):JTAG_CPU0_TDO

GENOA_SP5-SOCKET6096_13568-001,SMLF,IO,DGA^6000030  I227  U25
 A68 APML_CPU0_ALERT_N ALERT_L @T6G_MB_LIB.T6G(SCH_1):APML_CPU0_ALERT_N
 B66 PRSNT_CPU0_N CPU_PRESENT_L @T6G_MB_LIB.T6G(SCH_1):PRSNT_CPU0_N
 C16 JTAG_CPU0_DBREQ_N DBREQ_L @T6G_MB_LIB.T6G(SCH_1):JTAG_CPU0_DBREQ_N
 A69 CPU0_PROCHOT_N PROCHOT_L @T6G_MB_LIB.T6G(SCH_1):CPU0_PROCHOT_N
DJ55 CPU0_SA0    SA0 @T6G_MB_LIB.T6G(SCH_1):CPU0_SA0
DJ71 SMB_APML_CPU0_SCL    SIC @T6G_MB_LIB.T6G(SCH_1):SMB_APML_CPU0_SCL
DH71 SMB_APML_CPU0_SDA    SID @T6G_MB_LIB.T6G(SCH_1):SMB_APML_CPU0_SDA
 C17 JTAG_CPU0_TDI    TDI @T6G_MB_LIB.T6G(SCH_1):JTAG_CPU0_TDI
 C18 JTAG_CPU0_R_TDO    TDO @T6G_MB_LIB.T6G(SCH_1):JTAG_CPU0_R_TDO
 DJ9 CPU0_THERMTRIP_N THERMTRIP_L @T6G_MB_LIB.T6G(SCH_1):CPU0_THERMTRIP_N
 A16 JTAG_CPU0_TMS    TMS @T6G_MB_LIB.T6G(SCH_1):JTAG_CPU0_TMS
 A17 JTAG_CPU0_TRST_N TRST_L @T6G_MB_LIB.T6G(SCH_1):JTAG_CPU0_TRST_N
 C66 CPU0_XTRIG_R2_L4 XTRIG_L4 @T6G_MB_LIB.T6G(SCH_1):CPU0_XTRIG_R2_L4
 C65 CPU0_XTRIG_R2_L5 XTRIG_L5 @T6G_MB_LIB.T6G(SCH_1):CPU0_XTRIG_R2_L5
 A66 CPU0_XTRIG_R2_L6 XTRIG_L6 @T6G_MB_LIB.T6G(SCH_1):CPU0_XTRIG_R2_L6
 A65 CPU0_XTRIG_R2_L7 XTRIG_L7 @T6G_MB_LIB.T6G(SCH_1):CPU0_XTRIG_R2_L7
DJ56 CPU0_SA1    SA1 @T6G_MB_LIB.T6G(SCH_1):CPU0_SA1
 C70 CPU0_CORETYPE0 CORETYPE0 @T6G_MB_LIB.T6G(SCH_1):CPU0_CORETYPE0
 B69 CPU0_CORETYPE1 CORETYPE1 @T6G_MB_LIB.T6G(SCH_1):CPU0_CORETYPE1
 C68 CPU0_SP5R2  SP5R2 @T6G_MB_LIB.T6G(SCH_1):CPU0_SP5R2
DH73 CPU0_SP5R3  SP5R3 @T6G_MB_LIB.T6G(SCH_1):CPU0_SP5R3
DH10 CPU0_SP5R4  SP5R4 @T6G_MB_LIB.T6G(SCH_1):CPU0_SP5R4
 C22 FM_P0_PCC0_N PCC0_L @T6G_MB_LIB.T6G(SCH_1):FM_P0_PCC0_N
DG72 FM_P0_PCC1_N PCC1_L @T6G_MB_LIB.T6G(SCH_1):FM_P0_PCC1_N
 C32 NC_CPU0_AZ_BITCLK AZ_BITCLK @T6G_MB_LIB.T6G(SCH_1):NC_CPU0_AZ_BITCLK
 D32 NC_CPU0_AZ_SYNC AZ_SYNC @T6G_MB_LIB.T6G(SCH_1):NC_CPU0_AZ_SYNC
 A22 SVID_PVDDCR_CPU0_P0_SVD   SVD0 @T6G_MB_LIB.T6G(SCH_1):SVID_PVDDCR_CPU0_P0_SVD
 B21 SVID_PVDDCR_CPU0_P0_SVTO   SVT0 @T6G_MB_LIB.T6G(SCH_1):SVID_PVDDCR_CPU0_P0_SVTO
DH72 SVID_PVDDCR_CPU1_P0_SVD   SVD1 @T6G_MB_LIB.T6G(SCH_1):SVID_PVDDCR_CPU1_P0_SVD
 A23 SVID_PVDDCR_CPU0_P0_SVC   SVC0 @T6G_MB_LIB.T6G(SCH_1):SVID_PVDDCR_CPU0_P0_SVC
DG73 SVID_PVDDCR_CPU1_P0_SVTO   SVT1 @T6G_MB_LIB.T6G(SCH_1):SVID_PVDDCR_CPU1_P0_SVTO
DJ72 SVID_PVDDCR_CPU1_P0_SVC   SVC1 @T6G_MB_LIB.T6G(SCH_1):SVID_PVDDCR_CPU1_P0_SVC
DG35 UART_CPU0_UART0_RX UART0_RXD||AGPIO136 @T6G_MB_LIB.T6G(SCH_1):UART_CPU0_UART0_RX
DF34 TP_UART_CPU0_UART0_RTS_N UART0_RTS_L||UART2_RXD||AGPIO137 @T6G_MB_LIB.T6G(SCH_1):TP_UART_CPU0_UART0_RTS_N
DG34 TP_CPU0_UART0_INTR UART0_INTR||AGPIO139 @T6G_MB_LIB.T6G(SCH_1):TP_CPU0_UART0_INTR
DJ34 UART_CPU0_UART0_R_TX UART0_TXD||AGPIO138 @T6G_MB_LIB.T6G(SCH_1):UART_CPU0_UART0_R_TX
DJ33 FM_BIOS_USB_RECOVERY_R UART0_CTS_L||UART2_TXD||AGPIO135 @T6G_MB_LIB.T6G(SCH_1):FM_BIOS_USB_RECOVERY_R
 A33 NC_CPU0_AZ_SDIN2 AZ_SDIN2||SW_MDATA0 @T6G_MB_LIB.T6G(SCH_1):NC_CPU0_AZ_SDIN2
 A32 NC_CPU0_AZ_SDOUT AZ_SDOUT||SW_MDATA2 @T6G_MB_LIB.T6G(SCH_1):NC_CPU0_AZ_SDOUT
 A34 NC_CPU0_AZ_RST_N AZ_RST_L||SW_MDATA1 @T6G_MB_LIB.T6G(SCH_1):NC_CPU0_AZ_RST_N
 C33 NC_CPU0_AZ_SDIN0 AZ_SDIN0||SW_MDATA3 @T6G_MB_LIB.T6G(SCH_1):NC_CPU0_AZ_SDIN0
 D33 NC_CPU0_AZ_SDIN1 AZ_SDIN1||SW_MCLK @T6G_MB_LIB.T6G(SCH_1):NC_CPU0_AZ_SDIN1
 C19 CPU0_SP5R1  SP5R1 @T6G_MB_LIB.T6G(SCH_1):CPU0_SP5R1
 B17 JTAG_CPU0_TCK    TCK @T6G_MB_LIB.T6G(SCH_1):JTAG_CPU0_TCK
 DH8 CPU0_RTC_LDO_SELECT RTC_LDO_SELECT @T6G_MB_LIB.T6G(SCH_1):CPU0_RTC_LDO_SELECT
DH33 UART_CPU0_SCM_UART1_RX UART1_RXD||AGPIO141 @T6G_MB_LIB.T6G(SCH_1):UART_CPU0_SCM_UART1_RX
DJ32 UART_CPU0_SCM_UART1_R_TX UART1_TXD||AGPIO142 @T6G_MB_LIB.T6G(SCH_1):UART_CPU0_SCM_UART1_R_TX
  C3 VSENSE_VSS_SENSE_A_P0 VSS_SENSE_A @T6G_MB_LIB.T6G(SCH_1):VSENSE_VSS_SENSE_A_P0
BR54 VSENSE_VSS_SENSE_B_P0 VSS_SENSE_B @T6G_MB_LIB.T6G(SCH_1):VSENSE_VSS_SENSE_B_P0
 DJ3 VSENSE_VSS_SENSE_C_P0 VSS_SENSE_C @T6G_MB_LIB.T6G(SCH_1):VSENSE_VSS_SENSE_C_P0
 B73 VSENSE_PVDD18_S5_P0_DN VSS_SENSE_D @T6G_MB_LIB.T6G(SCH_1):VSENSE_PVDD18_S5_P0_DN
BR53 VSENSE_PVDDIO_P0_DP VDDIO_SENSE @T6G_MB_LIB.T6G(SCH_1):VSENSE_PVDDIO_P0_DP
 DH3 VSENSE_PVDD11_S3_P0_DP VDD_11_S3_SENSE @T6G_MB_LIB.T6G(SCH_1):VSENSE_PVDD11_S3_P0_DP
 C74 VSENSE_PVDD18_S5_P0_DP VDD_18_S5_SENSE @T6G_MB_LIB.T6G(SCH_1):VSENSE_PVDD18_S5_P0_DP
BP53 TP_VSENSE_PVDD33_S5_P0 VDD_33_S5_SENSE @T6G_MB_LIB.T6G(SCH_1):TP_VSENSE_PVDD33_S5_P0
  B3 VSENSE_PVDDCR_SOC_P0_DP VDDCR_SOC_SENSE @T6G_MB_LIB.T6G(SCH_1):VSENSE_PVDDCR_SOC_P0_DP
 DG3 VSENSE_PVDDCR_CPU1_P0_DP VDDCR_CPU1_SENSE @T6G_MB_LIB.T6G(SCH_1):VSENSE_PVDDCR_CPU1_P0_DP
  C2 VSENSE_PVDDCR_CPU0_P0_DP VDDCR_CPU0_SENSE @T6G_MB_LIB.T6G(SCH_1):VSENSE_PVDDCR_CPU0_P0_DP
AA23 TP_CPU0_TEST6_X3D4 TEST6_X3D4 @T6G_MB_LIB.T6G(SCH_1):TP_CPU0_TEST6_X3D4
CJ30 TP_CPU0_TEST6_CCD1 TEST6_CCD1 @T6G_MB_LIB.T6G(SCH_1):TP_CPU0_TEST6_CCD1
AA51 TP_CPU0_TEST5_CCD0 TEST5_CCD0 @T6G_MB_LIB.T6G(SCH_1):TP_CPU0_TEST5_CCD0
CJ53 TP_CPU0_TEST6_X3D5 TEST6_X3D5 @T6G_MB_LIB.T6G(SCH_1):TP_CPU0_TEST6_X3D5
CJ46 TP_CPU0_TEST6_CCD2 TEST6_CCD2 @T6G_MB_LIB.T6G(SCH_1):TP_CPU0_TEST6_CCD2
CJ27 TP_CPU0_TEST5_CCD1 TEST5_CCD1 @T6G_MB_LIB.T6G(SCH_1):TP_CPU0_TEST5_CCD1
AA50 TP_CPU0_TEST4_CCD0 TEST4_CCD0 @T6G_MB_LIB.T6G(SCH_1):TP_CPU0_TEST4_CCD0
 Y46 TP_CPU0_TEST6_CCD3 TEST6_CCD3 @T6G_MB_LIB.T6G(SCH_1):TP_CPU0_TEST6_CCD3
CJ49 TP_CPU0_TEST5_CCD2 TEST5_CCD2 @T6G_MB_LIB.T6G(SCH_1):TP_CPU0_TEST5_CCD2
CJ28 TP_CPU0_TEST4_CCD1 TEST4_CCD1 @T6G_MB_LIB.T6G(SCH_1):TP_CPU0_TEST4_CCD1
 Y30 TP_CPU0_TEST5_CCD3 TEST5_CCD3 @T6G_MB_LIB.T6G(SCH_1):TP_CPU0_TEST5_CCD3
AA25 TP_CPU0_TEST4_IOD TEST4_IOD @T6G_MB_LIB.T6G(SCH_1):TP_CPU0_TEST4_IOD
CJ48 TP_CPU0_TEST4_CCD2 TEST4_CCD2 @T6G_MB_LIB.T6G(SCH_1):TP_CPU0_TEST4_CCD2
AA24 TP_CPU0_TEST5_IOD TEST5_IOD @T6G_MB_LIB.T6G(SCH_1):TP_CPU0_TEST5_IOD
AA53 TP_CPU0_TEST5_CCD4 TEST5_CCD4 @T6G_MB_LIB.T6G(SCH_1):TP_CPU0_TEST5_CCD4
AA30 TP_CPU0_TEST4_CCD3 TEST4_CCD3 @T6G_MB_LIB.T6G(SCH_1):TP_CPU0_TEST4_CCD3
AA49 TP_CPU0_TEST6_IOD TEST6_IOD @T6G_MB_LIB.T6G(SCH_1):TP_CPU0_TEST6_IOD
CJ25 TP_CPU0_TEST5_CCD5 TEST5_CCD5 @T6G_MB_LIB.T6G(SCH_1):TP_CPU0_TEST5_CCD5
AA52 TP_CPU0_TEST4_CCD4 TEST4_CCD4 @T6G_MB_LIB.T6G(SCH_1):TP_CPU0_TEST4_CCD4
CJ51 TP_CPU0_TEST5_CCD6 TEST5_CCD6 @T6G_MB_LIB.T6G(SCH_1):TP_CPU0_TEST5_CCD6
CJ26 TP_CPU0_TEST4_CCD5 TEST4_CCD5 @T6G_MB_LIB.T6G(SCH_1):TP_CPU0_TEST4_CCD5
AA26 TP_CPU0_TEST5_CCD7 TEST5_CCD7 @T6G_MB_LIB.T6G(SCH_1):TP_CPU0_TEST5_CCD7
CJ50 TP_CPU0_TEST4_CCD6 TEST4_CCD6 @T6G_MB_LIB.T6G(SCH_1):TP_CPU0_TEST4_CCD6
 B60 TP_CPU0_TEST47_CCD0 TEST47_CCD0 @T6G_MB_LIB.T6G(SCH_1):TP_CPU0_TEST47_CCD0
 Y47 TP_CPU0_TEST5_CCD8 TEST5_CCD8 @T6G_MB_LIB.T6G(SCH_1):TP_CPU0_TEST5_CCD8
 B61 TP_CPU0_TEST50_IOD TEST50_IOD @T6G_MB_LIB.T6G(SCH_1):TP_CPU0_TEST50_IOD
AA27 TP_CPU0_TEST4_CCD7 TEST4_CCD7 @T6G_MB_LIB.T6G(SCH_1):TP_CPU0_TEST4_CCD7
CJ24 TP_CPU0_TEST47_CCD1 TEST47_CCD1 @T6G_MB_LIB.T6G(SCH_1):TP_CPU0_TEST47_CCD1
CK29 TP_CPU0_TEST5_CCD9 TEST5_CCD9 @T6G_MB_LIB.T6G(SCH_1):TP_CPU0_TEST5_CCD9
AA48 TP_CPU0_TEST4_CCD8 TEST4_CCD8 @T6G_MB_LIB.T6G(SCH_1):TP_CPU0_TEST4_CCD8
CK46 TP_CPU0_TEST47_CCD2 TEST47_CCD2 @T6G_MB_LIB.T6G(SCH_1):TP_CPU0_TEST47_CCD2
CJ47 TP_CPU0_TEST4_CCD10 TEST4_CCD10 @T6G_MB_LIB.T6G(SCH_1):TP_CPU0_TEST4_CCD10
CK30 TP_CPU0_TEST4_CCD9 TEST4_CCD9 @T6G_MB_LIB.T6G(SCH_1):TP_CPU0_TEST4_CCD9
CK47 TP_CPU0_TEST5_CCD10 TEST5_CCD10 @T6G_MB_LIB.T6G(SCH_1):TP_CPU0_TEST5_CCD10
AA28 TP_CPU0_TEST4_CCD11 TEST4_CCD11 @T6G_MB_LIB.T6G(SCH_1):TP_CPU0_TEST4_CCD11
 Y29 TP_CPU0_TEST5_CCD11 TEST5_CCD11 @T6G_MB_LIB.T6G(SCH_1):TP_CPU0_TEST5_CCD11
AA47 TP_CPU0_TEST6_X3D0 TEST6_X3D0 @T6G_MB_LIB.T6G(SCH_1):TP_CPU0_TEST6_X3D0
 B58 TP_CPU0_TEST47_IOD0 TEST47_IOD0 @T6G_MB_LIB.T6G(SCH_1):TP_CPU0_TEST47_IOD0
CJ29 TP_CPU0_TEST6_X3D1 TEST6_X3D1 @T6G_MB_LIB.T6G(SCH_1):TP_CPU0_TEST6_X3D1
  D7 TP_CPU0_TEST47_IOD1 TEST47_IOD1 @T6G_MB_LIB.T6G(SCH_1):TP_CPU0_TEST47_IOD1
AA29 TP_CPU0_TEST6_X3D2 TEST6_X3D2 @T6G_MB_LIB.T6G(SCH_1):TP_CPU0_TEST6_X3D2
CJ52 TP_CPU0_TEST6_X3D3 TEST6_X3D3 @T6G_MB_LIB.T6G(SCH_1):TP_CPU0_TEST6_X3D3
AA46 TP_CPU0_TEST6_CCD0 TEST6_CCD0 @T6G_MB_LIB.T6G(SCH_1):TP_CPU0_TEST6_CCD0
 E32 TP_CPU0_TEST47_CCD3 TEST47_CCD3 @T6G_MB_LIB.T6G(SCH_1):TP_CPU0_TEST47_CCD3
 W31 TP_CPU0_TEST41_IDO TEST41_IOD @T6G_MB_LIB.T6G(SCH_1):TP_CPU0_TEST41_IDO
 C63 CPU0_BP0    BP0 @T6G_MB_LIB.T6G(SCH_1):CPU0_BP0
 C62 CPU0_BP1    BP1 @T6G_MB_LIB.T6G(SCH_1):CPU0_BP1
 A63 CPU0_BP2    BP2 @T6G_MB_LIB.T6G(SCH_1):CPU0_BP2
 A62 CPU0_BP3    BP3 @T6G_MB_LIB.T6G(SCH_1):CPU0_BP3
 D68 CPU0_CORETYPE2 CORETYPE2 @T6G_MB_LIB.T6G(SCH_1):CPU0_CORETYPE2

Q_RES_0402LF-0,5%,1/16W,CHIP,CS00002JB13  I279  R405
   1 UART_CPU0_UART0_TX      A @T6G_MB_LIB.T6G(SCH_1):UART_CPU0_UART0_TX
   2 UART_CPU0_UART0_R_TX      B @T6G_MB_LIB.T6G(SCH_1):UART_CPU0_UART0_R_TX

Q_RES_0402LF-0,5%,1/16W,CHIP,CS00002JB13  I288  R2318
   1 UART_CPU0_SCM_UART1_R_TX      A @T6G_MB_LIB.T6G(SCH_1):UART_CPU0_SCM_UART1_R_TX
   2 UART_CPU0_SCM_UART1_TX      B @T6G_MB_LIB.T6G(SCH_1):UART_CPU0_SCM_UART1_TX

Q_RES_0402LF-1K,1%,1/16W,CHIP,CS21002FB06  I294  R403
   1 PVDD18_S5_P0      A @T6G_MB_LIB.T6G(SCH_1):PVDD18_S5_P0
   2 JTAG_CPU0_DBREQ_N      B @T6G_MB_LIB.T6G(SCH_1):JTAG_CPU0_DBREQ_N

Q_CAP_C0402-0.001UF,50V,10%,EMPTY,CH30106KB19  I295  C212
   1 JTAG_CPU0_DBREQ_N      A @T6G_MB_LIB.T6G(SCH_1):JTAG_CPU0_DBREQ_N
   2    GND      B @T6G_MB_LIB.T6G(SCH_1):GND

Q_RES_0402LF-1K,1%,1/16W,CHIP,CS21002FB06  I296  R402
   1 PVDD18_S5_P0      A @T6G_MB_LIB.T6G(SCH_1):PVDD18_S5_P0
   2 JTAG_CPU0_TMS      B @T6G_MB_LIB.T6G(SCH_1):JTAG_CPU0_TMS

Q_CAP_C0402-0.001UF,50V,10%,EMPTY,CH30106KB19  I297  C211
   1 JTAG_CPU0_TMS      A @T6G_MB_LIB.T6G(SCH_1):JTAG_CPU0_TMS
   2    GND      B @T6G_MB_LIB.T6G(SCH_1):GND

Q_RES_0402LF-1K,1%,1/16W,CHIP,CS21002FB06  I300  R401
   1 PVDD18_S5_P0      A @T6G_MB_LIB.T6G(SCH_1):PVDD18_S5_P0
   2 JTAG_CPU0_TCK      B @T6G_MB_LIB.T6G(SCH_1):JTAG_CPU0_TCK

Q_RES_0402LF-1K,1%,1/16W,CHIP,CS21002FB06  I301  R400
   1 PVDD18_S5_P0      A @T6G_MB_LIB.T6G(SCH_1):PVDD18_S5_P0
   2 JTAG_CPU0_TRST_N      B @T6G_MB_LIB.T6G(SCH_1):JTAG_CPU0_TRST_N

Q_CAP_C0402-0.001UF,50V,10%,EMPTY,CH30106KB19  I302  C210
   1 JTAG_CPU0_TCK      A @T6G_MB_LIB.T6G(SCH_1):JTAG_CPU0_TCK
   2    GND      B @T6G_MB_LIB.T6G(SCH_1):GND

Q_CAP_C0402-0.001UF,50V,10%,EMPTY,CH30106KB19  I303  C209
   1 JTAG_CPU0_TRST_N      A @T6G_MB_LIB.T6G(SCH_1):JTAG_CPU0_TRST_N
   2    GND      B @T6G_MB_LIB.T6G(SCH_1):GND

Q_RES_0402LF-1K,1%,1/16W,CHIP,CS21002FB06  I304  R399
   1 PVDD18_S5_P0      A @T6G_MB_LIB.T6G(SCH_1):PVDD18_S5_P0
   2 JTAG_CPU0_TDI      B @T6G_MB_LIB.T6G(SCH_1):JTAG_CPU0_TDI

Q_RES_0402LF-1K,1%,1/16W,CHIP,CS21002FB06  I305  R398
   1 PVDD18_S5_P0      A @T6G_MB_LIB.T6G(SCH_1):PVDD18_S5_P0
   2 JTAG_CPU0_TDO      B @T6G_MB_LIB.T6G(SCH_1):JTAG_CPU0_TDO

Q_CAP_C0402-0.001UF,50V,10%,EMPTY,CH30106KB19  I306  C208
   1 JTAG_CPU0_TDI      A @T6G_MB_LIB.T6G(SCH_1):JTAG_CPU0_TDI
   2    GND      B @T6G_MB_LIB.T6G(SCH_1):GND

Q_CAP_C0402-0.001UF,50V,10%,EMPTY,CH30106KB19  I307  C207
   1 JTAG_CPU0_TDO      A @T6G_MB_LIB.T6G(SCH_1):JTAG_CPU0_TDO
   2    GND      B @T6G_MB_LIB.T6G(SCH_1):GND

Q_RES_0402LF-0,5%,1/16W,CHIP,CS00002JB13  I318  PR59
   1 SVID_PVDDCR_CPU1_P0_SVC_R      A @T6G_MB_LIB.T6G(SCH_1):SVID_PVDDCR_CPU1_P0_SVC_R
   2 SVID_PVDDCR_CPU1_P0_SVC      B @T6G_MB_LIB.T6G(SCH_1):SVID_PVDDCR_CPU1_P0_SVC

Q_RES_0402LF-0,5%,1/16W,CHIP,CS00002JB13  I319  PR60
   1 SVID_PVDDCR_CPU1_P0_SVD_R      A @T6G_MB_LIB.T6G(SCH_1):SVID_PVDDCR_CPU1_P0_SVD_R
   2 SVID_PVDDCR_CPU1_P0_SVD      B @T6G_MB_LIB.T6G(SCH_1):SVID_PVDDCR_CPU1_P0_SVD

Q_RES_0402LF-0,5%,1/16W,CHIP,CS00002JB13  I322  PR303
   1 SVID_PVDDCR_CPU0_P0_SVD_R      A @T6G_MB_LIB.T6G(SCH_1):SVID_PVDDCR_CPU0_P0_SVD_R
   2 SVID_PVDDCR_CPU0_P0_SVD      B @T6G_MB_LIB.T6G(SCH_1):SVID_PVDDCR_CPU0_P0_SVD

Q_RES_0402LF-0,5%,1/16W,CHIP,CS00002JB13  I323  PR302
   1 SVID_PVDDCR_CPU0_P0_SVC_R      A @T6G_MB_LIB.T6G(SCH_1):SVID_PVDDCR_CPU0_P0_SVC_R
   2 SVID_PVDDCR_CPU0_P0_SVC      B @T6G_MB_LIB.T6G(SCH_1):SVID_PVDDCR_CPU0_P0_SVC

Q_RES_0402LF-0,5%,1/16W,CHIP,CS00002JB13  I334  R483
   1 CPU0_XTRIG_L5      A @T6G_MB_LIB.T6G(SCH_1):CPU0_XTRIG_L5
   2 CPU0_XTRIG_R1_L5      B @T6G_MB_LIB.T6G(SCH_1):CPU0_XTRIG_R1_L5

Q_RES_0402LF-0,5%,1/16W,CHIP,CS00002JB13  I335  R481
   1 CPU0_XTRIG_L4      A @T6G_MB_LIB.T6G(SCH_1):CPU0_XTRIG_L4
   2 CPU0_XTRIG_R1_L4      B @T6G_MB_LIB.T6G(SCH_1):CPU0_XTRIG_R1_L4

Q_RES_0402LF-0,5%,1/16W,CHIP,CS00002JB13  I336  R484
   1 CPU0_XTRIG_L6      A @T6G_MB_LIB.T6G(SCH_1):CPU0_XTRIG_L6
   2 CPU0_XTRIG_R1_L6      B @T6G_MB_LIB.T6G(SCH_1):CPU0_XTRIG_R1_L6

Q_RES_0402LF-0,5%,1/16W,CHIP,CS00002JB13  I337  R485
   1 CPU0_XTRIG_L7      A @T6G_MB_LIB.T6G(SCH_1):CPU0_XTRIG_L7
   2 CPU0_XTRIG_R1_L7      B @T6G_MB_LIB.T6G(SCH_1):CPU0_XTRIG_R1_L7

Q_RES_0402LF-0,5%,1/16W,CHIP,CS00002JB13  I346  R156
   1 CPU0_XTRIG_R2_L4      A @T6G_MB_LIB.T6G(SCH_1):CPU0_XTRIG_R2_L4
   2 CPU0_XTRIG_L4      B @T6G_MB_LIB.T6G(SCH_1):CPU0_XTRIG_L4

Q_RES_0402LF-0,5%,1/16W,CHIP,CS00002JB13  I347  R157
   1 CPU0_XTRIG_R2_L5      A @T6G_MB_LIB.T6G(SCH_1):CPU0_XTRIG_R2_L5
   2 CPU0_XTRIG_L5      B @T6G_MB_LIB.T6G(SCH_1):CPU0_XTRIG_L5

Q_RES_0402LF-0,5%,1/16W,CHIP,CS00002JB13  I348  R357
   1 CPU0_XTRIG_R2_L7      A @T6G_MB_LIB.T6G(SCH_1):CPU0_XTRIG_R2_L7
   2 CPU0_XTRIG_L7      B @T6G_MB_LIB.T6G(SCH_1):CPU0_XTRIG_L7

Q_RES_0402LF-0,5%,1/16W,CHIP,CS00002JB13  I349  R356
   1 CPU0_XTRIG_R2_L6      A @T6G_MB_LIB.T6G(SCH_1):CPU0_XTRIG_R2_L6
   2 CPU0_XTRIG_L6      B @T6G_MB_LIB.T6G(SCH_1):CPU0_XTRIG_L6

Q_RES_0402LF-0,5%,1/16W,CHIP,CS00002JB13  I353  R1204
   1 FM_BIOS_USB_RECOVERY_R      A @T6G_MB_LIB.T6G(SCH_1):FM_BIOS_USB_RECOVERY_R
   2 FM_BIOS_USB_RECOVERY      B @T6G_MB_LIB.T6G(SCH_1):FM_BIOS_USB_RECOVERY

TP_TP-NA,TP30  I355  TP9
   1 VSENSE_PVDD18_S5_P0_DP     TP @T6G_MB_LIB.T6G(SCH_1):VSENSE_PVDD18_S5_P0_DP

TP_TP-NA,TP30  I356  TP8
   1 VSENSE_PVDD11_S3_P0_DP     TP @T6G_MB_LIB.T6G(SCH_1):VSENSE_PVDD11_S3_P0_DP

TP_TP-NA,TP30  I357  TP7
   1 VSENSE_PVDDCR_CPU0_P0_DP     TP @T6G_MB_LIB.T6G(SCH_1):VSENSE_PVDDCR_CPU0_P0_DP

TP_TP-NA,TP30  I358  TP6
   1 VSENSE_PVDDCR_CPU1_P0_DP     TP @T6G_MB_LIB.T6G(SCH_1):VSENSE_PVDDCR_CPU1_P0_DP

TP_TP-NA,TP30  I359  TP5
   1 VSENSE_PVDDIO_P0_DP     TP @T6G_MB_LIB.T6G(SCH_1):VSENSE_PVDDIO_P0_DP

TP_TP-NA,TP30  I360  TP4
   1 VSENSE_PVDD18_S5_P0_DN     TP @T6G_MB_LIB.T6G(SCH_1):VSENSE_PVDD18_S5_P0_DN

TP_TP-NA,TP30  I361  TP3
   1 VSENSE_VSS_SENSE_C_P0     TP @T6G_MB_LIB.T6G(SCH_1):VSENSE_VSS_SENSE_C_P0

TP_TP-NA,TP30  I362  TP2
   1 VSENSE_VSS_SENSE_B_P0     TP @T6G_MB_LIB.T6G(SCH_1):VSENSE_VSS_SENSE_B_P0

Q_RES_0402LF-2.2K,5%,1/16W,CHIP,CS22202JB07  I377  R412
   1 CPU0_PROCHOT_N      A @T6G_MB_LIB.T6G(SCH_1):CPU0_PROCHOT_N
   2 PVDD18_S5_P0      B @T6G_MB_LIB.T6G(SCH_1):PVDD18_S5_P0

Q_RES_0402LF-2.2K,5%,1/16W,CHIP,CS22202JB07  I378  R418
   1 APML_CPU0_ALERT_N      A @T6G_MB_LIB.T6G(SCH_1):APML_CPU0_ALERT_N
   2 PVDD18_S5_P0      B @T6G_MB_LIB.T6G(SCH_1):PVDD18_S5_P0

Q_RES_0402LF-2.2K,5%,1/16W,CHIP,CS22202JB07  I379  R417
   1 CPU0_THERMTRIP_N      A @T6G_MB_LIB.T6G(SCH_1):CPU0_THERMTRIP_N
   2 PVDD18_S5_P0      B @T6G_MB_LIB.T6G(SCH_1):PVDD18_S5_P0

Q_RES_0402LF-2.2K,5%,1/16W,CHIP,CS22202JB07  I380  R408
   1 CPU0_BP0      A @T6G_MB_LIB.T6G(SCH_1):CPU0_BP0
   2 PVDD18_S5_P0      B @T6G_MB_LIB.T6G(SCH_1):PVDD18_S5_P0

Q_RES_0402LF-2.2K,5%,1/16W,CHIP,CS22202JB07  I381  R409
   1 CPU0_BP1      A @T6G_MB_LIB.T6G(SCH_1):CPU0_BP1
   2 PVDD18_S5_P0      B @T6G_MB_LIB.T6G(SCH_1):PVDD18_S5_P0

Q_RES_0402LF-2.2K,5%,1/16W,CHIP,CS22202JB07  I382  R410
   1 CPU0_BP2      A @T6G_MB_LIB.T6G(SCH_1):CPU0_BP2
   2 PVDD18_S5_P0      B @T6G_MB_LIB.T6G(SCH_1):PVDD18_S5_P0

Q_RES_0402LF-2.2K,5%,1/16W,CHIP,CS22202JB07  I383  R411
   1 CPU0_BP3      A @T6G_MB_LIB.T6G(SCH_1):CPU0_BP3
   2 PVDD18_S5_P0      B @T6G_MB_LIB.T6G(SCH_1):PVDD18_S5_P0

Q_RES_0402LF-2.2K,5%,1/16W,CHIP,CS22202JB07  I384  R413
   1 CPU0_XTRIG_L4      A @T6G_MB_LIB.T6G(SCH_1):CPU0_XTRIG_L4
   2 PVDD18_S5_P0      B @T6G_MB_LIB.T6G(SCH_1):PVDD18_S5_P0

Q_RES_0402LF-2.2K,5%,1/16W,CHIP,CS22202JB07  I385  R414
   1 CPU0_XTRIG_L5      A @T6G_MB_LIB.T6G(SCH_1):CPU0_XTRIG_L5
   2 PVDD18_S5_P0      B @T6G_MB_LIB.T6G(SCH_1):PVDD18_S5_P0

Q_RES_0402LF-2.2K,5%,1/16W,CHIP,CS22202JB07  I386  R415
   1 CPU0_XTRIG_L6      A @T6G_MB_LIB.T6G(SCH_1):CPU0_XTRIG_L6
   2 PVDD18_S5_P0      B @T6G_MB_LIB.T6G(SCH_1):PVDD18_S5_P0

Q_RES_0402LF-2.2K,5%,1/16W,CHIP,CS22202JB07  I387  R416
   1 CPU0_XTRIG_L7      A @T6G_MB_LIB.T6G(SCH_1):CPU0_XTRIG_L7
   2 PVDD18_S5_P0      B @T6G_MB_LIB.T6G(SCH_1):PVDD18_S5_P0

Q_RES_0402LF-2.2K,5%,1/16W,CHIP,CS22202JB07  I388  R387
   1 P3V3_AUX      A @T6G_MB_LIB.T6G(SCH_1):P3V3_AUX
   2 CPU0_CORETYPE2      B @T6G_MB_LIB.T6G(SCH_1):CPU0_CORETYPE2

Q_RES_0402LF-2.2K,5%,1/16W,CHIP,CS22202JB07  I389  R388
   1 P3V3_AUX      A @T6G_MB_LIB.T6G(SCH_1):P3V3_AUX
   2 CPU0_CORETYPE1      B @T6G_MB_LIB.T6G(SCH_1):CPU0_CORETYPE1

Q_RES_0402LF-2.2K,5%,1/16W,CHIP,CS22202JB07  I390  R390
   1 P3V3_AUX      A @T6G_MB_LIB.T6G(SCH_1):P3V3_AUX
   2 CPU0_CORETYPE0      B @T6G_MB_LIB.T6G(SCH_1):CPU0_CORETYPE0

Q_RES_0402LF-2.2K,5%,1/16W,CHIP,CS22202JB07  I391  R389
   1 P3V3_AUX      A @T6G_MB_LIB.T6G(SCH_1):P3V3_AUX
   2 CPU0_SP5R4      B @T6G_MB_LIB.T6G(SCH_1):CPU0_SP5R4

Q_RES_0402LF-2.2K,5%,1/16W,CHIP,CS22202JB07  I392  R391
   1 P3V3_AUX      A @T6G_MB_LIB.T6G(SCH_1):P3V3_AUX
   2 CPU0_SP5R3      B @T6G_MB_LIB.T6G(SCH_1):CPU0_SP5R3

Q_RES_0402LF-2.2K,5%,1/16W,CHIP,CS22202JB07  I393  R396
   1 P3V3_AUX      A @T6G_MB_LIB.T6G(SCH_1):P3V3_AUX
   2 CPU0_SP5R2      B @T6G_MB_LIB.T6G(SCH_1):CPU0_SP5R2

Q_RES_0402LF-2.2K,5%,1/16W,CHIP,CS22202JB07  I394  R397
   1 P3V3_AUX      A @T6G_MB_LIB.T6G(SCH_1):P3V3_AUX
   2 CPU0_SP5R1      B @T6G_MB_LIB.T6G(SCH_1):CPU0_SP5R1

Q_RES_0402LF-2.2K,5%,1/16W,EMPTY,CS22202JB07  I395  R392
   1 PVDD18_S5_P0      A @T6G_MB_LIB.T6G(SCH_1):PVDD18_S5_P0
   2 CPU0_SA0      B @T6G_MB_LIB.T6G(SCH_1):CPU0_SA0

Q_RES_0402LF-2.2K,5%,1/16W,CHIP,CS22202JB07  I396  R393
   1 CPU0_SA0      A @T6G_MB_LIB.T6G(SCH_1):CPU0_SA0
   2    GND      B @T6G_MB_LIB.T6G(SCH_1):GND

Q_RES_0402LF-2.2K,5%,1/16W,CHIP,CS22202JB07  I397  R394
   1 CPU0_SA1      A @T6G_MB_LIB.T6G(SCH_1):CPU0_SA1
   2    GND      B @T6G_MB_LIB.T6G(SCH_1):GND

Q_RES_0402LF-33,5%,1/16W,CHIP,CS03302JB10  I399  R489
   1 CPU0_THERMTRIP_N      A @T6G_MB_LIB.T6G(SCH_1):CPU0_THERMTRIP_N
   2 CPU0_THERMTRIP_R_N      B @T6G_MB_LIB.T6G(SCH_1):CPU0_THERMTRIP_R_N

Q_RES_0402LF-33,5%,1/16W,CHIP,CS03302JB10  I401  R247
   1 APML_CPU0_ALERT_N      A @T6G_MB_LIB.T6G(SCH_1):APML_CPU0_ALERT_N
   2 APML_CPU0_ALERT_R_N      B @T6G_MB_LIB.T6G(SCH_1):APML_CPU0_ALERT_R_N

TP_TP-NA,TP26  I403  TP10
   1 VSENSE_PVDDCR_SOC_P0_DP     TP @T6G_MB_LIB.T6G(SCH_1):VSENSE_PVDDCR_SOC_P0_DP

TP_TP-NA,TP26  I404  TP1
   1 VSENSE_VSS_SENSE_A_P0     TP @T6G_MB_LIB.T6G(SCH_1):VSENSE_VSS_SENSE_A_P0

CONN10_HBC1051L300D8H-CONN10_HBC1051-L300D-8H,THLFA  I423  J212
   1 CPU0_XTRIG_L4      1 @T6G_MB_LIB.T6G(SCH_1):CPU0_XTRIG_L4
   2 CPU1_XTRIG_L4      2 @T6G_MB_LIB.T6G(SCH_1):CPU1_XTRIG_L4
   3 CPU0_XTRIG_L5      3 @T6G_MB_LIB.T6G(SCH_1):CPU0_XTRIG_L5
   4 CPU1_XTRIG_L5      4 @T6G_MB_LIB.T6G(SCH_1):CPU1_XTRIG_L5
   5 CPU0_XTRIG_L6      5 @T6G_MB_LIB.T6G(SCH_1):CPU0_XTRIG_L6
   6 CPU1_XTRIG_L6      6 @T6G_MB_LIB.T6G(SCH_1):CPU1_XTRIG_L6
   7 CPU0_XTRIG_L7      7 @T6G_MB_LIB.T6G(SCH_1):CPU0_XTRIG_L7
   9     NC      9     NC
   8 CPU1_XTRIG_L7      8 @T6G_MB_LIB.T6G(SCH_1):CPU1_XTRIG_L7
  10     NC     10     NC

SCONN8_G802M0083150RD3HR-SCONN8_G802M0083150RD3HR,A  I424  J48
   1 CPU0_BP0      1 @T6G_MB_LIB.T6G(SCH_1):CPU0_BP0
   2    GND      2 @T6G_MB_LIB.T6G(SCH_1):GND
   3 CPU0_BP1      3 @T6G_MB_LIB.T6G(SCH_1):CPU0_BP1
   4    GND      4 @T6G_MB_LIB.T6G(SCH_1):GND
   5 CPU0_BP2      5 @T6G_MB_LIB.T6G(SCH_1):CPU0_BP2
   6    GND      6 @T6G_MB_LIB.T6G(SCH_1):GND
   7 CPU0_BP3      7 @T6G_MB_LIB.T6G(SCH_1):CPU0_BP3
   8    GND      8 @T6G_MB_LIB.T6G(SCH_1):GND

SCONN8_G802M0083150RD3HR-SCONN8_G802M0083150RD3HR,A  I425  J5
   1 CPU0_XTRIG_R1_L4      1 @T6G_MB_LIB.T6G(SCH_1):CPU0_XTRIG_R1_L4
   2    GND      2 @T6G_MB_LIB.T6G(SCH_1):GND
   3 CPU0_XTRIG_R1_L5      3 @T6G_MB_LIB.T6G(SCH_1):CPU0_XTRIG_R1_L5
   4    GND      4 @T6G_MB_LIB.T6G(SCH_1):GND
   5 CPU0_XTRIG_R1_L6      5 @T6G_MB_LIB.T6G(SCH_1):CPU0_XTRIG_R1_L6
   6    GND      6 @T6G_MB_LIB.T6G(SCH_1):GND
   7 CPU0_XTRIG_R1_L7      7 @T6G_MB_LIB.T6G(SCH_1):CPU0_XTRIG_R1_L7
   8    GND      8 @T6G_MB_LIB.T6G(SCH_1):GND

Q_RES_0402LF-10K,5%,1/16W,CHIP,CS31002JB08  I427  R5055
   1 P1V5_BAT      A @T6G_MB_LIB.T6G(SCH_1):P1V5_BAT
   2 CPU0_RTC_LDO_SELECT      B @T6G_MB_LIB.T6G(SCH_1):CPU0_RTC_LDO_SELECT

Q_RES_0402LF-10K,5%,1/16W,EMPTY,CS31002JB08  I428  R5056
   1 CPU0_RTC_LDO_SELECT      A @T6G_MB_LIB.T6G(SCH_1):CPU0_RTC_LDO_SELECT
   2    GND      B @T6G_MB_LIB.T6G(SCH_1):GND

Q_RES_0402LF-0,5%,1/16W,CHIP,CS00002JB13  I429  R1533
   1 CPU0_THERMTRIP_R_N      A @T6G_MB_LIB.T6G(SCH_1):CPU0_THERMTRIP_R_N
   2 CPU1_THERMTRIP_R_N      B @T6G_MB_LIB.T6G(SCH_1):CPU1_THERMTRIP_R_N


DRAWING: @T6G_MB_LIB.T6G(SCH_1):PAGE29 

Q_RES_0402LF-4.7K,5%,1/16W,EMPTY,CS24702JB10  I282  R457
   1 PVDD18_S5_P0      A @T6G_MB_LIB.T6G(SCH_1):PVDD18_S5_P0
   2 RST_ESPI_CPU0_RSTOUT_N      B @T6G_MB_LIB.T6G(SCH_1):RST_ESPI_CPU0_RSTOUT_N

Q_RES_0402LF-4.7K,5%,1/16W,EMPTY,CS24702JB10  I284  R455
   1 PVDD18_S5_P0      A @T6G_MB_LIB.T6G(SCH_1):PVDD18_S5_P0
   2 ESPI_CPU0_CS1_N      B @T6G_MB_LIB.T6G(SCH_1):ESPI_CPU0_CS1_N

GENOA_SP5-SOCKET6096_13568-001,SMLF,IO,DGA^6000030  I287  U25
 A25 USB2_CPU0_P0_DN USB00_DN @T6G_MB_LIB.T6G(SCH_1):USB2_CPU0_P0_DN
 A26 USB2_CPU0_P0_DP USB00_DP @T6G_MB_LIB.T6G(SCH_1):USB2_CPU0_P0_DP
 E26 USB3_CPU0_BMC_RX_HUB_C_DN USB00_RXN @T6G_MB_LIB.T6G(SCH_1):USB3_CPU0_BMC_RX_HUB_C_DN
 E27 USB3_CPU0_BMC_RX_HUB_C_DP USB00_RXP @T6G_MB_LIB.T6G(SCH_1):USB3_CPU0_BMC_RX_HUB_C_DP
 C26 USB3_CPU0_BMC_TX_DN USB00_TXN @T6G_MB_LIB.T6G(SCH_1):USB3_CPU0_BMC_TX_DN
 C25 USB3_CPU0_BMC_TX_DP USB00_TXP @T6G_MB_LIB.T6G(SCH_1):USB3_CPU0_BMC_TX_DP
 A29 USB2_CPU0_P1_DN USB01_DN @T6G_MB_LIB.T6G(SCH_1):USB2_CPU0_P1_DN
 A28 USB2_CPU0_P1_DP USB01_DP @T6G_MB_LIB.T6G(SCH_1):USB2_CPU0_P1_DP
 C28     NC USB01_RXN     NC
 C29     NC USB01_RXP     NC
 E29     NC USB01_TXN     NC
 E30     NC USB01_TXP     NC
DH67 USB2_CPU0_P10_DN USB10_DN @T6G_MB_LIB.T6G(SCH_1):USB2_CPU0_P10_DN
DJ67 USB2_CPU0_P10_DP USB10_DP @T6G_MB_LIB.T6G(SCH_1):USB2_CPU0_P10_DP
DH65     NC USB10_RXN     NC
DJ65     NC USB10_RXP     NC
DJ69     NC USB10_TXN     NC
DH69     NC USB10_TXP     NC
DJ60 USB2_CPU0_P11_DN USB11_DN @T6G_MB_LIB.T6G(SCH_1):USB2_CPU0_P11_DN
DH60 USB2_CPU0_P11_DP USB11_DP @T6G_MB_LIB.T6G(SCH_1):USB2_CPU0_P11_DP
DH62     NC USB11_RXN     NC
DJ62     NC USB11_RXP     NC
DH58     NC USB11_TXN     NC
DG58     NC USB11_TXP     NC
DG40     NC USB10_OC_L||AGPIO16     NC
DH40     NC USB11_OC_L||AGPIO17     NC
DG28 CPU0_ESPI_CS0_N ESPI_CS0_L||AGPIO124 @T6G_MB_LIB.T6G(SCH_1):CPU0_ESPI_CS0_N
 E23 SCM_USB_OC_BUF_N USB00_OC_L||AGPIO264 @T6G_MB_LIB.T6G(SCH_1):SCM_USB_OC_BUF_N
DF30 SPI_CPU0_R_CS0_N SPI_CS0_L||AGPIO118 @T6G_MB_LIB.T6G(SCH_1):SPI_CPU0_R_CS0_N
DE24 ESPI_CPU0_R_D1 ESPI1_DAT1||SPI1_DAT1||AGPIO132 @T6G_MB_LIB.T6G(SCH_1):ESPI_CPU0_R_D1
DH24 ESPI_CPU0_R_D0 ESPI1_DAT0||SPI1_DAT0||AGPIO131 @T6G_MB_LIB.T6G(SCH_1):ESPI_CPU0_R_D0
DJ23 ESPI_CPU0_R_CS1_N ESPI_CS1_L||AGPIO125 @T6G_MB_LIB.T6G(SCH_1):ESPI_CPU0_R_CS1_N
DG25 ESPI_CPU0_R_D3 ESPI1_DAT3||SPI1_DAT3||AGPIO134 @T6G_MB_LIB.T6G(SCH_1):ESPI_CPU0_R_D3
DF25 ESPI_CPU0_R_D2 ESPI1_DAT2||SPI1_DAT2||AGPIO133 @T6G_MB_LIB.T6G(SCH_1):ESPI_CPU0_R_D2
DG29 SPI_CPU0_R_D3 ESPI0_DAT3||SPI0_DAT3||AGPIO123 @T6G_MB_LIB.T6G(SCH_1):SPI_CPU0_R_D3
DJ28 SPI_CPU0_R_D2 ESPI0_DAT2||SPI0_DAT2||AGPIO122 @T6G_MB_LIB.T6G(SCH_1):SPI_CPU0_R_D2
DG22 SPI_CPU0_R_D1 ESPI0_DAT1||SPI0_DAT1||AGPIO121 @T6G_MB_LIB.T6G(SCH_1):SPI_CPU0_R_D1
DF28 SPI_CPU0_R_D0 ESPI0_DAT0||SPI0_DAT0||AGPIO120 @T6G_MB_LIB.T6G(SCH_1):SPI_CPU0_R_D0
DH27 NC_CPU0_SPI_CS2_N SPI_CS2_L||AGPIO126 @T6G_MB_LIB.T6G(SCH_1):NC_CPU0_SPI_CS2_N
DG26 SPI_CPU0_R_CS1_N SPI_CS1_L||AGPIO119 @T6G_MB_LIB.T6G(SCH_1):SPI_CPU0_R_CS1_N
 E24     NC USB01_OC_L||AGPIO265     NC
DJ26 RST_CPU0_KBRST_R_N ESPI_RSTIN_L||KBRST_L||AGPIO129 @T6G_MB_LIB.T6G(SCH_1):RST_CPU0_KBRST_R_N
DF24 ESPI_CPU0_R_ALERT_N ESPI1_ALERT_L||AGPIO110 @T6G_MB_LIB.T6G(SCH_1):ESPI_CPU0_R_ALERT_N
DJ27 SPI_CPU0_R_CLK ESPI_CLK0||SPI_CLK0||AGPIO117 @T6G_MB_LIB.T6G(SCH_1):SPI_CPU0_R_CLK
DJ25 SPI_CPU0_R_TPM_CS_N AGPIO76||SPI_TPM_CS_L @T6G_MB_LIB.T6G(SCH_1):SPI_CPU0_R_TPM_CS_N
DJ22 CPU0_ESPI0_ALERT_N ESPI0_ALERT_L||AGPIO108 @T6G_MB_LIB.T6G(SCH_1):CPU0_ESPI0_ALERT_N
DF27 PD_ESPI_CPU0_CLK2 ESPI_CLK2||AGPIO74 @T6G_MB_LIB.T6G(SCH_1):PD_ESPI_CPU0_CLK2
DG23 CLK_ESPI_CPU0_R_CLK1 ESPI_CLK1||SPI_CLK1||AGPIO75 @T6G_MB_LIB.T6G(SCH_1):CLK_ESPI_CPU0_R_CLK1
DE27 RST_ESPI_CPU0_R_RSTOUT_N ESPI_RSTOUT_L||AGPIO23 @T6G_MB_LIB.T6G(SCH_1):RST_ESPI_CPU0_R_RSTOUT_N

Q_RES_0402LF-33,5%,1/16W,CHIP,CS03302JB10  I327  R470
   1 ESPI_CPU0_D2      A @T6G_MB_LIB.T6G(SCH_1):ESPI_CPU0_D2
   2 ESPI_CPU0_R_D2      B @T6G_MB_LIB.T6G(SCH_1):ESPI_CPU0_R_D2

Q_RES_0402LF-33,5%,1/16W,CHIP,CS03302JB10  I328  R469
   1 ESPI_CPU0_D1      A @T6G_MB_LIB.T6G(SCH_1):ESPI_CPU0_D1
   2 ESPI_CPU0_R_D1      B @T6G_MB_LIB.T6G(SCH_1):ESPI_CPU0_R_D1

Q_RES_0402LF-33,5%,1/16W,CHIP,CS03302JB10  I329  R468
   1 ESPI_CPU0_D0      A @T6G_MB_LIB.T6G(SCH_1):ESPI_CPU0_D0
   2 ESPI_CPU0_R_D0      B @T6G_MB_LIB.T6G(SCH_1):ESPI_CPU0_R_D0

Q_RES_0402LF-33,5%,1/16W,CHIP,CS03302JB10  I330  R471
   1 ESPI_CPU0_D3      A @T6G_MB_LIB.T6G(SCH_1):ESPI_CPU0_D3
   2 ESPI_CPU0_R_D3      B @T6G_MB_LIB.T6G(SCH_1):ESPI_CPU0_R_D3

Q_RES_0402LF-0,5%,1/16W,CHIP,CS00002JB13  I332  R474
   1 RST_ESPI_CPU0_RSTOUT_N      A @T6G_MB_LIB.T6G(SCH_1):RST_ESPI_CPU0_RSTOUT_N
   2 RST_ESPI_CPU0_R_RSTOUT_N      B @T6G_MB_LIB.T6G(SCH_1):RST_ESPI_CPU0_R_RSTOUT_N

SN74LVC1G07DBVR_SMLF-SN74LVC1G07DBVR,IC,AL1G0007024  I373  U3
   2 SCM_USB_OC_N      A @T6G_MB_LIB.T6G(SCH_1):SCM_USB_OC_N
   4 SCM_USB_OC_BU_R_N      Y @T6G_MB_LIB.T6G(SCH_1):SCM_USB_OC_BU_R_N
   1     NC     NC     NC
   5 P1V8_AUX    VCC @T6G_MB_LIB.T6G(SCH_1):P1V8_AUX
   3    GND    GND @T6G_MB_LIB.T6G(SCH_1):GND

Q_RES_0402LF-0,5%,1/16W,CHIP,CS00002JB13  I377  R589
   1 SCM_USB_OC_BU_R_N      A @T6G_MB_LIB.T6G(SCH_1):SCM_USB_OC_BU_R_N
   2 SCM_USB_OC_BUF_N      B @T6G_MB_LIB.T6G(SCH_1):SCM_USB_OC_BUF_N

Q_CAP_0402-0.1UF,25V,10%,X7R,CH4104K1B00  I379  C30
   1 P1V8_AUX      A @T6G_MB_LIB.T6G(SCH_1):P1V8_AUX
   2    GND      B @T6G_MB_LIB.T6G(SCH_1):GND

Q_RES_0402LF-10K,5%,1/16W,CHIP,CS31002JB08  I383  R454
   1 PVDD18_S5_P0      A @T6G_MB_LIB.T6G(SCH_1):PVDD18_S5_P0
   2 SCM_USB_OC_BUF_N      B @T6G_MB_LIB.T6G(SCH_1):SCM_USB_OC_BUF_N

Q_RES_0402LF-30K,1%,1/16W,CHIP,CS33002FB02  I396  R1503
   1 PVDD18_S5_P0      A @T6G_MB_LIB.T6G(SCH_1):PVDD18_S5_P0
   2 ESPI_CPU0_D0      B @T6G_MB_LIB.T6G(SCH_1):ESPI_CPU0_D0

Q_RES_0402LF-30K,1%,1/16W,CHIP,CS33002FB02  I397  R1504
   1 PVDD18_S5_P0      A @T6G_MB_LIB.T6G(SCH_1):PVDD18_S5_P0
   2 ESPI_CPU0_D1      B @T6G_MB_LIB.T6G(SCH_1):ESPI_CPU0_D1

Q_RES_0402LF-30K,1%,1/16W,CHIP,CS33002FB02  I398  R1505
   1 PVDD18_S5_P0      A @T6G_MB_LIB.T6G(SCH_1):PVDD18_S5_P0
   2 ESPI_CPU0_D2      B @T6G_MB_LIB.T6G(SCH_1):ESPI_CPU0_D2

Q_RES_0402LF-30K,1%,1/16W,CHIP,CS33002FB02  I399  R1506
   1 PVDD18_S5_P0      A @T6G_MB_LIB.T6G(SCH_1):PVDD18_S5_P0
   2 ESPI_CPU0_D3      B @T6G_MB_LIB.T6G(SCH_1):ESPI_CPU0_D3

Q_RES_0402LF-30K,1%,1/16W,EMPTY,CS33002FB02  I405  R458
   1 PVDD18_S5_P0      A @T6G_MB_LIB.T6G(SCH_1):PVDD18_S5_P0
   2 ESPI_CPU0_ALERT_P0_N      B @T6G_MB_LIB.T6G(SCH_1):ESPI_CPU0_ALERT_P0_N

Q_RES_0402LF-33,5%,1/16W,CHIP,CS03302JB10  I407  R459
   1 SPI_CPU0_CS0_N      A @T6G_MB_LIB.T6G(SCH_1):SPI_CPU0_CS0_N
   2 SPI_CPU0_R_CS0_N      B @T6G_MB_LIB.T6G(SCH_1):SPI_CPU0_R_CS0_N

Q_RES_0402LF-33,5%,1/16W,CHIP,CS03302JB10  I408  R460
   1 SPI_CPU0_CS1_N      A @T6G_MB_LIB.T6G(SCH_1):SPI_CPU0_CS1_N
   2 SPI_CPU0_R_CS1_N      B @T6G_MB_LIB.T6G(SCH_1):SPI_CPU0_R_CS1_N

Q_RES_0402LF-33,5%,1/16W,CHIP,CS03302JB10  I409  R461
   1 SPI_CPU0_CLK      A @T6G_MB_LIB.T6G(SCH_1):SPI_CPU0_CLK
   2 SPI_CPU0_R_CLK      B @T6G_MB_LIB.T6G(SCH_1):SPI_CPU0_R_CLK

Q_RES_0402LF-33,5%,1/16W,CHIP,CS03302JB10  I410  R464
   1 SPI_CPU0_D0      A @T6G_MB_LIB.T6G(SCH_1):SPI_CPU0_D0
   2 SPI_CPU0_R_D0      B @T6G_MB_LIB.T6G(SCH_1):SPI_CPU0_R_D0

Q_RES_0402LF-49.9,1%,1/16W,CHIP,CS04992FB07  I411  R465
   1 SPI_CPU0_D1      A @T6G_MB_LIB.T6G(SCH_1):SPI_CPU0_D1
   2 SPI_CPU0_R_D1      B @T6G_MB_LIB.T6G(SCH_1):SPI_CPU0_R_D1

Q_RES_0402LF-33,5%,1/16W,CHIP,CS03302JB10  I412  R466
   1 SPI_CPU0_D2      A @T6G_MB_LIB.T6G(SCH_1):SPI_CPU0_D2
   2 SPI_CPU0_R_D2      B @T6G_MB_LIB.T6G(SCH_1):SPI_CPU0_R_D2

Q_RES_0402LF-33,5%,1/16W,CHIP,CS03302JB10  I413  R467
   1 SPI_CPU0_D3      A @T6G_MB_LIB.T6G(SCH_1):SPI_CPU0_D3
   2 SPI_CPU0_R_D3      B @T6G_MB_LIB.T6G(SCH_1):SPI_CPU0_R_D3

Q_RES_0402LF-33,5%,1/16W,CHIP,CS03302JB10  I414  R475
   1 SPI_CPU0_TPM_CS_N      A @T6G_MB_LIB.T6G(SCH_1):SPI_CPU0_TPM_CS_N
   2 SPI_CPU0_R_TPM_CS_N      B @T6G_MB_LIB.T6G(SCH_1):SPI_CPU0_R_TPM_CS_N

Q_RES_0402LF-33,5%,1/16W,EMPTY,CS03302JB10  I425  R462
   1 ESPI_CPU0_CS1_N      A @T6G_MB_LIB.T6G(SCH_1):ESPI_CPU0_CS1_N
   2 ESPI_CPU0_R_CS1_N      B @T6G_MB_LIB.T6G(SCH_1):ESPI_CPU0_R_CS1_N

Q_RES_0402LF-33,5%,1/16W,CHIP,CS03302JB10  I426  R1592
   1 ESPI_CPU0_CS1_N      A @T6G_MB_LIB.T6G(SCH_1):ESPI_CPU0_CS1_N
   2 CPU0_ESPI_CS0_N      B @T6G_MB_LIB.T6G(SCH_1):CPU0_ESPI_CS0_N

Q_RES_0402LF-33,5%,1/16W,CHIP,CS03302JB10  I427  R1593
   1 ESPI_CPU0_ALERT_P0_N      A @T6G_MB_LIB.T6G(SCH_1):ESPI_CPU0_ALERT_P0_N
   2 CPU0_ESPI0_ALERT_N      B @T6G_MB_LIB.T6G(SCH_1):CPU0_ESPI0_ALERT_N

Q_RES_0402LF-33,5%,1/16W,EMPTY,CS03302JB10  I428  R472
   1 ESPI_CPU0_ALERT_P0_N      A @T6G_MB_LIB.T6G(SCH_1):ESPI_CPU0_ALERT_P0_N
   2 ESPI_CPU0_R_ALERT_N      B @T6G_MB_LIB.T6G(SCH_1):ESPI_CPU0_R_ALERT_N

Q_RES_0402LF-0,5%,1/16W,CHIP,CS00002JB13  I430  R473
   1 CLK_ESPI_CPU0_CLK1      A @T6G_MB_LIB.T6G(SCH_1):CLK_ESPI_CPU0_CLK1
   2 CLK_ESPI_CPU0_R_CLK1      B @T6G_MB_LIB.T6G(SCH_1):CLK_ESPI_CPU0_R_CLK1


DRAWING: @T6G_MB_LIB.T6G(SCH_1):PAGE30 

GENOA_SP5-SOCKET6096_13568-001,SMLF,IO,DGA^6000030  I28  U25
 H57 PVDDIO_P0 VDDIO_H57 @T6G_MB_LIB.T6G(SCH_1):PVDDIO_P0
 H64 PVDDIO_P0 VDDIO_H64 @T6G_MB_LIB.T6G(SCH_1):PVDDIO_P0
 H71 PVDDIO_P0 VDDIO_H71 @T6G_MB_LIB.T6G(SCH_1):PVDDIO_P0
 K54 PVDDIO_P0 VDDIO_K54 @T6G_MB_LIB.T6G(SCH_1):PVDDIO_P0
 L58 PVDDIO_P0 VDDIO_L58 @T6G_MB_LIB.T6G(SCH_1):PVDDIO_P0
 L65 PVDDIO_P0 VDDIO_L65 @T6G_MB_LIB.T6G(SCH_1):PVDDIO_P0
 L72 PVDDIO_P0 VDDIO_L72 @T6G_MB_LIB.T6G(SCH_1):PVDDIO_P0
 P54 PVDDIO_P0 VDDIO_P54 @T6G_MB_LIB.T6G(SCH_1):PVDDIO_P0
 P57 PVDDIO_P0 VDDIO_P57 @T6G_MB_LIB.T6G(SCH_1):PVDDIO_P0
 P64 PVDDIO_P0 VDDIO_P64 @T6G_MB_LIB.T6G(SCH_1):PVDDIO_P0
 P71 PVDDIO_P0 VDDIO_P71 @T6G_MB_LIB.T6G(SCH_1):PVDDIO_P0
 U58 PVDDIO_P0 VDDIO_U58 @T6G_MB_LIB.T6G(SCH_1):PVDDIO_P0
 U65 PVDDIO_P0 VDDIO_U65 @T6G_MB_LIB.T6G(SCH_1):PVDDIO_P0
 U72 PVDDIO_P0 VDDIO_U72 @T6G_MB_LIB.T6G(SCH_1):PVDDIO_P0
 V54 PVDDIO_P0 VDDIO_V54 @T6G_MB_LIB.T6G(SCH_1):PVDDIO_P0
 Y57 PVDDIO_P0 VDDIO_Y57 @T6G_MB_LIB.T6G(SCH_1):PVDDIO_P0
 Y64 PVDDIO_P0 VDDIO_Y64 @T6G_MB_LIB.T6G(SCH_1):PVDDIO_P0
 Y71 PVDDIO_P0 VDDIO_Y71 @T6G_MB_LIB.T6G(SCH_1):PVDDIO_P0
AA54 PVDDIO_P0 VDDIO_AA54 @T6G_MB_LIB.T6G(SCH_1):PVDDIO_P0
AC58 PVDDIO_P0 VDDIO_AC58 @T6G_MB_LIB.T6G(SCH_1):PVDDIO_P0
AC65 PVDDIO_P0 VDDIO_AC65 @T6G_MB_LIB.T6G(SCH_1):PVDDIO_P0
AC72 PVDDIO_P0 VDDIO_AC72 @T6G_MB_LIB.T6G(SCH_1):PVDDIO_P0
AD54 PVDDIO_P0 VDDIO_AD54 @T6G_MB_LIB.T6G(SCH_1):PVDDIO_P0
AF57 PVDDIO_P0 VDDIO_AF57 @T6G_MB_LIB.T6G(SCH_1):PVDDIO_P0
AF64 PVDDIO_P0 VDDIO_AF64 @T6G_MB_LIB.T6G(SCH_1):PVDDIO_P0
AF71 PVDDIO_P0 VDDIO_AF71 @T6G_MB_LIB.T6G(SCH_1):PVDDIO_P0
AH54 PVDDIO_P0 VDDIO_AH54 @T6G_MB_LIB.T6G(SCH_1):PVDDIO_P0
AJ58 PVDDIO_P0 VDDIO_AJ58 @T6G_MB_LIB.T6G(SCH_1):PVDDIO_P0
AJ65 PVDDIO_P0 VDDIO_AJ65 @T6G_MB_LIB.T6G(SCH_1):PVDDIO_P0
AJ72 PVDDIO_P0 VDDIO_AJ72 @T6G_MB_LIB.T6G(SCH_1):PVDDIO_P0
AM54 PVDDIO_P0 VDDIO_AM54 @T6G_MB_LIB.T6G(SCH_1):PVDDIO_P0
AM57 PVDDIO_P0 VDDIO_AM57 @T6G_MB_LIB.T6G(SCH_1):PVDDIO_P0
AM64 PVDDIO_P0 VDDIO_AM64 @T6G_MB_LIB.T6G(SCH_1):PVDDIO_P0
AM71 PVDDIO_P0 VDDIO_AM71 @T6G_MB_LIB.T6G(SCH_1):PVDDIO_P0
AR58 PVDDIO_P0 VDDIO_AR58 @T6G_MB_LIB.T6G(SCH_1):PVDDIO_P0
AR65 PVDDIO_P0 VDDIO_AR65 @T6G_MB_LIB.T6G(SCH_1):PVDDIO_P0
AR72 PVDDIO_P0 VDDIO_AR72 @T6G_MB_LIB.T6G(SCH_1):PVDDIO_P0
AV57 PVDDIO_P0 VDDIO_AV57 @T6G_MB_LIB.T6G(SCH_1):PVDDIO_P0
AV64 PVDDIO_P0 VDDIO_AV64 @T6G_MB_LIB.T6G(SCH_1):PVDDIO_P0
AV71 PVDDIO_P0 VDDIO_AV71 @T6G_MB_LIB.T6G(SCH_1):PVDDIO_P0
BA58 PVDDIO_P0 VDDIO_BA58 @T6G_MB_LIB.T6G(SCH_1):PVDDIO_P0
BA65 PVDDIO_P0 VDDIO_BA65 @T6G_MB_LIB.T6G(SCH_1):PVDDIO_P0
BA72 PVDDIO_P0 VDDIO_BA72 @T6G_MB_LIB.T6G(SCH_1):PVDDIO_P0
BD50 PVDDIO_P0 VDDIO_BD50 @T6G_MB_LIB.T6G(SCH_1):PVDDIO_P0
BD52 PVDDIO_P0 VDDIO_BD52 @T6G_MB_LIB.T6G(SCH_1):PVDDIO_P0
BD54 PVDDIO_P0 VDDIO_BD54 @T6G_MB_LIB.T6G(SCH_1):PVDDIO_P0
BF51 PVDDIO_P0 VDDIO_BF51 @T6G_MB_LIB.T6G(SCH_1):PVDDIO_P0
BF53 PVDDIO_P0 VDDIO_BF53 @T6G_MB_LIB.T6G(SCH_1):PVDDIO_P0
BF57 PVDDIO_P0 VDDIO_BF57 @T6G_MB_LIB.T6G(SCH_1):PVDDIO_P0
BF64 PVDDIO_P0 VDDIO_BF64 @T6G_MB_LIB.T6G(SCH_1):PVDDIO_P0
BF71 PVDDIO_P0 VDDIO_BF71 @T6G_MB_LIB.T6G(SCH_1):PVDDIO_P0
BG50 PVDDIO_P0 VDDIO_BG50 @T6G_MB_LIB.T6G(SCH_1):PVDDIO_P0
BG52 PVDDIO_P0 VDDIO_BG52 @T6G_MB_LIB.T6G(SCH_1):PVDDIO_P0
BG54 PVDDIO_P0 VDDIO_BG54 @T6G_MB_LIB.T6G(SCH_1):PVDDIO_P0
BH51 PVDDIO_P0 VDDIO_BH51 @T6G_MB_LIB.T6G(SCH_1):PVDDIO_P0
BH53 PVDDIO_P0 VDDIO_BH53 @T6G_MB_LIB.T6G(SCH_1):PVDDIO_P0
BJ50 PVDDIO_P0 VDDIO_BJ50 @T6G_MB_LIB.T6G(SCH_1):PVDDIO_P0
BJ52 PVDDIO_P0 VDDIO_BJ52 @T6G_MB_LIB.T6G(SCH_1):PVDDIO_P0
BJ54 PVDDIO_P0 VDDIO_BJ54 @T6G_MB_LIB.T6G(SCH_1):PVDDIO_P0
BJ58 PVDDIO_P0 VDDIO_BJ58 @T6G_MB_LIB.T6G(SCH_1):PVDDIO_P0
BJ65 PVDDIO_P0 VDDIO_BJ65 @T6G_MB_LIB.T6G(SCH_1):PVDDIO_P0
BJ72 PVDDIO_P0 VDDIO_BJ72 @T6G_MB_LIB.T6G(SCH_1):PVDDIO_P0
BK51 PVDDIO_P0 VDDIO_BK51 @T6G_MB_LIB.T6G(SCH_1):PVDDIO_P0
BK53 PVDDIO_P0 VDDIO_BK53 @T6G_MB_LIB.T6G(SCH_1):PVDDIO_P0
BL50 PVDDIO_P0 VDDIO_BL50 @T6G_MB_LIB.T6G(SCH_1):PVDDIO_P0
BL52 PVDDIO_P0 VDDIO_BL52 @T6G_MB_LIB.T6G(SCH_1):PVDDIO_P0
BL54 PVDDIO_P0 VDDIO_BL54 @T6G_MB_LIB.T6G(SCH_1):PVDDIO_P0
BM51 PVDDIO_P0 VDDIO_BM51 @T6G_MB_LIB.T6G(SCH_1):PVDDIO_P0
BM53 PVDDIO_P0 VDDIO_BM53 @T6G_MB_LIB.T6G(SCH_1):PVDDIO_P0
BM57 PVDDIO_P0 VDDIO_BM57 @T6G_MB_LIB.T6G(SCH_1):PVDDIO_P0
BM64 PVDDIO_P0 VDDIO_BM64 @T6G_MB_LIB.T6G(SCH_1):PVDDIO_P0
BM71 PVDDIO_P0 VDDIO_BM71 @T6G_MB_LIB.T6G(SCH_1):PVDDIO_P0
BN54 PVDDIO_P0 VDDIO_BN54 @T6G_MB_LIB.T6G(SCH_1):PVDDIO_P0
BR58 PVDDIO_P0 VDDIO_BR58 @T6G_MB_LIB.T6G(SCH_1):PVDDIO_P0
BR65 PVDDIO_P0 VDDIO_BR65 @T6G_MB_LIB.T6G(SCH_1):PVDDIO_P0
BR72 PVDDIO_P0 VDDIO_BR72 @T6G_MB_LIB.T6G(SCH_1):PVDDIO_P0
BV54 PVDDIO_P0 VDDIO_BV54 @T6G_MB_LIB.T6G(SCH_1):PVDDIO_P0
BV57 PVDDIO_P0 VDDIO_BV57 @T6G_MB_LIB.T6G(SCH_1):PVDDIO_P0
BV64 PVDDIO_P0 VDDIO_BV64 @T6G_MB_LIB.T6G(SCH_1):PVDDIO_P0
BV71 PVDDIO_P0 VDDIO_BV71 @T6G_MB_LIB.T6G(SCH_1):PVDDIO_P0
CA58 PVDDIO_P0 VDDIO_CA58 @T6G_MB_LIB.T6G(SCH_1):PVDDIO_P0
CA65 PVDDIO_P0 VDDIO_CA65 @T6G_MB_LIB.T6G(SCH_1):PVDDIO_P0
CA72 PVDDIO_P0 VDDIO_CA72 @T6G_MB_LIB.T6G(SCH_1):PVDDIO_P0
CB54 PVDDIO_P0 VDDIO_CB54 @T6G_MB_LIB.T6G(SCH_1):PVDDIO_P0
CD57 PVDDIO_P0 VDDIO_CD57 @T6G_MB_LIB.T6G(SCH_1):PVDDIO_P0
CD64 PVDDIO_P0 VDDIO_CD64 @T6G_MB_LIB.T6G(SCH_1):PVDDIO_P0
CD71 PVDDIO_P0 VDDIO_CD71 @T6G_MB_LIB.T6G(SCH_1):PVDDIO_P0
CF54 PVDDIO_P0 VDDIO_CF54 @T6G_MB_LIB.T6G(SCH_1):PVDDIO_P0
CG58 PVDDIO_P0 VDDIO_CG58 @T6G_MB_LIB.T6G(SCH_1):PVDDIO_P0
CG65 PVDDIO_P0 VDDIO_CG65 @T6G_MB_LIB.T6G(SCH_1):PVDDIO_P0
CG72 PVDDIO_P0 VDDIO_CG72 @T6G_MB_LIB.T6G(SCH_1):PVDDIO_P0
CJ54 PVDDIO_P0 VDDIO_CJ54 @T6G_MB_LIB.T6G(SCH_1):PVDDIO_P0
CK57 PVDDIO_P0 VDDIO_CK57 @T6G_MB_LIB.T6G(SCH_1):PVDDIO_P0
CK64 PVDDIO_P0 VDDIO_CK64 @T6G_MB_LIB.T6G(SCH_1):PVDDIO_P0
CK71 PVDDIO_P0 VDDIO_CK71 @T6G_MB_LIB.T6G(SCH_1):PVDDIO_P0
CM54 PVDDIO_P0 VDDIO_CM54 @T6G_MB_LIB.T6G(SCH_1):PVDDIO_P0
CN58 PVDDIO_P0 VDDIO_CN58 @T6G_MB_LIB.T6G(SCH_1):PVDDIO_P0
CN65 PVDDIO_P0 VDDIO_CN65 @T6G_MB_LIB.T6G(SCH_1):PVDDIO_P0
CN72 PVDDIO_P0 VDDIO_CN72 @T6G_MB_LIB.T6G(SCH_1):PVDDIO_P0
CT54 PVDDIO_P0 VDDIO_CT54 @T6G_MB_LIB.T6G(SCH_1):PVDDIO_P0
CT57 PVDDIO_P0 VDDIO_CT57 @T6G_MB_LIB.T6G(SCH_1):PVDDIO_P0
BJ18 PVDD11_S3_P0 VDD_11_S3_BJ18 @T6G_MB_LIB.T6G(SCH_1):PVDD11_S3_P0
BJ23 PVDD11_S3_P0 VDD_11_S3_BJ23 @T6G_MB_LIB.T6G(SCH_1):PVDD11_S3_P0
BJ25 PVDD11_S3_P0 VDD_11_S3_BJ25 @T6G_MB_LIB.T6G(SCH_1):PVDD11_S3_P0
BJ27 PVDD11_S3_P0 VDD_11_S3_BJ27 @T6G_MB_LIB.T6G(SCH_1):PVDD11_S3_P0
BK22 PVDD11_S3_P0 VDD_11_S3_BK22 @T6G_MB_LIB.T6G(SCH_1):PVDD11_S3_P0
BK24 PVDD11_S3_P0 VDD_11_S3_BK24 @T6G_MB_LIB.T6G(SCH_1):PVDD11_S3_P0
BK26 PVDD11_S3_P0 VDD_11_S3_BK26 @T6G_MB_LIB.T6G(SCH_1):PVDD11_S3_P0
BK28 PVDD11_S3_P0 VDD_11_S3_BK28 @T6G_MB_LIB.T6G(SCH_1):PVDD11_S3_P0
BK49 PVDD11_S3_P0 VDD_11_S3_BK49 @T6G_MB_LIB.T6G(SCH_1):PVDD11_S3_P0
BL23 PVDD11_S3_P0 VDD_11_S3_BL23 @T6G_MB_LIB.T6G(SCH_1):PVDD11_S3_P0
BL25 PVDD11_S3_P0 VDD_11_S3_BL25 @T6G_MB_LIB.T6G(SCH_1):PVDD11_S3_P0
BL27 PVDD11_S3_P0 VDD_11_S3_BL27 @T6G_MB_LIB.T6G(SCH_1):PVDD11_S3_P0
BL48 PVDD11_S3_P0 VDD_11_S3_BL48 @T6G_MB_LIB.T6G(SCH_1):PVDD11_S3_P0
BM12 PVDD11_S3_P0 VDD_11_S3_BM12 @T6G_MB_LIB.T6G(SCH_1):PVDD11_S3_P0
BM19 PVDD11_S3_P0 VDD_11_S3_BM19 @T6G_MB_LIB.T6G(SCH_1):PVDD11_S3_P0
BM22 PVDD11_S3_P0 VDD_11_S3_BM22 @T6G_MB_LIB.T6G(SCH_1):PVDD11_S3_P0
BM24 PVDD11_S3_P0 VDD_11_S3_BM24 @T6G_MB_LIB.T6G(SCH_1):PVDD11_S3_P0
BM26 PVDD11_S3_P0 VDD_11_S3_BM26 @T6G_MB_LIB.T6G(SCH_1):PVDD11_S3_P0
BM28 PVDD11_S3_P0 VDD_11_S3_BM28 @T6G_MB_LIB.T6G(SCH_1):PVDD11_S3_P0
BM30 PVDD11_S3_P0 VDD_11_S3_BM30 @T6G_MB_LIB.T6G(SCH_1):PVDD11_S3_P0
BM32 PVDD11_S3_P0 VDD_11_S3_BM32 @T6G_MB_LIB.T6G(SCH_1):PVDD11_S3_P0
BM34 PVDD11_S3_P0 VDD_11_S3_BM34 @T6G_MB_LIB.T6G(SCH_1):PVDD11_S3_P0
BM36 PVDD11_S3_P0 VDD_11_S3_BM36 @T6G_MB_LIB.T6G(SCH_1):PVDD11_S3_P0
BM39 PVDD11_S3_P0 VDD_11_S3_BM39 @T6G_MB_LIB.T6G(SCH_1):PVDD11_S3_P0
BM41 PVDD11_S3_P0 VDD_11_S3_BM41 @T6G_MB_LIB.T6G(SCH_1):PVDD11_S3_P0
BM43 PVDD11_S3_P0 VDD_11_S3_BM43 @T6G_MB_LIB.T6G(SCH_1):PVDD11_S3_P0
BM45 PVDD11_S3_P0 VDD_11_S3_BM45 @T6G_MB_LIB.T6G(SCH_1):PVDD11_S3_P0
BM47 PVDD11_S3_P0 VDD_11_S3_BM47 @T6G_MB_LIB.T6G(SCH_1):PVDD11_S3_P0
BM49 PVDD11_S3_P0 VDD_11_S3_BM49 @T6G_MB_LIB.T6G(SCH_1):PVDD11_S3_P0
BN25 PVDD11_S3_P0 VDD_11_S3_BN25 @T6G_MB_LIB.T6G(SCH_1):PVDD11_S3_P0
BN29 PVDD11_S3_P0 VDD_11_S3_BN29 @T6G_MB_LIB.T6G(SCH_1):PVDD11_S3_P0
BN33 PVDD11_S3_P0 VDD_11_S3_BN33 @T6G_MB_LIB.T6G(SCH_1):PVDD11_S3_P0
BN40 PVDD11_S3_P0 VDD_11_S3_BN40 @T6G_MB_LIB.T6G(SCH_1):PVDD11_S3_P0
BN44 PVDD11_S3_P0 VDD_11_S3_BN44 @T6G_MB_LIB.T6G(SCH_1):PVDD11_S3_P0
BN48 PVDD11_S3_P0 VDD_11_S3_BN48 @T6G_MB_LIB.T6G(SCH_1):PVDD11_S3_P0
BP22 PVDD11_S3_P0 VDD_11_S3_BP22 @T6G_MB_LIB.T6G(SCH_1):PVDD11_S3_P0
 BR4 PVDD11_S3_P0 VDD_11_S3_BR4 @T6G_MB_LIB.T6G(SCH_1):PVDD11_S3_P0
BR11 PVDD11_S3_P0 VDD_11_S3_BR11 @T6G_MB_LIB.T6G(SCH_1):PVDD11_S3_P0
BR18 PVDD11_S3_P0 VDD_11_S3_BR18 @T6G_MB_LIB.T6G(SCH_1):PVDD11_S3_P0
 BV5 PVDD11_S3_P0 VDD_11_S3_BV5 @T6G_MB_LIB.T6G(SCH_1):PVDD11_S3_P0
BV12 PVDD11_S3_P0 VDD_11_S3_BV12 @T6G_MB_LIB.T6G(SCH_1):PVDD11_S3_P0
BV19 PVDD11_S3_P0 VDD_11_S3_BV19 @T6G_MB_LIB.T6G(SCH_1):PVDD11_S3_P0
BV22 PVDD11_S3_P0 VDD_11_S3_BV22 @T6G_MB_LIB.T6G(SCH_1):PVDD11_S3_P0
 CA4 PVDD11_S3_P0 VDD_11_S3_CA4 @T6G_MB_LIB.T6G(SCH_1):PVDD11_S3_P0
CA11 PVDD11_S3_P0 VDD_11_S3_CA11 @T6G_MB_LIB.T6G(SCH_1):PVDD11_S3_P0
CA18 PVDD11_S3_P0 VDD_11_S3_CA18 @T6G_MB_LIB.T6G(SCH_1):PVDD11_S3_P0
CB22 PVDD11_S3_P0 VDD_11_S3_CB22 @T6G_MB_LIB.T6G(SCH_1):PVDD11_S3_P0
 CD5 PVDD11_S3_P0 VDD_11_S3_CD5 @T6G_MB_LIB.T6G(SCH_1):PVDD11_S3_P0
CD12 PVDD11_S3_P0 VDD_11_S3_CD12 @T6G_MB_LIB.T6G(SCH_1):PVDD11_S3_P0
CD19 PVDD11_S3_P0 VDD_11_S3_CD19 @T6G_MB_LIB.T6G(SCH_1):PVDD11_S3_P0
CF22 PVDD11_S3_P0 VDD_11_S3_CF22 @T6G_MB_LIB.T6G(SCH_1):PVDD11_S3_P0
 CG4 PVDD11_S3_P0 VDD_11_S3_CG4 @T6G_MB_LIB.T6G(SCH_1):PVDD11_S3_P0
CG11 PVDD11_S3_P0 VDD_11_S3_CG11 @T6G_MB_LIB.T6G(SCH_1):PVDD11_S3_P0
CG18 PVDD11_S3_P0 VDD_11_S3_CG18 @T6G_MB_LIB.T6G(SCH_1):PVDD11_S3_P0
CJ22 PVDD11_S3_P0 VDD_11_S3_CJ22 @T6G_MB_LIB.T6G(SCH_1):PVDD11_S3_P0
 CK5 PVDD11_S3_P0 VDD_11_S3_CK5 @T6G_MB_LIB.T6G(SCH_1):PVDD11_S3_P0
CK12 PVDD11_S3_P0 VDD_11_S3_CK12 @T6G_MB_LIB.T6G(SCH_1):PVDD11_S3_P0
CK19 PVDD11_S3_P0 VDD_11_S3_CK19 @T6G_MB_LIB.T6G(SCH_1):PVDD11_S3_P0
CM22 PVDD11_S3_P0 VDD_11_S3_CM22 @T6G_MB_LIB.T6G(SCH_1):PVDD11_S3_P0
 CN4 PVDD11_S3_P0 VDD_11_S3_CN4 @T6G_MB_LIB.T6G(SCH_1):PVDD11_S3_P0
CN11 PVDD11_S3_P0 VDD_11_S3_CN11 @T6G_MB_LIB.T6G(SCH_1):PVDD11_S3_P0
CN18 PVDD11_S3_P0 VDD_11_S3_CN18 @T6G_MB_LIB.T6G(SCH_1):PVDD11_S3_P0
 CT5 PVDD11_S3_P0 VDD_11_S3_CT5 @T6G_MB_LIB.T6G(SCH_1):PVDD11_S3_P0
AU54 PVDD18_S5_P0 VDD_18_S5_AU54 @T6G_MB_LIB.T6G(SCH_1):PVDD18_S5_P0
AR52 PVDD18_S5_P0 VDD_18_S5_AR52 @T6G_MB_LIB.T6G(SCH_1):PVDD18_S5_P0
AR54 PVDD18_S5_P0 VDD_18_S5_AR54 @T6G_MB_LIB.T6G(SCH_1):PVDD18_S5_P0
AT51 PVDD18_S5_P0 VDD_18_S5_AT51 @T6G_MB_LIB.T6G(SCH_1):PVDD18_S5_P0
AT53 PVDD18_S5_P0 VDD_18_S5_AT53 @T6G_MB_LIB.T6G(SCH_1):PVDD18_S5_P0
AU50 PVDD18_S5_P0 VDD_18_S5_AU50 @T6G_MB_LIB.T6G(SCH_1):PVDD18_S5_P0
AU52 PVDD18_S5_P0 VDD_18_S5_AU52 @T6G_MB_LIB.T6G(SCH_1):PVDD18_S5_P0
AV49 PVDD18_S5_P0 VDD_18_S5_AV49 @T6G_MB_LIB.T6G(SCH_1):PVDD18_S5_P0
AV51 PVDD18_S5_P0 VDD_18_S5_AV51 @T6G_MB_LIB.T6G(SCH_1):PVDD18_S5_P0
AV53 PVDD18_S5_P0 VDD_18_S5_AV53 @T6G_MB_LIB.T6G(SCH_1):PVDD18_S5_P0
AW50 PVDD18_S5_P0 VDD_18_S5_AW50 @T6G_MB_LIB.T6G(SCH_1):PVDD18_S5_P0
BC52 PVDD18_S5_P0 VDD_18_S5_BC52 @T6G_MB_LIB.T6G(SCH_1):PVDD18_S5_P0
BC54 PVDD18_S5_P0 VDD_18_S5_BC54 @T6G_MB_LIB.T6G(SCH_1):PVDD18_S5_P0
AW52 PVDD18_S5_P0 VDD_18_S5_AW52 @T6G_MB_LIB.T6G(SCH_1):PVDD18_S5_P0
AW54 PVDD18_S5_P0 VDD_18_S5_AW54 @T6G_MB_LIB.T6G(SCH_1):PVDD18_S5_P0
AY51 PVDD18_S5_P0 VDD_18_S5_AY51 @T6G_MB_LIB.T6G(SCH_1):PVDD18_S5_P0
AY53 PVDD18_S5_P0 VDD_18_S5_AY53 @T6G_MB_LIB.T6G(SCH_1):PVDD18_S5_P0
BA50 PVDD18_S5_P0 VDD_18_S5_BA50 @T6G_MB_LIB.T6G(SCH_1):PVDD18_S5_P0
BA52 PVDD18_S5_P0 VDD_18_S5_BA52 @T6G_MB_LIB.T6G(SCH_1):PVDD18_S5_P0
BA54 PVDD18_S5_P0 VDD_18_S5_BA54 @T6G_MB_LIB.T6G(SCH_1):PVDD18_S5_P0
BB51 PVDD18_S5_P0 VDD_18_S5_BB51 @T6G_MB_LIB.T6G(SCH_1):PVDD18_S5_P0
BB53 PVDD18_S5_P0 VDD_18_S5_BB53 @T6G_MB_LIB.T6G(SCH_1):PVDD18_S5_P0
CT12 PVDD11_S3_P0 VDD_11_S3_CT12 @T6G_MB_LIB.T6G(SCH_1):PVDD11_S3_P0
BN52 PVDD_33_S5 VDD_33_S5_BN52 @T6G_MB_LIB.T6G(SCH_1):PVDD_33_S5
BP51 PVDD_33_S5 VDD_33_S5_BP51 @T6G_MB_LIB.T6G(SCH_1):PVDD_33_S5
BH27 PVDD18_S5_P0 VDDIO_AUDIO @T6G_MB_LIB.T6G(SCH_1):PVDD18_S5_P0
BN23 P1V5_BAT VDDBT_RTC_G @T6G_MB_LIB.T6G(SCH_1):P1V5_BAT
DG71 PVDDIO_P0 VDDIO_DG71 @T6G_MB_LIB.T6G(SCH_1):PVDDIO_P0
DG64 PVDDIO_P0 VDDIO_DG64 @T6G_MB_LIB.T6G(SCH_1):PVDDIO_P0
DE72 PVDDIO_P0 VDDIO_DE72 @T6G_MB_LIB.T6G(SCH_1):PVDDIO_P0
DE65 PVDDIO_P0 VDDIO_DE65 @T6G_MB_LIB.T6G(SCH_1):PVDDIO_P0
DE58 PVDDIO_P0 VDDIO_DE58 @T6G_MB_LIB.T6G(SCH_1):PVDDIO_P0
DB71 PVDDIO_P0 VDDIO_DB71 @T6G_MB_LIB.T6G(SCH_1):PVDDIO_P0
DB64 PVDDIO_P0 VDDIO_DB64 @T6G_MB_LIB.T6G(SCH_1):PVDDIO_P0
DB57 PVDDIO_P0 VDDIO_DB57 @T6G_MB_LIB.T6G(SCH_1):PVDDIO_P0
CY54 PVDDIO_P0 VDDIO_CY54 @T6G_MB_LIB.T6G(SCH_1):PVDDIO_P0
CW72 PVDDIO_P0 VDDIO_CW72 @T6G_MB_LIB.T6G(SCH_1):PVDDIO_P0
CW65 PVDDIO_P0 VDDIO_CW65 @T6G_MB_LIB.T6G(SCH_1):PVDDIO_P0
CW58 PVDDIO_P0 VDDIO_CW58 @T6G_MB_LIB.T6G(SCH_1):PVDDIO_P0
CT71 PVDDIO_P0 VDDIO_CT71 @T6G_MB_LIB.T6G(SCH_1):PVDDIO_P0
CT64 PVDDIO_P0 VDDIO_CT64 @T6G_MB_LIB.T6G(SCH_1):PVDDIO_P0
 DG5 PVDD11_S3_P0 VDD_11_S3_DG5 @T6G_MB_LIB.T6G(SCH_1):PVDD11_S3_P0
DE18 PVDD11_S3_P0 VDD_11_S3_DE18 @T6G_MB_LIB.T6G(SCH_1):PVDD11_S3_P0
DE11 PVDD11_S3_P0 VDD_11_S3_DE11 @T6G_MB_LIB.T6G(SCH_1):PVDD11_S3_P0
 DE4 PVDD11_S3_P0 VDD_11_S3_DE4 @T6G_MB_LIB.T6G(SCH_1):PVDD11_S3_P0
DB19 PVDD11_S3_P0 VDD_11_S3_DB19 @T6G_MB_LIB.T6G(SCH_1):PVDD11_S3_P0
DB12 PVDD11_S3_P0 VDD_11_S3_DB12 @T6G_MB_LIB.T6G(SCH_1):PVDD11_S3_P0
 DB5 PVDD11_S3_P0 VDD_11_S3_DB5 @T6G_MB_LIB.T6G(SCH_1):PVDD11_S3_P0
CY22 PVDD11_S3_P0 VDD_11_S3_CY22 @T6G_MB_LIB.T6G(SCH_1):PVDD11_S3_P0
CW18 PVDD11_S3_P0 VDD_11_S3_CW18 @T6G_MB_LIB.T6G(SCH_1):PVDD11_S3_P0
CW11 PVDD11_S3_P0 VDD_11_S3_CW11 @T6G_MB_LIB.T6G(SCH_1):PVDD11_S3_P0
 CW4 PVDD11_S3_P0 VDD_11_S3_CW4 @T6G_MB_LIB.T6G(SCH_1):PVDD11_S3_P0
CT22 PVDD11_S3_P0 VDD_11_S3_CT22 @T6G_MB_LIB.T6G(SCH_1):PVDD11_S3_P0
CT19 PVDD11_S3_P0 VDD_11_S3_CT19 @T6G_MB_LIB.T6G(SCH_1):PVDD11_S3_P0

GENOA_SP5-SOCKET6096_13568-001,SMLF,IO,DGA^6000030  I29  U25
BD62     NC RSVD_BD62     NC
 D72     NC RSVD_D72     NC
 C54     NC RSVD_C54     NC
BD65     NC RSVD_BD65     NC
 E33     NC RSVD_E33     NC
  D4     NC RSVD_D4     NC
 A55     NC RSVD_A55     NC
BD69     NC RSVD_BD69     NC
 E36     NC RSVD_E36     NC
  D8     NC RSVD_D8     NC
 A56     NC RSVD_A56     NC
BD72     NC RSVD_BD72     NC
 BD4     NC RSVD_BD4     NC
 D11     NC RSVD_D11     NC
 A57     NC RSVD_A57     NC
DG17     NC RSVD_DG17     NC
 D22     NC RSVD_D22     NC
 A59     NC RSVD_A59     NC
DH17     NC RSVD_DH17     NC
BD11     NC RSVD_BD11     NC
 D34     NC RSVD_D34     NC
 A31     NC RSVD_A31     NC
DH21     NC RSVD_DH21     NC
BD14     NC RSVD_BD14     NC
 B40     NC RSVD_B40     NC
 A35     NC RSVD_A35     NC
 DJ4     NC RSVD_DJ4     NC
BD18     NC RSVD_BD18     NC
 D58     NC RSVD_D58     NC
 C31     NC RSVD_C31     NC
 A41     NC RSVD_A41     NC
BD21     NC RSVD_BD21     NC
 D62     NC RSVD_D62     NC
 C34     NC RSVD_C34     NC
 A42     NC RSVD_A42     NC
 D65     NC RSVD_D65     NC
 C35     NC RSVD_C35     NC
 A45     NC RSVD_A45     NC
 C53     NC RSVD_C53     NC
 A48     NC RSVD_A48     NC
 A50     NC RSVD_A50     NC
 A51     NC RSVD_A51     NC
 A54     NC RSVD_A54     NC
BD55     NC RSVD_BD55     NC
BD58     NC RSVD_BD58     NC
 D36     NC RSVD_D36     NC
 BD7     NC RSVD_BD7     NC
 A60     NC RSVD_A60     NC
DJ57     NC TEST6_X3D7     NC
DH14     NC TEST5_CCD13     NC
DH13     NC TEST4_CCD13     NC
DG42     NC TEST5_CCD14     NC
DF41     NC TEST4_CCD14     NC
 D23     NC TEST5_CCD15     NC
 C59     NC TEST5_CCD12     NC
 C58     NC TEST4_CCD12     NC
 C23     NC TEST4_CCD15     NC
 B36     NC TEST6_X3D6     NC

GENOA_SP5-SOCKET6096_13568-001,SMLF,IO,DGA^6000030  I42  U25
 W47 PVDDCR_CPU0_P0 VDDCR_CPU0_W47 @T6G_MB_LIB.T6G(SCH_1):PVDDCR_CPU0_P0
 W46 PVDDCR_CPU0_P0 VDDCR_CPU0_W46 @T6G_MB_LIB.T6G(SCH_1):PVDDCR_CPU0_P0
 W44 PVDDCR_CPU0_P0 VDDCR_CPU0_W44 @T6G_MB_LIB.T6G(SCH_1):PVDDCR_CPU0_P0
 W43 PVDDCR_CPU0_P0 VDDCR_CPU0_W43 @T6G_MB_LIB.T6G(SCH_1):PVDDCR_CPU0_P0
 W33 PVDDCR_CPU0_P0 VDDCR_CPU0_W33 @T6G_MB_LIB.T6G(SCH_1):PVDDCR_CPU0_P0
 W32 PVDDCR_CPU0_P0 VDDCR_CPU0_W32 @T6G_MB_LIB.T6G(SCH_1):PVDDCR_CPU0_P0
 W30 PVDDCR_CPU0_P0 VDDCR_CPU0_W30 @T6G_MB_LIB.T6G(SCH_1):PVDDCR_CPU0_P0
 W29 PVDDCR_CPU0_P0 VDDCR_CPU0_W29 @T6G_MB_LIB.T6G(SCH_1):PVDDCR_CPU0_P0
 U41 PVDDCR_CPU0_P0 VDDCR_CPU0_U41 @T6G_MB_LIB.T6G(SCH_1):PVDDCR_CPU0_P0
 U40 PVDDCR_CPU0_P0 VDDCR_CPU0_U40 @T6G_MB_LIB.T6G(SCH_1):PVDDCR_CPU0_P0
 U36 PVDDCR_CPU0_P0 VDDCR_CPU0_U36 @T6G_MB_LIB.T6G(SCH_1):PVDDCR_CPU0_P0
 U35 PVDDCR_CPU0_P0 VDDCR_CPU0_U35 @T6G_MB_LIB.T6G(SCH_1):PVDDCR_CPU0_P0
 T53 PVDDCR_CPU0_P0 VDDCR_CPU0_T53 @T6G_MB_LIB.T6G(SCH_1):PVDDCR_CPU0_P0
 T52 PVDDCR_CPU0_P0 VDDCR_CPU0_T52 @T6G_MB_LIB.T6G(SCH_1):PVDDCR_CPU0_P0
 T50 PVDDCR_CPU0_P0 VDDCR_CPU0_T50 @T6G_MB_LIB.T6G(SCH_1):PVDDCR_CPU0_P0
 T49 PVDDCR_CPU0_P0 VDDCR_CPU0_T49 @T6G_MB_LIB.T6G(SCH_1):PVDDCR_CPU0_P0
 T47 PVDDCR_CPU0_P0 VDDCR_CPU0_T47 @T6G_MB_LIB.T6G(SCH_1):PVDDCR_CPU0_P0
 T46 PVDDCR_CPU0_P0 VDDCR_CPU0_T46 @T6G_MB_LIB.T6G(SCH_1):PVDDCR_CPU0_P0
 T44 PVDDCR_CPU0_P0 VDDCR_CPU0_T44 @T6G_MB_LIB.T6G(SCH_1):PVDDCR_CPU0_P0
 T43 PVDDCR_CPU0_P0 VDDCR_CPU0_T43 @T6G_MB_LIB.T6G(SCH_1):PVDDCR_CPU0_P0
 T33 PVDDCR_CPU0_P0 VDDCR_CPU0_T33 @T6G_MB_LIB.T6G(SCH_1):PVDDCR_CPU0_P0
 T32 PVDDCR_CPU0_P0 VDDCR_CPU0_T32 @T6G_MB_LIB.T6G(SCH_1):PVDDCR_CPU0_P0
 T30 PVDDCR_CPU0_P0 VDDCR_CPU0_T30 @T6G_MB_LIB.T6G(SCH_1):PVDDCR_CPU0_P0
 T29 PVDDCR_CPU0_P0 VDDCR_CPU0_T29 @T6G_MB_LIB.T6G(SCH_1):PVDDCR_CPU0_P0
 T27 PVDDCR_CPU0_P0 VDDCR_CPU0_T27 @T6G_MB_LIB.T6G(SCH_1):PVDDCR_CPU0_P0
 T26 PVDDCR_CPU0_P0 VDDCR_CPU0_T26 @T6G_MB_LIB.T6G(SCH_1):PVDDCR_CPU0_P0
 T24 PVDDCR_CPU0_P0 VDDCR_CPU0_T24 @T6G_MB_LIB.T6G(SCH_1):PVDDCR_CPU0_P0
 T23 PVDDCR_CPU0_P0 VDDCR_CPU0_T23 @T6G_MB_LIB.T6G(SCH_1):PVDDCR_CPU0_P0
 N41 PVDDCR_CPU0_P0 VDDCR_CPU0_N41 @T6G_MB_LIB.T6G(SCH_1):PVDDCR_CPU0_P0
 N40 PVDDCR_CPU0_P0 VDDCR_CPU0_N40 @T6G_MB_LIB.T6G(SCH_1):PVDDCR_CPU0_P0
 N36 PVDDCR_CPU0_P0 VDDCR_CPU0_N36 @T6G_MB_LIB.T6G(SCH_1):PVDDCR_CPU0_P0
 N35 PVDDCR_CPU0_P0 VDDCR_CPU0_N35 @T6G_MB_LIB.T6G(SCH_1):PVDDCR_CPU0_P0
 M53 PVDDCR_CPU0_P0 VDDCR_CPU0_M53 @T6G_MB_LIB.T6G(SCH_1):PVDDCR_CPU0_P0
 M52 PVDDCR_CPU0_P0 VDDCR_CPU0_M52 @T6G_MB_LIB.T6G(SCH_1):PVDDCR_CPU0_P0
 M50 PVDDCR_CPU0_P0 VDDCR_CPU0_M50 @T6G_MB_LIB.T6G(SCH_1):PVDDCR_CPU0_P0
 M49 PVDDCR_CPU0_P0 VDDCR_CPU0_M49 @T6G_MB_LIB.T6G(SCH_1):PVDDCR_CPU0_P0
 M47 PVDDCR_CPU0_P0 VDDCR_CPU0_M47 @T6G_MB_LIB.T6G(SCH_1):PVDDCR_CPU0_P0
 M46 PVDDCR_CPU0_P0 VDDCR_CPU0_M46 @T6G_MB_LIB.T6G(SCH_1):PVDDCR_CPU0_P0
 M44 PVDDCR_CPU0_P0 VDDCR_CPU0_M44 @T6G_MB_LIB.T6G(SCH_1):PVDDCR_CPU0_P0
 M43 PVDDCR_CPU0_P0 VDDCR_CPU0_M43 @T6G_MB_LIB.T6G(SCH_1):PVDDCR_CPU0_P0
 M33 PVDDCR_CPU0_P0 VDDCR_CPU0_M33 @T6G_MB_LIB.T6G(SCH_1):PVDDCR_CPU0_P0
 M32 PVDDCR_CPU0_P0 VDDCR_CPU0_M32 @T6G_MB_LIB.T6G(SCH_1):PVDDCR_CPU0_P0
 M30 PVDDCR_CPU0_P0 VDDCR_CPU0_M30 @T6G_MB_LIB.T6G(SCH_1):PVDDCR_CPU0_P0
 M29 PVDDCR_CPU0_P0 VDDCR_CPU0_M29 @T6G_MB_LIB.T6G(SCH_1):PVDDCR_CPU0_P0
 M27 PVDDCR_CPU0_P0 VDDCR_CPU0_M27 @T6G_MB_LIB.T6G(SCH_1):PVDDCR_CPU0_P0
 M26 PVDDCR_CPU0_P0 VDDCR_CPU0_M26 @T6G_MB_LIB.T6G(SCH_1):PVDDCR_CPU0_P0
 M24 PVDDCR_CPU0_P0 VDDCR_CPU0_M24 @T6G_MB_LIB.T6G(SCH_1):PVDDCR_CPU0_P0
 M23 PVDDCR_CPU0_P0 VDDCR_CPU0_M23 @T6G_MB_LIB.T6G(SCH_1):PVDDCR_CPU0_P0
 J41 PVDDCR_CPU0_P0 VDDCR_CPU0_J41 @T6G_MB_LIB.T6G(SCH_1):PVDDCR_CPU0_P0
 J40 PVDDCR_CPU0_P0 VDDCR_CPU0_J40 @T6G_MB_LIB.T6G(SCH_1):PVDDCR_CPU0_P0
 J36 PVDDCR_CPU0_P0 VDDCR_CPU0_J36 @T6G_MB_LIB.T6G(SCH_1):PVDDCR_CPU0_P0
 J35 PVDDCR_CPU0_P0 VDDCR_CPU0_J35 @T6G_MB_LIB.T6G(SCH_1):PVDDCR_CPU0_P0
 H53 PVDDCR_CPU0_P0 VDDCR_CPU0_H53 @T6G_MB_LIB.T6G(SCH_1):PVDDCR_CPU0_P0
 H52 PVDDCR_CPU0_P0 VDDCR_CPU0_H52 @T6G_MB_LIB.T6G(SCH_1):PVDDCR_CPU0_P0
 H50 PVDDCR_CPU0_P0 VDDCR_CPU0_H50 @T6G_MB_LIB.T6G(SCH_1):PVDDCR_CPU0_P0
 H49 PVDDCR_CPU0_P0 VDDCR_CPU0_H49 @T6G_MB_LIB.T6G(SCH_1):PVDDCR_CPU0_P0
 H47 PVDDCR_CPU0_P0 VDDCR_CPU0_H47 @T6G_MB_LIB.T6G(SCH_1):PVDDCR_CPU0_P0
 H46 PVDDCR_CPU0_P0 VDDCR_CPU0_H46 @T6G_MB_LIB.T6G(SCH_1):PVDDCR_CPU0_P0
 H44 PVDDCR_CPU0_P0 VDDCR_CPU0_H44 @T6G_MB_LIB.T6G(SCH_1):PVDDCR_CPU0_P0
 H43 PVDDCR_CPU0_P0 VDDCR_CPU0_H43 @T6G_MB_LIB.T6G(SCH_1):PVDDCR_CPU0_P0
 H33 PVDDCR_CPU0_P0 VDDCR_CPU0_H33 @T6G_MB_LIB.T6G(SCH_1):PVDDCR_CPU0_P0
 H32 PVDDCR_CPU0_P0 VDDCR_CPU0_H32 @T6G_MB_LIB.T6G(SCH_1):PVDDCR_CPU0_P0
 H30 PVDDCR_CPU0_P0 VDDCR_CPU0_H30 @T6G_MB_LIB.T6G(SCH_1):PVDDCR_CPU0_P0
 H29 PVDDCR_CPU0_P0 VDDCR_CPU0_H29 @T6G_MB_LIB.T6G(SCH_1):PVDDCR_CPU0_P0
 H27 PVDDCR_CPU0_P0 VDDCR_CPU0_H27 @T6G_MB_LIB.T6G(SCH_1):PVDDCR_CPU0_P0
 H26 PVDDCR_CPU0_P0 VDDCR_CPU0_H26 @T6G_MB_LIB.T6G(SCH_1):PVDDCR_CPU0_P0
 H24 PVDDCR_CPU0_P0 VDDCR_CPU0_H24 @T6G_MB_LIB.T6G(SCH_1):PVDDCR_CPU0_P0
 H23 PVDDCR_CPU0_P0 VDDCR_CPU0_H23 @T6G_MB_LIB.T6G(SCH_1):PVDDCR_CPU0_P0
 G41 PVDDCR_CPU0_P0 VDDCR_CPU0_G41 @T6G_MB_LIB.T6G(SCH_1):PVDDCR_CPU0_P0
 G40 PVDDCR_CPU0_P0 VDDCR_CPU0_G40 @T6G_MB_LIB.T6G(SCH_1):PVDDCR_CPU0_P0
 G36 PVDDCR_CPU0_P0 VDDCR_CPU0_G36 @T6G_MB_LIB.T6G(SCH_1):PVDDCR_CPU0_P0
 G35 PVDDCR_CPU0_P0 VDDCR_CPU0_G35 @T6G_MB_LIB.T6G(SCH_1):PVDDCR_CPU0_P0
 F54 PVDDCR_CPU0_P0 VDDCR_CPU0_F54 @T6G_MB_LIB.T6G(SCH_1):PVDDCR_CPU0_P0
 F51 PVDDCR_CPU0_P0 VDDCR_CPU0_F51 @T6G_MB_LIB.T6G(SCH_1):PVDDCR_CPU0_P0
 F48 PVDDCR_CPU0_P0 VDDCR_CPU0_F48 @T6G_MB_LIB.T6G(SCH_1):PVDDCR_CPU0_P0
 F45 PVDDCR_CPU0_P0 VDDCR_CPU0_F45 @T6G_MB_LIB.T6G(SCH_1):PVDDCR_CPU0_P0
 F42 PVDDCR_CPU0_P0 VDDCR_CPU0_F42 @T6G_MB_LIB.T6G(SCH_1):PVDDCR_CPU0_P0
 F34 PVDDCR_CPU0_P0 VDDCR_CPU0_F34 @T6G_MB_LIB.T6G(SCH_1):PVDDCR_CPU0_P0
 F31 PVDDCR_CPU0_P0 VDDCR_CPU0_F31 @T6G_MB_LIB.T6G(SCH_1):PVDDCR_CPU0_P0
 F28 PVDDCR_CPU0_P0 VDDCR_CPU0_F28 @T6G_MB_LIB.T6G(SCH_1):PVDDCR_CPU0_P0
 F25 PVDDCR_CPU0_P0 VDDCR_CPU0_F25 @T6G_MB_LIB.T6G(SCH_1):PVDDCR_CPU0_P0
 F22 PVDDCR_CPU0_P0 VDDCR_CPU0_F22 @T6G_MB_LIB.T6G(SCH_1):PVDDCR_CPU0_P0
 E54 PVDDCR_CPU0_P0 VDDCR_CPU0_E54 @T6G_MB_LIB.T6G(SCH_1):PVDDCR_CPU0_P0
 E51 PVDDCR_CPU0_P0 VDDCR_CPU0_E51 @T6G_MB_LIB.T6G(SCH_1):PVDDCR_CPU0_P0
 E48 PVDDCR_CPU0_P0 VDDCR_CPU0_E48 @T6G_MB_LIB.T6G(SCH_1):PVDDCR_CPU0_P0
 E45 PVDDCR_CPU0_P0 VDDCR_CPU0_E45 @T6G_MB_LIB.T6G(SCH_1):PVDDCR_CPU0_P0
 E42 PVDDCR_CPU0_P0 VDDCR_CPU0_E42 @T6G_MB_LIB.T6G(SCH_1):PVDDCR_CPU0_P0
 E35 PVDDCR_CPU0_P0 VDDCR_CPU0_E35 @T6G_MB_LIB.T6G(SCH_1):PVDDCR_CPU0_P0
 E34 PVDDCR_CPU0_P0 VDDCR_CPU0_E34 @T6G_MB_LIB.T6G(SCH_1):PVDDCR_CPU0_P0
 E31 PVDDCR_CPU0_P0 VDDCR_CPU0_E31 @T6G_MB_LIB.T6G(SCH_1):PVDDCR_CPU0_P0
 E28 PVDDCR_CPU0_P0 VDDCR_CPU0_E28 @T6G_MB_LIB.T6G(SCH_1):PVDDCR_CPU0_P0
 E25 PVDDCR_CPU0_P0 VDDCR_CPU0_E25 @T6G_MB_LIB.T6G(SCH_1):PVDDCR_CPU0_P0
 E22 PVDDCR_CPU0_P0 VDDCR_CPU0_E22 @T6G_MB_LIB.T6G(SCH_1):PVDDCR_CPU0_P0
 D56 PVDDCR_CPU0_P0 VDDCR_CPU0_D56 @T6G_MB_LIB.T6G(SCH_1):PVDDCR_CPU0_P0
 D55 PVDDCR_CPU0_P0 VDDCR_CPU0_D55 @T6G_MB_LIB.T6G(SCH_1):PVDDCR_CPU0_P0
 C20 PVDDCR_CPU0_P0 VDDCR_CPU0_C20 @T6G_MB_LIB.T6G(SCH_1):PVDDCR_CPU0_P0
 B57 PVDDCR_CPU0_P0 VDDCR_CPU0_B57 @T6G_MB_LIB.T6G(SCH_1):PVDDCR_CPU0_P0
 B56 PVDDCR_CPU0_P0 VDDCR_CPU0_B56 @T6G_MB_LIB.T6G(SCH_1):PVDDCR_CPU0_P0
 B54 PVDDCR_CPU0_P0 VDDCR_CPU0_B54 @T6G_MB_LIB.T6G(SCH_1):PVDDCR_CPU0_P0
 B53 PVDDCR_CPU0_P0 VDDCR_CPU0_B53 @T6G_MB_LIB.T6G(SCH_1):PVDDCR_CPU0_P0
 B51 PVDDCR_CPU0_P0 VDDCR_CPU0_B51 @T6G_MB_LIB.T6G(SCH_1):PVDDCR_CPU0_P0
 B50 PVDDCR_CPU0_P0 VDDCR_CPU0_B50 @T6G_MB_LIB.T6G(SCH_1):PVDDCR_CPU0_P0
 B48 PVDDCR_CPU0_P0 VDDCR_CPU0_B48 @T6G_MB_LIB.T6G(SCH_1):PVDDCR_CPU0_P0
 B47 PVDDCR_CPU0_P0 VDDCR_CPU0_B47 @T6G_MB_LIB.T6G(SCH_1):PVDDCR_CPU0_P0
 B45 PVDDCR_CPU0_P0 VDDCR_CPU0_B45 @T6G_MB_LIB.T6G(SCH_1):PVDDCR_CPU0_P0
 B44 PVDDCR_CPU0_P0 VDDCR_CPU0_B44 @T6G_MB_LIB.T6G(SCH_1):PVDDCR_CPU0_P0
 B42 PVDDCR_CPU0_P0 VDDCR_CPU0_B42 @T6G_MB_LIB.T6G(SCH_1):PVDDCR_CPU0_P0
 B41 PVDDCR_CPU0_P0 VDDCR_CPU0_B41 @T6G_MB_LIB.T6G(SCH_1):PVDDCR_CPU0_P0
 B35 PVDDCR_CPU0_P0 VDDCR_CPU0_B35 @T6G_MB_LIB.T6G(SCH_1):PVDDCR_CPU0_P0
 B34 PVDDCR_CPU0_P0 VDDCR_CPU0_B34 @T6G_MB_LIB.T6G(SCH_1):PVDDCR_CPU0_P0
 B32 PVDDCR_CPU0_P0 VDDCR_CPU0_B32 @T6G_MB_LIB.T6G(SCH_1):PVDDCR_CPU0_P0
 B31 PVDDCR_CPU0_P0 VDDCR_CPU0_B31 @T6G_MB_LIB.T6G(SCH_1):PVDDCR_CPU0_P0
 B29 PVDDCR_CPU0_P0 VDDCR_CPU0_B29 @T6G_MB_LIB.T6G(SCH_1):PVDDCR_CPU0_P0
 B28 PVDDCR_CPU0_P0 VDDCR_CPU0_B28 @T6G_MB_LIB.T6G(SCH_1):PVDDCR_CPU0_P0
 B26 PVDDCR_CPU0_P0 VDDCR_CPU0_B26 @T6G_MB_LIB.T6G(SCH_1):PVDDCR_CPU0_P0
 B25 PVDDCR_CPU0_P0 VDDCR_CPU0_B25 @T6G_MB_LIB.T6G(SCH_1):PVDDCR_CPU0_P0
 B23 PVDDCR_CPU0_P0 VDDCR_CPU0_B23 @T6G_MB_LIB.T6G(SCH_1):PVDDCR_CPU0_P0
 B22 PVDDCR_CPU0_P0 VDDCR_CPU0_B22 @T6G_MB_LIB.T6G(SCH_1):PVDDCR_CPU0_P0
 B20 PVDDCR_CPU0_P0 VDDCR_CPU0_B20 @T6G_MB_LIB.T6G(SCH_1):PVDDCR_CPU0_P0
 B19 PVDDCR_CPU0_P0 VDDCR_CPU0_B19 @T6G_MB_LIB.T6G(SCH_1):PVDDCR_CPU0_P0
AT47 PVDDCR_CPU0_P0 VDDCR_CPU0_AT47 @T6G_MB_LIB.T6G(SCH_1):PVDDCR_CPU0_P0
AT45 PVDDCR_CPU0_P0 VDDCR_CPU0_AT45 @T6G_MB_LIB.T6G(SCH_1):PVDDCR_CPU0_P0
AT43 PVDDCR_CPU0_P0 VDDCR_CPU0_AT43 @T6G_MB_LIB.T6G(SCH_1):PVDDCR_CPU0_P0
AT41 PVDDCR_CPU0_P0 VDDCR_CPU0_AT41 @T6G_MB_LIB.T6G(SCH_1):PVDDCR_CPU0_P0
AT39 PVDDCR_CPU0_P0 VDDCR_CPU0_AT39 @T6G_MB_LIB.T6G(SCH_1):PVDDCR_CPU0_P0
AT36 PVDDCR_CPU0_P0 VDDCR_CPU0_AT36 @T6G_MB_LIB.T6G(SCH_1):PVDDCR_CPU0_P0
AT34 PVDDCR_CPU0_P0 VDDCR_CPU0_AT34 @T6G_MB_LIB.T6G(SCH_1):PVDDCR_CPU0_P0
AT32 PVDDCR_CPU0_P0 VDDCR_CPU0_AT32 @T6G_MB_LIB.T6G(SCH_1):PVDDCR_CPU0_P0
AT30 PVDDCR_CPU0_P0 VDDCR_CPU0_AT30 @T6G_MB_LIB.T6G(SCH_1):PVDDCR_CPU0_P0
AT28 PVDDCR_CPU0_P0 VDDCR_CPU0_AT28 @T6G_MB_LIB.T6G(SCH_1):PVDDCR_CPU0_P0
AT26 PVDDCR_CPU0_P0 VDDCR_CPU0_AT26 @T6G_MB_LIB.T6G(SCH_1):PVDDCR_CPU0_P0
AT24 PVDDCR_CPU0_P0 VDDCR_CPU0_AT24 @T6G_MB_LIB.T6G(SCH_1):PVDDCR_CPU0_P0
AR50 PVDDCR_CPU0_P0 VDDCR_CPU0_AR50 @T6G_MB_LIB.T6G(SCH_1):PVDDCR_CPU0_P0
AR48 PVDDCR_CPU0_P0 VDDCR_CPU0_AR48 @T6G_MB_LIB.T6G(SCH_1):PVDDCR_CPU0_P0
AR46 PVDDCR_CPU0_P0 VDDCR_CPU0_AR46 @T6G_MB_LIB.T6G(SCH_1):PVDDCR_CPU0_P0
AR44 PVDDCR_CPU0_P0 VDDCR_CPU0_AR44 @T6G_MB_LIB.T6G(SCH_1):PVDDCR_CPU0_P0
AR42 PVDDCR_CPU0_P0 VDDCR_CPU0_AR42 @T6G_MB_LIB.T6G(SCH_1):PVDDCR_CPU0_P0
AR40 PVDDCR_CPU0_P0 VDDCR_CPU0_AR40 @T6G_MB_LIB.T6G(SCH_1):PVDDCR_CPU0_P0
AR35 PVDDCR_CPU0_P0 VDDCR_CPU0_AR35 @T6G_MB_LIB.T6G(SCH_1):PVDDCR_CPU0_P0
AR33 PVDDCR_CPU0_P0 VDDCR_CPU0_AR33 @T6G_MB_LIB.T6G(SCH_1):PVDDCR_CPU0_P0
AR31 PVDDCR_CPU0_P0 VDDCR_CPU0_AR31 @T6G_MB_LIB.T6G(SCH_1):PVDDCR_CPU0_P0
AR29 PVDDCR_CPU0_P0 VDDCR_CPU0_AR29 @T6G_MB_LIB.T6G(SCH_1):PVDDCR_CPU0_P0
AR27 PVDDCR_CPU0_P0 VDDCR_CPU0_AR27 @T6G_MB_LIB.T6G(SCH_1):PVDDCR_CPU0_P0
AR25 PVDDCR_CPU0_P0 VDDCR_CPU0_AR25 @T6G_MB_LIB.T6G(SCH_1):PVDDCR_CPU0_P0
AR23 PVDDCR_CPU0_P0 VDDCR_CPU0_AR23 @T6G_MB_LIB.T6G(SCH_1):PVDDCR_CPU0_P0
AP53 PVDDCR_CPU0_P0 VDDCR_CPU0_AP53 @T6G_MB_LIB.T6G(SCH_1):PVDDCR_CPU0_P0
AP52 PVDDCR_CPU0_P0 VDDCR_CPU0_AP52 @T6G_MB_LIB.T6G(SCH_1):PVDDCR_CPU0_P0
AP50 PVDDCR_CPU0_P0 VDDCR_CPU0_AP50 @T6G_MB_LIB.T6G(SCH_1):PVDDCR_CPU0_P0
AP49 PVDDCR_CPU0_P0 VDDCR_CPU0_AP49 @T6G_MB_LIB.T6G(SCH_1):PVDDCR_CPU0_P0
AP47 PVDDCR_CPU0_P0 VDDCR_CPU0_AP47 @T6G_MB_LIB.T6G(SCH_1):PVDDCR_CPU0_P0
AP46 PVDDCR_CPU0_P0 VDDCR_CPU0_AP46 @T6G_MB_LIB.T6G(SCH_1):PVDDCR_CPU0_P0
AP44 PVDDCR_CPU0_P0 VDDCR_CPU0_AP44 @T6G_MB_LIB.T6G(SCH_1):PVDDCR_CPU0_P0
AP43 PVDDCR_CPU0_P0 VDDCR_CPU0_AP43 @T6G_MB_LIB.T6G(SCH_1):PVDDCR_CPU0_P0
AP33 PVDDCR_CPU0_P0 VDDCR_CPU0_AP33 @T6G_MB_LIB.T6G(SCH_1):PVDDCR_CPU0_P0
AP32 PVDDCR_CPU0_P0 VDDCR_CPU0_AP32 @T6G_MB_LIB.T6G(SCH_1):PVDDCR_CPU0_P0
AP30 PVDDCR_CPU0_P0 VDDCR_CPU0_AP30 @T6G_MB_LIB.T6G(SCH_1):PVDDCR_CPU0_P0
AP29 PVDDCR_CPU0_P0 VDDCR_CPU0_AP29 @T6G_MB_LIB.T6G(SCH_1):PVDDCR_CPU0_P0
AP27 PVDDCR_CPU0_P0 VDDCR_CPU0_AP27 @T6G_MB_LIB.T6G(SCH_1):PVDDCR_CPU0_P0
AP26 PVDDCR_CPU0_P0 VDDCR_CPU0_AP26 @T6G_MB_LIB.T6G(SCH_1):PVDDCR_CPU0_P0
AP24 PVDDCR_CPU0_P0 VDDCR_CPU0_AP24 @T6G_MB_LIB.T6G(SCH_1):PVDDCR_CPU0_P0
AP23 PVDDCR_CPU0_P0 VDDCR_CPU0_AP23 @T6G_MB_LIB.T6G(SCH_1):PVDDCR_CPU0_P0
AL41 PVDDCR_CPU0_P0 VDDCR_CPU0_AL41 @T6G_MB_LIB.T6G(SCH_1):PVDDCR_CPU0_P0
AL40 PVDDCR_CPU0_P0 VDDCR_CPU0_AL40 @T6G_MB_LIB.T6G(SCH_1):PVDDCR_CPU0_P0
AL36 PVDDCR_CPU0_P0 VDDCR_CPU0_AL36 @T6G_MB_LIB.T6G(SCH_1):PVDDCR_CPU0_P0
AL35 PVDDCR_CPU0_P0 VDDCR_CPU0_AL35 @T6G_MB_LIB.T6G(SCH_1):PVDDCR_CPU0_P0
AK53 PVDDCR_CPU0_P0 VDDCR_CPU0_AK53 @T6G_MB_LIB.T6G(SCH_1):PVDDCR_CPU0_P0
AK52 PVDDCR_CPU0_P0 VDDCR_CPU0_AK52 @T6G_MB_LIB.T6G(SCH_1):PVDDCR_CPU0_P0
AK50 PVDDCR_CPU0_P0 VDDCR_CPU0_AK50 @T6G_MB_LIB.T6G(SCH_1):PVDDCR_CPU0_P0
AK49 PVDDCR_CPU0_P0 VDDCR_CPU0_AK49 @T6G_MB_LIB.T6G(SCH_1):PVDDCR_CPU0_P0
AK47 PVDDCR_CPU0_P0 VDDCR_CPU0_AK47 @T6G_MB_LIB.T6G(SCH_1):PVDDCR_CPU0_P0
AK46 PVDDCR_CPU0_P0 VDDCR_CPU0_AK46 @T6G_MB_LIB.T6G(SCH_1):PVDDCR_CPU0_P0
AK44 PVDDCR_CPU0_P0 VDDCR_CPU0_AK44 @T6G_MB_LIB.T6G(SCH_1):PVDDCR_CPU0_P0
AK43 PVDDCR_CPU0_P0 VDDCR_CPU0_AK43 @T6G_MB_LIB.T6G(SCH_1):PVDDCR_CPU0_P0
AK33 PVDDCR_CPU0_P0 VDDCR_CPU0_AK33 @T6G_MB_LIB.T6G(SCH_1):PVDDCR_CPU0_P0
AK32 PVDDCR_CPU0_P0 VDDCR_CPU0_AK32 @T6G_MB_LIB.T6G(SCH_1):PVDDCR_CPU0_P0
AK30 PVDDCR_CPU0_P0 VDDCR_CPU0_AK30 @T6G_MB_LIB.T6G(SCH_1):PVDDCR_CPU0_P0
AK29 PVDDCR_CPU0_P0 VDDCR_CPU0_AK29 @T6G_MB_LIB.T6G(SCH_1):PVDDCR_CPU0_P0
AK27 PVDDCR_CPU0_P0 VDDCR_CPU0_AK27 @T6G_MB_LIB.T6G(SCH_1):PVDDCR_CPU0_P0
AK26 PVDDCR_CPU0_P0 VDDCR_CPU0_AK26 @T6G_MB_LIB.T6G(SCH_1):PVDDCR_CPU0_P0
AK24 PVDDCR_CPU0_P0 VDDCR_CPU0_AK24 @T6G_MB_LIB.T6G(SCH_1):PVDDCR_CPU0_P0
AK23 PVDDCR_CPU0_P0 VDDCR_CPU0_AK23 @T6G_MB_LIB.T6G(SCH_1):PVDDCR_CPU0_P0
AG41 PVDDCR_CPU0_P0 VDDCR_CPU0_AG41 @T6G_MB_LIB.T6G(SCH_1):PVDDCR_CPU0_P0
AG40 PVDDCR_CPU0_P0 VDDCR_CPU0_AG40 @T6G_MB_LIB.T6G(SCH_1):PVDDCR_CPU0_P0
AG36 PVDDCR_CPU0_P0 VDDCR_CPU0_AG36 @T6G_MB_LIB.T6G(SCH_1):PVDDCR_CPU0_P0
AG35 PVDDCR_CPU0_P0 VDDCR_CPU0_AG35 @T6G_MB_LIB.T6G(SCH_1):PVDDCR_CPU0_P0
AF53 PVDDCR_CPU0_P0 VDDCR_CPU0_AF53 @T6G_MB_LIB.T6G(SCH_1):PVDDCR_CPU0_P0
AF52 PVDDCR_CPU0_P0 VDDCR_CPU0_AF52 @T6G_MB_LIB.T6G(SCH_1):PVDDCR_CPU0_P0
AF50 PVDDCR_CPU0_P0 VDDCR_CPU0_AF50 @T6G_MB_LIB.T6G(SCH_1):PVDDCR_CPU0_P0
AF49 PVDDCR_CPU0_P0 VDDCR_CPU0_AF49 @T6G_MB_LIB.T6G(SCH_1):PVDDCR_CPU0_P0
AF47 PVDDCR_CPU0_P0 VDDCR_CPU0_AF47 @T6G_MB_LIB.T6G(SCH_1):PVDDCR_CPU0_P0
AF46 PVDDCR_CPU0_P0 VDDCR_CPU0_AF46 @T6G_MB_LIB.T6G(SCH_1):PVDDCR_CPU0_P0
AF44 PVDDCR_CPU0_P0 VDDCR_CPU0_AF44 @T6G_MB_LIB.T6G(SCH_1):PVDDCR_CPU0_P0
AF43 PVDDCR_CPU0_P0 VDDCR_CPU0_AF43 @T6G_MB_LIB.T6G(SCH_1):PVDDCR_CPU0_P0
AF33 PVDDCR_CPU0_P0 VDDCR_CPU0_AF33 @T6G_MB_LIB.T6G(SCH_1):PVDDCR_CPU0_P0
AF32 PVDDCR_CPU0_P0 VDDCR_CPU0_AF32 @T6G_MB_LIB.T6G(SCH_1):PVDDCR_CPU0_P0
AF30 PVDDCR_CPU0_P0 VDDCR_CPU0_AF30 @T6G_MB_LIB.T6G(SCH_1):PVDDCR_CPU0_P0
AF29 PVDDCR_CPU0_P0 VDDCR_CPU0_AF29 @T6G_MB_LIB.T6G(SCH_1):PVDDCR_CPU0_P0
AF27 PVDDCR_CPU0_P0 VDDCR_CPU0_AF27 @T6G_MB_LIB.T6G(SCH_1):PVDDCR_CPU0_P0
AF26 PVDDCR_CPU0_P0 VDDCR_CPU0_AF26 @T6G_MB_LIB.T6G(SCH_1):PVDDCR_CPU0_P0
AF24 PVDDCR_CPU0_P0 VDDCR_CPU0_AF24 @T6G_MB_LIB.T6G(SCH_1):PVDDCR_CPU0_P0
AF23 PVDDCR_CPU0_P0 VDDCR_CPU0_AF23 @T6G_MB_LIB.T6G(SCH_1):PVDDCR_CPU0_P0
AC41 PVDDCR_CPU0_P0 VDDCR_CPU0_AC41 @T6G_MB_LIB.T6G(SCH_1):PVDDCR_CPU0_P0
AC40 PVDDCR_CPU0_P0 VDDCR_CPU0_AC40 @T6G_MB_LIB.T6G(SCH_1):PVDDCR_CPU0_P0
AC36 PVDDCR_CPU0_P0 VDDCR_CPU0_AC36 @T6G_MB_LIB.T6G(SCH_1):PVDDCR_CPU0_P0
AC35 PVDDCR_CPU0_P0 VDDCR_CPU0_AC35 @T6G_MB_LIB.T6G(SCH_1):PVDDCR_CPU0_P0
AB53 PVDDCR_CPU0_P0 VDDCR_CPU0_AB53 @T6G_MB_LIB.T6G(SCH_1):PVDDCR_CPU0_P0
AB52 PVDDCR_CPU0_P0 VDDCR_CPU0_AB52 @T6G_MB_LIB.T6G(SCH_1):PVDDCR_CPU0_P0
AB50 PVDDCR_CPU0_P0 VDDCR_CPU0_AB50 @T6G_MB_LIB.T6G(SCH_1):PVDDCR_CPU0_P0
AB49 PVDDCR_CPU0_P0 VDDCR_CPU0_AB49 @T6G_MB_LIB.T6G(SCH_1):PVDDCR_CPU0_P0
AB47 PVDDCR_CPU0_P0 VDDCR_CPU0_AB47 @T6G_MB_LIB.T6G(SCH_1):PVDDCR_CPU0_P0
AB46 PVDDCR_CPU0_P0 VDDCR_CPU0_AB46 @T6G_MB_LIB.T6G(SCH_1):PVDDCR_CPU0_P0
AB44 PVDDCR_CPU0_P0 VDDCR_CPU0_AB44 @T6G_MB_LIB.T6G(SCH_1):PVDDCR_CPU0_P0
AB43 PVDDCR_CPU0_P0 VDDCR_CPU0_AB43 @T6G_MB_LIB.T6G(SCH_1):PVDDCR_CPU0_P0
AB33 PVDDCR_CPU0_P0 VDDCR_CPU0_AB33 @T6G_MB_LIB.T6G(SCH_1):PVDDCR_CPU0_P0
AB32 PVDDCR_CPU0_P0 VDDCR_CPU0_AB32 @T6G_MB_LIB.T6G(SCH_1):PVDDCR_CPU0_P0
AB30 PVDDCR_CPU0_P0 VDDCR_CPU0_AB30 @T6G_MB_LIB.T6G(SCH_1):PVDDCR_CPU0_P0
AB29 PVDDCR_CPU0_P0 VDDCR_CPU0_AB29 @T6G_MB_LIB.T6G(SCH_1):PVDDCR_CPU0_P0
AB27 PVDDCR_CPU0_P0 VDDCR_CPU0_AB27 @T6G_MB_LIB.T6G(SCH_1):PVDDCR_CPU0_P0
AB26 PVDDCR_CPU0_P0 VDDCR_CPU0_AB26 @T6G_MB_LIB.T6G(SCH_1):PVDDCR_CPU0_P0
AB24 PVDDCR_CPU0_P0 VDDCR_CPU0_AB24 @T6G_MB_LIB.T6G(SCH_1):PVDDCR_CPU0_P0
AB23 PVDDCR_CPU0_P0 VDDCR_CPU0_AB23 @T6G_MB_LIB.T6G(SCH_1):PVDDCR_CPU0_P0
 Y41 PVDDCR_CPU0_P0 VDDCR_CPU0_Y41 @T6G_MB_LIB.T6G(SCH_1):PVDDCR_CPU0_P0
 Y40 PVDDCR_CPU0_P0 VDDCR_CPU0_Y40 @T6G_MB_LIB.T6G(SCH_1):PVDDCR_CPU0_P0
 Y36 PVDDCR_CPU0_P0 VDDCR_CPU0_Y36 @T6G_MB_LIB.T6G(SCH_1):PVDDCR_CPU0_P0
 Y35 PVDDCR_CPU0_P0 VDDCR_CPU0_Y35 @T6G_MB_LIB.T6G(SCH_1):PVDDCR_CPU0_P0
AU42 PVDDCR_CPU0_P0 VDDCR_CPU0_AU42 @T6G_MB_LIB.T6G(SCH_1):PVDDCR_CPU0_P0
AU46 PVDDCR_CPU0_P0 VDDCR_CPU0_AU46 @T6G_MB_LIB.T6G(SCH_1):PVDDCR_CPU0_P0
AT49 PVDDCR_CPU0_P0 VDDCR_CPU0_AT49 @T6G_MB_LIB.T6G(SCH_1):PVDDCR_CPU0_P0
AU29 PVDDCR_CPU0_P0 VDDCR_CPU0_AU29 @T6G_MB_LIB.T6G(SCH_1):PVDDCR_CPU0_P0
AU44 PVDDCR_CPU0_P0 VDDCR_CPU0_AU44 @T6G_MB_LIB.T6G(SCH_1):PVDDCR_CPU0_P0
AU48 PVDDCR_CPU0_P0 VDDCR_CPU0_AU48 @T6G_MB_LIB.T6G(SCH_1):PVDDCR_CPU0_P0
AU25 PVDDCR_CPU0_P0 VDDCR_CPU0_AU25 @T6G_MB_LIB.T6G(SCH_1):PVDDCR_CPU0_P0
AU33 PVDDCR_CPU0_P0 VDDCR_CPU0_AU33 @T6G_MB_LIB.T6G(SCH_1):PVDDCR_CPU0_P0

GENOA_SP5-SOCKET6096_13568-001,SMLF,IO,DGA^6000030  I45  U25
BN31 PVDDCR_CPU1_P0 VDDCR_CPU1_BN31 @T6G_MB_LIB.T6G(SCH_1):PVDDCR_CPU1_P0
BN42 PVDDCR_CPU1_P0 VDDCR_CPU1_BN42 @T6G_MB_LIB.T6G(SCH_1):PVDDCR_CPU1_P0
BN50 PVDDCR_CPU1_P0 VDDCR_CPU1_BN50 @T6G_MB_LIB.T6G(SCH_1):PVDDCR_CPU1_P0
BP26 PVDDCR_CPU1_P0 VDDCR_CPU1_BP26 @T6G_MB_LIB.T6G(SCH_1):PVDDCR_CPU1_P0
BP30 PVDDCR_CPU1_P0 VDDCR_CPU1_BP30 @T6G_MB_LIB.T6G(SCH_1):PVDDCR_CPU1_P0
BP34 PVDDCR_CPU1_P0 VDDCR_CPU1_BP34 @T6G_MB_LIB.T6G(SCH_1):PVDDCR_CPU1_P0
BP36 PVDDCR_CPU1_P0 VDDCR_CPU1_BP36 @T6G_MB_LIB.T6G(SCH_1):PVDDCR_CPU1_P0
BP39 PVDDCR_CPU1_P0 VDDCR_CPU1_BP39 @T6G_MB_LIB.T6G(SCH_1):PVDDCR_CPU1_P0
BP41 PVDDCR_CPU1_P0 VDDCR_CPU1_BP41 @T6G_MB_LIB.T6G(SCH_1):PVDDCR_CPU1_P0
BP43 PVDDCR_CPU1_P0 VDDCR_CPU1_BP43 @T6G_MB_LIB.T6G(SCH_1):PVDDCR_CPU1_P0
BP45 PVDDCR_CPU1_P0 VDDCR_CPU1_BP45 @T6G_MB_LIB.T6G(SCH_1):PVDDCR_CPU1_P0
BP47 PVDDCR_CPU1_P0 VDDCR_CPU1_BP47 @T6G_MB_LIB.T6G(SCH_1):PVDDCR_CPU1_P0
BP49 PVDDCR_CPU1_P0 VDDCR_CPU1_BP49 @T6G_MB_LIB.T6G(SCH_1):PVDDCR_CPU1_P0
BR23 PVDDCR_CPU1_P0 VDDCR_CPU1_BR23 @T6G_MB_LIB.T6G(SCH_1):PVDDCR_CPU1_P0
BR25 PVDDCR_CPU1_P0 VDDCR_CPU1_BR25 @T6G_MB_LIB.T6G(SCH_1):PVDDCR_CPU1_P0
BR27 PVDDCR_CPU1_P0 VDDCR_CPU1_BR27 @T6G_MB_LIB.T6G(SCH_1):PVDDCR_CPU1_P0
BR29 PVDDCR_CPU1_P0 VDDCR_CPU1_BR29 @T6G_MB_LIB.T6G(SCH_1):PVDDCR_CPU1_P0
BR31 PVDDCR_CPU1_P0 VDDCR_CPU1_BR31 @T6G_MB_LIB.T6G(SCH_1):PVDDCR_CPU1_P0
BR33 PVDDCR_CPU1_P0 VDDCR_CPU1_BR33 @T6G_MB_LIB.T6G(SCH_1):PVDDCR_CPU1_P0
BR35 PVDDCR_CPU1_P0 VDDCR_CPU1_BR35 @T6G_MB_LIB.T6G(SCH_1):PVDDCR_CPU1_P0
BR40 PVDDCR_CPU1_P0 VDDCR_CPU1_BR40 @T6G_MB_LIB.T6G(SCH_1):PVDDCR_CPU1_P0
BR42 PVDDCR_CPU1_P0 VDDCR_CPU1_BR42 @T6G_MB_LIB.T6G(SCH_1):PVDDCR_CPU1_P0
BR44 PVDDCR_CPU1_P0 VDDCR_CPU1_BR44 @T6G_MB_LIB.T6G(SCH_1):PVDDCR_CPU1_P0
BR46 PVDDCR_CPU1_P0 VDDCR_CPU1_BR46 @T6G_MB_LIB.T6G(SCH_1):PVDDCR_CPU1_P0
BR48 PVDDCR_CPU1_P0 VDDCR_CPU1_BR48 @T6G_MB_LIB.T6G(SCH_1):PVDDCR_CPU1_P0
BR50 PVDDCR_CPU1_P0 VDDCR_CPU1_BR50 @T6G_MB_LIB.T6G(SCH_1):PVDDCR_CPU1_P0
BR52 PVDDCR_CPU1_P0 VDDCR_CPU1_BR52 @T6G_MB_LIB.T6G(SCH_1):PVDDCR_CPU1_P0
BT23 PVDDCR_CPU1_P0 VDDCR_CPU1_BT23 @T6G_MB_LIB.T6G(SCH_1):PVDDCR_CPU1_P0
BT24 PVDDCR_CPU1_P0 VDDCR_CPU1_BT24 @T6G_MB_LIB.T6G(SCH_1):PVDDCR_CPU1_P0
BT26 PVDDCR_CPU1_P0 VDDCR_CPU1_BT26 @T6G_MB_LIB.T6G(SCH_1):PVDDCR_CPU1_P0
BT27 PVDDCR_CPU1_P0 VDDCR_CPU1_BT27 @T6G_MB_LIB.T6G(SCH_1):PVDDCR_CPU1_P0
BT29 PVDDCR_CPU1_P0 VDDCR_CPU1_BT29 @T6G_MB_LIB.T6G(SCH_1):PVDDCR_CPU1_P0
BT30 PVDDCR_CPU1_P0 VDDCR_CPU1_BT30 @T6G_MB_LIB.T6G(SCH_1):PVDDCR_CPU1_P0
BT32 PVDDCR_CPU1_P0 VDDCR_CPU1_BT32 @T6G_MB_LIB.T6G(SCH_1):PVDDCR_CPU1_P0
BT33 PVDDCR_CPU1_P0 VDDCR_CPU1_BT33 @T6G_MB_LIB.T6G(SCH_1):PVDDCR_CPU1_P0
BT43 PVDDCR_CPU1_P0 VDDCR_CPU1_BT43 @T6G_MB_LIB.T6G(SCH_1):PVDDCR_CPU1_P0
BT44 PVDDCR_CPU1_P0 VDDCR_CPU1_BT44 @T6G_MB_LIB.T6G(SCH_1):PVDDCR_CPU1_P0
BT46 PVDDCR_CPU1_P0 VDDCR_CPU1_BT46 @T6G_MB_LIB.T6G(SCH_1):PVDDCR_CPU1_P0
BT47 PVDDCR_CPU1_P0 VDDCR_CPU1_BT47 @T6G_MB_LIB.T6G(SCH_1):PVDDCR_CPU1_P0
BT49 PVDDCR_CPU1_P0 VDDCR_CPU1_BT49 @T6G_MB_LIB.T6G(SCH_1):PVDDCR_CPU1_P0
BT50 PVDDCR_CPU1_P0 VDDCR_CPU1_BT50 @T6G_MB_LIB.T6G(SCH_1):PVDDCR_CPU1_P0
BT52 PVDDCR_CPU1_P0 VDDCR_CPU1_BT52 @T6G_MB_LIB.T6G(SCH_1):PVDDCR_CPU1_P0
BT53 PVDDCR_CPU1_P0 VDDCR_CPU1_BT53 @T6G_MB_LIB.T6G(SCH_1):PVDDCR_CPU1_P0
BW35 PVDDCR_CPU1_P0 VDDCR_CPU1_BW35 @T6G_MB_LIB.T6G(SCH_1):PVDDCR_CPU1_P0
BW36 PVDDCR_CPU1_P0 VDDCR_CPU1_BW36 @T6G_MB_LIB.T6G(SCH_1):PVDDCR_CPU1_P0
BW40 PVDDCR_CPU1_P0 VDDCR_CPU1_BW40 @T6G_MB_LIB.T6G(SCH_1):PVDDCR_CPU1_P0
BW41 PVDDCR_CPU1_P0 VDDCR_CPU1_BW41 @T6G_MB_LIB.T6G(SCH_1):PVDDCR_CPU1_P0
BY23 PVDDCR_CPU1_P0 VDDCR_CPU1_BY23 @T6G_MB_LIB.T6G(SCH_1):PVDDCR_CPU1_P0
BY24 PVDDCR_CPU1_P0 VDDCR_CPU1_BY24 @T6G_MB_LIB.T6G(SCH_1):PVDDCR_CPU1_P0
BY26 PVDDCR_CPU1_P0 VDDCR_CPU1_BY26 @T6G_MB_LIB.T6G(SCH_1):PVDDCR_CPU1_P0
BY27 PVDDCR_CPU1_P0 VDDCR_CPU1_BY27 @T6G_MB_LIB.T6G(SCH_1):PVDDCR_CPU1_P0
BY29 PVDDCR_CPU1_P0 VDDCR_CPU1_BY29 @T6G_MB_LIB.T6G(SCH_1):PVDDCR_CPU1_P0
BY30 PVDDCR_CPU1_P0 VDDCR_CPU1_BY30 @T6G_MB_LIB.T6G(SCH_1):PVDDCR_CPU1_P0
BY32 PVDDCR_CPU1_P0 VDDCR_CPU1_BY32 @T6G_MB_LIB.T6G(SCH_1):PVDDCR_CPU1_P0
BY33 PVDDCR_CPU1_P0 VDDCR_CPU1_BY33 @T6G_MB_LIB.T6G(SCH_1):PVDDCR_CPU1_P0
BY43 PVDDCR_CPU1_P0 VDDCR_CPU1_BY43 @T6G_MB_LIB.T6G(SCH_1):PVDDCR_CPU1_P0
BY44 PVDDCR_CPU1_P0 VDDCR_CPU1_BY44 @T6G_MB_LIB.T6G(SCH_1):PVDDCR_CPU1_P0
BY46 PVDDCR_CPU1_P0 VDDCR_CPU1_BY46 @T6G_MB_LIB.T6G(SCH_1):PVDDCR_CPU1_P0
BY47 PVDDCR_CPU1_P0 VDDCR_CPU1_BY47 @T6G_MB_LIB.T6G(SCH_1):PVDDCR_CPU1_P0
BY49 PVDDCR_CPU1_P0 VDDCR_CPU1_BY49 @T6G_MB_LIB.T6G(SCH_1):PVDDCR_CPU1_P0
BY50 PVDDCR_CPU1_P0 VDDCR_CPU1_BY50 @T6G_MB_LIB.T6G(SCH_1):PVDDCR_CPU1_P0
BY52 PVDDCR_CPU1_P0 VDDCR_CPU1_BY52 @T6G_MB_LIB.T6G(SCH_1):PVDDCR_CPU1_P0
BY53 PVDDCR_CPU1_P0 VDDCR_CPU1_BY53 @T6G_MB_LIB.T6G(SCH_1):PVDDCR_CPU1_P0
CC35 PVDDCR_CPU1_P0 VDDCR_CPU1_CC35 @T6G_MB_LIB.T6G(SCH_1):PVDDCR_CPU1_P0
CC36 PVDDCR_CPU1_P0 VDDCR_CPU1_CC36 @T6G_MB_LIB.T6G(SCH_1):PVDDCR_CPU1_P0
CC40 PVDDCR_CPU1_P0 VDDCR_CPU1_CC40 @T6G_MB_LIB.T6G(SCH_1):PVDDCR_CPU1_P0
CC41 PVDDCR_CPU1_P0 VDDCR_CPU1_CC41 @T6G_MB_LIB.T6G(SCH_1):PVDDCR_CPU1_P0
CD23 PVDDCR_CPU1_P0 VDDCR_CPU1_CD23 @T6G_MB_LIB.T6G(SCH_1):PVDDCR_CPU1_P0
CD24 PVDDCR_CPU1_P0 VDDCR_CPU1_CD24 @T6G_MB_LIB.T6G(SCH_1):PVDDCR_CPU1_P0
CD26 PVDDCR_CPU1_P0 VDDCR_CPU1_CD26 @T6G_MB_LIB.T6G(SCH_1):PVDDCR_CPU1_P0
CD27 PVDDCR_CPU1_P0 VDDCR_CPU1_CD27 @T6G_MB_LIB.T6G(SCH_1):PVDDCR_CPU1_P0
CD29 PVDDCR_CPU1_P0 VDDCR_CPU1_CD29 @T6G_MB_LIB.T6G(SCH_1):PVDDCR_CPU1_P0
CD30 PVDDCR_CPU1_P0 VDDCR_CPU1_CD30 @T6G_MB_LIB.T6G(SCH_1):PVDDCR_CPU1_P0
CD32 PVDDCR_CPU1_P0 VDDCR_CPU1_CD32 @T6G_MB_LIB.T6G(SCH_1):PVDDCR_CPU1_P0
CD33 PVDDCR_CPU1_P0 VDDCR_CPU1_CD33 @T6G_MB_LIB.T6G(SCH_1):PVDDCR_CPU1_P0
CD43 PVDDCR_CPU1_P0 VDDCR_CPU1_CD43 @T6G_MB_LIB.T6G(SCH_1):PVDDCR_CPU1_P0
CD44 PVDDCR_CPU1_P0 VDDCR_CPU1_CD44 @T6G_MB_LIB.T6G(SCH_1):PVDDCR_CPU1_P0
CD46 PVDDCR_CPU1_P0 VDDCR_CPU1_CD46 @T6G_MB_LIB.T6G(SCH_1):PVDDCR_CPU1_P0
CD47 PVDDCR_CPU1_P0 VDDCR_CPU1_CD47 @T6G_MB_LIB.T6G(SCH_1):PVDDCR_CPU1_P0
CD49 PVDDCR_CPU1_P0 VDDCR_CPU1_CD49 @T6G_MB_LIB.T6G(SCH_1):PVDDCR_CPU1_P0
CD50 PVDDCR_CPU1_P0 VDDCR_CPU1_CD50 @T6G_MB_LIB.T6G(SCH_1):PVDDCR_CPU1_P0
CD52 PVDDCR_CPU1_P0 VDDCR_CPU1_CD52 @T6G_MB_LIB.T6G(SCH_1):PVDDCR_CPU1_P0
CD53 PVDDCR_CPU1_P0 VDDCR_CPU1_CD53 @T6G_MB_LIB.T6G(SCH_1):PVDDCR_CPU1_P0
CG35 PVDDCR_CPU1_P0 VDDCR_CPU1_CG35 @T6G_MB_LIB.T6G(SCH_1):PVDDCR_CPU1_P0
CG36 PVDDCR_CPU1_P0 VDDCR_CPU1_CG36 @T6G_MB_LIB.T6G(SCH_1):PVDDCR_CPU1_P0
CG40 PVDDCR_CPU1_P0 VDDCR_CPU1_CG40 @T6G_MB_LIB.T6G(SCH_1):PVDDCR_CPU1_P0
CG41 PVDDCR_CPU1_P0 VDDCR_CPU1_CG41 @T6G_MB_LIB.T6G(SCH_1):PVDDCR_CPU1_P0
CH23 PVDDCR_CPU1_P0 VDDCR_CPU1_CH23 @T6G_MB_LIB.T6G(SCH_1):PVDDCR_CPU1_P0
CH24 PVDDCR_CPU1_P0 VDDCR_CPU1_CH24 @T6G_MB_LIB.T6G(SCH_1):PVDDCR_CPU1_P0
CH26 PVDDCR_CPU1_P0 VDDCR_CPU1_CH26 @T6G_MB_LIB.T6G(SCH_1):PVDDCR_CPU1_P0
CH27 PVDDCR_CPU1_P0 VDDCR_CPU1_CH27 @T6G_MB_LIB.T6G(SCH_1):PVDDCR_CPU1_P0
CH29 PVDDCR_CPU1_P0 VDDCR_CPU1_CH29 @T6G_MB_LIB.T6G(SCH_1):PVDDCR_CPU1_P0
CH30 PVDDCR_CPU1_P0 VDDCR_CPU1_CH30 @T6G_MB_LIB.T6G(SCH_1):PVDDCR_CPU1_P0
CH32 PVDDCR_CPU1_P0 VDDCR_CPU1_CH32 @T6G_MB_LIB.T6G(SCH_1):PVDDCR_CPU1_P0
CH33 PVDDCR_CPU1_P0 VDDCR_CPU1_CH33 @T6G_MB_LIB.T6G(SCH_1):PVDDCR_CPU1_P0
CH43 PVDDCR_CPU1_P0 VDDCR_CPU1_CH43 @T6G_MB_LIB.T6G(SCH_1):PVDDCR_CPU1_P0
CH44 PVDDCR_CPU1_P0 VDDCR_CPU1_CH44 @T6G_MB_LIB.T6G(SCH_1):PVDDCR_CPU1_P0
CH46 PVDDCR_CPU1_P0 VDDCR_CPU1_CH46 @T6G_MB_LIB.T6G(SCH_1):PVDDCR_CPU1_P0
CH47 PVDDCR_CPU1_P0 VDDCR_CPU1_CH47 @T6G_MB_LIB.T6G(SCH_1):PVDDCR_CPU1_P0
CH49 PVDDCR_CPU1_P0 VDDCR_CPU1_CH49 @T6G_MB_LIB.T6G(SCH_1):PVDDCR_CPU1_P0
CH50 PVDDCR_CPU1_P0 VDDCR_CPU1_CH50 @T6G_MB_LIB.T6G(SCH_1):PVDDCR_CPU1_P0
CH52 PVDDCR_CPU1_P0 VDDCR_CPU1_CH52 @T6G_MB_LIB.T6G(SCH_1):PVDDCR_CPU1_P0
CH53 PVDDCR_CPU1_P0 VDDCR_CPU1_CH53 @T6G_MB_LIB.T6G(SCH_1):PVDDCR_CPU1_P0
CK35 PVDDCR_CPU1_P0 VDDCR_CPU1_CK35 @T6G_MB_LIB.T6G(SCH_1):PVDDCR_CPU1_P0
CK36 PVDDCR_CPU1_P0 VDDCR_CPU1_CK36 @T6G_MB_LIB.T6G(SCH_1):PVDDCR_CPU1_P0
CK40 PVDDCR_CPU1_P0 VDDCR_CPU1_CK40 @T6G_MB_LIB.T6G(SCH_1):PVDDCR_CPU1_P0
CK41 PVDDCR_CPU1_P0 VDDCR_CPU1_CK41 @T6G_MB_LIB.T6G(SCH_1):PVDDCR_CPU1_P0
CL29 PVDDCR_CPU1_P0 VDDCR_CPU1_CL29 @T6G_MB_LIB.T6G(SCH_1):PVDDCR_CPU1_P0
CL30 PVDDCR_CPU1_P0 VDDCR_CPU1_CL30 @T6G_MB_LIB.T6G(SCH_1):PVDDCR_CPU1_P0
CL32 PVDDCR_CPU1_P0 VDDCR_CPU1_CL32 @T6G_MB_LIB.T6G(SCH_1):PVDDCR_CPU1_P0
CL33 PVDDCR_CPU1_P0 VDDCR_CPU1_CL33 @T6G_MB_LIB.T6G(SCH_1):PVDDCR_CPU1_P0
CL43 PVDDCR_CPU1_P0 VDDCR_CPU1_CL43 @T6G_MB_LIB.T6G(SCH_1):PVDDCR_CPU1_P0
CL44 PVDDCR_CPU1_P0 VDDCR_CPU1_CL44 @T6G_MB_LIB.T6G(SCH_1):PVDDCR_CPU1_P0
CL46 PVDDCR_CPU1_P0 VDDCR_CPU1_CL46 @T6G_MB_LIB.T6G(SCH_1):PVDDCR_CPU1_P0
CL47 PVDDCR_CPU1_P0 VDDCR_CPU1_CL47 @T6G_MB_LIB.T6G(SCH_1):PVDDCR_CPU1_P0
CN35 PVDDCR_CPU1_P0 VDDCR_CPU1_CN35 @T6G_MB_LIB.T6G(SCH_1):PVDDCR_CPU1_P0
CN36 PVDDCR_CPU1_P0 VDDCR_CPU1_CN36 @T6G_MB_LIB.T6G(SCH_1):PVDDCR_CPU1_P0
CN40 PVDDCR_CPU1_P0 VDDCR_CPU1_CN40 @T6G_MB_LIB.T6G(SCH_1):PVDDCR_CPU1_P0
CN41 PVDDCR_CPU1_P0 VDDCR_CPU1_CN41 @T6G_MB_LIB.T6G(SCH_1):PVDDCR_CPU1_P0
CP23 PVDDCR_CPU1_P0 VDDCR_CPU1_CP23 @T6G_MB_LIB.T6G(SCH_1):PVDDCR_CPU1_P0
CP24 PVDDCR_CPU1_P0 VDDCR_CPU1_CP24 @T6G_MB_LIB.T6G(SCH_1):PVDDCR_CPU1_P0
CP26 PVDDCR_CPU1_P0 VDDCR_CPU1_CP26 @T6G_MB_LIB.T6G(SCH_1):PVDDCR_CPU1_P0
CP27 PVDDCR_CPU1_P0 VDDCR_CPU1_CP27 @T6G_MB_LIB.T6G(SCH_1):PVDDCR_CPU1_P0
CP29 PVDDCR_CPU1_P0 VDDCR_CPU1_CP29 @T6G_MB_LIB.T6G(SCH_1):PVDDCR_CPU1_P0
CP30 PVDDCR_CPU1_P0 VDDCR_CPU1_CP30 @T6G_MB_LIB.T6G(SCH_1):PVDDCR_CPU1_P0
CP32 PVDDCR_CPU1_P0 VDDCR_CPU1_CP32 @T6G_MB_LIB.T6G(SCH_1):PVDDCR_CPU1_P0
CP33 PVDDCR_CPU1_P0 VDDCR_CPU1_CP33 @T6G_MB_LIB.T6G(SCH_1):PVDDCR_CPU1_P0
CP43 PVDDCR_CPU1_P0 VDDCR_CPU1_CP43 @T6G_MB_LIB.T6G(SCH_1):PVDDCR_CPU1_P0
CP44 PVDDCR_CPU1_P0 VDDCR_CPU1_CP44 @T6G_MB_LIB.T6G(SCH_1):PVDDCR_CPU1_P0
CP46 PVDDCR_CPU1_P0 VDDCR_CPU1_CP46 @T6G_MB_LIB.T6G(SCH_1):PVDDCR_CPU1_P0
CP47 PVDDCR_CPU1_P0 VDDCR_CPU1_CP47 @T6G_MB_LIB.T6G(SCH_1):PVDDCR_CPU1_P0
CP49 PVDDCR_CPU1_P0 VDDCR_CPU1_CP49 @T6G_MB_LIB.T6G(SCH_1):PVDDCR_CPU1_P0
CP50 PVDDCR_CPU1_P0 VDDCR_CPU1_CP50 @T6G_MB_LIB.T6G(SCH_1):PVDDCR_CPU1_P0
CP52 PVDDCR_CPU1_P0 VDDCR_CPU1_CP52 @T6G_MB_LIB.T6G(SCH_1):PVDDCR_CPU1_P0
CP53 PVDDCR_CPU1_P0 VDDCR_CPU1_CP53 @T6G_MB_LIB.T6G(SCH_1):PVDDCR_CPU1_P0
CU35 PVDDCR_CPU1_P0 VDDCR_CPU1_CU35 @T6G_MB_LIB.T6G(SCH_1):PVDDCR_CPU1_P0
CU36 PVDDCR_CPU1_P0 VDDCR_CPU1_CU36 @T6G_MB_LIB.T6G(SCH_1):PVDDCR_CPU1_P0
CU40 PVDDCR_CPU1_P0 VDDCR_CPU1_CU40 @T6G_MB_LIB.T6G(SCH_1):PVDDCR_CPU1_P0
CU41 PVDDCR_CPU1_P0 VDDCR_CPU1_CU41 @T6G_MB_LIB.T6G(SCH_1):PVDDCR_CPU1_P0
CV23 PVDDCR_CPU1_P0 VDDCR_CPU1_CV23 @T6G_MB_LIB.T6G(SCH_1):PVDDCR_CPU1_P0
CV24 PVDDCR_CPU1_P0 VDDCR_CPU1_CV24 @T6G_MB_LIB.T6G(SCH_1):PVDDCR_CPU1_P0
CV26 PVDDCR_CPU1_P0 VDDCR_CPU1_CV26 @T6G_MB_LIB.T6G(SCH_1):PVDDCR_CPU1_P0
CV27 PVDDCR_CPU1_P0 VDDCR_CPU1_CV27 @T6G_MB_LIB.T6G(SCH_1):PVDDCR_CPU1_P0
CV29 PVDDCR_CPU1_P0 VDDCR_CPU1_CV29 @T6G_MB_LIB.T6G(SCH_1):PVDDCR_CPU1_P0
CV30 PVDDCR_CPU1_P0 VDDCR_CPU1_CV30 @T6G_MB_LIB.T6G(SCH_1):PVDDCR_CPU1_P0
CV32 PVDDCR_CPU1_P0 VDDCR_CPU1_CV32 @T6G_MB_LIB.T6G(SCH_1):PVDDCR_CPU1_P0
CV33 PVDDCR_CPU1_P0 VDDCR_CPU1_CV33 @T6G_MB_LIB.T6G(SCH_1):PVDDCR_CPU1_P0
CV43 PVDDCR_CPU1_P0 VDDCR_CPU1_CV43 @T6G_MB_LIB.T6G(SCH_1):PVDDCR_CPU1_P0
CV44 PVDDCR_CPU1_P0 VDDCR_CPU1_CV44 @T6G_MB_LIB.T6G(SCH_1):PVDDCR_CPU1_P0
CV46 PVDDCR_CPU1_P0 VDDCR_CPU1_CV46 @T6G_MB_LIB.T6G(SCH_1):PVDDCR_CPU1_P0
CV47 PVDDCR_CPU1_P0 VDDCR_CPU1_CV47 @T6G_MB_LIB.T6G(SCH_1):PVDDCR_CPU1_P0
CV49 PVDDCR_CPU1_P0 VDDCR_CPU1_CV49 @T6G_MB_LIB.T6G(SCH_1):PVDDCR_CPU1_P0
CV50 PVDDCR_CPU1_P0 VDDCR_CPU1_CV50 @T6G_MB_LIB.T6G(SCH_1):PVDDCR_CPU1_P0
CV52 PVDDCR_CPU1_P0 VDDCR_CPU1_CV52 @T6G_MB_LIB.T6G(SCH_1):PVDDCR_CPU1_P0
CV53 PVDDCR_CPU1_P0 VDDCR_CPU1_CV53 @T6G_MB_LIB.T6G(SCH_1):PVDDCR_CPU1_P0
DA35 PVDDCR_CPU1_P0 VDDCR_CPU1_DA35 @T6G_MB_LIB.T6G(SCH_1):PVDDCR_CPU1_P0
DA36 PVDDCR_CPU1_P0 VDDCR_CPU1_DA36 @T6G_MB_LIB.T6G(SCH_1):PVDDCR_CPU1_P0
DA40 PVDDCR_CPU1_P0 VDDCR_CPU1_DA40 @T6G_MB_LIB.T6G(SCH_1):PVDDCR_CPU1_P0
DA41 PVDDCR_CPU1_P0 VDDCR_CPU1_DA41 @T6G_MB_LIB.T6G(SCH_1):PVDDCR_CPU1_P0
DB23 PVDDCR_CPU1_P0 VDDCR_CPU1_DB23 @T6G_MB_LIB.T6G(SCH_1):PVDDCR_CPU1_P0
DB24 PVDDCR_CPU1_P0 VDDCR_CPU1_DB24 @T6G_MB_LIB.T6G(SCH_1):PVDDCR_CPU1_P0
DB26 PVDDCR_CPU1_P0 VDDCR_CPU1_DB26 @T6G_MB_LIB.T6G(SCH_1):PVDDCR_CPU1_P0
DB27 PVDDCR_CPU1_P0 VDDCR_CPU1_DB27 @T6G_MB_LIB.T6G(SCH_1):PVDDCR_CPU1_P0
DB29 PVDDCR_CPU1_P0 VDDCR_CPU1_DB29 @T6G_MB_LIB.T6G(SCH_1):PVDDCR_CPU1_P0
DB30 PVDDCR_CPU1_P0 VDDCR_CPU1_DB30 @T6G_MB_LIB.T6G(SCH_1):PVDDCR_CPU1_P0
DB32 PVDDCR_CPU1_P0 VDDCR_CPU1_DB32 @T6G_MB_LIB.T6G(SCH_1):PVDDCR_CPU1_P0
DB33 PVDDCR_CPU1_P0 VDDCR_CPU1_DB33 @T6G_MB_LIB.T6G(SCH_1):PVDDCR_CPU1_P0
DB43 PVDDCR_CPU1_P0 VDDCR_CPU1_DB43 @T6G_MB_LIB.T6G(SCH_1):PVDDCR_CPU1_P0
DB44 PVDDCR_CPU1_P0 VDDCR_CPU1_DB44 @T6G_MB_LIB.T6G(SCH_1):PVDDCR_CPU1_P0
DB46 PVDDCR_CPU1_P0 VDDCR_CPU1_DB46 @T6G_MB_LIB.T6G(SCH_1):PVDDCR_CPU1_P0
DB47 PVDDCR_CPU1_P0 VDDCR_CPU1_DB47 @T6G_MB_LIB.T6G(SCH_1):PVDDCR_CPU1_P0
DB49 PVDDCR_CPU1_P0 VDDCR_CPU1_DB49 @T6G_MB_LIB.T6G(SCH_1):PVDDCR_CPU1_P0
DB50 PVDDCR_CPU1_P0 VDDCR_CPU1_DB50 @T6G_MB_LIB.T6G(SCH_1):PVDDCR_CPU1_P0
DB52 PVDDCR_CPU1_P0 VDDCR_CPU1_DB52 @T6G_MB_LIB.T6G(SCH_1):PVDDCR_CPU1_P0
DB53 PVDDCR_CPU1_P0 VDDCR_CPU1_DB53 @T6G_MB_LIB.T6G(SCH_1):PVDDCR_CPU1_P0
DC35 PVDDCR_CPU1_P0 VDDCR_CPU1_DC35 @T6G_MB_LIB.T6G(SCH_1):PVDDCR_CPU1_P0
DC36 PVDDCR_CPU1_P0 VDDCR_CPU1_DC36 @T6G_MB_LIB.T6G(SCH_1):PVDDCR_CPU1_P0
DC40 PVDDCR_CPU1_P0 VDDCR_CPU1_DC40 @T6G_MB_LIB.T6G(SCH_1):PVDDCR_CPU1_P0
DC41 PVDDCR_CPU1_P0 VDDCR_CPU1_DC41 @T6G_MB_LIB.T6G(SCH_1):PVDDCR_CPU1_P0
DD22 PVDDCR_CPU1_P0 VDDCR_CPU1_DD22 @T6G_MB_LIB.T6G(SCH_1):PVDDCR_CPU1_P0
DD25 PVDDCR_CPU1_P0 VDDCR_CPU1_DD25 @T6G_MB_LIB.T6G(SCH_1):PVDDCR_CPU1_P0
DD28 PVDDCR_CPU1_P0 VDDCR_CPU1_DD28 @T6G_MB_LIB.T6G(SCH_1):PVDDCR_CPU1_P0
DD31 PVDDCR_CPU1_P0 VDDCR_CPU1_DD31 @T6G_MB_LIB.T6G(SCH_1):PVDDCR_CPU1_P0
DD34 PVDDCR_CPU1_P0 VDDCR_CPU1_DD34 @T6G_MB_LIB.T6G(SCH_1):PVDDCR_CPU1_P0
DD42 PVDDCR_CPU1_P0 VDDCR_CPU1_DD42 @T6G_MB_LIB.T6G(SCH_1):PVDDCR_CPU1_P0
DD45 PVDDCR_CPU1_P0 VDDCR_CPU1_DD45 @T6G_MB_LIB.T6G(SCH_1):PVDDCR_CPU1_P0
DD48 PVDDCR_CPU1_P0 VDDCR_CPU1_DD48 @T6G_MB_LIB.T6G(SCH_1):PVDDCR_CPU1_P0
DD51 PVDDCR_CPU1_P0 VDDCR_CPU1_DD51 @T6G_MB_LIB.T6G(SCH_1):PVDDCR_CPU1_P0
DD54 PVDDCR_CPU1_P0 VDDCR_CPU1_DD54 @T6G_MB_LIB.T6G(SCH_1):PVDDCR_CPU1_P0
DE22 PVDDCR_CPU1_P0 VDDCR_CPU1_DE22 @T6G_MB_LIB.T6G(SCH_1):PVDDCR_CPU1_P0
DE25 PVDDCR_CPU1_P0 VDDCR_CPU1_DE25 @T6G_MB_LIB.T6G(SCH_1):PVDDCR_CPU1_P0
DE28 PVDDCR_CPU1_P0 VDDCR_CPU1_DE28 @T6G_MB_LIB.T6G(SCH_1):PVDDCR_CPU1_P0
DE31 PVDDCR_CPU1_P0 VDDCR_CPU1_DE31 @T6G_MB_LIB.T6G(SCH_1):PVDDCR_CPU1_P0
DE34 PVDDCR_CPU1_P0 VDDCR_CPU1_DE34 @T6G_MB_LIB.T6G(SCH_1):PVDDCR_CPU1_P0
DE35 PVDDCR_CPU1_P0 VDDCR_CPU1_DE35 @T6G_MB_LIB.T6G(SCH_1):PVDDCR_CPU1_P0
DE41 PVDDCR_CPU1_P0 VDDCR_CPU1_DE41 @T6G_MB_LIB.T6G(SCH_1):PVDDCR_CPU1_P0
DE42 PVDDCR_CPU1_P0 VDDCR_CPU1_DE42 @T6G_MB_LIB.T6G(SCH_1):PVDDCR_CPU1_P0
DE45 PVDDCR_CPU1_P0 VDDCR_CPU1_DE45 @T6G_MB_LIB.T6G(SCH_1):PVDDCR_CPU1_P0
DE48 PVDDCR_CPU1_P0 VDDCR_CPU1_DE48 @T6G_MB_LIB.T6G(SCH_1):PVDDCR_CPU1_P0
DE51 PVDDCR_CPU1_P0 VDDCR_CPU1_DE51 @T6G_MB_LIB.T6G(SCH_1):PVDDCR_CPU1_P0
DE54 PVDDCR_CPU1_P0 VDDCR_CPU1_DE54 @T6G_MB_LIB.T6G(SCH_1):PVDDCR_CPU1_P0
DG19 PVDDCR_CPU1_P0 VDDCR_CPU1_DG19 @T6G_MB_LIB.T6G(SCH_1):PVDDCR_CPU1_P0
DG57 PVDDCR_CPU1_P0 VDDCR_CPU1_DG57 @T6G_MB_LIB.T6G(SCH_1):PVDDCR_CPU1_P0
DH19 PVDDCR_CPU1_P0 VDDCR_CPU1_DH19 @T6G_MB_LIB.T6G(SCH_1):PVDDCR_CPU1_P0
DH20 PVDDCR_CPU1_P0 VDDCR_CPU1_DH20 @T6G_MB_LIB.T6G(SCH_1):PVDDCR_CPU1_P0
DH22 PVDDCR_CPU1_P0 VDDCR_CPU1_DH22 @T6G_MB_LIB.T6G(SCH_1):PVDDCR_CPU1_P0
DH23 PVDDCR_CPU1_P0 VDDCR_CPU1_DH23 @T6G_MB_LIB.T6G(SCH_1):PVDDCR_CPU1_P0
DH25 PVDDCR_CPU1_P0 VDDCR_CPU1_DH25 @T6G_MB_LIB.T6G(SCH_1):PVDDCR_CPU1_P0
DH26 PVDDCR_CPU1_P0 VDDCR_CPU1_DH26 @T6G_MB_LIB.T6G(SCH_1):PVDDCR_CPU1_P0
DH28 PVDDCR_CPU1_P0 VDDCR_CPU1_DH28 @T6G_MB_LIB.T6G(SCH_1):PVDDCR_CPU1_P0
DH29 PVDDCR_CPU1_P0 VDDCR_CPU1_DH29 @T6G_MB_LIB.T6G(SCH_1):PVDDCR_CPU1_P0
DH31 PVDDCR_CPU1_P0 VDDCR_CPU1_DH31 @T6G_MB_LIB.T6G(SCH_1):PVDDCR_CPU1_P0
DH32 PVDDCR_CPU1_P0 VDDCR_CPU1_DH32 @T6G_MB_LIB.T6G(SCH_1):PVDDCR_CPU1_P0
DH34 PVDDCR_CPU1_P0 VDDCR_CPU1_DH34 @T6G_MB_LIB.T6G(SCH_1):PVDDCR_CPU1_P0
DH35 PVDDCR_CPU1_P0 VDDCR_CPU1_DH35 @T6G_MB_LIB.T6G(SCH_1):PVDDCR_CPU1_P0
DH41 PVDDCR_CPU1_P0 VDDCR_CPU1_DH41 @T6G_MB_LIB.T6G(SCH_1):PVDDCR_CPU1_P0
DH42 PVDDCR_CPU1_P0 VDDCR_CPU1_DH42 @T6G_MB_LIB.T6G(SCH_1):PVDDCR_CPU1_P0
DH44 PVDDCR_CPU1_P0 VDDCR_CPU1_DH44 @T6G_MB_LIB.T6G(SCH_1):PVDDCR_CPU1_P0
DH53 PVDDCR_CPU1_P0 VDDCR_CPU1_DH53 @T6G_MB_LIB.T6G(SCH_1):PVDDCR_CPU1_P0
DH54 PVDDCR_CPU1_P0 VDDCR_CPU1_DH54 @T6G_MB_LIB.T6G(SCH_1):PVDDCR_CPU1_P0
DH56 PVDDCR_CPU1_P0 VDDCR_CPU1_DH56 @T6G_MB_LIB.T6G(SCH_1):PVDDCR_CPU1_P0
DH57 PVDDCR_CPU1_P0 VDDCR_CPU1_DH57 @T6G_MB_LIB.T6G(SCH_1):PVDDCR_CPU1_P0
DH45 PVDDCR_CPU1_P0 VDDCR_CPU1_DH45 @T6G_MB_LIB.T6G(SCH_1):PVDDCR_CPU1_P0
DH47 PVDDCR_CPU1_P0 VDDCR_CPU1_DH47 @T6G_MB_LIB.T6G(SCH_1):PVDDCR_CPU1_P0
DH48 PVDDCR_CPU1_P0 VDDCR_CPU1_DH48 @T6G_MB_LIB.T6G(SCH_1):PVDDCR_CPU1_P0
DH50 PVDDCR_CPU1_P0 VDDCR_CPU1_DH50 @T6G_MB_LIB.T6G(SCH_1):PVDDCR_CPU1_P0
DH51 PVDDCR_CPU1_P0 VDDCR_CPU1_DH51 @T6G_MB_LIB.T6G(SCH_1):PVDDCR_CPU1_P0
BP24 PVDDCR_CPU1_P0 VDDCR_CPU1_BP24 @T6G_MB_LIB.T6G(SCH_1):PVDDCR_CPU1_P0
BP28 PVDDCR_CPU1_P0 VDDCR_CPU1_BP28 @T6G_MB_LIB.T6G(SCH_1):PVDDCR_CPU1_P0
BP32 PVDDCR_CPU1_P0 VDDCR_CPU1_BP32 @T6G_MB_LIB.T6G(SCH_1):PVDDCR_CPU1_P0
BN27 PVDDCR_CPU1_P0 VDDCR_CPU1_BN27 @T6G_MB_LIB.T6G(SCH_1):PVDDCR_CPU1_P0
BN35 PVDDCR_CPU1_P0 VDDCR_CPU1_BN35 @T6G_MB_LIB.T6G(SCH_1):PVDDCR_CPU1_P0
BN46 PVDDCR_CPU1_P0 VDDCR_CPU1_BN46 @T6G_MB_LIB.T6G(SCH_1):PVDDCR_CPU1_P0

GENOA_SP5-SOCKET6096_13568-001,SMLF,IO,DGA^6000030  I50  U25
  B5 PVDDCR_SOC_P0 VDDCR_SOC_B5 @T6G_MB_LIB.T6G(SCH_1):PVDDCR_SOC_P0
  C4 PVDDCR_SOC_P0 VDDCR_SOC_C4 @T6G_MB_LIB.T6G(SCH_1):PVDDCR_SOC_P0
  E4 PVDDCR_SOC_P0 VDDCR_SOC_E4 @T6G_MB_LIB.T6G(SCH_1):PVDDCR_SOC_P0
 E11 PVDDCR_SOC_P0 VDDCR_SOC_E11 @T6G_MB_LIB.T6G(SCH_1):PVDDCR_SOC_P0
  H5 PVDDCR_SOC_P0 VDDCR_SOC_H5 @T6G_MB_LIB.T6G(SCH_1):PVDDCR_SOC_P0
 H12 PVDDCR_SOC_P0 VDDCR_SOC_H12 @T6G_MB_LIB.T6G(SCH_1):PVDDCR_SOC_P0
 H19 PVDDCR_SOC_P0 VDDCR_SOC_H19 @T6G_MB_LIB.T6G(SCH_1):PVDDCR_SOC_P0
 K22 PVDDCR_SOC_P0 VDDCR_SOC_K22 @T6G_MB_LIB.T6G(SCH_1):PVDDCR_SOC_P0
  L4 PVDDCR_SOC_P0 VDDCR_SOC_L4 @T6G_MB_LIB.T6G(SCH_1):PVDDCR_SOC_P0
 L11 PVDDCR_SOC_P0 VDDCR_SOC_L11 @T6G_MB_LIB.T6G(SCH_1):PVDDCR_SOC_P0
 L18 PVDDCR_SOC_P0 VDDCR_SOC_L18 @T6G_MB_LIB.T6G(SCH_1):PVDDCR_SOC_P0
  P5 PVDDCR_SOC_P0 VDDCR_SOC_P5 @T6G_MB_LIB.T6G(SCH_1):PVDDCR_SOC_P0
 P12 PVDDCR_SOC_P0 VDDCR_SOC_P12 @T6G_MB_LIB.T6G(SCH_1):PVDDCR_SOC_P0
 P19 PVDDCR_SOC_P0 VDDCR_SOC_P19 @T6G_MB_LIB.T6G(SCH_1):PVDDCR_SOC_P0
 P22 PVDDCR_SOC_P0 VDDCR_SOC_P22 @T6G_MB_LIB.T6G(SCH_1):PVDDCR_SOC_P0
  U4 PVDDCR_SOC_P0 VDDCR_SOC_U4 @T6G_MB_LIB.T6G(SCH_1):PVDDCR_SOC_P0
 U11 PVDDCR_SOC_P0 VDDCR_SOC_U11 @T6G_MB_LIB.T6G(SCH_1):PVDDCR_SOC_P0
 U18 PVDDCR_SOC_P0 VDDCR_SOC_U18 @T6G_MB_LIB.T6G(SCH_1):PVDDCR_SOC_P0
 V22 PVDDCR_SOC_P0 VDDCR_SOC_V22 @T6G_MB_LIB.T6G(SCH_1):PVDDCR_SOC_P0
  Y5 PVDDCR_SOC_P0 VDDCR_SOC_Y5 @T6G_MB_LIB.T6G(SCH_1):PVDDCR_SOC_P0
 Y12 PVDDCR_SOC_P0 VDDCR_SOC_Y12 @T6G_MB_LIB.T6G(SCH_1):PVDDCR_SOC_P0
 Y19 PVDDCR_SOC_P0 VDDCR_SOC_Y19 @T6G_MB_LIB.T6G(SCH_1):PVDDCR_SOC_P0
AA22 PVDDCR_SOC_P0 VDDCR_SOC_AA22 @T6G_MB_LIB.T6G(SCH_1):PVDDCR_SOC_P0
 AC4 PVDDCR_SOC_P0 VDDCR_SOC_AC4 @T6G_MB_LIB.T6G(SCH_1):PVDDCR_SOC_P0
AC11 PVDDCR_SOC_P0 VDDCR_SOC_AC11 @T6G_MB_LIB.T6G(SCH_1):PVDDCR_SOC_P0
AC18 PVDDCR_SOC_P0 VDDCR_SOC_AC18 @T6G_MB_LIB.T6G(SCH_1):PVDDCR_SOC_P0
AD22 PVDDCR_SOC_P0 VDDCR_SOC_AD22 @T6G_MB_LIB.T6G(SCH_1):PVDDCR_SOC_P0
 AF5 PVDDCR_SOC_P0 VDDCR_SOC_AF5 @T6G_MB_LIB.T6G(SCH_1):PVDDCR_SOC_P0
AF12 PVDDCR_SOC_P0 VDDCR_SOC_AF12 @T6G_MB_LIB.T6G(SCH_1):PVDDCR_SOC_P0
AF19 PVDDCR_SOC_P0 VDDCR_SOC_AF19 @T6G_MB_LIB.T6G(SCH_1):PVDDCR_SOC_P0
AH22 PVDDCR_SOC_P0 VDDCR_SOC_AH22 @T6G_MB_LIB.T6G(SCH_1):PVDDCR_SOC_P0
 AJ4 PVDDCR_SOC_P0 VDDCR_SOC_AJ4 @T6G_MB_LIB.T6G(SCH_1):PVDDCR_SOC_P0
AJ11 PVDDCR_SOC_P0 VDDCR_SOC_AJ11 @T6G_MB_LIB.T6G(SCH_1):PVDDCR_SOC_P0
AJ18 PVDDCR_SOC_P0 VDDCR_SOC_AJ18 @T6G_MB_LIB.T6G(SCH_1):PVDDCR_SOC_P0
 AM5 PVDDCR_SOC_P0 VDDCR_SOC_AM5 @T6G_MB_LIB.T6G(SCH_1):PVDDCR_SOC_P0
AM12 PVDDCR_SOC_P0 VDDCR_SOC_AM12 @T6G_MB_LIB.T6G(SCH_1):PVDDCR_SOC_P0
AM19 PVDDCR_SOC_P0 VDDCR_SOC_AM19 @T6G_MB_LIB.T6G(SCH_1):PVDDCR_SOC_P0
AM22 PVDDCR_SOC_P0 VDDCR_SOC_AM22 @T6G_MB_LIB.T6G(SCH_1):PVDDCR_SOC_P0
 AR4 PVDDCR_SOC_P0 VDDCR_SOC_AR4 @T6G_MB_LIB.T6G(SCH_1):PVDDCR_SOC_P0
AR11 PVDDCR_SOC_P0 VDDCR_SOC_AR11 @T6G_MB_LIB.T6G(SCH_1):PVDDCR_SOC_P0
AR18 PVDDCR_SOC_P0 VDDCR_SOC_AR18 @T6G_MB_LIB.T6G(SCH_1):PVDDCR_SOC_P0
AT22 PVDDCR_SOC_P0 VDDCR_SOC_AT22 @T6G_MB_LIB.T6G(SCH_1):PVDDCR_SOC_P0
AU23 PVDDCR_SOC_P0 VDDCR_SOC_AU23 @T6G_MB_LIB.T6G(SCH_1):PVDDCR_SOC_P0
AU27 PVDDCR_SOC_P0 VDDCR_SOC_AU27 @T6G_MB_LIB.T6G(SCH_1):PVDDCR_SOC_P0
AU31 PVDDCR_SOC_P0 VDDCR_SOC_AU31 @T6G_MB_LIB.T6G(SCH_1):PVDDCR_SOC_P0
AU35 PVDDCR_SOC_P0 VDDCR_SOC_AU35 @T6G_MB_LIB.T6G(SCH_1):PVDDCR_SOC_P0
AU40 PVDDCR_SOC_P0 VDDCR_SOC_AU40 @T6G_MB_LIB.T6G(SCH_1):PVDDCR_SOC_P0
 AV5 PVDDCR_SOC_P0 VDDCR_SOC_AV5 @T6G_MB_LIB.T6G(SCH_1):PVDDCR_SOC_P0
AV12 PVDDCR_SOC_P0 VDDCR_SOC_AV12 @T6G_MB_LIB.T6G(SCH_1):PVDDCR_SOC_P0
AV19 PVDDCR_SOC_P0 VDDCR_SOC_AV19 @T6G_MB_LIB.T6G(SCH_1):PVDDCR_SOC_P0
AV22 PVDDCR_SOC_P0 VDDCR_SOC_AV22 @T6G_MB_LIB.T6G(SCH_1):PVDDCR_SOC_P0
AV24 PVDDCR_SOC_P0 VDDCR_SOC_AV24 @T6G_MB_LIB.T6G(SCH_1):PVDDCR_SOC_P0
AV26 PVDDCR_SOC_P0 VDDCR_SOC_AV26 @T6G_MB_LIB.T6G(SCH_1):PVDDCR_SOC_P0
AV28 PVDDCR_SOC_P0 VDDCR_SOC_AV28 @T6G_MB_LIB.T6G(SCH_1):PVDDCR_SOC_P0
AV30 PVDDCR_SOC_P0 VDDCR_SOC_AV30 @T6G_MB_LIB.T6G(SCH_1):PVDDCR_SOC_P0
AV32 PVDDCR_SOC_P0 VDDCR_SOC_AV32 @T6G_MB_LIB.T6G(SCH_1):PVDDCR_SOC_P0
AV34 PVDDCR_SOC_P0 VDDCR_SOC_AV34 @T6G_MB_LIB.T6G(SCH_1):PVDDCR_SOC_P0
AV36 PVDDCR_SOC_P0 VDDCR_SOC_AV36 @T6G_MB_LIB.T6G(SCH_1):PVDDCR_SOC_P0
AV39 PVDDCR_SOC_P0 VDDCR_SOC_AV39 @T6G_MB_LIB.T6G(SCH_1):PVDDCR_SOC_P0
AV41 PVDDCR_SOC_P0 VDDCR_SOC_AV41 @T6G_MB_LIB.T6G(SCH_1):PVDDCR_SOC_P0
AV43 PVDDCR_SOC_P0 VDDCR_SOC_AV43 @T6G_MB_LIB.T6G(SCH_1):PVDDCR_SOC_P0
AV45 PVDDCR_SOC_P0 VDDCR_SOC_AV45 @T6G_MB_LIB.T6G(SCH_1):PVDDCR_SOC_P0
AV47 PVDDCR_SOC_P0 VDDCR_SOC_AV47 @T6G_MB_LIB.T6G(SCH_1):PVDDCR_SOC_P0
AW23 PVDDCR_SOC_P0 VDDCR_SOC_AW23 @T6G_MB_LIB.T6G(SCH_1):PVDDCR_SOC_P0
AW25 PVDDCR_SOC_P0 VDDCR_SOC_AW25 @T6G_MB_LIB.T6G(SCH_1):PVDDCR_SOC_P0
AW27 PVDDCR_SOC_P0 VDDCR_SOC_AW27 @T6G_MB_LIB.T6G(SCH_1):PVDDCR_SOC_P0
AW48 PVDDCR_SOC_P0 VDDCR_SOC_AW48 @T6G_MB_LIB.T6G(SCH_1):PVDDCR_SOC_P0
AY22 PVDDCR_SOC_P0 VDDCR_SOC_AY22 @T6G_MB_LIB.T6G(SCH_1):PVDDCR_SOC_P0
AY24 PVDDCR_SOC_P0 VDDCR_SOC_AY24 @T6G_MB_LIB.T6G(SCH_1):PVDDCR_SOC_P0
AY26 PVDDCR_SOC_P0 VDDCR_SOC_AY26 @T6G_MB_LIB.T6G(SCH_1):PVDDCR_SOC_P0
AY28 PVDDCR_SOC_P0 VDDCR_SOC_AY28 @T6G_MB_LIB.T6G(SCH_1):PVDDCR_SOC_P0
AY49 PVDDCR_SOC_P0 VDDCR_SOC_AY49 @T6G_MB_LIB.T6G(SCH_1):PVDDCR_SOC_P0
 BA4 PVDDCR_SOC_P0 VDDCR_SOC_BA4 @T6G_MB_LIB.T6G(SCH_1):PVDDCR_SOC_P0
BA11 PVDDCR_SOC_P0 VDDCR_SOC_BA11 @T6G_MB_LIB.T6G(SCH_1):PVDDCR_SOC_P0
BA18 PVDDCR_SOC_P0 VDDCR_SOC_BA18 @T6G_MB_LIB.T6G(SCH_1):PVDDCR_SOC_P0
BA23 PVDDCR_SOC_P0 VDDCR_SOC_BA23 @T6G_MB_LIB.T6G(SCH_1):PVDDCR_SOC_P0
BA25 PVDDCR_SOC_P0 VDDCR_SOC_BA25 @T6G_MB_LIB.T6G(SCH_1):PVDDCR_SOC_P0
BA27 PVDDCR_SOC_P0 VDDCR_SOC_BA27 @T6G_MB_LIB.T6G(SCH_1):PVDDCR_SOC_P0
BA48 PVDDCR_SOC_P0 VDDCR_SOC_BA48 @T6G_MB_LIB.T6G(SCH_1):PVDDCR_SOC_P0
BB22 PVDDCR_SOC_P0 VDDCR_SOC_BB22 @T6G_MB_LIB.T6G(SCH_1):PVDDCR_SOC_P0
BB24 PVDDCR_SOC_P0 VDDCR_SOC_BB24 @T6G_MB_LIB.T6G(SCH_1):PVDDCR_SOC_P0
BB26 PVDDCR_SOC_P0 VDDCR_SOC_BB26 @T6G_MB_LIB.T6G(SCH_1):PVDDCR_SOC_P0
BB28 PVDDCR_SOC_P0 VDDCR_SOC_BB28 @T6G_MB_LIB.T6G(SCH_1):PVDDCR_SOC_P0
BB49 PVDDCR_SOC_P0 VDDCR_SOC_BB49 @T6G_MB_LIB.T6G(SCH_1):PVDDCR_SOC_P0
BC23 PVDDCR_SOC_P0 VDDCR_SOC_BC23 @T6G_MB_LIB.T6G(SCH_1):PVDDCR_SOC_P0
BC25 PVDDCR_SOC_P0 VDDCR_SOC_BC25 @T6G_MB_LIB.T6G(SCH_1):PVDDCR_SOC_P0
BC27 PVDDCR_SOC_P0 VDDCR_SOC_BC27 @T6G_MB_LIB.T6G(SCH_1):PVDDCR_SOC_P0
BC48 PVDDCR_SOC_P0 VDDCR_SOC_BC48 @T6G_MB_LIB.T6G(SCH_1):PVDDCR_SOC_P0
 BD5 PVDDCR_SOC_P0 VDDCR_SOC_BD5 @T6G_MB_LIB.T6G(SCH_1):PVDDCR_SOC_P0
BD12 PVDDCR_SOC_P0 VDDCR_SOC_BD12 @T6G_MB_LIB.T6G(SCH_1):PVDDCR_SOC_P0
BD19 PVDDCR_SOC_P0 VDDCR_SOC_BD19 @T6G_MB_LIB.T6G(SCH_1):PVDDCR_SOC_P0
BD22 PVDDCR_SOC_P0 VDDCR_SOC_BD22 @T6G_MB_LIB.T6G(SCH_1):PVDDCR_SOC_P0
BD24 PVDDCR_SOC_P0 VDDCR_SOC_BD24 @T6G_MB_LIB.T6G(SCH_1):PVDDCR_SOC_P0
BD26 PVDDCR_SOC_P0 VDDCR_SOC_BD26 @T6G_MB_LIB.T6G(SCH_1):PVDDCR_SOC_P0
BD28 PVDDCR_SOC_P0 VDDCR_SOC_BD28 @T6G_MB_LIB.T6G(SCH_1):PVDDCR_SOC_P0
BD48 PVDDCR_SOC_P0 VDDCR_SOC_BD48 @T6G_MB_LIB.T6G(SCH_1):PVDDCR_SOC_P0
BF23 PVDDCR_SOC_P0 VDDCR_SOC_BF23 @T6G_MB_LIB.T6G(SCH_1):PVDDCR_SOC_P0
BF25 PVDDCR_SOC_P0 VDDCR_SOC_BF25 @T6G_MB_LIB.T6G(SCH_1):PVDDCR_SOC_P0
BF27 PVDDCR_SOC_P0 VDDCR_SOC_BF27 @T6G_MB_LIB.T6G(SCH_1):PVDDCR_SOC_P0
BF48 PVDDCR_SOC_P0 VDDCR_SOC_BF48 @T6G_MB_LIB.T6G(SCH_1):PVDDCR_SOC_P0
 BM5 PVDDCR_SOC_P0 VDDCR_SOC_BM5 @T6G_MB_LIB.T6G(SCH_1):PVDDCR_SOC_P0
BJ48 PVDDCR_SOC_P0 VDDCR_SOC_BJ48 @T6G_MB_LIB.T6G(SCH_1):PVDDCR_SOC_P0
BJ11 PVDDCR_SOC_P0 VDDCR_SOC_BJ11 @T6G_MB_LIB.T6G(SCH_1):PVDDCR_SOC_P0
 BJ4 PVDDCR_SOC_P0 VDDCR_SOC_BJ4 @T6G_MB_LIB.T6G(SCH_1):PVDDCR_SOC_P0
BH48 PVDDCR_SOC_P0 VDDCR_SOC_BH48 @T6G_MB_LIB.T6G(SCH_1):PVDDCR_SOC_P0
BH25 PVDDCR_SOC_P0 VDDCR_SOC_BH25 @T6G_MB_LIB.T6G(SCH_1):PVDDCR_SOC_P0
BH23 PVDDCR_SOC_P0 VDDCR_SOC_BH23 @T6G_MB_LIB.T6G(SCH_1):PVDDCR_SOC_P0
BG48 PVDDCR_SOC_P0 VDDCR_SOC_BG48 @T6G_MB_LIB.T6G(SCH_1):PVDDCR_SOC_P0
BG28 PVDDCR_SOC_P0 VDDCR_SOC_BG28 @T6G_MB_LIB.T6G(SCH_1):PVDDCR_SOC_P0
BG26 PVDDCR_SOC_P0 VDDCR_SOC_BG26 @T6G_MB_LIB.T6G(SCH_1):PVDDCR_SOC_P0
BG24 PVDDCR_SOC_P0 VDDCR_SOC_BG24 @T6G_MB_LIB.T6G(SCH_1):PVDDCR_SOC_P0
BG22 PVDDCR_SOC_P0 VDDCR_SOC_BG22 @T6G_MB_LIB.T6G(SCH_1):PVDDCR_SOC_P0


DRAWING: @T6G_MB_LIB.T6G(SCH_1):PAGE31 

GENOA_SP5-SOCKET6096_13568-001,SMLF,IO,DGA^6000030  I19  U25
 H37    GND VSS_H37 @T6G_MB_LIB.T6G(SCH_1):GND
 H39    GND VSS_H39 @T6G_MB_LIB.T6G(SCH_1):GND
 H42    GND VSS_H42 @T6G_MB_LIB.T6G(SCH_1):GND
 H45    GND VSS_H45 @T6G_MB_LIB.T6G(SCH_1):GND
 H48    GND VSS_H48 @T6G_MB_LIB.T6G(SCH_1):GND
 H51    GND VSS_H51 @T6G_MB_LIB.T6G(SCH_1):GND
 H54    GND VSS_H54 @T6G_MB_LIB.T6G(SCH_1):GND
 H59    GND VSS_H59 @T6G_MB_LIB.T6G(SCH_1):GND
 H61    GND VSS_H61 @T6G_MB_LIB.T6G(SCH_1):GND
 H66    GND VSS_H66 @T6G_MB_LIB.T6G(SCH_1):GND
 H68    GND VSS_H68 @T6G_MB_LIB.T6G(SCH_1):GND
 H73    GND VSS_H73 @T6G_MB_LIB.T6G(SCH_1):GND
  J1    GND VSS_J1 @T6G_MB_LIB.T6G(SCH_1):GND
  J4    GND VSS_J4 @T6G_MB_LIB.T6G(SCH_1):GND
  J6    GND VSS_J6 @T6G_MB_LIB.T6G(SCH_1):GND
  J8    GND VSS_J8 @T6G_MB_LIB.T6G(SCH_1):GND
 J11    GND VSS_J11 @T6G_MB_LIB.T6G(SCH_1):GND
 J13    GND VSS_J13 @T6G_MB_LIB.T6G(SCH_1):GND
  A3    GND VSS_A3 @T6G_MB_LIB.T6G(SCH_1):GND
  A9    GND VSS_A9 @T6G_MB_LIB.T6G(SCH_1):GND
 A15    GND VSS_A15 @T6G_MB_LIB.T6G(SCH_1):GND
 A21    GND VSS_A21 @T6G_MB_LIB.T6G(SCH_1):GND
 A27    GND VSS_A27 @T6G_MB_LIB.T6G(SCH_1):GND
 A43    GND VSS_A43 @T6G_MB_LIB.T6G(SCH_1):GND
 A44    GND VSS_A44 @T6G_MB_LIB.T6G(SCH_1):GND
 A47    GND VSS_A47 @T6G_MB_LIB.T6G(SCH_1):GND
 A49    GND VSS_A49 @T6G_MB_LIB.T6G(SCH_1):GND
 A53    GND VSS_A53 @T6G_MB_LIB.T6G(SCH_1):GND
 A61    GND VSS_A61 @T6G_MB_LIB.T6G(SCH_1):GND
 A67    GND VSS_A67 @T6G_MB_LIB.T6G(SCH_1):GND
 A72    GND VSS_A72 @T6G_MB_LIB.T6G(SCH_1):GND
 A73    GND VSS_A73 @T6G_MB_LIB.T6G(SCH_1):GND
  B7    GND VSS_B7 @T6G_MB_LIB.T6G(SCH_1):GND
  B8    GND VSS_B8 @T6G_MB_LIB.T6G(SCH_1):GND
 B10    GND VSS_B10 @T6G_MB_LIB.T6G(SCH_1):GND
 B11    GND VSS_B11 @T6G_MB_LIB.T6G(SCH_1):GND
 B13    GND VSS_B13 @T6G_MB_LIB.T6G(SCH_1):GND
 B18    GND VSS_B18 @T6G_MB_LIB.T6G(SCH_1):GND
 B24    GND VSS_B24 @T6G_MB_LIB.T6G(SCH_1):GND
 B27    GND VSS_B27 @T6G_MB_LIB.T6G(SCH_1):GND
 B30    GND VSS_B30 @T6G_MB_LIB.T6G(SCH_1):GND
 B33    GND VSS_B33 @T6G_MB_LIB.T6G(SCH_1):GND
 B37    GND VSS_B37 @T6G_MB_LIB.T6G(SCH_1):GND
 B39    GND VSS_B39 @T6G_MB_LIB.T6G(SCH_1):GND
 B43    GND VSS_B43 @T6G_MB_LIB.T6G(SCH_1):GND
 B46    GND VSS_B46 @T6G_MB_LIB.T6G(SCH_1):GND
 B49    GND VSS_B49 @T6G_MB_LIB.T6G(SCH_1):GND
 B52    GND VSS_B52 @T6G_MB_LIB.T6G(SCH_1):GND
 B55    GND VSS_B55 @T6G_MB_LIB.T6G(SCH_1):GND
 B59    GND VSS_B59 @T6G_MB_LIB.T6G(SCH_1):GND
 B62    GND VSS_B62 @T6G_MB_LIB.T6G(SCH_1):GND
 B65    GND VSS_B65 @T6G_MB_LIB.T6G(SCH_1):GND
 B68    GND VSS_B68 @T6G_MB_LIB.T6G(SCH_1):GND
 B70    GND VSS_B70 @T6G_MB_LIB.T6G(SCH_1):GND
  C1    GND VSS_C1 @T6G_MB_LIB.T6G(SCH_1):GND
  C5    GND VSS_C5 @T6G_MB_LIB.T6G(SCH_1):GND
  C8    GND VSS_C8 @T6G_MB_LIB.T6G(SCH_1):GND
 C10    GND VSS_C10 @T6G_MB_LIB.T6G(SCH_1):GND
 C11    GND VSS_C11 @T6G_MB_LIB.T6G(SCH_1):GND
 C13    GND VSS_C13 @T6G_MB_LIB.T6G(SCH_1):GND
 C15    GND VSS_C15 @T6G_MB_LIB.T6G(SCH_1):GND
 C21    GND VSS_C21 @T6G_MB_LIB.T6G(SCH_1):GND
 C24    GND VSS_C24 @T6G_MB_LIB.T6G(SCH_1):GND
 C27    GND VSS_C27 @T6G_MB_LIB.T6G(SCH_1):GND
 C30    GND VSS_C30 @T6G_MB_LIB.T6G(SCH_1):GND
 C36    GND VSS_C36 @T6G_MB_LIB.T6G(SCH_1):GND
 C40    GND VSS_C40 @T6G_MB_LIB.T6G(SCH_1):GND
 C43    GND VSS_C43 @T6G_MB_LIB.T6G(SCH_1):GND
 C46    GND VSS_C46 @T6G_MB_LIB.T6G(SCH_1):GND
 C49    GND VSS_C49 @T6G_MB_LIB.T6G(SCH_1):GND
 C52    GND VSS_C52 @T6G_MB_LIB.T6G(SCH_1):GND
 C55    GND VSS_C55 @T6G_MB_LIB.T6G(SCH_1):GND
 C56    GND VSS_C56 @T6G_MB_LIB.T6G(SCH_1):GND
 C57    GND VSS_C57 @T6G_MB_LIB.T6G(SCH_1):GND
 C61    GND VSS_C61 @T6G_MB_LIB.T6G(SCH_1):GND
 C64    GND VSS_C64 @T6G_MB_LIB.T6G(SCH_1):GND
 C67    GND VSS_C67 @T6G_MB_LIB.T6G(SCH_1):GND
 C69    GND VSS_C69 @T6G_MB_LIB.T6G(SCH_1):GND
 C71    GND VSS_C71 @T6G_MB_LIB.T6G(SCH_1):GND
 C73    GND VSS_C73 @T6G_MB_LIB.T6G(SCH_1):GND
 C75    GND VSS_C75 @T6G_MB_LIB.T6G(SCH_1):GND
  D2    GND VSS_D2 @T6G_MB_LIB.T6G(SCH_1):GND
  D3    GND VSS_D3 @T6G_MB_LIB.T6G(SCH_1):GND
  D5    GND VSS_D5 @T6G_MB_LIB.T6G(SCH_1):GND
  D6    GND VSS_D6 @T6G_MB_LIB.T6G(SCH_1):GND
  D9    GND VSS_D9 @T6G_MB_LIB.T6G(SCH_1):GND
 D10    GND VSS_D10 @T6G_MB_LIB.T6G(SCH_1):GND
 D12    GND VSS_D12 @T6G_MB_LIB.T6G(SCH_1):GND
 D13    GND VSS_D13 @T6G_MB_LIB.T6G(SCH_1):GND
 D16    GND VSS_D16 @T6G_MB_LIB.T6G(SCH_1):GND
 D17    GND VSS_D17 @T6G_MB_LIB.T6G(SCH_1):GND
 D19    GND VSS_D19 @T6G_MB_LIB.T6G(SCH_1):GND
 D20    GND VSS_D20 @T6G_MB_LIB.T6G(SCH_1):GND
 D21    GND VSS_D21 @T6G_MB_LIB.T6G(SCH_1):GND
 D24    GND VSS_D24 @T6G_MB_LIB.T6G(SCH_1):GND
 D25    GND VSS_D25 @T6G_MB_LIB.T6G(SCH_1):GND
 D26    GND VSS_D26 @T6G_MB_LIB.T6G(SCH_1):GND
 D27    GND VSS_D27 @T6G_MB_LIB.T6G(SCH_1):GND
 D28    GND VSS_D28 @T6G_MB_LIB.T6G(SCH_1):GND
 D29    GND VSS_D29 @T6G_MB_LIB.T6G(SCH_1):GND
 D30    GND VSS_D30 @T6G_MB_LIB.T6G(SCH_1):GND
 D31    GND VSS_D31 @T6G_MB_LIB.T6G(SCH_1):GND
 D35    GND VSS_D35 @T6G_MB_LIB.T6G(SCH_1):GND
 D37    GND VSS_D37 @T6G_MB_LIB.T6G(SCH_1):GND
 D39    GND VSS_D39 @T6G_MB_LIB.T6G(SCH_1):GND
 D40    GND VSS_D40 @T6G_MB_LIB.T6G(SCH_1):GND
 D41    GND VSS_D41 @T6G_MB_LIB.T6G(SCH_1):GND
 D42    GND VSS_D42 @T6G_MB_LIB.T6G(SCH_1):GND
 D43    GND VSS_D43 @T6G_MB_LIB.T6G(SCH_1):GND
 D44    GND VSS_D44 @T6G_MB_LIB.T6G(SCH_1):GND
 D45    GND VSS_D45 @T6G_MB_LIB.T6G(SCH_1):GND
 D46    GND VSS_D46 @T6G_MB_LIB.T6G(SCH_1):GND
 D47    GND VSS_D47 @T6G_MB_LIB.T6G(SCH_1):GND
 D48    GND VSS_D48 @T6G_MB_LIB.T6G(SCH_1):GND
 D49    GND VSS_D49 @T6G_MB_LIB.T6G(SCH_1):GND
 D50    GND VSS_D50 @T6G_MB_LIB.T6G(SCH_1):GND
 D51    GND VSS_D51 @T6G_MB_LIB.T6G(SCH_1):GND
 D52    GND VSS_D52 @T6G_MB_LIB.T6G(SCH_1):GND
 D53    GND VSS_D53 @T6G_MB_LIB.T6G(SCH_1):GND
 D54    GND VSS_D54 @T6G_MB_LIB.T6G(SCH_1):GND
 D57    GND VSS_D57 @T6G_MB_LIB.T6G(SCH_1):GND
 D59    GND VSS_D59 @T6G_MB_LIB.T6G(SCH_1):GND
 D60    GND VSS_D60 @T6G_MB_LIB.T6G(SCH_1):GND
 D61    GND VSS_D61 @T6G_MB_LIB.T6G(SCH_1):GND
 D63    GND VSS_D63 @T6G_MB_LIB.T6G(SCH_1):GND
 D64    GND VSS_D64 @T6G_MB_LIB.T6G(SCH_1):GND
 D66    GND VSS_D66 @T6G_MB_LIB.T6G(SCH_1):GND
 D67    GND VSS_D67 @T6G_MB_LIB.T6G(SCH_1):GND
 D70    GND VSS_D70 @T6G_MB_LIB.T6G(SCH_1):GND
 D71    GND VSS_D71 @T6G_MB_LIB.T6G(SCH_1):GND
 D73    GND VSS_D73 @T6G_MB_LIB.T6G(SCH_1):GND
 D74    GND VSS_D74 @T6G_MB_LIB.T6G(SCH_1):GND
  E1    GND VSS_E1 @T6G_MB_LIB.T6G(SCH_1):GND
  E3    GND VSS_E3 @T6G_MB_LIB.T6G(SCH_1):GND
  E6    GND VSS_E6 @T6G_MB_LIB.T6G(SCH_1):GND
  E7    GND VSS_E7 @T6G_MB_LIB.T6G(SCH_1):GND
  E8    GND VSS_E8 @T6G_MB_LIB.T6G(SCH_1):GND
 E10    GND VSS_E10 @T6G_MB_LIB.T6G(SCH_1):GND
 E13    GND VSS_E13 @T6G_MB_LIB.T6G(SCH_1):GND
 E14    GND VSS_E14 @T6G_MB_LIB.T6G(SCH_1):GND
 E15    GND VSS_E15 @T6G_MB_LIB.T6G(SCH_1):GND
 E17    GND VSS_E17 @T6G_MB_LIB.T6G(SCH_1):GND
 E18    GND VSS_E18 @T6G_MB_LIB.T6G(SCH_1):GND
 E20    GND VSS_E20 @T6G_MB_LIB.T6G(SCH_1):GND
 E21    GND VSS_E21 @T6G_MB_LIB.T6G(SCH_1):GND
 E52    GND VSS_E52 @T6G_MB_LIB.T6G(SCH_1):GND
 E53    GND VSS_E53 @T6G_MB_LIB.T6G(SCH_1):GND
 E55    GND VSS_E55 @T6G_MB_LIB.T6G(SCH_1):GND
 E56    GND VSS_E56 @T6G_MB_LIB.T6G(SCH_1):GND
 E58    GND VSS_E58 @T6G_MB_LIB.T6G(SCH_1):GND
 E59    GND VSS_E59 @T6G_MB_LIB.T6G(SCH_1):GND
 E61    GND VSS_E61 @T6G_MB_LIB.T6G(SCH_1):GND
 E62    GND VSS_E62 @T6G_MB_LIB.T6G(SCH_1):GND
 E63    GND VSS_E63 @T6G_MB_LIB.T6G(SCH_1):GND
 E65    GND VSS_E65 @T6G_MB_LIB.T6G(SCH_1):GND
 E66    GND VSS_E66 @T6G_MB_LIB.T6G(SCH_1):GND
 E68    GND VSS_E68 @T6G_MB_LIB.T6G(SCH_1):GND
 E69    GND VSS_E69 @T6G_MB_LIB.T6G(SCH_1):GND
 E70    GND VSS_E70 @T6G_MB_LIB.T6G(SCH_1):GND
 E72    GND VSS_E72 @T6G_MB_LIB.T6G(SCH_1):GND
 E73    GND VSS_E73 @T6G_MB_LIB.T6G(SCH_1):GND
 E75    GND VSS_E75 @T6G_MB_LIB.T6G(SCH_1):GND
  F3    GND VSS_F3 @T6G_MB_LIB.T6G(SCH_1):GND
  F5    GND VSS_F5 @T6G_MB_LIB.T6G(SCH_1):GND
  F8    GND VSS_F8 @T6G_MB_LIB.T6G(SCH_1):GND
 F10    GND VSS_F10 @T6G_MB_LIB.T6G(SCH_1):GND
 F12    GND VSS_F12 @T6G_MB_LIB.T6G(SCH_1):GND
 F15    GND VSS_F15 @T6G_MB_LIB.T6G(SCH_1):GND
 F17    GND VSS_F17 @T6G_MB_LIB.T6G(SCH_1):GND
 F19    GND VSS_F19 @T6G_MB_LIB.T6G(SCH_1):GND
 F23    GND VSS_F23 @T6G_MB_LIB.T6G(SCH_1):GND
 F24    GND VSS_F24 @T6G_MB_LIB.T6G(SCH_1):GND
 F26    GND VSS_F26 @T6G_MB_LIB.T6G(SCH_1):GND
 F27    GND VSS_F27 @T6G_MB_LIB.T6G(SCH_1):GND
 F29    GND VSS_F29 @T6G_MB_LIB.T6G(SCH_1):GND
 F30    GND VSS_F30 @T6G_MB_LIB.T6G(SCH_1):GND
 F32    GND VSS_F32 @T6G_MB_LIB.T6G(SCH_1):GND
 F33    GND VSS_F33 @T6G_MB_LIB.T6G(SCH_1):GND
 F35    GND VSS_F35 @T6G_MB_LIB.T6G(SCH_1):GND
 F36    GND VSS_F36 @T6G_MB_LIB.T6G(SCH_1):GND
 F37    GND VSS_F37 @T6G_MB_LIB.T6G(SCH_1):GND
 F39    GND VSS_F39 @T6G_MB_LIB.T6G(SCH_1):GND
 F40    GND VSS_F40 @T6G_MB_LIB.T6G(SCH_1):GND
 F41    GND VSS_F41 @T6G_MB_LIB.T6G(SCH_1):GND
 F43    GND VSS_F43 @T6G_MB_LIB.T6G(SCH_1):GND
 F44    GND VSS_F44 @T6G_MB_LIB.T6G(SCH_1):GND
 F46    GND VSS_F46 @T6G_MB_LIB.T6G(SCH_1):GND
 F47    GND VSS_F47 @T6G_MB_LIB.T6G(SCH_1):GND
 F49    GND VSS_F49 @T6G_MB_LIB.T6G(SCH_1):GND
 F50    GND VSS_F50 @T6G_MB_LIB.T6G(SCH_1):GND
 F52    GND VSS_F52 @T6G_MB_LIB.T6G(SCH_1):GND
 F53    GND VSS_F53 @T6G_MB_LIB.T6G(SCH_1):GND
 F57    GND VSS_F57 @T6G_MB_LIB.T6G(SCH_1):GND
 F59    GND VSS_F59 @T6G_MB_LIB.T6G(SCH_1):GND
 F61    GND VSS_F61 @T6G_MB_LIB.T6G(SCH_1):GND
 F64    GND VSS_F64 @T6G_MB_LIB.T6G(SCH_1):GND
 F66    GND VSS_F66 @T6G_MB_LIB.T6G(SCH_1):GND
 F68    GND VSS_F68 @T6G_MB_LIB.T6G(SCH_1):GND
 F71    GND VSS_F71 @T6G_MB_LIB.T6G(SCH_1):GND
 F73    GND VSS_F73 @T6G_MB_LIB.T6G(SCH_1):GND
  G1    GND VSS_G1 @T6G_MB_LIB.T6G(SCH_1):GND
  G4    GND VSS_G4 @T6G_MB_LIB.T6G(SCH_1):GND
  G6    GND VSS_G6 @T6G_MB_LIB.T6G(SCH_1):GND
  G8    GND VSS_G8 @T6G_MB_LIB.T6G(SCH_1):GND
 G11    GND VSS_G11 @T6G_MB_LIB.T6G(SCH_1):GND
 G13    GND VSS_G13 @T6G_MB_LIB.T6G(SCH_1):GND
 G15    GND VSS_G15 @T6G_MB_LIB.T6G(SCH_1):GND
 G18    GND VSS_G18 @T6G_MB_LIB.T6G(SCH_1):GND
 G20    GND VSS_G20 @T6G_MB_LIB.T6G(SCH_1):GND
 G22    GND VSS_G22 @T6G_MB_LIB.T6G(SCH_1):GND
 G25    GND VSS_G25 @T6G_MB_LIB.T6G(SCH_1):GND
 G28    GND VSS_G28 @T6G_MB_LIB.T6G(SCH_1):GND
 G31    GND VSS_G31 @T6G_MB_LIB.T6G(SCH_1):GND
 G34    GND VSS_G34 @T6G_MB_LIB.T6G(SCH_1):GND
 G42    GND VSS_G42 @T6G_MB_LIB.T6G(SCH_1):GND
 G45    GND VSS_G45 @T6G_MB_LIB.T6G(SCH_1):GND
 G48    GND VSS_G48 @T6G_MB_LIB.T6G(SCH_1):GND
 G51    GND VSS_G51 @T6G_MB_LIB.T6G(SCH_1):GND
 G54    GND VSS_G54 @T6G_MB_LIB.T6G(SCH_1):GND
 G56    GND VSS_G56 @T6G_MB_LIB.T6G(SCH_1):GND
 G58    GND VSS_G58 @T6G_MB_LIB.T6G(SCH_1):GND
 G61    GND VSS_G61 @T6G_MB_LIB.T6G(SCH_1):GND
 G63    GND VSS_G63 @T6G_MB_LIB.T6G(SCH_1):GND
 G65    GND VSS_G65 @T6G_MB_LIB.T6G(SCH_1):GND
 G68    GND VSS_G68 @T6G_MB_LIB.T6G(SCH_1):GND
 G70    GND VSS_G70 @T6G_MB_LIB.T6G(SCH_1):GND
 G72    GND VSS_G72 @T6G_MB_LIB.T6G(SCH_1):GND
 G75    GND VSS_G75 @T6G_MB_LIB.T6G(SCH_1):GND
  H3    GND VSS_H3 @T6G_MB_LIB.T6G(SCH_1):GND
  H8    GND VSS_H8 @T6G_MB_LIB.T6G(SCH_1):GND
 H10    GND VSS_H10 @T6G_MB_LIB.T6G(SCH_1):GND
 H15    GND VSS_H15 @T6G_MB_LIB.T6G(SCH_1):GND
 H17    GND VSS_H17 @T6G_MB_LIB.T6G(SCH_1):GND
 H22    GND VSS_H22 @T6G_MB_LIB.T6G(SCH_1):GND
 H25    GND VSS_H25 @T6G_MB_LIB.T6G(SCH_1):GND
 H28    GND VSS_H28 @T6G_MB_LIB.T6G(SCH_1):GND
 H31    GND VSS_H31 @T6G_MB_LIB.T6G(SCH_1):GND
 H34    GND VSS_H34 @T6G_MB_LIB.T6G(SCH_1):GND

GENOA_SP5-SOCKET6096_13568-001,SMLF,IO,DGA^6000030  I20  U25
 R48    GND VSS_R48 @T6G_MB_LIB.T6G(SCH_1):GND
 R51    GND VSS_R51 @T6G_MB_LIB.T6G(SCH_1):GND
 R54    GND VSS_R54 @T6G_MB_LIB.T6G(SCH_1):GND
 R56    GND VSS_R56 @T6G_MB_LIB.T6G(SCH_1):GND
 R58    GND VSS_R58 @T6G_MB_LIB.T6G(SCH_1):GND
 R61    GND VSS_R61 @T6G_MB_LIB.T6G(SCH_1):GND
 R63    GND VSS_R63 @T6G_MB_LIB.T6G(SCH_1):GND
 R65    GND VSS_R65 @T6G_MB_LIB.T6G(SCH_1):GND
 R68    GND VSS_R68 @T6G_MB_LIB.T6G(SCH_1):GND
 R70    GND VSS_R70 @T6G_MB_LIB.T6G(SCH_1):GND
 R72    GND VSS_R72 @T6G_MB_LIB.T6G(SCH_1):GND
 R75    GND VSS_R75 @T6G_MB_LIB.T6G(SCH_1):GND
  T3    GND VSS_T3 @T6G_MB_LIB.T6G(SCH_1):GND
  T5    GND VSS_T5 @T6G_MB_LIB.T6G(SCH_1):GND
  T8    GND VSS_T8 @T6G_MB_LIB.T6G(SCH_1):GND
 T10    GND VSS_T10 @T6G_MB_LIB.T6G(SCH_1):GND
 T12    GND VSS_T12 @T6G_MB_LIB.T6G(SCH_1):GND
 T15    GND VSS_T15 @T6G_MB_LIB.T6G(SCH_1):GND
 T17    GND VSS_T17 @T6G_MB_LIB.T6G(SCH_1):GND
 T19    GND VSS_T19 @T6G_MB_LIB.T6G(SCH_1):GND
 T22    GND VSS_T22 @T6G_MB_LIB.T6G(SCH_1):GND
 T25    GND VSS_T25 @T6G_MB_LIB.T6G(SCH_1):GND
 T28    GND VSS_T28 @T6G_MB_LIB.T6G(SCH_1):GND
 T31    GND VSS_T31 @T6G_MB_LIB.T6G(SCH_1):GND
 T34    GND VSS_T34 @T6G_MB_LIB.T6G(SCH_1):GND
 T37    GND VSS_T37 @T6G_MB_LIB.T6G(SCH_1):GND
 T39    GND VSS_T39 @T6G_MB_LIB.T6G(SCH_1):GND
 T42    GND VSS_T42 @T6G_MB_LIB.T6G(SCH_1):GND
 T45    GND VSS_T45 @T6G_MB_LIB.T6G(SCH_1):GND
 T48    GND VSS_T48 @T6G_MB_LIB.T6G(SCH_1):GND
 T51    GND VSS_T51 @T6G_MB_LIB.T6G(SCH_1):GND
 T54    GND VSS_T54 @T6G_MB_LIB.T6G(SCH_1):GND
 T57    GND VSS_T57 @T6G_MB_LIB.T6G(SCH_1):GND
 T59    GND VSS_T59 @T6G_MB_LIB.T6G(SCH_1):GND
 T61    GND VSS_T61 @T6G_MB_LIB.T6G(SCH_1):GND
 T64    GND VSS_T64 @T6G_MB_LIB.T6G(SCH_1):GND
 J15    GND VSS_J15 @T6G_MB_LIB.T6G(SCH_1):GND
 J18    GND VSS_J18 @T6G_MB_LIB.T6G(SCH_1):GND
 J20    GND VSS_J20 @T6G_MB_LIB.T6G(SCH_1):GND
 J22    GND VSS_J22 @T6G_MB_LIB.T6G(SCH_1):GND
 J25    GND VSS_J25 @T6G_MB_LIB.T6G(SCH_1):GND
 J28    GND VSS_J28 @T6G_MB_LIB.T6G(SCH_1):GND
 J31    GND VSS_J31 @T6G_MB_LIB.T6G(SCH_1):GND
 J34    GND VSS_J34 @T6G_MB_LIB.T6G(SCH_1):GND
 J42    GND VSS_J42 @T6G_MB_LIB.T6G(SCH_1):GND
 J45    GND VSS_J45 @T6G_MB_LIB.T6G(SCH_1):GND
 J48    GND VSS_J48 @T6G_MB_LIB.T6G(SCH_1):GND
 J51    GND VSS_J51 @T6G_MB_LIB.T6G(SCH_1):GND
 J54    GND VSS_J54 @T6G_MB_LIB.T6G(SCH_1):GND
 J56    GND VSS_J56 @T6G_MB_LIB.T6G(SCH_1):GND
 J58    GND VSS_J58 @T6G_MB_LIB.T6G(SCH_1):GND
 J61    GND VSS_J61 @T6G_MB_LIB.T6G(SCH_1):GND
 J63    GND VSS_J63 @T6G_MB_LIB.T6G(SCH_1):GND
 J65    GND VSS_J65 @T6G_MB_LIB.T6G(SCH_1):GND
 J68    GND VSS_J68 @T6G_MB_LIB.T6G(SCH_1):GND
 J70    GND VSS_J70 @T6G_MB_LIB.T6G(SCH_1):GND
 J72    GND VSS_J72 @T6G_MB_LIB.T6G(SCH_1):GND
 J75    GND VSS_J75 @T6G_MB_LIB.T6G(SCH_1):GND
  K3    GND VSS_K3 @T6G_MB_LIB.T6G(SCH_1):GND
  K5    GND VSS_K5 @T6G_MB_LIB.T6G(SCH_1):GND
  K8    GND VSS_K8 @T6G_MB_LIB.T6G(SCH_1):GND
 K10    GND VSS_K10 @T6G_MB_LIB.T6G(SCH_1):GND
 K12    GND VSS_K12 @T6G_MB_LIB.T6G(SCH_1):GND
 K15    GND VSS_K15 @T6G_MB_LIB.T6G(SCH_1):GND
 K17    GND VSS_K17 @T6G_MB_LIB.T6G(SCH_1):GND
 K19    GND VSS_K19 @T6G_MB_LIB.T6G(SCH_1):GND
 K24    GND VSS_K24 @T6G_MB_LIB.T6G(SCH_1):GND
 K25    GND VSS_K25 @T6G_MB_LIB.T6G(SCH_1):GND
 K26    GND VSS_K26 @T6G_MB_LIB.T6G(SCH_1):GND
 K27    GND VSS_K27 @T6G_MB_LIB.T6G(SCH_1):GND
 K28    GND VSS_K28 @T6G_MB_LIB.T6G(SCH_1):GND
 K29    GND VSS_K29 @T6G_MB_LIB.T6G(SCH_1):GND
 K30    GND VSS_K30 @T6G_MB_LIB.T6G(SCH_1):GND
 K31    GND VSS_K31 @T6G_MB_LIB.T6G(SCH_1):GND
 K32    GND VSS_K32 @T6G_MB_LIB.T6G(SCH_1):GND
 K33    GND VSS_K33 @T6G_MB_LIB.T6G(SCH_1):GND
 K34    GND VSS_K34 @T6G_MB_LIB.T6G(SCH_1):GND
 K37    GND VSS_K37 @T6G_MB_LIB.T6G(SCH_1):GND
 K39    GND VSS_K39 @T6G_MB_LIB.T6G(SCH_1):GND
 K42    GND VSS_K42 @T6G_MB_LIB.T6G(SCH_1):GND
 K43    GND VSS_K43 @T6G_MB_LIB.T6G(SCH_1):GND
 K44    GND VSS_K44 @T6G_MB_LIB.T6G(SCH_1):GND
 K45    GND VSS_K45 @T6G_MB_LIB.T6G(SCH_1):GND
 K46    GND VSS_K46 @T6G_MB_LIB.T6G(SCH_1):GND
 K47    GND VSS_K47 @T6G_MB_LIB.T6G(SCH_1):GND
 K48    GND VSS_K48 @T6G_MB_LIB.T6G(SCH_1):GND
 K49    GND VSS_K49 @T6G_MB_LIB.T6G(SCH_1):GND
 K50    GND VSS_K50 @T6G_MB_LIB.T6G(SCH_1):GND
 K51    GND VSS_K51 @T6G_MB_LIB.T6G(SCH_1):GND
 K52    GND VSS_K52 @T6G_MB_LIB.T6G(SCH_1):GND
 K53    GND VSS_K53 @T6G_MB_LIB.T6G(SCH_1):GND
 K57    GND VSS_K57 @T6G_MB_LIB.T6G(SCH_1):GND
 K61    GND VSS_K61 @T6G_MB_LIB.T6G(SCH_1):GND
 K64    GND VSS_K64 @T6G_MB_LIB.T6G(SCH_1):GND
 K66    GND VSS_K66 @T6G_MB_LIB.T6G(SCH_1):GND
 K68    GND VSS_K68 @T6G_MB_LIB.T6G(SCH_1):GND
 K71    GND VSS_K71 @T6G_MB_LIB.T6G(SCH_1):GND
 K73    GND VSS_K73 @T6G_MB_LIB.T6G(SCH_1):GND
  L1    GND VSS_L1 @T6G_MB_LIB.T6G(SCH_1):GND
  L6    GND VSS_L6 @T6G_MB_LIB.T6G(SCH_1):GND
  L8    GND VSS_L8 @T6G_MB_LIB.T6G(SCH_1):GND
 L13    GND VSS_L13 @T6G_MB_LIB.T6G(SCH_1):GND
 L15    GND VSS_L15 @T6G_MB_LIB.T6G(SCH_1):GND
 L20    GND VSS_L20 @T6G_MB_LIB.T6G(SCH_1):GND
 L22    GND VSS_L22 @T6G_MB_LIB.T6G(SCH_1):GND
 L25    GND VSS_L25 @T6G_MB_LIB.T6G(SCH_1):GND
 L28    GND VSS_L28 @T6G_MB_LIB.T6G(SCH_1):GND
 L31    GND VSS_L31 @T6G_MB_LIB.T6G(SCH_1):GND
 L34    GND VSS_L34 @T6G_MB_LIB.T6G(SCH_1):GND
 L35    GND VSS_L35 @T6G_MB_LIB.T6G(SCH_1):GND
 L36    GND VSS_L36 @T6G_MB_LIB.T6G(SCH_1):GND
 L40    GND VSS_L40 @T6G_MB_LIB.T6G(SCH_1):GND
 L41    GND VSS_L41 @T6G_MB_LIB.T6G(SCH_1):GND
 L42    GND VSS_L42 @T6G_MB_LIB.T6G(SCH_1):GND
 L45    GND VSS_L45 @T6G_MB_LIB.T6G(SCH_1):GND
 L48    GND VSS_L48 @T6G_MB_LIB.T6G(SCH_1):GND
 L51    GND VSS_L51 @T6G_MB_LIB.T6G(SCH_1):GND
 L54    GND VSS_L54 @T6G_MB_LIB.T6G(SCH_1):GND
 L56    GND VSS_L56 @T6G_MB_LIB.T6G(SCH_1):GND
 L61    GND VSS_L61 @T6G_MB_LIB.T6G(SCH_1):GND
 L63    GND VSS_L63 @T6G_MB_LIB.T6G(SCH_1):GND
 L68    GND VSS_L68 @T6G_MB_LIB.T6G(SCH_1):GND
 L70    GND VSS_L70 @T6G_MB_LIB.T6G(SCH_1):GND
 L75    GND VSS_L75 @T6G_MB_LIB.T6G(SCH_1):GND
  M3    GND VSS_M3 @T6G_MB_LIB.T6G(SCH_1):GND
  M5    GND VSS_M5 @T6G_MB_LIB.T6G(SCH_1):GND
  M8    GND VSS_M8 @T6G_MB_LIB.T6G(SCH_1):GND
 M10    GND VSS_M10 @T6G_MB_LIB.T6G(SCH_1):GND
 M12    GND VSS_M12 @T6G_MB_LIB.T6G(SCH_1):GND
 M15    GND VSS_M15 @T6G_MB_LIB.T6G(SCH_1):GND
 M17    GND VSS_M17 @T6G_MB_LIB.T6G(SCH_1):GND
 M19    GND VSS_M19 @T6G_MB_LIB.T6G(SCH_1):GND
 M22    GND VSS_M22 @T6G_MB_LIB.T6G(SCH_1):GND
 M25    GND VSS_M25 @T6G_MB_LIB.T6G(SCH_1):GND
 M28    GND VSS_M28 @T6G_MB_LIB.T6G(SCH_1):GND
 M31    GND VSS_M31 @T6G_MB_LIB.T6G(SCH_1):GND
 M34    GND VSS_M34 @T6G_MB_LIB.T6G(SCH_1):GND
 M37    GND VSS_M37 @T6G_MB_LIB.T6G(SCH_1):GND
 M39    GND VSS_M39 @T6G_MB_LIB.T6G(SCH_1):GND
 M42    GND VSS_M42 @T6G_MB_LIB.T6G(SCH_1):GND
 M45    GND VSS_M45 @T6G_MB_LIB.T6G(SCH_1):GND
 M48    GND VSS_M48 @T6G_MB_LIB.T6G(SCH_1):GND
 M51    GND VSS_M51 @T6G_MB_LIB.T6G(SCH_1):GND
 M54    GND VSS_M54 @T6G_MB_LIB.T6G(SCH_1):GND
 M57    GND VSS_M57 @T6G_MB_LIB.T6G(SCH_1):GND
 M59    GND VSS_M59 @T6G_MB_LIB.T6G(SCH_1):GND
 M61    GND VSS_M61 @T6G_MB_LIB.T6G(SCH_1):GND
 M64    GND VSS_M64 @T6G_MB_LIB.T6G(SCH_1):GND
 M66    GND VSS_M66 @T6G_MB_LIB.T6G(SCH_1):GND
 M68    GND VSS_M68 @T6G_MB_LIB.T6G(SCH_1):GND
 M71    GND VSS_M71 @T6G_MB_LIB.T6G(SCH_1):GND
 M73    GND VSS_M73 @T6G_MB_LIB.T6G(SCH_1):GND
  N1    GND VSS_N1 @T6G_MB_LIB.T6G(SCH_1):GND
  N4    GND VSS_N4 @T6G_MB_LIB.T6G(SCH_1):GND
  N6    GND VSS_N6 @T6G_MB_LIB.T6G(SCH_1):GND
  N8    GND VSS_N8 @T6G_MB_LIB.T6G(SCH_1):GND
 N11    GND VSS_N11 @T6G_MB_LIB.T6G(SCH_1):GND
 N13    GND VSS_N13 @T6G_MB_LIB.T6G(SCH_1):GND
 N15    GND VSS_N15 @T6G_MB_LIB.T6G(SCH_1):GND
 N18    GND VSS_N18 @T6G_MB_LIB.T6G(SCH_1):GND
 N20    GND VSS_N20 @T6G_MB_LIB.T6G(SCH_1):GND
 N22    GND VSS_N22 @T6G_MB_LIB.T6G(SCH_1):GND
 N25    GND VSS_N25 @T6G_MB_LIB.T6G(SCH_1):GND
 N28    GND VSS_N28 @T6G_MB_LIB.T6G(SCH_1):GND
 N31    GND VSS_N31 @T6G_MB_LIB.T6G(SCH_1):GND
 N34    GND VSS_N34 @T6G_MB_LIB.T6G(SCH_1):GND
 N42    GND VSS_N42 @T6G_MB_LIB.T6G(SCH_1):GND
 N45    GND VSS_N45 @T6G_MB_LIB.T6G(SCH_1):GND
 N48    GND VSS_N48 @T6G_MB_LIB.T6G(SCH_1):GND
 N51    GND VSS_N51 @T6G_MB_LIB.T6G(SCH_1):GND
 N54    GND VSS_N54 @T6G_MB_LIB.T6G(SCH_1):GND
 N56    GND VSS_N56 @T6G_MB_LIB.T6G(SCH_1):GND
 N58    GND VSS_N58 @T6G_MB_LIB.T6G(SCH_1):GND
 N61    GND VSS_N61 @T6G_MB_LIB.T6G(SCH_1):GND
 N63    GND VSS_N63 @T6G_MB_LIB.T6G(SCH_1):GND
 N65    GND VSS_N65 @T6G_MB_LIB.T6G(SCH_1):GND
 N68    GND VSS_N68 @T6G_MB_LIB.T6G(SCH_1):GND
 N70    GND VSS_N70 @T6G_MB_LIB.T6G(SCH_1):GND
 N72    GND VSS_N72 @T6G_MB_LIB.T6G(SCH_1):GND
 N75    GND VSS_N75 @T6G_MB_LIB.T6G(SCH_1):GND
  P3    GND VSS_P3 @T6G_MB_LIB.T6G(SCH_1):GND
  P8    GND VSS_P8 @T6G_MB_LIB.T6G(SCH_1):GND
 P10    GND VSS_P10 @T6G_MB_LIB.T6G(SCH_1):GND
 P15    GND VSS_P15 @T6G_MB_LIB.T6G(SCH_1):GND
 P17    GND VSS_P17 @T6G_MB_LIB.T6G(SCH_1):GND
 P23    GND VSS_P23 @T6G_MB_LIB.T6G(SCH_1):GND
 P24    GND VSS_P24 @T6G_MB_LIB.T6G(SCH_1):GND
 P26    GND VSS_P26 @T6G_MB_LIB.T6G(SCH_1):GND
 P27    GND VSS_P27 @T6G_MB_LIB.T6G(SCH_1):GND
 P28    GND VSS_P28 @T6G_MB_LIB.T6G(SCH_1):GND
 P29    GND VSS_P29 @T6G_MB_LIB.T6G(SCH_1):GND
 P30    GND VSS_P30 @T6G_MB_LIB.T6G(SCH_1):GND
 P31    GND VSS_P31 @T6G_MB_LIB.T6G(SCH_1):GND
 P32    GND VSS_P32 @T6G_MB_LIB.T6G(SCH_1):GND
 P33    GND VSS_P33 @T6G_MB_LIB.T6G(SCH_1):GND
 P34    GND VSS_P34 @T6G_MB_LIB.T6G(SCH_1):GND
 P37    GND VSS_P37 @T6G_MB_LIB.T6G(SCH_1):GND
 P39    GND VSS_P39 @T6G_MB_LIB.T6G(SCH_1):GND
 P42    GND VSS_P42 @T6G_MB_LIB.T6G(SCH_1):GND
 P43    GND VSS_P43 @T6G_MB_LIB.T6G(SCH_1):GND
 P44    GND VSS_P44 @T6G_MB_LIB.T6G(SCH_1):GND
 P45    GND VSS_P45 @T6G_MB_LIB.T6G(SCH_1):GND
 P46    GND VSS_P46 @T6G_MB_LIB.T6G(SCH_1):GND
 P47    GND VSS_P47 @T6G_MB_LIB.T6G(SCH_1):GND
 P48    GND VSS_P48 @T6G_MB_LIB.T6G(SCH_1):GND
 P49    GND VSS_P49 @T6G_MB_LIB.T6G(SCH_1):GND
 P50    GND VSS_P50 @T6G_MB_LIB.T6G(SCH_1):GND
 P51    GND VSS_P51 @T6G_MB_LIB.T6G(SCH_1):GND
 P52    GND VSS_P52 @T6G_MB_LIB.T6G(SCH_1):GND
 P53    GND VSS_P53 @T6G_MB_LIB.T6G(SCH_1):GND
 P59    GND VSS_P59 @T6G_MB_LIB.T6G(SCH_1):GND
 P61    GND VSS_P61 @T6G_MB_LIB.T6G(SCH_1):GND
 P66    GND VSS_P66 @T6G_MB_LIB.T6G(SCH_1):GND
 P73    GND VSS_P73 @T6G_MB_LIB.T6G(SCH_1):GND
  R1    GND VSS_R1 @T6G_MB_LIB.T6G(SCH_1):GND
  R4    GND VSS_R4 @T6G_MB_LIB.T6G(SCH_1):GND
  R6    GND VSS_R6 @T6G_MB_LIB.T6G(SCH_1):GND
  R8    GND VSS_R8 @T6G_MB_LIB.T6G(SCH_1):GND
 R11    GND VSS_R11 @T6G_MB_LIB.T6G(SCH_1):GND
 R13    GND VSS_R13 @T6G_MB_LIB.T6G(SCH_1):GND
 R15    GND VSS_R15 @T6G_MB_LIB.T6G(SCH_1):GND
 R18    GND VSS_R18 @T6G_MB_LIB.T6G(SCH_1):GND
 R20    GND VSS_R20 @T6G_MB_LIB.T6G(SCH_1):GND
 R22    GND VSS_R22 @T6G_MB_LIB.T6G(SCH_1):GND
 R25    GND VSS_R25 @T6G_MB_LIB.T6G(SCH_1):GND
 R28    GND VSS_R28 @T6G_MB_LIB.T6G(SCH_1):GND
 R31    GND VSS_R31 @T6G_MB_LIB.T6G(SCH_1):GND
 R34    GND VSS_R34 @T6G_MB_LIB.T6G(SCH_1):GND
 R35    GND VSS_R35 @T6G_MB_LIB.T6G(SCH_1):GND
 R36    GND VSS_R36 @T6G_MB_LIB.T6G(SCH_1):GND
 R40    GND VSS_R40 @T6G_MB_LIB.T6G(SCH_1):GND
 R41    GND VSS_R41 @T6G_MB_LIB.T6G(SCH_1):GND
 R42    GND VSS_R42 @T6G_MB_LIB.T6G(SCH_1):GND
 R45    GND VSS_R45 @T6G_MB_LIB.T6G(SCH_1):GND

GENOA_SP5-SOCKET6096_13568-001,SMLF,IO,DGA^6000030  I21  U25
AB68    GND VSS_AB68 @T6G_MB_LIB.T6G(SCH_1):GND
AB71    GND VSS_AB71 @T6G_MB_LIB.T6G(SCH_1):GND
AB73    GND VSS_AB73 @T6G_MB_LIB.T6G(SCH_1):GND
 AC1    GND VSS_AC1 @T6G_MB_LIB.T6G(SCH_1):GND
 AC6    GND VSS_AC6 @T6G_MB_LIB.T6G(SCH_1):GND
 AC8    GND VSS_AC8 @T6G_MB_LIB.T6G(SCH_1):GND
AC13    GND VSS_AC13 @T6G_MB_LIB.T6G(SCH_1):GND
AC15    GND VSS_AC15 @T6G_MB_LIB.T6G(SCH_1):GND
AC20    GND VSS_AC20 @T6G_MB_LIB.T6G(SCH_1):GND
AC22    GND VSS_AC22 @T6G_MB_LIB.T6G(SCH_1):GND
AC25    GND VSS_AC25 @T6G_MB_LIB.T6G(SCH_1):GND
AC28    GND VSS_AC28 @T6G_MB_LIB.T6G(SCH_1):GND
AC31    GND VSS_AC31 @T6G_MB_LIB.T6G(SCH_1):GND
AC34    GND VSS_AC34 @T6G_MB_LIB.T6G(SCH_1):GND
AC42    GND VSS_AC42 @T6G_MB_LIB.T6G(SCH_1):GND
AC45    GND VSS_AC45 @T6G_MB_LIB.T6G(SCH_1):GND
AC48    GND VSS_AC48 @T6G_MB_LIB.T6G(SCH_1):GND
AC51    GND VSS_AC51 @T6G_MB_LIB.T6G(SCH_1):GND
AC54    GND VSS_AC54 @T6G_MB_LIB.T6G(SCH_1):GND
AC56    GND VSS_AC56 @T6G_MB_LIB.T6G(SCH_1):GND
AC61    GND VSS_AC61 @T6G_MB_LIB.T6G(SCH_1):GND
AC63    GND VSS_AC63 @T6G_MB_LIB.T6G(SCH_1):GND
AC68    GND VSS_AC68 @T6G_MB_LIB.T6G(SCH_1):GND
AC70    GND VSS_AC70 @T6G_MB_LIB.T6G(SCH_1):GND
AC75    GND VSS_AC75 @T6G_MB_LIB.T6G(SCH_1):GND
 AD3    GND VSS_AD3 @T6G_MB_LIB.T6G(SCH_1):GND
 AD5    GND VSS_AD5 @T6G_MB_LIB.T6G(SCH_1):GND
 AD8    GND VSS_AD8 @T6G_MB_LIB.T6G(SCH_1):GND
AD10    GND VSS_AD10 @T6G_MB_LIB.T6G(SCH_1):GND
AD12    GND VSS_AD12 @T6G_MB_LIB.T6G(SCH_1):GND
AD15    GND VSS_AD15 @T6G_MB_LIB.T6G(SCH_1):GND
AD17    GND VSS_AD17 @T6G_MB_LIB.T6G(SCH_1):GND
AD19    GND VSS_AD19 @T6G_MB_LIB.T6G(SCH_1):GND
AD23    GND VSS_AD23 @T6G_MB_LIB.T6G(SCH_1):GND
AD24    GND VSS_AD24 @T6G_MB_LIB.T6G(SCH_1):GND
AD25    GND VSS_AD25 @T6G_MB_LIB.T6G(SCH_1):GND
AD26    GND VSS_AD26 @T6G_MB_LIB.T6G(SCH_1):GND
AD27    GND VSS_AD27 @T6G_MB_LIB.T6G(SCH_1):GND
AD28    GND VSS_AD28 @T6G_MB_LIB.T6G(SCH_1):GND
AD29    GND VSS_AD29 @T6G_MB_LIB.T6G(SCH_1):GND
AD30    GND VSS_AD30 @T6G_MB_LIB.T6G(SCH_1):GND
AD32    GND VSS_AD32 @T6G_MB_LIB.T6G(SCH_1):GND
AD33    GND VSS_AD33 @T6G_MB_LIB.T6G(SCH_1):GND
AD34    GND VSS_AD34 @T6G_MB_LIB.T6G(SCH_1):GND
AD37    GND VSS_AD37 @T6G_MB_LIB.T6G(SCH_1):GND
AD39    GND VSS_AD39 @T6G_MB_LIB.T6G(SCH_1):GND
AD42    GND VSS_AD42 @T6G_MB_LIB.T6G(SCH_1):GND
AD43    GND VSS_AD43 @T6G_MB_LIB.T6G(SCH_1):GND
AD44    GND VSS_AD44 @T6G_MB_LIB.T6G(SCH_1):GND
AD45    GND VSS_AD45 @T6G_MB_LIB.T6G(SCH_1):GND
AD46    GND VSS_AD46 @T6G_MB_LIB.T6G(SCH_1):GND
AD47    GND VSS_AD47 @T6G_MB_LIB.T6G(SCH_1):GND
AD48    GND VSS_AD48 @T6G_MB_LIB.T6G(SCH_1):GND
 T66    GND VSS_T66 @T6G_MB_LIB.T6G(SCH_1):GND
 T68    GND VSS_T68 @T6G_MB_LIB.T6G(SCH_1):GND
 T71    GND VSS_T71 @T6G_MB_LIB.T6G(SCH_1):GND
 T73    GND VSS_T73 @T6G_MB_LIB.T6G(SCH_1):GND
  U1    GND VSS_U1 @T6G_MB_LIB.T6G(SCH_1):GND
  U6    GND VSS_U6 @T6G_MB_LIB.T6G(SCH_1):GND
  U8    GND VSS_U8 @T6G_MB_LIB.T6G(SCH_1):GND
 U13    GND VSS_U13 @T6G_MB_LIB.T6G(SCH_1):GND
 U15    GND VSS_U15 @T6G_MB_LIB.T6G(SCH_1):GND
 U20    GND VSS_U20 @T6G_MB_LIB.T6G(SCH_1):GND
 U22    GND VSS_U22 @T6G_MB_LIB.T6G(SCH_1):GND
 U25    GND VSS_U25 @T6G_MB_LIB.T6G(SCH_1):GND
 U28    GND VSS_U28 @T6G_MB_LIB.T6G(SCH_1):GND
 U31    GND VSS_U31 @T6G_MB_LIB.T6G(SCH_1):GND
 U34    GND VSS_U34 @T6G_MB_LIB.T6G(SCH_1):GND
 U42    GND VSS_U42 @T6G_MB_LIB.T6G(SCH_1):GND
 U45    GND VSS_U45 @T6G_MB_LIB.T6G(SCH_1):GND
 U48    GND VSS_U48 @T6G_MB_LIB.T6G(SCH_1):GND
 U51    GND VSS_U51 @T6G_MB_LIB.T6G(SCH_1):GND
 U54    GND VSS_U54 @T6G_MB_LIB.T6G(SCH_1):GND
 U56    GND VSS_U56 @T6G_MB_LIB.T6G(SCH_1):GND
 U61    GND VSS_U61 @T6G_MB_LIB.T6G(SCH_1):GND
 U63    GND VSS_U63 @T6G_MB_LIB.T6G(SCH_1):GND
 U68    GND VSS_U68 @T6G_MB_LIB.T6G(SCH_1):GND
 U70    GND VSS_U70 @T6G_MB_LIB.T6G(SCH_1):GND
 U75    GND VSS_U75 @T6G_MB_LIB.T6G(SCH_1):GND
  V3    GND VSS_V3 @T6G_MB_LIB.T6G(SCH_1):GND
  V5    GND VSS_V5 @T6G_MB_LIB.T6G(SCH_1):GND
  V8    GND VSS_V8 @T6G_MB_LIB.T6G(SCH_1):GND
 V10    GND VSS_V10 @T6G_MB_LIB.T6G(SCH_1):GND
 V12    GND VSS_V12 @T6G_MB_LIB.T6G(SCH_1):GND
 V15    GND VSS_V15 @T6G_MB_LIB.T6G(SCH_1):GND
 V17    GND VSS_V17 @T6G_MB_LIB.T6G(SCH_1):GND
 V19    GND VSS_V19 @T6G_MB_LIB.T6G(SCH_1):GND
 V23    GND VSS_V23 @T6G_MB_LIB.T6G(SCH_1):GND
 V24    GND VSS_V24 @T6G_MB_LIB.T6G(SCH_1):GND
 V25    GND VSS_V25 @T6G_MB_LIB.T6G(SCH_1):GND
 V26    GND VSS_V26 @T6G_MB_LIB.T6G(SCH_1):GND
 V28    GND VSS_V28 @T6G_MB_LIB.T6G(SCH_1):GND
 V29    GND VSS_V29 @T6G_MB_LIB.T6G(SCH_1):GND
 V30    GND VSS_V30 @T6G_MB_LIB.T6G(SCH_1):GND
 V31    GND VSS_V31 @T6G_MB_LIB.T6G(SCH_1):GND
 V32    GND VSS_V32 @T6G_MB_LIB.T6G(SCH_1):GND
 V33    GND VSS_V33 @T6G_MB_LIB.T6G(SCH_1):GND
 V34    GND VSS_V34 @T6G_MB_LIB.T6G(SCH_1):GND
 V37    GND VSS_V37 @T6G_MB_LIB.T6G(SCH_1):GND
 V39    GND VSS_V39 @T6G_MB_LIB.T6G(SCH_1):GND
 V42    GND VSS_V42 @T6G_MB_LIB.T6G(SCH_1):GND
 V43    GND VSS_V43 @T6G_MB_LIB.T6G(SCH_1):GND
 V44    GND VSS_V44 @T6G_MB_LIB.T6G(SCH_1):GND
 V45    GND VSS_V45 @T6G_MB_LIB.T6G(SCH_1):GND
 V46    GND VSS_V46 @T6G_MB_LIB.T6G(SCH_1):GND
 V47    GND VSS_V47 @T6G_MB_LIB.T6G(SCH_1):GND
 V48    GND VSS_V48 @T6G_MB_LIB.T6G(SCH_1):GND
 V49    GND VSS_V49 @T6G_MB_LIB.T6G(SCH_1):GND
 V50    GND VSS_V50 @T6G_MB_LIB.T6G(SCH_1):GND
 V51    GND VSS_V51 @T6G_MB_LIB.T6G(SCH_1):GND
 V52    GND VSS_V52 @T6G_MB_LIB.T6G(SCH_1):GND
 V53    GND VSS_V53 @T6G_MB_LIB.T6G(SCH_1):GND
 V57    GND VSS_V57 @T6G_MB_LIB.T6G(SCH_1):GND
 V59    GND VSS_V59 @T6G_MB_LIB.T6G(SCH_1):GND
 V61    GND VSS_V61 @T6G_MB_LIB.T6G(SCH_1):GND
 V64    GND VSS_V64 @T6G_MB_LIB.T6G(SCH_1):GND
 V66    GND VSS_V66 @T6G_MB_LIB.T6G(SCH_1):GND
 V71    GND VSS_V71 @T6G_MB_LIB.T6G(SCH_1):GND
 V73    GND VSS_V73 @T6G_MB_LIB.T6G(SCH_1):GND
  W1    GND VSS_W1 @T6G_MB_LIB.T6G(SCH_1):GND
  W4    GND VSS_W4 @T6G_MB_LIB.T6G(SCH_1):GND
  W6    GND VSS_W6 @T6G_MB_LIB.T6G(SCH_1):GND
  W8    GND VSS_W8 @T6G_MB_LIB.T6G(SCH_1):GND
 W11    GND VSS_W11 @T6G_MB_LIB.T6G(SCH_1):GND
 W13    GND VSS_W13 @T6G_MB_LIB.T6G(SCH_1):GND
 W15    GND VSS_W15 @T6G_MB_LIB.T6G(SCH_1):GND
 W18    GND VSS_W18 @T6G_MB_LIB.T6G(SCH_1):GND
 W20    GND VSS_W20 @T6G_MB_LIB.T6G(SCH_1):GND
 W22    GND VSS_W22 @T6G_MB_LIB.T6G(SCH_1):GND
 W25    GND VSS_W25 @T6G_MB_LIB.T6G(SCH_1):GND
 W28    GND VSS_W28 @T6G_MB_LIB.T6G(SCH_1):GND
 W34    GND VSS_W34 @T6G_MB_LIB.T6G(SCH_1):GND
 W35    GND VSS_W35 @T6G_MB_LIB.T6G(SCH_1):GND
 W36    GND VSS_W36 @T6G_MB_LIB.T6G(SCH_1):GND
 W40    GND VSS_W40 @T6G_MB_LIB.T6G(SCH_1):GND
 W41    GND VSS_W41 @T6G_MB_LIB.T6G(SCH_1):GND
 W42    GND VSS_W42 @T6G_MB_LIB.T6G(SCH_1):GND
 W45    GND VSS_W45 @T6G_MB_LIB.T6G(SCH_1):GND
 W48    GND VSS_W48 @T6G_MB_LIB.T6G(SCH_1):GND
 W51    GND VSS_W51 @T6G_MB_LIB.T6G(SCH_1):GND
 W54    GND VSS_W54 @T6G_MB_LIB.T6G(SCH_1):GND
 W56    GND VSS_W56 @T6G_MB_LIB.T6G(SCH_1):GND
 W58    GND VSS_W58 @T6G_MB_LIB.T6G(SCH_1):GND
 W61    GND VSS_W61 @T6G_MB_LIB.T6G(SCH_1):GND
 W63    GND VSS_W63 @T6G_MB_LIB.T6G(SCH_1):GND
 W65    GND VSS_W65 @T6G_MB_LIB.T6G(SCH_1):GND
 W68    GND VSS_W68 @T6G_MB_LIB.T6G(SCH_1):GND
 W70    GND VSS_W70 @T6G_MB_LIB.T6G(SCH_1):GND
 W72    GND VSS_W72 @T6G_MB_LIB.T6G(SCH_1):GND
 W75    GND VSS_W75 @T6G_MB_LIB.T6G(SCH_1):GND
  Y3    GND VSS_Y3 @T6G_MB_LIB.T6G(SCH_1):GND
  Y8    GND VSS_Y8 @T6G_MB_LIB.T6G(SCH_1):GND
 Y10    GND VSS_Y10 @T6G_MB_LIB.T6G(SCH_1):GND
 Y15    GND VSS_Y15 @T6G_MB_LIB.T6G(SCH_1):GND
 Y17    GND VSS_Y17 @T6G_MB_LIB.T6G(SCH_1):GND
 Y22    GND VSS_Y22 @T6G_MB_LIB.T6G(SCH_1):GND
 Y23    GND VSS_Y23 @T6G_MB_LIB.T6G(SCH_1):GND
 Y24    GND VSS_Y24 @T6G_MB_LIB.T6G(SCH_1):GND
 Y25    GND VSS_Y25 @T6G_MB_LIB.T6G(SCH_1):GND
 Y26    GND VSS_Y26 @T6G_MB_LIB.T6G(SCH_1):GND
 Y27    GND VSS_Y27 @T6G_MB_LIB.T6G(SCH_1):GND
 Y28    GND VSS_Y28 @T6G_MB_LIB.T6G(SCH_1):GND
 Y31    GND VSS_Y31 @T6G_MB_LIB.T6G(SCH_1):GND
 Y32    GND VSS_Y32 @T6G_MB_LIB.T6G(SCH_1):GND
 Y33    GND VSS_Y33 @T6G_MB_LIB.T6G(SCH_1):GND
 Y34    GND VSS_Y34 @T6G_MB_LIB.T6G(SCH_1):GND
 Y37    GND VSS_Y37 @T6G_MB_LIB.T6G(SCH_1):GND
 Y39    GND VSS_Y39 @T6G_MB_LIB.T6G(SCH_1):GND
 Y42    GND VSS_Y42 @T6G_MB_LIB.T6G(SCH_1):GND
 Y43    GND VSS_Y43 @T6G_MB_LIB.T6G(SCH_1):GND
 Y44    GND VSS_Y44 @T6G_MB_LIB.T6G(SCH_1):GND
 Y45    GND VSS_Y45 @T6G_MB_LIB.T6G(SCH_1):GND
 Y48    GND VSS_Y48 @T6G_MB_LIB.T6G(SCH_1):GND
 Y49    GND VSS_Y49 @T6G_MB_LIB.T6G(SCH_1):GND
 Y50    GND VSS_Y50 @T6G_MB_LIB.T6G(SCH_1):GND
 Y51    GND VSS_Y51 @T6G_MB_LIB.T6G(SCH_1):GND
 Y52    GND VSS_Y52 @T6G_MB_LIB.T6G(SCH_1):GND
 Y53    GND VSS_Y53 @T6G_MB_LIB.T6G(SCH_1):GND
 Y54    GND VSS_Y54 @T6G_MB_LIB.T6G(SCH_1):GND
 Y59    GND VSS_Y59 @T6G_MB_LIB.T6G(SCH_1):GND
 Y61    GND VSS_Y61 @T6G_MB_LIB.T6G(SCH_1):GND
 Y66    GND VSS_Y66 @T6G_MB_LIB.T6G(SCH_1):GND
 Y68    GND VSS_Y68 @T6G_MB_LIB.T6G(SCH_1):GND
 Y73    GND VSS_Y73 @T6G_MB_LIB.T6G(SCH_1):GND
 AA1    GND VSS_AA1 @T6G_MB_LIB.T6G(SCH_1):GND
 AA4    GND VSS_AA4 @T6G_MB_LIB.T6G(SCH_1):GND
 AA6    GND VSS_AA6 @T6G_MB_LIB.T6G(SCH_1):GND
 AA8    GND VSS_AA8 @T6G_MB_LIB.T6G(SCH_1):GND
AA11    GND VSS_AA11 @T6G_MB_LIB.T6G(SCH_1):GND
AA13    GND VSS_AA13 @T6G_MB_LIB.T6G(SCH_1):GND
AA15    GND VSS_AA15 @T6G_MB_LIB.T6G(SCH_1):GND
AA18    GND VSS_AA18 @T6G_MB_LIB.T6G(SCH_1):GND
AA20    GND VSS_AA20 @T6G_MB_LIB.T6G(SCH_1):GND
AA31    GND VSS_AA31 @T6G_MB_LIB.T6G(SCH_1):GND
AA34    GND VSS_AA34 @T6G_MB_LIB.T6G(SCH_1):GND
AA35    GND VSS_AA35 @T6G_MB_LIB.T6G(SCH_1):GND
AA36    GND VSS_AA36 @T6G_MB_LIB.T6G(SCH_1):GND
AA40    GND VSS_AA40 @T6G_MB_LIB.T6G(SCH_1):GND
AA41    GND VSS_AA41 @T6G_MB_LIB.T6G(SCH_1):GND
AA45    GND VSS_AA45 @T6G_MB_LIB.T6G(SCH_1):GND
AA56    GND VSS_AA56 @T6G_MB_LIB.T6G(SCH_1):GND
AA58    GND VSS_AA58 @T6G_MB_LIB.T6G(SCH_1):GND
AA61    GND VSS_AA61 @T6G_MB_LIB.T6G(SCH_1):GND
AA63    GND VSS_AA63 @T6G_MB_LIB.T6G(SCH_1):GND
AA65    GND VSS_AA65 @T6G_MB_LIB.T6G(SCH_1):GND
AA68    GND VSS_AA68 @T6G_MB_LIB.T6G(SCH_1):GND
AA70    GND VSS_AA70 @T6G_MB_LIB.T6G(SCH_1):GND
AA75    GND VSS_AA75 @T6G_MB_LIB.T6G(SCH_1):GND
 AB3    GND VSS_AB3 @T6G_MB_LIB.T6G(SCH_1):GND
 AB5    GND VSS_AB5 @T6G_MB_LIB.T6G(SCH_1):GND
 AB8    GND VSS_AB8 @T6G_MB_LIB.T6G(SCH_1):GND
AB10    GND VSS_AB10 @T6G_MB_LIB.T6G(SCH_1):GND
AB12    GND VSS_AB12 @T6G_MB_LIB.T6G(SCH_1):GND
AB15    GND VSS_AB15 @T6G_MB_LIB.T6G(SCH_1):GND
AB17    GND VSS_AB17 @T6G_MB_LIB.T6G(SCH_1):GND
AB19    GND VSS_AB19 @T6G_MB_LIB.T6G(SCH_1):GND
AB22    GND VSS_AB22 @T6G_MB_LIB.T6G(SCH_1):GND
AB25    GND VSS_AB25 @T6G_MB_LIB.T6G(SCH_1):GND
AB28    GND VSS_AB28 @T6G_MB_LIB.T6G(SCH_1):GND
AB31    GND VSS_AB31 @T6G_MB_LIB.T6G(SCH_1):GND
AB34    GND VSS_AB34 @T6G_MB_LIB.T6G(SCH_1):GND
AB37    GND VSS_AB37 @T6G_MB_LIB.T6G(SCH_1):GND
AB39    GND VSS_AB39 @T6G_MB_LIB.T6G(SCH_1):GND
AB42    GND VSS_AB42 @T6G_MB_LIB.T6G(SCH_1):GND
AB45    GND VSS_AB45 @T6G_MB_LIB.T6G(SCH_1):GND
AB48    GND VSS_AB48 @T6G_MB_LIB.T6G(SCH_1):GND
AB51    GND VSS_AB51 @T6G_MB_LIB.T6G(SCH_1):GND
AB54    GND VSS_AB54 @T6G_MB_LIB.T6G(SCH_1):GND
AB57    GND VSS_AB57 @T6G_MB_LIB.T6G(SCH_1):GND
AB59    GND VSS_AB59 @T6G_MB_LIB.T6G(SCH_1):GND
AB61    GND VSS_AB61 @T6G_MB_LIB.T6G(SCH_1):GND
AB64    GND VSS_AB64 @T6G_MB_LIB.T6G(SCH_1):GND
AB66    GND VSS_AB66 @T6G_MB_LIB.T6G(SCH_1):GND

GENOA_SP5-SOCKET6096_13568-001,SMLF,IO,DGA^6000030  I22  U25
AK10    GND VSS_AK10 @T6G_MB_LIB.T6G(SCH_1):GND
AK12    GND VSS_AK12 @T6G_MB_LIB.T6G(SCH_1):GND
AK15    GND VSS_AK15 @T6G_MB_LIB.T6G(SCH_1):GND
AK17    GND VSS_AK17 @T6G_MB_LIB.T6G(SCH_1):GND
AK19    GND VSS_AK19 @T6G_MB_LIB.T6G(SCH_1):GND
AK22    GND VSS_AK22 @T6G_MB_LIB.T6G(SCH_1):GND
AK25    GND VSS_AK25 @T6G_MB_LIB.T6G(SCH_1):GND
AK28    GND VSS_AK28 @T6G_MB_LIB.T6G(SCH_1):GND
AK31    GND VSS_AK31 @T6G_MB_LIB.T6G(SCH_1):GND
AK34    GND VSS_AK34 @T6G_MB_LIB.T6G(SCH_1):GND
AK37    GND VSS_AK37 @T6G_MB_LIB.T6G(SCH_1):GND
AK39    GND VSS_AK39 @T6G_MB_LIB.T6G(SCH_1):GND
AK42    GND VSS_AK42 @T6G_MB_LIB.T6G(SCH_1):GND
AK45    GND VSS_AK45 @T6G_MB_LIB.T6G(SCH_1):GND
AK48    GND VSS_AK48 @T6G_MB_LIB.T6G(SCH_1):GND
AK51    GND VSS_AK51 @T6G_MB_LIB.T6G(SCH_1):GND
AK54    GND VSS_AK54 @T6G_MB_LIB.T6G(SCH_1):GND
AK57    GND VSS_AK57 @T6G_MB_LIB.T6G(SCH_1):GND
AK59    GND VSS_AK59 @T6G_MB_LIB.T6G(SCH_1):GND
AK61    GND VSS_AK61 @T6G_MB_LIB.T6G(SCH_1):GND
AK64    GND VSS_AK64 @T6G_MB_LIB.T6G(SCH_1):GND
AK66    GND VSS_AK66 @T6G_MB_LIB.T6G(SCH_1):GND
AK68    GND VSS_AK68 @T6G_MB_LIB.T6G(SCH_1):GND
AK71    GND VSS_AK71 @T6G_MB_LIB.T6G(SCH_1):GND
AK73    GND VSS_AK73 @T6G_MB_LIB.T6G(SCH_1):GND
 AL1    GND VSS_AL1 @T6G_MB_LIB.T6G(SCH_1):GND
 AL4    GND VSS_AL4 @T6G_MB_LIB.T6G(SCH_1):GND
 AL6    GND VSS_AL6 @T6G_MB_LIB.T6G(SCH_1):GND
 AL8    GND VSS_AL8 @T6G_MB_LIB.T6G(SCH_1):GND
AL11    GND VSS_AL11 @T6G_MB_LIB.T6G(SCH_1):GND
AL13    GND VSS_AL13 @T6G_MB_LIB.T6G(SCH_1):GND
AL15    GND VSS_AL15 @T6G_MB_LIB.T6G(SCH_1):GND
AL18    GND VSS_AL18 @T6G_MB_LIB.T6G(SCH_1):GND
AL20    GND VSS_AL20 @T6G_MB_LIB.T6G(SCH_1):GND
AL22    GND VSS_AL22 @T6G_MB_LIB.T6G(SCH_1):GND
AL25    GND VSS_AL25 @T6G_MB_LIB.T6G(SCH_1):GND
AL28    GND VSS_AL28 @T6G_MB_LIB.T6G(SCH_1):GND
AL31    GND VSS_AL31 @T6G_MB_LIB.T6G(SCH_1):GND
AL34    GND VSS_AL34 @T6G_MB_LIB.T6G(SCH_1):GND
AL42    GND VSS_AL42 @T6G_MB_LIB.T6G(SCH_1):GND
AL45    GND VSS_AL45 @T6G_MB_LIB.T6G(SCH_1):GND
AL48    GND VSS_AL48 @T6G_MB_LIB.T6G(SCH_1):GND
AL51    GND VSS_AL51 @T6G_MB_LIB.T6G(SCH_1):GND
AL54    GND VSS_AL54 @T6G_MB_LIB.T6G(SCH_1):GND
AL56    GND VSS_AL56 @T6G_MB_LIB.T6G(SCH_1):GND
AL58    GND VSS_AL58 @T6G_MB_LIB.T6G(SCH_1):GND
AL61    GND VSS_AL61 @T6G_MB_LIB.T6G(SCH_1):GND
AL63    GND VSS_AL63 @T6G_MB_LIB.T6G(SCH_1):GND
AL65    GND VSS_AL65 @T6G_MB_LIB.T6G(SCH_1):GND
AL68    GND VSS_AL68 @T6G_MB_LIB.T6G(SCH_1):GND
AL70    GND VSS_AL70 @T6G_MB_LIB.T6G(SCH_1):GND
AL72    GND VSS_AL72 @T6G_MB_LIB.T6G(SCH_1):GND
AL75    GND VSS_AL75 @T6G_MB_LIB.T6G(SCH_1):GND
 AM3    GND VSS_AM3 @T6G_MB_LIB.T6G(SCH_1):GND
 AM8    GND VSS_AM8 @T6G_MB_LIB.T6G(SCH_1):GND
AM10    GND VSS_AM10 @T6G_MB_LIB.T6G(SCH_1):GND
AM15    GND VSS_AM15 @T6G_MB_LIB.T6G(SCH_1):GND
AM17    GND VSS_AM17 @T6G_MB_LIB.T6G(SCH_1):GND
AM23    GND VSS_AM23 @T6G_MB_LIB.T6G(SCH_1):GND
AM24    GND VSS_AM24 @T6G_MB_LIB.T6G(SCH_1):GND
AM25    GND VSS_AM25 @T6G_MB_LIB.T6G(SCH_1):GND
AM26    GND VSS_AM26 @T6G_MB_LIB.T6G(SCH_1):GND
AM27    GND VSS_AM27 @T6G_MB_LIB.T6G(SCH_1):GND
AM28    GND VSS_AM28 @T6G_MB_LIB.T6G(SCH_1):GND
AM29    GND VSS_AM29 @T6G_MB_LIB.T6G(SCH_1):GND
AM30    GND VSS_AM30 @T6G_MB_LIB.T6G(SCH_1):GND
AM31    GND VSS_AM31 @T6G_MB_LIB.T6G(SCH_1):GND
AM32    GND VSS_AM32 @T6G_MB_LIB.T6G(SCH_1):GND
AM33    GND VSS_AM33 @T6G_MB_LIB.T6G(SCH_1):GND
AM34    GND VSS_AM34 @T6G_MB_LIB.T6G(SCH_1):GND
AM39    GND VSS_AM39 @T6G_MB_LIB.T6G(SCH_1):GND
AD49    GND VSS_AD49 @T6G_MB_LIB.T6G(SCH_1):GND
AD50    GND VSS_AD50 @T6G_MB_LIB.T6G(SCH_1):GND
AD51    GND VSS_AD51 @T6G_MB_LIB.T6G(SCH_1):GND
AD52    GND VSS_AD52 @T6G_MB_LIB.T6G(SCH_1):GND
AD53    GND VSS_AD53 @T6G_MB_LIB.T6G(SCH_1):GND
AD57    GND VSS_AD57 @T6G_MB_LIB.T6G(SCH_1):GND
AD59    GND VSS_AD59 @T6G_MB_LIB.T6G(SCH_1):GND
AD61    GND VSS_AD61 @T6G_MB_LIB.T6G(SCH_1):GND
AD64    GND VSS_AD64 @T6G_MB_LIB.T6G(SCH_1):GND
AD66    GND VSS_AD66 @T6G_MB_LIB.T6G(SCH_1):GND
AD68    GND VSS_AD68 @T6G_MB_LIB.T6G(SCH_1):GND
AD71    GND VSS_AD71 @T6G_MB_LIB.T6G(SCH_1):GND
AD73    GND VSS_AD73 @T6G_MB_LIB.T6G(SCH_1):GND
 AE1    GND VSS_AE1 @T6G_MB_LIB.T6G(SCH_1):GND
 AE6    GND VSS_AE6 @T6G_MB_LIB.T6G(SCH_1):GND
 AE8    GND VSS_AE8 @T6G_MB_LIB.T6G(SCH_1):GND
AE11    GND VSS_AE11 @T6G_MB_LIB.T6G(SCH_1):GND
AE13    GND VSS_AE13 @T6G_MB_LIB.T6G(SCH_1):GND
AE15    GND VSS_AE15 @T6G_MB_LIB.T6G(SCH_1):GND
AE18    GND VSS_AE18 @T6G_MB_LIB.T6G(SCH_1):GND
AE20    GND VSS_AE20 @T6G_MB_LIB.T6G(SCH_1):GND
AE22    GND VSS_AE22 @T6G_MB_LIB.T6G(SCH_1):GND
AE25    GND VSS_AE25 @T6G_MB_LIB.T6G(SCH_1):GND
AE28    GND VSS_AE28 @T6G_MB_LIB.T6G(SCH_1):GND
AE31    GND VSS_AE31 @T6G_MB_LIB.T6G(SCH_1):GND
AE34    GND VSS_AE34 @T6G_MB_LIB.T6G(SCH_1):GND
AE35    GND VSS_AE35 @T6G_MB_LIB.T6G(SCH_1):GND
AE36    GND VSS_AE36 @T6G_MB_LIB.T6G(SCH_1):GND
AE40    GND VSS_AE40 @T6G_MB_LIB.T6G(SCH_1):GND
AE41    GND VSS_AE41 @T6G_MB_LIB.T6G(SCH_1):GND
AE42    GND VSS_AE42 @T6G_MB_LIB.T6G(SCH_1):GND
AE45    GND VSS_AE45 @T6G_MB_LIB.T6G(SCH_1):GND
AE48    GND VSS_AE48 @T6G_MB_LIB.T6G(SCH_1):GND
AE51    GND VSS_AE51 @T6G_MB_LIB.T6G(SCH_1):GND
AE54    GND VSS_AE54 @T6G_MB_LIB.T6G(SCH_1):GND
AE56    GND VSS_AE56 @T6G_MB_LIB.T6G(SCH_1):GND
AE58    GND VSS_AE58 @T6G_MB_LIB.T6G(SCH_1):GND
AE61    GND VSS_AE61 @T6G_MB_LIB.T6G(SCH_1):GND
AE63    GND VSS_AE63 @T6G_MB_LIB.T6G(SCH_1):GND
AE65    GND VSS_AE65 @T6G_MB_LIB.T6G(SCH_1):GND
AE68    GND VSS_AE68 @T6G_MB_LIB.T6G(SCH_1):GND
AE70    GND VSS_AE70 @T6G_MB_LIB.T6G(SCH_1):GND
AE72    GND VSS_AE72 @T6G_MB_LIB.T6G(SCH_1):GND
AE75    GND VSS_AE75 @T6G_MB_LIB.T6G(SCH_1):GND
 AF3    GND VSS_AF3 @T6G_MB_LIB.T6G(SCH_1):GND
 AF8    GND VSS_AF8 @T6G_MB_LIB.T6G(SCH_1):GND
AF10    GND VSS_AF10 @T6G_MB_LIB.T6G(SCH_1):GND
AF15    GND VSS_AF15 @T6G_MB_LIB.T6G(SCH_1):GND
AF17    GND VSS_AF17 @T6G_MB_LIB.T6G(SCH_1):GND
AF22    GND VSS_AF22 @T6G_MB_LIB.T6G(SCH_1):GND
AF25    GND VSS_AF25 @T6G_MB_LIB.T6G(SCH_1):GND
AF28    GND VSS_AF28 @T6G_MB_LIB.T6G(SCH_1):GND
AF31    GND VSS_AF31 @T6G_MB_LIB.T6G(SCH_1):GND
AF34    GND VSS_AF34 @T6G_MB_LIB.T6G(SCH_1):GND
AF37    GND VSS_AF37 @T6G_MB_LIB.T6G(SCH_1):GND
AF39    GND VSS_AF39 @T6G_MB_LIB.T6G(SCH_1):GND
AF42    GND VSS_AF42 @T6G_MB_LIB.T6G(SCH_1):GND
AF45    GND VSS_AF45 @T6G_MB_LIB.T6G(SCH_1):GND
AF48    GND VSS_AF48 @T6G_MB_LIB.T6G(SCH_1):GND
AF51    GND VSS_AF51 @T6G_MB_LIB.T6G(SCH_1):GND
AF54    GND VSS_AF54 @T6G_MB_LIB.T6G(SCH_1):GND
AF59    GND VSS_AF59 @T6G_MB_LIB.T6G(SCH_1):GND
AF61    GND VSS_AF61 @T6G_MB_LIB.T6G(SCH_1):GND
AF66    GND VSS_AF66 @T6G_MB_LIB.T6G(SCH_1):GND
AF68    GND VSS_AF68 @T6G_MB_LIB.T6G(SCH_1):GND
AF73    GND VSS_AF73 @T6G_MB_LIB.T6G(SCH_1):GND
 AG1    GND VSS_AG1 @T6G_MB_LIB.T6G(SCH_1):GND
 AG4    GND VSS_AG4 @T6G_MB_LIB.T6G(SCH_1):GND
 AG6    GND VSS_AG6 @T6G_MB_LIB.T6G(SCH_1):GND
 AG8    GND VSS_AG8 @T6G_MB_LIB.T6G(SCH_1):GND
AG11    GND VSS_AG11 @T6G_MB_LIB.T6G(SCH_1):GND
AG13    GND VSS_AG13 @T6G_MB_LIB.T6G(SCH_1):GND
AG15    GND VSS_AG15 @T6G_MB_LIB.T6G(SCH_1):GND
AG18    GND VSS_AG18 @T6G_MB_LIB.T6G(SCH_1):GND
AG20    GND VSS_AG20 @T6G_MB_LIB.T6G(SCH_1):GND
AG22    GND VSS_AG22 @T6G_MB_LIB.T6G(SCH_1):GND
AG25    GND VSS_AG25 @T6G_MB_LIB.T6G(SCH_1):GND
AG28    GND VSS_AG28 @T6G_MB_LIB.T6G(SCH_1):GND
AG31    GND VSS_AG31 @T6G_MB_LIB.T6G(SCH_1):GND
AG34    GND VSS_AG34 @T6G_MB_LIB.T6G(SCH_1):GND
AG42    GND VSS_AG42 @T6G_MB_LIB.T6G(SCH_1):GND
AG45    GND VSS_AG45 @T6G_MB_LIB.T6G(SCH_1):GND
AG48    GND VSS_AG48 @T6G_MB_LIB.T6G(SCH_1):GND
AG51    GND VSS_AG51 @T6G_MB_LIB.T6G(SCH_1):GND
AG54    GND VSS_AG54 @T6G_MB_LIB.T6G(SCH_1):GND
AG56    GND VSS_AG56 @T6G_MB_LIB.T6G(SCH_1):GND
AG58    GND VSS_AG58 @T6G_MB_LIB.T6G(SCH_1):GND
AG61    GND VSS_AG61 @T6G_MB_LIB.T6G(SCH_1):GND
AG63    GND VSS_AG63 @T6G_MB_LIB.T6G(SCH_1):GND
AG65    GND VSS_AG65 @T6G_MB_LIB.T6G(SCH_1):GND
AG68    GND VSS_AG68 @T6G_MB_LIB.T6G(SCH_1):GND
AG70    GND VSS_AG70 @T6G_MB_LIB.T6G(SCH_1):GND
AG72    GND VSS_AG72 @T6G_MB_LIB.T6G(SCH_1):GND
AG75    GND VSS_AG75 @T6G_MB_LIB.T6G(SCH_1):GND
 AH3    GND VSS_AH3 @T6G_MB_LIB.T6G(SCH_1):GND
 AH5    GND VSS_AH5 @T6G_MB_LIB.T6G(SCH_1):GND
 AH8    GND VSS_AH8 @T6G_MB_LIB.T6G(SCH_1):GND
AH10    GND VSS_AH10 @T6G_MB_LIB.T6G(SCH_1):GND
AH12    GND VSS_AH12 @T6G_MB_LIB.T6G(SCH_1):GND
AH15    GND VSS_AH15 @T6G_MB_LIB.T6G(SCH_1):GND
AH17    GND VSS_AH17 @T6G_MB_LIB.T6G(SCH_1):GND
AH19    GND VSS_AH19 @T6G_MB_LIB.T6G(SCH_1):GND
AH23    GND VSS_AH23 @T6G_MB_LIB.T6G(SCH_1):GND
AH24    GND VSS_AH24 @T6G_MB_LIB.T6G(SCH_1):GND
AH25    GND VSS_AH25 @T6G_MB_LIB.T6G(SCH_1):GND
AH26    GND VSS_AH26 @T6G_MB_LIB.T6G(SCH_1):GND
AH27    GND VSS_AH27 @T6G_MB_LIB.T6G(SCH_1):GND
AH28    GND VSS_AH28 @T6G_MB_LIB.T6G(SCH_1):GND
AH29    GND VSS_AH29 @T6G_MB_LIB.T6G(SCH_1):GND
AH30    GND VSS_AH30 @T6G_MB_LIB.T6G(SCH_1):GND
AH31    GND VSS_AH31 @T6G_MB_LIB.T6G(SCH_1):GND
AH32    GND VSS_AH32 @T6G_MB_LIB.T6G(SCH_1):GND
AH34    GND VSS_AH34 @T6G_MB_LIB.T6G(SCH_1):GND
AH37    GND VSS_AH37 @T6G_MB_LIB.T6G(SCH_1):GND
AH39    GND VSS_AH39 @T6G_MB_LIB.T6G(SCH_1):GND
AH42    GND VSS_AH42 @T6G_MB_LIB.T6G(SCH_1):GND
AH43    GND VSS_AH43 @T6G_MB_LIB.T6G(SCH_1):GND
AH44    GND VSS_AH44 @T6G_MB_LIB.T6G(SCH_1):GND
AH45    GND VSS_AH45 @T6G_MB_LIB.T6G(SCH_1):GND
AH46    GND VSS_AH46 @T6G_MB_LIB.T6G(SCH_1):GND
AH47    GND VSS_AH47 @T6G_MB_LIB.T6G(SCH_1):GND
AH48    GND VSS_AH48 @T6G_MB_LIB.T6G(SCH_1):GND
AH49    GND VSS_AH49 @T6G_MB_LIB.T6G(SCH_1):GND
AH50    GND VSS_AH50 @T6G_MB_LIB.T6G(SCH_1):GND
AH51    GND VSS_AH51 @T6G_MB_LIB.T6G(SCH_1):GND
AH52    GND VSS_AH52 @T6G_MB_LIB.T6G(SCH_1):GND
AH53    GND VSS_AH53 @T6G_MB_LIB.T6G(SCH_1):GND
AH57    GND VSS_AH57 @T6G_MB_LIB.T6G(SCH_1):GND
AH59    GND VSS_AH59 @T6G_MB_LIB.T6G(SCH_1):GND
AH61    GND VSS_AH61 @T6G_MB_LIB.T6G(SCH_1):GND
AH64    GND VSS_AH64 @T6G_MB_LIB.T6G(SCH_1):GND
AH66    GND VSS_AH66 @T6G_MB_LIB.T6G(SCH_1):GND
AH68    GND VSS_AH68 @T6G_MB_LIB.T6G(SCH_1):GND
AH71    GND VSS_AH71 @T6G_MB_LIB.T6G(SCH_1):GND
AH73    GND VSS_AH73 @T6G_MB_LIB.T6G(SCH_1):GND
 AJ1    GND VSS_AJ1 @T6G_MB_LIB.T6G(SCH_1):GND
 AJ6    GND VSS_AJ6 @T6G_MB_LIB.T6G(SCH_1):GND
 AJ8    GND VSS_AJ8 @T6G_MB_LIB.T6G(SCH_1):GND
AJ15    GND VSS_AJ15 @T6G_MB_LIB.T6G(SCH_1):GND
AJ20    GND VSS_AJ20 @T6G_MB_LIB.T6G(SCH_1):GND
AJ22    GND VSS_AJ22 @T6G_MB_LIB.T6G(SCH_1):GND
AJ25    GND VSS_AJ25 @T6G_MB_LIB.T6G(SCH_1):GND
AJ28    GND VSS_AJ28 @T6G_MB_LIB.T6G(SCH_1):GND
AJ31    GND VSS_AJ31 @T6G_MB_LIB.T6G(SCH_1):GND
AJ34    GND VSS_AJ34 @T6G_MB_LIB.T6G(SCH_1):GND
AJ35    GND VSS_AJ35 @T6G_MB_LIB.T6G(SCH_1):GND
AJ36    GND VSS_AJ36 @T6G_MB_LIB.T6G(SCH_1):GND
AJ40    GND VSS_AJ40 @T6G_MB_LIB.T6G(SCH_1):GND
AJ41    GND VSS_AJ41 @T6G_MB_LIB.T6G(SCH_1):GND
AJ42    GND VSS_AJ42 @T6G_MB_LIB.T6G(SCH_1):GND
AJ45    GND VSS_AJ45 @T6G_MB_LIB.T6G(SCH_1):GND
AJ48    GND VSS_AJ48 @T6G_MB_LIB.T6G(SCH_1):GND
AJ51    GND VSS_AJ51 @T6G_MB_LIB.T6G(SCH_1):GND
AJ54    GND VSS_AJ54 @T6G_MB_LIB.T6G(SCH_1):GND
AJ56    GND VSS_AJ56 @T6G_MB_LIB.T6G(SCH_1):GND
AJ61    GND VSS_AJ61 @T6G_MB_LIB.T6G(SCH_1):GND
AJ63    GND VSS_AJ63 @T6G_MB_LIB.T6G(SCH_1):GND
AJ68    GND VSS_AJ68 @T6G_MB_LIB.T6G(SCH_1):GND
AJ70    GND VSS_AJ70 @T6G_MB_LIB.T6G(SCH_1):GND
AJ75    GND VSS_AJ75 @T6G_MB_LIB.T6G(SCH_1):GND
 AK3    GND VSS_AK3 @T6G_MB_LIB.T6G(SCH_1):GND
 AK5    GND VSS_AK5 @T6G_MB_LIB.T6G(SCH_1):GND
 AK8    GND VSS_AK8 @T6G_MB_LIB.T6G(SCH_1):GND

GENOA_SP5-SOCKET6096_13568-001,SMLF,IO,DGA^6000030  I23  U25
AM42    GND VSS_AM42 @T6G_MB_LIB.T6G(SCH_1):GND
AM43    GND VSS_AM43 @T6G_MB_LIB.T6G(SCH_1):GND
AM44    GND VSS_AM44 @T6G_MB_LIB.T6G(SCH_1):GND
AM45    GND VSS_AM45 @T6G_MB_LIB.T6G(SCH_1):GND
AM46    GND VSS_AM46 @T6G_MB_LIB.T6G(SCH_1):GND
AM47    GND VSS_AM47 @T6G_MB_LIB.T6G(SCH_1):GND
AM48    GND VSS_AM48 @T6G_MB_LIB.T6G(SCH_1):GND
AM49    GND VSS_AM49 @T6G_MB_LIB.T6G(SCH_1):GND
AM50    GND VSS_AM50 @T6G_MB_LIB.T6G(SCH_1):GND
AM51    GND VSS_AM51 @T6G_MB_LIB.T6G(SCH_1):GND
AM52    GND VSS_AM52 @T6G_MB_LIB.T6G(SCH_1):GND
AM53    GND VSS_AM53 @T6G_MB_LIB.T6G(SCH_1):GND
AM59    GND VSS_AM59 @T6G_MB_LIB.T6G(SCH_1):GND
AM61    GND VSS_AM61 @T6G_MB_LIB.T6G(SCH_1):GND
AM66    GND VSS_AM66 @T6G_MB_LIB.T6G(SCH_1):GND
AM68    GND VSS_AM68 @T6G_MB_LIB.T6G(SCH_1):GND
AM73    GND VSS_AM73 @T6G_MB_LIB.T6G(SCH_1):GND
 AN1    GND VSS_AN1 @T6G_MB_LIB.T6G(SCH_1):GND
 AN4    GND VSS_AN4 @T6G_MB_LIB.T6G(SCH_1):GND
 AN6    GND VSS_AN6 @T6G_MB_LIB.T6G(SCH_1):GND
 AN8    GND VSS_AN8 @T6G_MB_LIB.T6G(SCH_1):GND
AN11    GND VSS_AN11 @T6G_MB_LIB.T6G(SCH_1):GND
AN13    GND VSS_AN13 @T6G_MB_LIB.T6G(SCH_1):GND
AN15    GND VSS_AN15 @T6G_MB_LIB.T6G(SCH_1):GND
AN18    GND VSS_AN18 @T6G_MB_LIB.T6G(SCH_1):GND
AN22    GND VSS_AN22 @T6G_MB_LIB.T6G(SCH_1):GND
AN25    GND VSS_AN25 @T6G_MB_LIB.T6G(SCH_1):GND
AN28    GND VSS_AN28 @T6G_MB_LIB.T6G(SCH_1):GND
AN31    GND VSS_AN31 @T6G_MB_LIB.T6G(SCH_1):GND
AN34    GND VSS_AN34 @T6G_MB_LIB.T6G(SCH_1):GND
AN35    GND VSS_AN35 @T6G_MB_LIB.T6G(SCH_1):GND
AN36    GND VSS_AN36 @T6G_MB_LIB.T6G(SCH_1):GND
AN40    GND VSS_AN40 @T6G_MB_LIB.T6G(SCH_1):GND
AN41    GND VSS_AN41 @T6G_MB_LIB.T6G(SCH_1):GND
AN42    GND VSS_AN42 @T6G_MB_LIB.T6G(SCH_1):GND
AN45    GND VSS_AN45 @T6G_MB_LIB.T6G(SCH_1):GND
AN48    GND VSS_AN48 @T6G_MB_LIB.T6G(SCH_1):GND
AN51    GND VSS_AN51 @T6G_MB_LIB.T6G(SCH_1):GND
AN54    GND VSS_AN54 @T6G_MB_LIB.T6G(SCH_1):GND
AN56    GND VSS_AN56 @T6G_MB_LIB.T6G(SCH_1):GND
AN58    GND VSS_AN58 @T6G_MB_LIB.T6G(SCH_1):GND
AN61    GND VSS_AN61 @T6G_MB_LIB.T6G(SCH_1):GND
AN63    GND VSS_AN63 @T6G_MB_LIB.T6G(SCH_1):GND
AN65    GND VSS_AN65 @T6G_MB_LIB.T6G(SCH_1):GND
AN68    GND VSS_AN68 @T6G_MB_LIB.T6G(SCH_1):GND
AN70    GND VSS_AN70 @T6G_MB_LIB.T6G(SCH_1):GND
AN72    GND VSS_AN72 @T6G_MB_LIB.T6G(SCH_1):GND
AN75    GND VSS_AN75 @T6G_MB_LIB.T6G(SCH_1):GND
 AP3    GND VSS_AP3 @T6G_MB_LIB.T6G(SCH_1):GND
 AP5    GND VSS_AP5 @T6G_MB_LIB.T6G(SCH_1):GND
 AP8    GND VSS_AP8 @T6G_MB_LIB.T6G(SCH_1):GND
AP10    GND VSS_AP10 @T6G_MB_LIB.T6G(SCH_1):GND
AP12    GND VSS_AP12 @T6G_MB_LIB.T6G(SCH_1):GND
AP15    GND VSS_AP15 @T6G_MB_LIB.T6G(SCH_1):GND
AP17    GND VSS_AP17 @T6G_MB_LIB.T6G(SCH_1):GND
AP19    GND VSS_AP19 @T6G_MB_LIB.T6G(SCH_1):GND
AP22    GND VSS_AP22 @T6G_MB_LIB.T6G(SCH_1):GND
AP25    GND VSS_AP25 @T6G_MB_LIB.T6G(SCH_1):GND
AP28    GND VSS_AP28 @T6G_MB_LIB.T6G(SCH_1):GND
AP31    GND VSS_AP31 @T6G_MB_LIB.T6G(SCH_1):GND
AP34    GND VSS_AP34 @T6G_MB_LIB.T6G(SCH_1):GND
AP37    GND VSS_AP37 @T6G_MB_LIB.T6G(SCH_1):GND
AP39    GND VSS_AP39 @T6G_MB_LIB.T6G(SCH_1):GND
AP42    GND VSS_AP42 @T6G_MB_LIB.T6G(SCH_1):GND
AP45    GND VSS_AP45 @T6G_MB_LIB.T6G(SCH_1):GND
AP48    GND VSS_AP48 @T6G_MB_LIB.T6G(SCH_1):GND
AP51    GND VSS_AP51 @T6G_MB_LIB.T6G(SCH_1):GND
AP54    GND VSS_AP54 @T6G_MB_LIB.T6G(SCH_1):GND
AP57    GND VSS_AP57 @T6G_MB_LIB.T6G(SCH_1):GND
AP59    GND VSS_AP59 @T6G_MB_LIB.T6G(SCH_1):GND
AP61    GND VSS_AP61 @T6G_MB_LIB.T6G(SCH_1):GND
AP64    GND VSS_AP64 @T6G_MB_LIB.T6G(SCH_1):GND
AP66    GND VSS_AP66 @T6G_MB_LIB.T6G(SCH_1):GND
AP68    GND VSS_AP68 @T6G_MB_LIB.T6G(SCH_1):GND
AP71    GND VSS_AP71 @T6G_MB_LIB.T6G(SCH_1):GND
AP73    GND VSS_AP73 @T6G_MB_LIB.T6G(SCH_1):GND
 AR1    GND VSS_AR1 @T6G_MB_LIB.T6G(SCH_1):GND
 AR5    GND VSS_AR5 @T6G_MB_LIB.T6G(SCH_1):GND
 AR6    GND VSS_AR6 @T6G_MB_LIB.T6G(SCH_1):GND
 AR8    GND VSS_AR8 @T6G_MB_LIB.T6G(SCH_1):GND
 AR9    GND VSS_AR9 @T6G_MB_LIB.T6G(SCH_1):GND
AR12    GND VSS_AR12 @T6G_MB_LIB.T6G(SCH_1):GND
AR13    GND VSS_AR13 @T6G_MB_LIB.T6G(SCH_1):GND
AR15    GND VSS_AR15 @T6G_MB_LIB.T6G(SCH_1):GND
AR16    GND VSS_AR16 @T6G_MB_LIB.T6G(SCH_1):GND
AR19    GND VSS_AR19 @T6G_MB_LIB.T6G(SCH_1):GND
AR20    GND VSS_AR20 @T6G_MB_LIB.T6G(SCH_1):GND
AR22    GND VSS_AR22 @T6G_MB_LIB.T6G(SCH_1):GND
AR24    GND VSS_AR24 @T6G_MB_LIB.T6G(SCH_1):GND
AR26    GND VSS_AR26 @T6G_MB_LIB.T6G(SCH_1):GND
AR28    GND VSS_AR28 @T6G_MB_LIB.T6G(SCH_1):GND
AR30    GND VSS_AR30 @T6G_MB_LIB.T6G(SCH_1):GND
AR32    GND VSS_AR32 @T6G_MB_LIB.T6G(SCH_1):GND
AR34    GND VSS_AR34 @T6G_MB_LIB.T6G(SCH_1):GND
AR36    GND VSS_AR36 @T6G_MB_LIB.T6G(SCH_1):GND
AR41    GND VSS_AR41 @T6G_MB_LIB.T6G(SCH_1):GND
AR43    GND VSS_AR43 @T6G_MB_LIB.T6G(SCH_1):GND
AR45    GND VSS_AR45 @T6G_MB_LIB.T6G(SCH_1):GND
AR47    GND VSS_AR47 @T6G_MB_LIB.T6G(SCH_1):GND
AR49    GND VSS_AR49 @T6G_MB_LIB.T6G(SCH_1):GND
AR51    GND VSS_AR51 @T6G_MB_LIB.T6G(SCH_1):GND
AR53    GND VSS_AR53 @T6G_MB_LIB.T6G(SCH_1):GND
AR56    GND VSS_AR56 @T6G_MB_LIB.T6G(SCH_1):GND
AR57    GND VSS_AR57 @T6G_MB_LIB.T6G(SCH_1):GND
AR60    GND VSS_AR60 @T6G_MB_LIB.T6G(SCH_1):GND
AR61    GND VSS_AR61 @T6G_MB_LIB.T6G(SCH_1):GND
AR63    GND VSS_AR63 @T6G_MB_LIB.T6G(SCH_1):GND
AR64    GND VSS_AR64 @T6G_MB_LIB.T6G(SCH_1):GND
AR67    GND VSS_AR67 @T6G_MB_LIB.T6G(SCH_1):GND
AR68    GND VSS_AR68 @T6G_MB_LIB.T6G(SCH_1):GND
AR70    GND VSS_AR70 @T6G_MB_LIB.T6G(SCH_1):GND
AR71    GND VSS_AR71 @T6G_MB_LIB.T6G(SCH_1):GND
AR75    GND VSS_AR75 @T6G_MB_LIB.T6G(SCH_1):GND
 AT3    GND VSS_AT3 @T6G_MB_LIB.T6G(SCH_1):GND
 AT4    GND VSS_AT4 @T6G_MB_LIB.T6G(SCH_1):GND
 AT5    GND VSS_AT5 @T6G_MB_LIB.T6G(SCH_1):GND
 AT6    GND VSS_AT6 @T6G_MB_LIB.T6G(SCH_1):GND
 AT8    GND VSS_AT8 @T6G_MB_LIB.T6G(SCH_1):GND
 AT9    GND VSS_AT9 @T6G_MB_LIB.T6G(SCH_1):GND
AT10    GND VSS_AT10 @T6G_MB_LIB.T6G(SCH_1):GND
AT12    GND VSS_AT12 @T6G_MB_LIB.T6G(SCH_1):GND
AT13    GND VSS_AT13 @T6G_MB_LIB.T6G(SCH_1):GND
AT15    GND VSS_AT15 @T6G_MB_LIB.T6G(SCH_1):GND
AT16    GND VSS_AT16 @T6G_MB_LIB.T6G(SCH_1):GND
AT17    GND VSS_AT17 @T6G_MB_LIB.T6G(SCH_1):GND
AT19    GND VSS_AT19 @T6G_MB_LIB.T6G(SCH_1):GND
AT20    GND VSS_AT20 @T6G_MB_LIB.T6G(SCH_1):GND
AT23    GND VSS_AT23 @T6G_MB_LIB.T6G(SCH_1):GND
AT25    GND VSS_AT25 @T6G_MB_LIB.T6G(SCH_1):GND
AT27    GND VSS_AT27 @T6G_MB_LIB.T6G(SCH_1):GND
AT29    GND VSS_AT29 @T6G_MB_LIB.T6G(SCH_1):GND
AT31    GND VSS_AT31 @T6G_MB_LIB.T6G(SCH_1):GND
AT33    GND VSS_AT33 @T6G_MB_LIB.T6G(SCH_1):GND
AT35    GND VSS_AT35 @T6G_MB_LIB.T6G(SCH_1):GND
AT37    GND VSS_AT37 @T6G_MB_LIB.T6G(SCH_1):GND
AT40    GND VSS_AT40 @T6G_MB_LIB.T6G(SCH_1):GND
AT42    GND VSS_AT42 @T6G_MB_LIB.T6G(SCH_1):GND
AT44    GND VSS_AT44 @T6G_MB_LIB.T6G(SCH_1):GND
AT46    GND VSS_AT46 @T6G_MB_LIB.T6G(SCH_1):GND
AT48    GND VSS_AT48 @T6G_MB_LIB.T6G(SCH_1):GND
AT50    GND VSS_AT50 @T6G_MB_LIB.T6G(SCH_1):GND
AT52    GND VSS_AT52 @T6G_MB_LIB.T6G(SCH_1):GND
AT54    GND VSS_AT54 @T6G_MB_LIB.T6G(SCH_1):GND
AT56    GND VSS_AT56 @T6G_MB_LIB.T6G(SCH_1):GND
AT57    GND VSS_AT57 @T6G_MB_LIB.T6G(SCH_1):GND
AT59    GND VSS_AT59 @T6G_MB_LIB.T6G(SCH_1):GND
AT60    GND VSS_AT60 @T6G_MB_LIB.T6G(SCH_1):GND
AT61    GND VSS_AT61 @T6G_MB_LIB.T6G(SCH_1):GND
AT63    GND VSS_AT63 @T6G_MB_LIB.T6G(SCH_1):GND
AT64    GND VSS_AT64 @T6G_MB_LIB.T6G(SCH_1):GND
AT66    GND VSS_AT66 @T6G_MB_LIB.T6G(SCH_1):GND
AT67    GND VSS_AT67 @T6G_MB_LIB.T6G(SCH_1):GND
AT68    GND VSS_AT68 @T6G_MB_LIB.T6G(SCH_1):GND
AT70    GND VSS_AT70 @T6G_MB_LIB.T6G(SCH_1):GND
AT71    GND VSS_AT71 @T6G_MB_LIB.T6G(SCH_1):GND
AT72    GND VSS_AT72 @T6G_MB_LIB.T6G(SCH_1):GND
AT73    GND VSS_AT73 @T6G_MB_LIB.T6G(SCH_1):GND
 AU1    GND VSS_AU1 @T6G_MB_LIB.T6G(SCH_1):GND
 AU3    GND VSS_AU3 @T6G_MB_LIB.T6G(SCH_1):GND
 AU4    GND VSS_AU4 @T6G_MB_LIB.T6G(SCH_1):GND
 AU6    GND VSS_AU6 @T6G_MB_LIB.T6G(SCH_1):GND
 AU8    GND VSS_AU8 @T6G_MB_LIB.T6G(SCH_1):GND
AU11    GND VSS_AU11 @T6G_MB_LIB.T6G(SCH_1):GND
AU13    GND VSS_AU13 @T6G_MB_LIB.T6G(SCH_1):GND
AU15    GND VSS_AU15 @T6G_MB_LIB.T6G(SCH_1):GND
AU18    GND VSS_AU18 @T6G_MB_LIB.T6G(SCH_1):GND
AU20    GND VSS_AU20 @T6G_MB_LIB.T6G(SCH_1):GND
AU22    GND VSS_AU22 @T6G_MB_LIB.T6G(SCH_1):GND
AU24    GND VSS_AU24 @T6G_MB_LIB.T6G(SCH_1):GND
AU26    GND VSS_AU26 @T6G_MB_LIB.T6G(SCH_1):GND
AU28    GND VSS_AU28 @T6G_MB_LIB.T6G(SCH_1):GND
AU30    GND VSS_AU30 @T6G_MB_LIB.T6G(SCH_1):GND
AU32    GND VSS_AU32 @T6G_MB_LIB.T6G(SCH_1):GND
AU34    GND VSS_AU34 @T6G_MB_LIB.T6G(SCH_1):GND
AU36    GND VSS_AU36 @T6G_MB_LIB.T6G(SCH_1):GND
AU41    GND VSS_AU41 @T6G_MB_LIB.T6G(SCH_1):GND
AU43    GND VSS_AU43 @T6G_MB_LIB.T6G(SCH_1):GND
AU45    GND VSS_AU45 @T6G_MB_LIB.T6G(SCH_1):GND
AU47    GND VSS_AU47 @T6G_MB_LIB.T6G(SCH_1):GND
AU49    GND VSS_AU49 @T6G_MB_LIB.T6G(SCH_1):GND
AU51    GND VSS_AU51 @T6G_MB_LIB.T6G(SCH_1):GND
AU53    GND VSS_AU53 @T6G_MB_LIB.T6G(SCH_1):GND
AU56    GND VSS_AU56 @T6G_MB_LIB.T6G(SCH_1):GND
AU58    GND VSS_AU58 @T6G_MB_LIB.T6G(SCH_1):GND
AU61    GND VSS_AU61 @T6G_MB_LIB.T6G(SCH_1):GND
AU63    GND VSS_AU63 @T6G_MB_LIB.T6G(SCH_1):GND
AU65    GND VSS_AU65 @T6G_MB_LIB.T6G(SCH_1):GND
AU68    GND VSS_AU68 @T6G_MB_LIB.T6G(SCH_1):GND
AU70    GND VSS_AU70 @T6G_MB_LIB.T6G(SCH_1):GND
AU72    GND VSS_AU72 @T6G_MB_LIB.T6G(SCH_1):GND
AU73    GND VSS_AU73 @T6G_MB_LIB.T6G(SCH_1):GND
AU75    GND VSS_AU75 @T6G_MB_LIB.T6G(SCH_1):GND
 AV3    GND VSS_AV3 @T6G_MB_LIB.T6G(SCH_1):GND
 AV8    GND VSS_AV8 @T6G_MB_LIB.T6G(SCH_1):GND
AV10    GND VSS_AV10 @T6G_MB_LIB.T6G(SCH_1):GND
AV15    GND VSS_AV15 @T6G_MB_LIB.T6G(SCH_1):GND
AV17    GND VSS_AV17 @T6G_MB_LIB.T6G(SCH_1):GND
AV23    GND VSS_AV23 @T6G_MB_LIB.T6G(SCH_1):GND
AV25    GND VSS_AV25 @T6G_MB_LIB.T6G(SCH_1):GND
AV27    GND VSS_AV27 @T6G_MB_LIB.T6G(SCH_1):GND
AV29    GND VSS_AV29 @T6G_MB_LIB.T6G(SCH_1):GND
AV31    GND VSS_AV31 @T6G_MB_LIB.T6G(SCH_1):GND
AV33    GND VSS_AV33 @T6G_MB_LIB.T6G(SCH_1):GND
AV35    GND VSS_AV35 @T6G_MB_LIB.T6G(SCH_1):GND
AV37    GND VSS_AV37 @T6G_MB_LIB.T6G(SCH_1):GND
AV40    GND VSS_AV40 @T6G_MB_LIB.T6G(SCH_1):GND
AV42    GND VSS_AV42 @T6G_MB_LIB.T6G(SCH_1):GND
AV44    GND VSS_AV44 @T6G_MB_LIB.T6G(SCH_1):GND
AV46    GND VSS_AV46 @T6G_MB_LIB.T6G(SCH_1):GND
AV48    GND VSS_AV48 @T6G_MB_LIB.T6G(SCH_1):GND
AV50    GND VSS_AV50 @T6G_MB_LIB.T6G(SCH_1):GND
AV52    GND VSS_AV52 @T6G_MB_LIB.T6G(SCH_1):GND
AV54    GND VSS_AV54 @T6G_MB_LIB.T6G(SCH_1):GND
AV59    GND VSS_AV59 @T6G_MB_LIB.T6G(SCH_1):GND
AV61    GND VSS_AV61 @T6G_MB_LIB.T6G(SCH_1):GND
AV66    GND VSS_AV66 @T6G_MB_LIB.T6G(SCH_1):GND
AV68    GND VSS_AV68 @T6G_MB_LIB.T6G(SCH_1):GND
AV73    GND VSS_AV73 @T6G_MB_LIB.T6G(SCH_1):GND
 AW1    GND VSS_AW1 @T6G_MB_LIB.T6G(SCH_1):GND
 AW4    GND VSS_AW4 @T6G_MB_LIB.T6G(SCH_1):GND
 AW6    GND VSS_AW6 @T6G_MB_LIB.T6G(SCH_1):GND
 AW8    GND VSS_AW8 @T6G_MB_LIB.T6G(SCH_1):GND
AW11    GND VSS_AW11 @T6G_MB_LIB.T6G(SCH_1):GND
AW13    GND VSS_AW13 @T6G_MB_LIB.T6G(SCH_1):GND
AW15    GND VSS_AW15 @T6G_MB_LIB.T6G(SCH_1):GND
AW18    GND VSS_AW18 @T6G_MB_LIB.T6G(SCH_1):GND
AW20    GND VSS_AW20 @T6G_MB_LIB.T6G(SCH_1):GND
AW22    GND VSS_AW22 @T6G_MB_LIB.T6G(SCH_1):GND
AW24    GND VSS_AW24 @T6G_MB_LIB.T6G(SCH_1):GND
AW26    GND VSS_AW26 @T6G_MB_LIB.T6G(SCH_1):GND
AW28    GND VSS_AW28 @T6G_MB_LIB.T6G(SCH_1):GND
AW49    GND VSS_AW49 @T6G_MB_LIB.T6G(SCH_1):GND
AW51    GND VSS_AW51 @T6G_MB_LIB.T6G(SCH_1):GND
AW53    GND VSS_AW53 @T6G_MB_LIB.T6G(SCH_1):GND
AW56    GND VSS_AW56 @T6G_MB_LIB.T6G(SCH_1):GND
AW58    GND VSS_AW58 @T6G_MB_LIB.T6G(SCH_1):GND
AW61    GND VSS_AW61 @T6G_MB_LIB.T6G(SCH_1):GND

GENOA_SP5-SOCKET6096_13568-001,SMLF,IO,DGA^6000030  I24  U25
AW63    GND VSS_AW63 @T6G_MB_LIB.T6G(SCH_1):GND
AW65    GND VSS_AW65 @T6G_MB_LIB.T6G(SCH_1):GND
AW68    GND VSS_AW68 @T6G_MB_LIB.T6G(SCH_1):GND
AW70    GND VSS_AW70 @T6G_MB_LIB.T6G(SCH_1):GND
AW72    GND VSS_AW72 @T6G_MB_LIB.T6G(SCH_1):GND
AW75    GND VSS_AW75 @T6G_MB_LIB.T6G(SCH_1):GND
 AY3    GND VSS_AY3 @T6G_MB_LIB.T6G(SCH_1):GND
 AY5    GND VSS_AY5 @T6G_MB_LIB.T6G(SCH_1):GND
 AY8    GND VSS_AY8 @T6G_MB_LIB.T6G(SCH_1):GND
AY10    GND VSS_AY10 @T6G_MB_LIB.T6G(SCH_1):GND
AY12    GND VSS_AY12 @T6G_MB_LIB.T6G(SCH_1):GND
AY15    GND VSS_AY15 @T6G_MB_LIB.T6G(SCH_1):GND
AY17    GND VSS_AY17 @T6G_MB_LIB.T6G(SCH_1):GND
AY19    GND VSS_AY19 @T6G_MB_LIB.T6G(SCH_1):GND
AY23    GND VSS_AY23 @T6G_MB_LIB.T6G(SCH_1):GND
AY25    GND VSS_AY25 @T6G_MB_LIB.T6G(SCH_1):GND
AY27    GND VSS_AY27 @T6G_MB_LIB.T6G(SCH_1):GND
AY48    GND VSS_AY48 @T6G_MB_LIB.T6G(SCH_1):GND
AY50    GND VSS_AY50 @T6G_MB_LIB.T6G(SCH_1):GND
AY52    GND VSS_AY52 @T6G_MB_LIB.T6G(SCH_1):GND
AY54    GND VSS_AY54 @T6G_MB_LIB.T6G(SCH_1):GND
AY57    GND VSS_AY57 @T6G_MB_LIB.T6G(SCH_1):GND
AY59    GND VSS_AY59 @T6G_MB_LIB.T6G(SCH_1):GND
AY61    GND VSS_AY61 @T6G_MB_LIB.T6G(SCH_1):GND
AY64    GND VSS_AY64 @T6G_MB_LIB.T6G(SCH_1):GND
AY66    GND VSS_AY66 @T6G_MB_LIB.T6G(SCH_1):GND
AY68    GND VSS_AY68 @T6G_MB_LIB.T6G(SCH_1):GND
AY71    GND VSS_AY71 @T6G_MB_LIB.T6G(SCH_1):GND
AY73    GND VSS_AY73 @T6G_MB_LIB.T6G(SCH_1):GND
 BA1    GND VSS_BA1 @T6G_MB_LIB.T6G(SCH_1):GND
 BA6    GND VSS_BA6 @T6G_MB_LIB.T6G(SCH_1):GND
 BA8    GND VSS_BA8 @T6G_MB_LIB.T6G(SCH_1):GND
BA13    GND VSS_BA13 @T6G_MB_LIB.T6G(SCH_1):GND
BA15    GND VSS_BA15 @T6G_MB_LIB.T6G(SCH_1):GND
BA20    GND VSS_BA20 @T6G_MB_LIB.T6G(SCH_1):GND
BA22    GND VSS_BA22 @T6G_MB_LIB.T6G(SCH_1):GND
BA24    GND VSS_BA24 @T6G_MB_LIB.T6G(SCH_1):GND
BA26    GND VSS_BA26 @T6G_MB_LIB.T6G(SCH_1):GND
BA28    GND VSS_BA28 @T6G_MB_LIB.T6G(SCH_1):GND
BA49    GND VSS_BA49 @T6G_MB_LIB.T6G(SCH_1):GND
BA51    GND VSS_BA51 @T6G_MB_LIB.T6G(SCH_1):GND
BA53    GND VSS_BA53 @T6G_MB_LIB.T6G(SCH_1):GND
BA56    GND VSS_BA56 @T6G_MB_LIB.T6G(SCH_1):GND
BA61    GND VSS_BA61 @T6G_MB_LIB.T6G(SCH_1):GND
BA63    GND VSS_BA63 @T6G_MB_LIB.T6G(SCH_1):GND
BA68    GND VSS_BA68 @T6G_MB_LIB.T6G(SCH_1):GND
BA70    GND VSS_BA70 @T6G_MB_LIB.T6G(SCH_1):GND
BA75    GND VSS_BA75 @T6G_MB_LIB.T6G(SCH_1):GND
 BB3    GND VSS_BB3 @T6G_MB_LIB.T6G(SCH_1):GND
 BB5    GND VSS_BB5 @T6G_MB_LIB.T6G(SCH_1):GND
 BB8    GND VSS_BB8 @T6G_MB_LIB.T6G(SCH_1):GND
BB10    GND VSS_BB10 @T6G_MB_LIB.T6G(SCH_1):GND
BB12    GND VSS_BB12 @T6G_MB_LIB.T6G(SCH_1):GND
BB15    GND VSS_BB15 @T6G_MB_LIB.T6G(SCH_1):GND
BB17    GND VSS_BB17 @T6G_MB_LIB.T6G(SCH_1):GND
BB19    GND VSS_BB19 @T6G_MB_LIB.T6G(SCH_1):GND
BB23    GND VSS_BB23 @T6G_MB_LIB.T6G(SCH_1):GND
BB25    GND VSS_BB25 @T6G_MB_LIB.T6G(SCH_1):GND
BB27    GND VSS_BB27 @T6G_MB_LIB.T6G(SCH_1):GND
BB48    GND VSS_BB48 @T6G_MB_LIB.T6G(SCH_1):GND
BB50    GND VSS_BB50 @T6G_MB_LIB.T6G(SCH_1):GND
BB52    GND VSS_BB52 @T6G_MB_LIB.T6G(SCH_1):GND
BB54    GND VSS_BB54 @T6G_MB_LIB.T6G(SCH_1):GND
BB57    GND VSS_BB57 @T6G_MB_LIB.T6G(SCH_1):GND
BB59    GND VSS_BB59 @T6G_MB_LIB.T6G(SCH_1):GND
BB61    GND VSS_BB61 @T6G_MB_LIB.T6G(SCH_1):GND
BB64    GND VSS_BB64 @T6G_MB_LIB.T6G(SCH_1):GND
BB66    GND VSS_BB66 @T6G_MB_LIB.T6G(SCH_1):GND
BB68    GND VSS_BB68 @T6G_MB_LIB.T6G(SCH_1):GND
BB71    GND VSS_BB71 @T6G_MB_LIB.T6G(SCH_1):GND
BB73    GND VSS_BB73 @T6G_MB_LIB.T6G(SCH_1):GND
 BC1    GND VSS_BC1 @T6G_MB_LIB.T6G(SCH_1):GND
 BC4    GND VSS_BC4 @T6G_MB_LIB.T6G(SCH_1):GND
 BC6    GND VSS_BC6 @T6G_MB_LIB.T6G(SCH_1):GND
 BC8    GND VSS_BC8 @T6G_MB_LIB.T6G(SCH_1):GND
BC11    GND VSS_BC11 @T6G_MB_LIB.T6G(SCH_1):GND
BC13    GND VSS_BC13 @T6G_MB_LIB.T6G(SCH_1):GND
BC15    GND VSS_BC15 @T6G_MB_LIB.T6G(SCH_1):GND
BC18    GND VSS_BC18 @T6G_MB_LIB.T6G(SCH_1):GND
BC20    GND VSS_BC20 @T6G_MB_LIB.T6G(SCH_1):GND
BC22    GND VSS_BC22 @T6G_MB_LIB.T6G(SCH_1):GND
BC24    GND VSS_BC24 @T6G_MB_LIB.T6G(SCH_1):GND
BC26    GND VSS_BC26 @T6G_MB_LIB.T6G(SCH_1):GND
BC28    GND VSS_BC28 @T6G_MB_LIB.T6G(SCH_1):GND
BC49    GND VSS_BC49 @T6G_MB_LIB.T6G(SCH_1):GND
BC50    GND VSS_BC50 @T6G_MB_LIB.T6G(SCH_1):GND
BC51    GND VSS_BC51 @T6G_MB_LIB.T6G(SCH_1):GND
BC53    GND VSS_BC53 @T6G_MB_LIB.T6G(SCH_1):GND
BC56    GND VSS_BC56 @T6G_MB_LIB.T6G(SCH_1):GND
BC58    GND VSS_BC58 @T6G_MB_LIB.T6G(SCH_1):GND
BC61    GND VSS_BC61 @T6G_MB_LIB.T6G(SCH_1):GND
BC63    GND VSS_BC63 @T6G_MB_LIB.T6G(SCH_1):GND
BC65    GND VSS_BC65 @T6G_MB_LIB.T6G(SCH_1):GND
BC68    GND VSS_BC68 @T6G_MB_LIB.T6G(SCH_1):GND
BC70    GND VSS_BC70 @T6G_MB_LIB.T6G(SCH_1):GND
BC72    GND VSS_BC72 @T6G_MB_LIB.T6G(SCH_1):GND
BC75    GND VSS_BC75 @T6G_MB_LIB.T6G(SCH_1):GND
 BD3    GND VSS_BD3 @T6G_MB_LIB.T6G(SCH_1):GND
 BD8    GND VSS_BD8 @T6G_MB_LIB.T6G(SCH_1):GND
BD10    GND VSS_BD10 @T6G_MB_LIB.T6G(SCH_1):GND
BD15    GND VSS_BD15 @T6G_MB_LIB.T6G(SCH_1):GND
BD17    GND VSS_BD17 @T6G_MB_LIB.T6G(SCH_1):GND
BD23    GND VSS_BD23 @T6G_MB_LIB.T6G(SCH_1):GND
BD25    GND VSS_BD25 @T6G_MB_LIB.T6G(SCH_1):GND
BD27    GND VSS_BD27 @T6G_MB_LIB.T6G(SCH_1):GND
BD49    GND VSS_BD49 @T6G_MB_LIB.T6G(SCH_1):GND
BD51    GND VSS_BD51 @T6G_MB_LIB.T6G(SCH_1):GND
BD53    GND VSS_BD53 @T6G_MB_LIB.T6G(SCH_1):GND
BD57    GND VSS_BD57 @T6G_MB_LIB.T6G(SCH_1):GND
BD59    GND VSS_BD59 @T6G_MB_LIB.T6G(SCH_1):GND
BD61    GND VSS_BD61 @T6G_MB_LIB.T6G(SCH_1):GND
BD64    GND VSS_BD64 @T6G_MB_LIB.T6G(SCH_1):GND
BD66    GND VSS_BD66 @T6G_MB_LIB.T6G(SCH_1):GND
BD68    GND VSS_BD68 @T6G_MB_LIB.T6G(SCH_1):GND
BD71    GND VSS_BD71 @T6G_MB_LIB.T6G(SCH_1):GND
BD73    GND VSS_BD73 @T6G_MB_LIB.T6G(SCH_1):GND
 BF3    GND VSS_BF3 @T6G_MB_LIB.T6G(SCH_1):GND
 BF5    GND VSS_BF5 @T6G_MB_LIB.T6G(SCH_1):GND
 BF8    GND VSS_BF8 @T6G_MB_LIB.T6G(SCH_1):GND
BF10    GND VSS_BF10 @T6G_MB_LIB.T6G(SCH_1):GND
BF12    GND VSS_BF12 @T6G_MB_LIB.T6G(SCH_1):GND
BF15    GND VSS_BF15 @T6G_MB_LIB.T6G(SCH_1):GND
BF17    GND VSS_BF17 @T6G_MB_LIB.T6G(SCH_1):GND
BF19    GND VSS_BF19 @T6G_MB_LIB.T6G(SCH_1):GND
BF22    GND VSS_BF22 @T6G_MB_LIB.T6G(SCH_1):GND
BF24    GND VSS_BF24 @T6G_MB_LIB.T6G(SCH_1):GND
BF26    GND VSS_BF26 @T6G_MB_LIB.T6G(SCH_1):GND
BF28    GND VSS_BF28 @T6G_MB_LIB.T6G(SCH_1):GND
BF49    GND VSS_BF49 @T6G_MB_LIB.T6G(SCH_1):GND
BF50    GND VSS_BF50 @T6G_MB_LIB.T6G(SCH_1):GND
BF52    GND VSS_BF52 @T6G_MB_LIB.T6G(SCH_1):GND
BF54    GND VSS_BF54 @T6G_MB_LIB.T6G(SCH_1):GND
BF59    GND VSS_BF59 @T6G_MB_LIB.T6G(SCH_1):GND
BF61    GND VSS_BF61 @T6G_MB_LIB.T6G(SCH_1):GND
BF66    GND VSS_BF66 @T6G_MB_LIB.T6G(SCH_1):GND
BF68    GND VSS_BF68 @T6G_MB_LIB.T6G(SCH_1):GND
BF73    GND VSS_BF73 @T6G_MB_LIB.T6G(SCH_1):GND
 BG1    GND VSS_BG1 @T6G_MB_LIB.T6G(SCH_1):GND
 BG4    GND VSS_BG4 @T6G_MB_LIB.T6G(SCH_1):GND
 BG6    GND VSS_BG6 @T6G_MB_LIB.T6G(SCH_1):GND
 BG8    GND VSS_BG8 @T6G_MB_LIB.T6G(SCH_1):GND
BG11    GND VSS_BG11 @T6G_MB_LIB.T6G(SCH_1):GND
BG13    GND VSS_BG13 @T6G_MB_LIB.T6G(SCH_1):GND
BG15    GND VSS_BG15 @T6G_MB_LIB.T6G(SCH_1):GND
BG18    GND VSS_BG18 @T6G_MB_LIB.T6G(SCH_1):GND
BG20    GND VSS_BG20 @T6G_MB_LIB.T6G(SCH_1):GND
BG23    GND VSS_BG23 @T6G_MB_LIB.T6G(SCH_1):GND
BG25    GND VSS_BG25 @T6G_MB_LIB.T6G(SCH_1):GND
BG27    GND VSS_BG27 @T6G_MB_LIB.T6G(SCH_1):GND
BG49    GND VSS_BG49 @T6G_MB_LIB.T6G(SCH_1):GND
BG51    GND VSS_BG51 @T6G_MB_LIB.T6G(SCH_1):GND
BG53    GND VSS_BG53 @T6G_MB_LIB.T6G(SCH_1):GND
BG56    GND VSS_BG56 @T6G_MB_LIB.T6G(SCH_1):GND
BG58    GND VSS_BG58 @T6G_MB_LIB.T6G(SCH_1):GND
BG61    GND VSS_BG61 @T6G_MB_LIB.T6G(SCH_1):GND
BG63    GND VSS_BG63 @T6G_MB_LIB.T6G(SCH_1):GND
BG65    GND VSS_BG65 @T6G_MB_LIB.T6G(SCH_1):GND
BG68    GND VSS_BG68 @T6G_MB_LIB.T6G(SCH_1):GND
BG70    GND VSS_BG70 @T6G_MB_LIB.T6G(SCH_1):GND
BG72    GND VSS_BG72 @T6G_MB_LIB.T6G(SCH_1):GND
BG75    GND VSS_BG75 @T6G_MB_LIB.T6G(SCH_1):GND
 BH3    GND VSS_BH3 @T6G_MB_LIB.T6G(SCH_1):GND
 BH5    GND VSS_BH5 @T6G_MB_LIB.T6G(SCH_1):GND
 BH8    GND VSS_BH8 @T6G_MB_LIB.T6G(SCH_1):GND
BH10    GND VSS_BH10 @T6G_MB_LIB.T6G(SCH_1):GND
BH12    GND VSS_BH12 @T6G_MB_LIB.T6G(SCH_1):GND
BH15    GND VSS_BH15 @T6G_MB_LIB.T6G(SCH_1):GND
BH17    GND VSS_BH17 @T6G_MB_LIB.T6G(SCH_1):GND
BH19    GND VSS_BH19 @T6G_MB_LIB.T6G(SCH_1):GND
BH22    GND VSS_BH22 @T6G_MB_LIB.T6G(SCH_1):GND
BH24    GND VSS_BH24 @T6G_MB_LIB.T6G(SCH_1):GND
BH26    GND VSS_BH26 @T6G_MB_LIB.T6G(SCH_1):GND
BH28    GND VSS_BH28 @T6G_MB_LIB.T6G(SCH_1):GND
BH49    GND VSS_BH49 @T6G_MB_LIB.T6G(SCH_1):GND
BH50    GND VSS_BH50 @T6G_MB_LIB.T6G(SCH_1):GND
BH52    GND VSS_BH52 @T6G_MB_LIB.T6G(SCH_1):GND
BH54    GND VSS_BH54 @T6G_MB_LIB.T6G(SCH_1):GND
BH57    GND VSS_BH57 @T6G_MB_LIB.T6G(SCH_1):GND
BH59    GND VSS_BH59 @T6G_MB_LIB.T6G(SCH_1):GND
BH61    GND VSS_BH61 @T6G_MB_LIB.T6G(SCH_1):GND
BH64    GND VSS_BH64 @T6G_MB_LIB.T6G(SCH_1):GND
BH66    GND VSS_BH66 @T6G_MB_LIB.T6G(SCH_1):GND
BH68    GND VSS_BH68 @T6G_MB_LIB.T6G(SCH_1):GND
BH71    GND VSS_BH71 @T6G_MB_LIB.T6G(SCH_1):GND
BH73    GND VSS_BH73 @T6G_MB_LIB.T6G(SCH_1):GND
 BJ1    GND VSS_BJ1 @T6G_MB_LIB.T6G(SCH_1):GND
 BJ6    GND VSS_BJ6 @T6G_MB_LIB.T6G(SCH_1):GND
 BJ8    GND VSS_BJ8 @T6G_MB_LIB.T6G(SCH_1):GND
BJ13    GND VSS_BJ13 @T6G_MB_LIB.T6G(SCH_1):GND
BJ15    GND VSS_BJ15 @T6G_MB_LIB.T6G(SCH_1):GND
BJ20    GND VSS_BJ20 @T6G_MB_LIB.T6G(SCH_1):GND
BJ22    GND VSS_BJ22 @T6G_MB_LIB.T6G(SCH_1):GND
BJ24    GND VSS_BJ24 @T6G_MB_LIB.T6G(SCH_1):GND
BJ26    GND VSS_BJ26 @T6G_MB_LIB.T6G(SCH_1):GND
BJ28    GND VSS_BJ28 @T6G_MB_LIB.T6G(SCH_1):GND
BJ49    GND VSS_BJ49 @T6G_MB_LIB.T6G(SCH_1):GND
BJ51    GND VSS_BJ51 @T6G_MB_LIB.T6G(SCH_1):GND
BJ53    GND VSS_BJ53 @T6G_MB_LIB.T6G(SCH_1):GND
BJ56    GND VSS_BJ56 @T6G_MB_LIB.T6G(SCH_1):GND
BJ61    GND VSS_BJ61 @T6G_MB_LIB.T6G(SCH_1):GND
BJ63    GND VSS_BJ63 @T6G_MB_LIB.T6G(SCH_1):GND
BJ68    GND VSS_BJ68 @T6G_MB_LIB.T6G(SCH_1):GND
BJ70    GND VSS_BJ70 @T6G_MB_LIB.T6G(SCH_1):GND
BJ75    GND VSS_BJ75 @T6G_MB_LIB.T6G(SCH_1):GND
 BK3    GND VSS_BK3 @T6G_MB_LIB.T6G(SCH_1):GND
 BK5    GND VSS_BK5 @T6G_MB_LIB.T6G(SCH_1):GND
 BK8    GND VSS_BK8 @T6G_MB_LIB.T6G(SCH_1):GND
BK10    GND VSS_BK10 @T6G_MB_LIB.T6G(SCH_1):GND
BK12    GND VSS_BK12 @T6G_MB_LIB.T6G(SCH_1):GND
BK15    GND VSS_BK15 @T6G_MB_LIB.T6G(SCH_1):GND
BK17    GND VSS_BK17 @T6G_MB_LIB.T6G(SCH_1):GND
BK19    GND VSS_BK19 @T6G_MB_LIB.T6G(SCH_1):GND
BK23    GND VSS_BK23 @T6G_MB_LIB.T6G(SCH_1):GND
BK25    GND VSS_BK25 @T6G_MB_LIB.T6G(SCH_1):GND
BK27    GND VSS_BK27 @T6G_MB_LIB.T6G(SCH_1):GND
BK48    GND VSS_BK48 @T6G_MB_LIB.T6G(SCH_1):GND
BK50    GND VSS_BK50 @T6G_MB_LIB.T6G(SCH_1):GND
BK52    GND VSS_BK52 @T6G_MB_LIB.T6G(SCH_1):GND
BK54    GND VSS_BK54 @T6G_MB_LIB.T6G(SCH_1):GND
BK57    GND VSS_BK57 @T6G_MB_LIB.T6G(SCH_1):GND
BK59    GND VSS_BK59 @T6G_MB_LIB.T6G(SCH_1):GND
BK61    GND VSS_BK61 @T6G_MB_LIB.T6G(SCH_1):GND
BK64    GND VSS_BK64 @T6G_MB_LIB.T6G(SCH_1):GND
BK66    GND VSS_BK66 @T6G_MB_LIB.T6G(SCH_1):GND
BK68    GND VSS_BK68 @T6G_MB_LIB.T6G(SCH_1):GND
BK71    GND VSS_BK71 @T6G_MB_LIB.T6G(SCH_1):GND
BK73    GND VSS_BK73 @T6G_MB_LIB.T6G(SCH_1):GND
 BL1    GND VSS_BL1 @T6G_MB_LIB.T6G(SCH_1):GND
 BL4    GND VSS_BL4 @T6G_MB_LIB.T6G(SCH_1):GND
 BL6    GND VSS_BL6 @T6G_MB_LIB.T6G(SCH_1):GND
 BL8    GND VSS_BL8 @T6G_MB_LIB.T6G(SCH_1):GND
BL11    GND VSS_BL11 @T6G_MB_LIB.T6G(SCH_1):GND
BL13    GND VSS_BL13 @T6G_MB_LIB.T6G(SCH_1):GND
BL15    GND VSS_BL15 @T6G_MB_LIB.T6G(SCH_1):GND
BL18    GND VSS_BL18 @T6G_MB_LIB.T6G(SCH_1):GND
BL20    GND VSS_BL20 @T6G_MB_LIB.T6G(SCH_1):GND
BL22    GND VSS_BL22 @T6G_MB_LIB.T6G(SCH_1):GND
BL24    GND VSS_BL24 @T6G_MB_LIB.T6G(SCH_1):GND


DRAWING: @T6G_MB_LIB.T6G(SCH_1):PAGE32 

GENOA_SP5-SOCKET6096_13568-001,SMLF,IO,DGA^6000030  I13  U25
BV37    GND VSS_BV37 @T6G_MB_LIB.T6G(SCH_1):GND
BL26    GND VSS_BL26 @T6G_MB_LIB.T6G(SCH_1):GND
BL28    GND VSS_BL28 @T6G_MB_LIB.T6G(SCH_1):GND
BL49    GND VSS_BL49 @T6G_MB_LIB.T6G(SCH_1):GND
BL51    GND VSS_BL51 @T6G_MB_LIB.T6G(SCH_1):GND
BL53    GND VSS_BL53 @T6G_MB_LIB.T6G(SCH_1):GND
BL56    GND VSS_BL56 @T6G_MB_LIB.T6G(SCH_1):GND
BL58    GND VSS_BL58 @T6G_MB_LIB.T6G(SCH_1):GND
BL61    GND VSS_BL61 @T6G_MB_LIB.T6G(SCH_1):GND
BL63    GND VSS_BL63 @T6G_MB_LIB.T6G(SCH_1):GND
BL65    GND VSS_BL65 @T6G_MB_LIB.T6G(SCH_1):GND
BL68    GND VSS_BL68 @T6G_MB_LIB.T6G(SCH_1):GND
BL70    GND VSS_BL70 @T6G_MB_LIB.T6G(SCH_1):GND
BL72    GND VSS_BL72 @T6G_MB_LIB.T6G(SCH_1):GND
BL75    GND VSS_BL75 @T6G_MB_LIB.T6G(SCH_1):GND
 BM3    GND VSS_BM3 @T6G_MB_LIB.T6G(SCH_1):GND
 BM8    GND VSS_BM8 @T6G_MB_LIB.T6G(SCH_1):GND
BM10    GND VSS_BM10 @T6G_MB_LIB.T6G(SCH_1):GND
BM15    GND VSS_BM15 @T6G_MB_LIB.T6G(SCH_1):GND
BM17    GND VSS_BM17 @T6G_MB_LIB.T6G(SCH_1):GND
BM23    GND VSS_BM23 @T6G_MB_LIB.T6G(SCH_1):GND
BM25    GND VSS_BM25 @T6G_MB_LIB.T6G(SCH_1):GND
BM27    GND VSS_BM27 @T6G_MB_LIB.T6G(SCH_1):GND
BM29    GND VSS_BM29 @T6G_MB_LIB.T6G(SCH_1):GND
BM31    GND VSS_BM31 @T6G_MB_LIB.T6G(SCH_1):GND
BM33    GND VSS_BM33 @T6G_MB_LIB.T6G(SCH_1):GND
BM35    GND VSS_BM35 @T6G_MB_LIB.T6G(SCH_1):GND
BM37    GND VSS_BM37 @T6G_MB_LIB.T6G(SCH_1):GND
BM40    GND VSS_BM40 @T6G_MB_LIB.T6G(SCH_1):GND
BM42    GND VSS_BM42 @T6G_MB_LIB.T6G(SCH_1):GND
BM44    GND VSS_BM44 @T6G_MB_LIB.T6G(SCH_1):GND
BM46    GND VSS_BM46 @T6G_MB_LIB.T6G(SCH_1):GND
BM48    GND VSS_BM48 @T6G_MB_LIB.T6G(SCH_1):GND
BM50    GND VSS_BM50 @T6G_MB_LIB.T6G(SCH_1):GND
BM52    GND VSS_BM52 @T6G_MB_LIB.T6G(SCH_1):GND
BM54    GND VSS_BM54 @T6G_MB_LIB.T6G(SCH_1):GND
BM59    GND VSS_BM59 @T6G_MB_LIB.T6G(SCH_1):GND
BM61    GND VSS_BM61 @T6G_MB_LIB.T6G(SCH_1):GND
BM66    GND VSS_BM66 @T6G_MB_LIB.T6G(SCH_1):GND
BM68    GND VSS_BM68 @T6G_MB_LIB.T6G(SCH_1):GND
BM73    GND VSS_BM73 @T6G_MB_LIB.T6G(SCH_1):GND
 BN1    GND VSS_BN1 @T6G_MB_LIB.T6G(SCH_1):GND
 BN4    GND VSS_BN4 @T6G_MB_LIB.T6G(SCH_1):GND
 BN6    GND VSS_BN6 @T6G_MB_LIB.T6G(SCH_1):GND
 BN8    GND VSS_BN8 @T6G_MB_LIB.T6G(SCH_1):GND
BN11    GND VSS_BN11 @T6G_MB_LIB.T6G(SCH_1):GND
BN13    GND VSS_BN13 @T6G_MB_LIB.T6G(SCH_1):GND
BN15    GND VSS_BN15 @T6G_MB_LIB.T6G(SCH_1):GND
BN18    GND VSS_BN18 @T6G_MB_LIB.T6G(SCH_1):GND
BN20    GND VSS_BN20 @T6G_MB_LIB.T6G(SCH_1):GND
BN22    GND VSS_BN22 @T6G_MB_LIB.T6G(SCH_1):GND
BN24    GND VSS_BN24 @T6G_MB_LIB.T6G(SCH_1):GND
BN26    GND VSS_BN26 @T6G_MB_LIB.T6G(SCH_1):GND
BN28    GND VSS_BN28 @T6G_MB_LIB.T6G(SCH_1):GND
BN30    GND VSS_BN30 @T6G_MB_LIB.T6G(SCH_1):GND
BN32    GND VSS_BN32 @T6G_MB_LIB.T6G(SCH_1):GND
BN34    GND VSS_BN34 @T6G_MB_LIB.T6G(SCH_1):GND
BN36    GND VSS_BN36 @T6G_MB_LIB.T6G(SCH_1):GND
BN41    GND VSS_BN41 @T6G_MB_LIB.T6G(SCH_1):GND
BN43    GND VSS_BN43 @T6G_MB_LIB.T6G(SCH_1):GND
BN45    GND VSS_BN45 @T6G_MB_LIB.T6G(SCH_1):GND
BN47    GND VSS_BN47 @T6G_MB_LIB.T6G(SCH_1):GND
BN49    GND VSS_BN49 @T6G_MB_LIB.T6G(SCH_1):GND
BN51    GND VSS_BN51 @T6G_MB_LIB.T6G(SCH_1):GND
BN53    GND VSS_BN53 @T6G_MB_LIB.T6G(SCH_1):GND
BN56    GND VSS_BN56 @T6G_MB_LIB.T6G(SCH_1):GND
BN58    GND VSS_BN58 @T6G_MB_LIB.T6G(SCH_1):GND
BN61    GND VSS_BN61 @T6G_MB_LIB.T6G(SCH_1):GND
BN63    GND VSS_BN63 @T6G_MB_LIB.T6G(SCH_1):GND
BN65    GND VSS_BN65 @T6G_MB_LIB.T6G(SCH_1):GND
BN68    GND VSS_BN68 @T6G_MB_LIB.T6G(SCH_1):GND
BN70    GND VSS_BN70 @T6G_MB_LIB.T6G(SCH_1):GND
BN72    GND VSS_BN72 @T6G_MB_LIB.T6G(SCH_1):GND
BN75    GND VSS_BN75 @T6G_MB_LIB.T6G(SCH_1):GND
 BP3    GND VSS_BP3 @T6G_MB_LIB.T6G(SCH_1):GND
 BP5    GND VSS_BP5 @T6G_MB_LIB.T6G(SCH_1):GND
 BP8    GND VSS_BP8 @T6G_MB_LIB.T6G(SCH_1):GND
BP10    GND VSS_BP10 @T6G_MB_LIB.T6G(SCH_1):GND
BP12    GND VSS_BP12 @T6G_MB_LIB.T6G(SCH_1):GND
BP15    GND VSS_BP15 @T6G_MB_LIB.T6G(SCH_1):GND
BP17    GND VSS_BP17 @T6G_MB_LIB.T6G(SCH_1):GND
BP19    GND VSS_BP19 @T6G_MB_LIB.T6G(SCH_1):GND
BP23    GND VSS_BP23 @T6G_MB_LIB.T6G(SCH_1):GND
BP25    GND VSS_BP25 @T6G_MB_LIB.T6G(SCH_1):GND
BP27    GND VSS_BP27 @T6G_MB_LIB.T6G(SCH_1):GND
BP29    GND VSS_BP29 @T6G_MB_LIB.T6G(SCH_1):GND
BP31    GND VSS_BP31 @T6G_MB_LIB.T6G(SCH_1):GND
BP33    GND VSS_BP33 @T6G_MB_LIB.T6G(SCH_1):GND
BP35    GND VSS_BP35 @T6G_MB_LIB.T6G(SCH_1):GND
BP37    GND VSS_BP37 @T6G_MB_LIB.T6G(SCH_1):GND
BP40    GND VSS_BP40 @T6G_MB_LIB.T6G(SCH_1):GND
BP42    GND VSS_BP42 @T6G_MB_LIB.T6G(SCH_1):GND
BP44    GND VSS_BP44 @T6G_MB_LIB.T6G(SCH_1):GND
BP46    GND VSS_BP46 @T6G_MB_LIB.T6G(SCH_1):GND
BP48    GND VSS_BP48 @T6G_MB_LIB.T6G(SCH_1):GND
BP50    GND VSS_BP50 @T6G_MB_LIB.T6G(SCH_1):GND
BP52    GND VSS_BP52 @T6G_MB_LIB.T6G(SCH_1):GND
BP54    GND VSS_BP54 @T6G_MB_LIB.T6G(SCH_1):GND
BP57    GND VSS_BP57 @T6G_MB_LIB.T6G(SCH_1):GND
BP59    GND VSS_BP59 @T6G_MB_LIB.T6G(SCH_1):GND
BP61    GND VSS_BP61 @T6G_MB_LIB.T6G(SCH_1):GND
BP64    GND VSS_BP64 @T6G_MB_LIB.T6G(SCH_1):GND
BP66    GND VSS_BP66 @T6G_MB_LIB.T6G(SCH_1):GND
BP68    GND VSS_BP68 @T6G_MB_LIB.T6G(SCH_1):GND
BP71    GND VSS_BP71 @T6G_MB_LIB.T6G(SCH_1):GND
BP73    GND VSS_BP73 @T6G_MB_LIB.T6G(SCH_1):GND
 BR1    GND VSS_BR1 @T6G_MB_LIB.T6G(SCH_1):GND
 BR3    GND VSS_BR3 @T6G_MB_LIB.T6G(SCH_1):GND
 BR6    GND VSS_BR6 @T6G_MB_LIB.T6G(SCH_1):GND
 BR7    GND VSS_BR7 @T6G_MB_LIB.T6G(SCH_1):GND
 BR8    GND VSS_BR8 @T6G_MB_LIB.T6G(SCH_1):GND
BR10    GND VSS_BR10 @T6G_MB_LIB.T6G(SCH_1):GND
BR13    GND VSS_BR13 @T6G_MB_LIB.T6G(SCH_1):GND
BR14    GND VSS_BR14 @T6G_MB_LIB.T6G(SCH_1):GND
BR15    GND VSS_BR15 @T6G_MB_LIB.T6G(SCH_1):GND
BR17    GND VSS_BR17 @T6G_MB_LIB.T6G(SCH_1):GND
BR20    GND VSS_BR20 @T6G_MB_LIB.T6G(SCH_1):GND
BR21    GND VSS_BR21 @T6G_MB_LIB.T6G(SCH_1):GND
BR22    GND VSS_BR22 @T6G_MB_LIB.T6G(SCH_1):GND
BR24    GND VSS_BR24 @T6G_MB_LIB.T6G(SCH_1):GND
BR26    GND VSS_BR26 @T6G_MB_LIB.T6G(SCH_1):GND
BR28    GND VSS_BR28 @T6G_MB_LIB.T6G(SCH_1):GND
BR30    GND VSS_BR30 @T6G_MB_LIB.T6G(SCH_1):GND
BR32    GND VSS_BR32 @T6G_MB_LIB.T6G(SCH_1):GND
BR34    GND VSS_BR34 @T6G_MB_LIB.T6G(SCH_1):GND
BR36    GND VSS_BR36 @T6G_MB_LIB.T6G(SCH_1):GND
BR41    GND VSS_BR41 @T6G_MB_LIB.T6G(SCH_1):GND
BR43    GND VSS_BR43 @T6G_MB_LIB.T6G(SCH_1):GND
BR45    GND VSS_BR45 @T6G_MB_LIB.T6G(SCH_1):GND
BR47    GND VSS_BR47 @T6G_MB_LIB.T6G(SCH_1):GND
BR49    GND VSS_BR49 @T6G_MB_LIB.T6G(SCH_1):GND
BR51    GND VSS_BR51 @T6G_MB_LIB.T6G(SCH_1):GND
BR55    GND VSS_BR55 @T6G_MB_LIB.T6G(SCH_1):GND
BR56    GND VSS_BR56 @T6G_MB_LIB.T6G(SCH_1):GND
BR59    GND VSS_BR59 @T6G_MB_LIB.T6G(SCH_1):GND
BR61    GND VSS_BR61 @T6G_MB_LIB.T6G(SCH_1):GND
BR62    GND VSS_BR62 @T6G_MB_LIB.T6G(SCH_1):GND
BR63    GND VSS_BR63 @T6G_MB_LIB.T6G(SCH_1):GND
BR66    GND VSS_BR66 @T6G_MB_LIB.T6G(SCH_1):GND
BR68    GND VSS_BR68 @T6G_MB_LIB.T6G(SCH_1):GND
BR69    GND VSS_BR69 @T6G_MB_LIB.T6G(SCH_1):GND
BR70    GND VSS_BR70 @T6G_MB_LIB.T6G(SCH_1):GND
BR73    GND VSS_BR73 @T6G_MB_LIB.T6G(SCH_1):GND
BR75    GND VSS_BR75 @T6G_MB_LIB.T6G(SCH_1):GND
 BT3    GND VSS_BT3 @T6G_MB_LIB.T6G(SCH_1):GND
 BT4    GND VSS_BT4 @T6G_MB_LIB.T6G(SCH_1):GND
 BT5    GND VSS_BT5 @T6G_MB_LIB.T6G(SCH_1):GND
 BT7    GND VSS_BT7 @T6G_MB_LIB.T6G(SCH_1):GND
 BT8    GND VSS_BT8 @T6G_MB_LIB.T6G(SCH_1):GND
BT10    GND VSS_BT10 @T6G_MB_LIB.T6G(SCH_1):GND
BT11    GND VSS_BT11 @T6G_MB_LIB.T6G(SCH_1):GND
BT12    GND VSS_BT12 @T6G_MB_LIB.T6G(SCH_1):GND
BT14    GND VSS_BT14 @T6G_MB_LIB.T6G(SCH_1):GND
BT15    GND VSS_BT15 @T6G_MB_LIB.T6G(SCH_1):GND
BT17    GND VSS_BT17 @T6G_MB_LIB.T6G(SCH_1):GND
BT18    GND VSS_BT18 @T6G_MB_LIB.T6G(SCH_1):GND
BT19    GND VSS_BT19 @T6G_MB_LIB.T6G(SCH_1):GND
BT21    GND VSS_BT21 @T6G_MB_LIB.T6G(SCH_1):GND
BT22    GND VSS_BT22 @T6G_MB_LIB.T6G(SCH_1):GND
BT25    GND VSS_BT25 @T6G_MB_LIB.T6G(SCH_1):GND
BT28    GND VSS_BT28 @T6G_MB_LIB.T6G(SCH_1):GND
BT31    GND VSS_BT31 @T6G_MB_LIB.T6G(SCH_1):GND
BT34    GND VSS_BT34 @T6G_MB_LIB.T6G(SCH_1):GND
BT37    GND VSS_BT37 @T6G_MB_LIB.T6G(SCH_1):GND
BT39    GND VSS_BT39 @T6G_MB_LIB.T6G(SCH_1):GND
BT42    GND VSS_BT42 @T6G_MB_LIB.T6G(SCH_1):GND
BT45    GND VSS_BT45 @T6G_MB_LIB.T6G(SCH_1):GND
BT48    GND VSS_BT48 @T6G_MB_LIB.T6G(SCH_1):GND
BT51    GND VSS_BT51 @T6G_MB_LIB.T6G(SCH_1):GND
BT54    GND VSS_BT54 @T6G_MB_LIB.T6G(SCH_1):GND
BT55    GND VSS_BT55 @T6G_MB_LIB.T6G(SCH_1):GND
BT57    GND VSS_BT57 @T6G_MB_LIB.T6G(SCH_1):GND
BT58    GND VSS_BT58 @T6G_MB_LIB.T6G(SCH_1):GND
BT59    GND VSS_BT59 @T6G_MB_LIB.T6G(SCH_1):GND
BT61    GND VSS_BT61 @T6G_MB_LIB.T6G(SCH_1):GND
BT62    GND VSS_BT62 @T6G_MB_LIB.T6G(SCH_1):GND
BT64    GND VSS_BT64 @T6G_MB_LIB.T6G(SCH_1):GND
BT65    GND VSS_BT65 @T6G_MB_LIB.T6G(SCH_1):GND
BT66    GND VSS_BT66 @T6G_MB_LIB.T6G(SCH_1):GND
BT68    GND VSS_BT68 @T6G_MB_LIB.T6G(SCH_1):GND
BT69    GND VSS_BT69 @T6G_MB_LIB.T6G(SCH_1):GND
BT71    GND VSS_BT71 @T6G_MB_LIB.T6G(SCH_1):GND
BT72    GND VSS_BT72 @T6G_MB_LIB.T6G(SCH_1):GND
BT73    GND VSS_BT73 @T6G_MB_LIB.T6G(SCH_1):GND
 BU1    GND VSS_BU1 @T6G_MB_LIB.T6G(SCH_1):GND
 BU4    GND VSS_BU4 @T6G_MB_LIB.T6G(SCH_1):GND
 BU6    GND VSS_BU6 @T6G_MB_LIB.T6G(SCH_1):GND
 BU8    GND VSS_BU8 @T6G_MB_LIB.T6G(SCH_1):GND
BU11    GND VSS_BU11 @T6G_MB_LIB.T6G(SCH_1):GND
BU13    GND VSS_BU13 @T6G_MB_LIB.T6G(SCH_1):GND
BU15    GND VSS_BU15 @T6G_MB_LIB.T6G(SCH_1):GND
BU18    GND VSS_BU18 @T6G_MB_LIB.T6G(SCH_1):GND
BU20    GND VSS_BU20 @T6G_MB_LIB.T6G(SCH_1):GND
BU22    GND VSS_BU22 @T6G_MB_LIB.T6G(SCH_1):GND
BU25    GND VSS_BU25 @T6G_MB_LIB.T6G(SCH_1):GND
BU28    GND VSS_BU28 @T6G_MB_LIB.T6G(SCH_1):GND
BU31    GND VSS_BU31 @T6G_MB_LIB.T6G(SCH_1):GND
BU34    GND VSS_BU34 @T6G_MB_LIB.T6G(SCH_1):GND
BU35    GND VSS_BU35 @T6G_MB_LIB.T6G(SCH_1):GND
BU36    GND VSS_BU36 @T6G_MB_LIB.T6G(SCH_1):GND
BU40    GND VSS_BU40 @T6G_MB_LIB.T6G(SCH_1):GND
BU41    GND VSS_BU41 @T6G_MB_LIB.T6G(SCH_1):GND
BU42    GND VSS_BU42 @T6G_MB_LIB.T6G(SCH_1):GND
BU45    GND VSS_BU45 @T6G_MB_LIB.T6G(SCH_1):GND
BU48    GND VSS_BU48 @T6G_MB_LIB.T6G(SCH_1):GND
BU51    GND VSS_BU51 @T6G_MB_LIB.T6G(SCH_1):GND
BU54    GND VSS_BU54 @T6G_MB_LIB.T6G(SCH_1):GND
BU56    GND VSS_BU56 @T6G_MB_LIB.T6G(SCH_1):GND
BU58    GND VSS_BU58 @T6G_MB_LIB.T6G(SCH_1):GND
BU61    GND VSS_BU61 @T6G_MB_LIB.T6G(SCH_1):GND
BU63    GND VSS_BU63 @T6G_MB_LIB.T6G(SCH_1):GND
BU65    GND VSS_BU65 @T6G_MB_LIB.T6G(SCH_1):GND
BU68    GND VSS_BU68 @T6G_MB_LIB.T6G(SCH_1):GND
BU70    GND VSS_BU70 @T6G_MB_LIB.T6G(SCH_1):GND
BU72    GND VSS_BU72 @T6G_MB_LIB.T6G(SCH_1):GND
BU75    GND VSS_BU75 @T6G_MB_LIB.T6G(SCH_1):GND
 BV3    GND VSS_BV3 @T6G_MB_LIB.T6G(SCH_1):GND
 BV8    GND VSS_BV8 @T6G_MB_LIB.T6G(SCH_1):GND
BV10    GND VSS_BV10 @T6G_MB_LIB.T6G(SCH_1):GND
BV15    GND VSS_BV15 @T6G_MB_LIB.T6G(SCH_1):GND
BV17    GND VSS_BV17 @T6G_MB_LIB.T6G(SCH_1):GND
BV23    GND VSS_BV23 @T6G_MB_LIB.T6G(SCH_1):GND
BV24    GND VSS_BV24 @T6G_MB_LIB.T6G(SCH_1):GND
BV25    GND VSS_BV25 @T6G_MB_LIB.T6G(SCH_1):GND
BV26    GND VSS_BV26 @T6G_MB_LIB.T6G(SCH_1):GND
BV27    GND VSS_BV27 @T6G_MB_LIB.T6G(SCH_1):GND
BV28    GND VSS_BV28 @T6G_MB_LIB.T6G(SCH_1):GND
BV29    GND VSS_BV29 @T6G_MB_LIB.T6G(SCH_1):GND
BV30    GND VSS_BV30 @T6G_MB_LIB.T6G(SCH_1):GND
BV31    GND VSS_BV31 @T6G_MB_LIB.T6G(SCH_1):GND
BV32    GND VSS_BV32 @T6G_MB_LIB.T6G(SCH_1):GND
BV33    GND VSS_BV33 @T6G_MB_LIB.T6G(SCH_1):GND
BV34    GND VSS_BV34 @T6G_MB_LIB.T6G(SCH_1):GND
BV39    GND VSS_BV39 @T6G_MB_LIB.T6G(SCH_1):GND
BV43    GND VSS_BV43 @T6G_MB_LIB.T6G(SCH_1):GND
BV44    GND VSS_BV44 @T6G_MB_LIB.T6G(SCH_1):GND
BV45    GND VSS_BV45 @T6G_MB_LIB.T6G(SCH_1):GND

GENOA_SP5-SOCKET6096_13568-001,SMLF,IO,DGA^6000030  I14  U25
BV46    GND VSS_BV46 @T6G_MB_LIB.T6G(SCH_1):GND
BV47    GND VSS_BV47 @T6G_MB_LIB.T6G(SCH_1):GND
BV48    GND VSS_BV48 @T6G_MB_LIB.T6G(SCH_1):GND
BV49    GND VSS_BV49 @T6G_MB_LIB.T6G(SCH_1):GND
BV50    GND VSS_BV50 @T6G_MB_LIB.T6G(SCH_1):GND
BV51    GND VSS_BV51 @T6G_MB_LIB.T6G(SCH_1):GND
BV52    GND VSS_BV52 @T6G_MB_LIB.T6G(SCH_1):GND
BV53    GND VSS_BV53 @T6G_MB_LIB.T6G(SCH_1):GND
BV59    GND VSS_BV59 @T6G_MB_LIB.T6G(SCH_1):GND
BV61    GND VSS_BV61 @T6G_MB_LIB.T6G(SCH_1):GND
BV66    GND VSS_BV66 @T6G_MB_LIB.T6G(SCH_1):GND
BV68    GND VSS_BV68 @T6G_MB_LIB.T6G(SCH_1):GND
BV73    GND VSS_BV73 @T6G_MB_LIB.T6G(SCH_1):GND
 BW1    GND VSS_BW1 @T6G_MB_LIB.T6G(SCH_1):GND
 BW4    GND VSS_BW4 @T6G_MB_LIB.T6G(SCH_1):GND
 BW6    GND VSS_BW6 @T6G_MB_LIB.T6G(SCH_1):GND
 BW8    GND VSS_BW8 @T6G_MB_LIB.T6G(SCH_1):GND
BW11    GND VSS_BW11 @T6G_MB_LIB.T6G(SCH_1):GND
BW13    GND VSS_BW13 @T6G_MB_LIB.T6G(SCH_1):GND
BW15    GND VSS_BW15 @T6G_MB_LIB.T6G(SCH_1):GND
BW18    GND VSS_BW18 @T6G_MB_LIB.T6G(SCH_1):GND
BW20    GND VSS_BW20 @T6G_MB_LIB.T6G(SCH_1):GND
BW22    GND VSS_BW22 @T6G_MB_LIB.T6G(SCH_1):GND
BW28    GND VSS_BW28 @T6G_MB_LIB.T6G(SCH_1):GND
BW31    GND VSS_BW31 @T6G_MB_LIB.T6G(SCH_1):GND
BW34    GND VSS_BW34 @T6G_MB_LIB.T6G(SCH_1):GND
BW42    GND VSS_BW42 @T6G_MB_LIB.T6G(SCH_1):GND
BW45    GND VSS_BW45 @T6G_MB_LIB.T6G(SCH_1):GND
BW48    GND VSS_BW48 @T6G_MB_LIB.T6G(SCH_1):GND
BW51    GND VSS_BW51 @T6G_MB_LIB.T6G(SCH_1):GND
BW54    GND VSS_BW54 @T6G_MB_LIB.T6G(SCH_1):GND
BW56    GND VSS_BW56 @T6G_MB_LIB.T6G(SCH_1):GND
BW58    GND VSS_BW58 @T6G_MB_LIB.T6G(SCH_1):GND
BW61    GND VSS_BW61 @T6G_MB_LIB.T6G(SCH_1):GND
BW63    GND VSS_BW63 @T6G_MB_LIB.T6G(SCH_1):GND
BW65    GND VSS_BW65 @T6G_MB_LIB.T6G(SCH_1):GND
BW68    GND VSS_BW68 @T6G_MB_LIB.T6G(SCH_1):GND
BW70    GND VSS_BW70 @T6G_MB_LIB.T6G(SCH_1):GND
BW72    GND VSS_BW72 @T6G_MB_LIB.T6G(SCH_1):GND
BW75    GND VSS_BW75 @T6G_MB_LIB.T6G(SCH_1):GND
 BY3    GND VSS_BY3 @T6G_MB_LIB.T6G(SCH_1):GND
 BY5    GND VSS_BY5 @T6G_MB_LIB.T6G(SCH_1):GND
 BY8    GND VSS_BY8 @T6G_MB_LIB.T6G(SCH_1):GND
BY10    GND VSS_BY10 @T6G_MB_LIB.T6G(SCH_1):GND
BY12    GND VSS_BY12 @T6G_MB_LIB.T6G(SCH_1):GND
BY15    GND VSS_BY15 @T6G_MB_LIB.T6G(SCH_1):GND
BY17    GND VSS_BY17 @T6G_MB_LIB.T6G(SCH_1):GND
BY19    GND VSS_BY19 @T6G_MB_LIB.T6G(SCH_1):GND
BY22    GND VSS_BY22 @T6G_MB_LIB.T6G(SCH_1):GND
BY25    GND VSS_BY25 @T6G_MB_LIB.T6G(SCH_1):GND
BY28    GND VSS_BY28 @T6G_MB_LIB.T6G(SCH_1):GND
BY31    GND VSS_BY31 @T6G_MB_LIB.T6G(SCH_1):GND
BY34    GND VSS_BY34 @T6G_MB_LIB.T6G(SCH_1):GND
BY37    GND VSS_BY37 @T6G_MB_LIB.T6G(SCH_1):GND
BY39    GND VSS_BY39 @T6G_MB_LIB.T6G(SCH_1):GND
BY42    GND VSS_BY42 @T6G_MB_LIB.T6G(SCH_1):GND
BY45    GND VSS_BY45 @T6G_MB_LIB.T6G(SCH_1):GND
BY48    GND VSS_BY48 @T6G_MB_LIB.T6G(SCH_1):GND
BY51    GND VSS_BY51 @T6G_MB_LIB.T6G(SCH_1):GND
BY54    GND VSS_BY54 @T6G_MB_LIB.T6G(SCH_1):GND
BY57    GND VSS_BY57 @T6G_MB_LIB.T6G(SCH_1):GND
BY59    GND VSS_BY59 @T6G_MB_LIB.T6G(SCH_1):GND
BY61    GND VSS_BY61 @T6G_MB_LIB.T6G(SCH_1):GND
BY64    GND VSS_BY64 @T6G_MB_LIB.T6G(SCH_1):GND
BY66    GND VSS_BY66 @T6G_MB_LIB.T6G(SCH_1):GND
BY68    GND VSS_BY68 @T6G_MB_LIB.T6G(SCH_1):GND
BY71    GND VSS_BY71 @T6G_MB_LIB.T6G(SCH_1):GND
BY73    GND VSS_BY73 @T6G_MB_LIB.T6G(SCH_1):GND
 CA1    GND VSS_CA1 @T6G_MB_LIB.T6G(SCH_1):GND
 CA6    GND VSS_CA6 @T6G_MB_LIB.T6G(SCH_1):GND
 CA8    GND VSS_CA8 @T6G_MB_LIB.T6G(SCH_1):GND
CA13    GND VSS_CA13 @T6G_MB_LIB.T6G(SCH_1):GND
CA15    GND VSS_CA15 @T6G_MB_LIB.T6G(SCH_1):GND
CA20    GND VSS_CA20 @T6G_MB_LIB.T6G(SCH_1):GND
CA22    GND VSS_CA22 @T6G_MB_LIB.T6G(SCH_1):GND
CA25    GND VSS_CA25 @T6G_MB_LIB.T6G(SCH_1):GND
CA28    GND VSS_CA28 @T6G_MB_LIB.T6G(SCH_1):GND
CA31    GND VSS_CA31 @T6G_MB_LIB.T6G(SCH_1):GND
CA34    GND VSS_CA34 @T6G_MB_LIB.T6G(SCH_1):GND
CA35    GND VSS_CA35 @T6G_MB_LIB.T6G(SCH_1):GND
CA36    GND VSS_CA36 @T6G_MB_LIB.T6G(SCH_1):GND
CA40    GND VSS_CA40 @T6G_MB_LIB.T6G(SCH_1):GND
CA41    GND VSS_CA41 @T6G_MB_LIB.T6G(SCH_1):GND
CA42    GND VSS_CA42 @T6G_MB_LIB.T6G(SCH_1):GND
CA45    GND VSS_CA45 @T6G_MB_LIB.T6G(SCH_1):GND
CA48    GND VSS_CA48 @T6G_MB_LIB.T6G(SCH_1):GND
CA51    GND VSS_CA51 @T6G_MB_LIB.T6G(SCH_1):GND
CA54    GND VSS_CA54 @T6G_MB_LIB.T6G(SCH_1):GND
CA56    GND VSS_CA56 @T6G_MB_LIB.T6G(SCH_1):GND
CA61    GND VSS_CA61 @T6G_MB_LIB.T6G(SCH_1):GND
CA63    GND VSS_CA63 @T6G_MB_LIB.T6G(SCH_1):GND
CA68    GND VSS_CA68 @T6G_MB_LIB.T6G(SCH_1):GND
CA70    GND VSS_CA70 @T6G_MB_LIB.T6G(SCH_1):GND
CA75    GND VSS_CA75 @T6G_MB_LIB.T6G(SCH_1):GND
 CB3    GND VSS_CB3 @T6G_MB_LIB.T6G(SCH_1):GND
 CB5    GND VSS_CB5 @T6G_MB_LIB.T6G(SCH_1):GND
 CB8    GND VSS_CB8 @T6G_MB_LIB.T6G(SCH_1):GND
CB10    GND VSS_CB10 @T6G_MB_LIB.T6G(SCH_1):GND
CB12    GND VSS_CB12 @T6G_MB_LIB.T6G(SCH_1):GND
CB15    GND VSS_CB15 @T6G_MB_LIB.T6G(SCH_1):GND
CB17    GND VSS_CB17 @T6G_MB_LIB.T6G(SCH_1):GND
CB19    GND VSS_CB19 @T6G_MB_LIB.T6G(SCH_1):GND
CB23    GND VSS_CB23 @T6G_MB_LIB.T6G(SCH_1):GND
CB24    GND VSS_CB24 @T6G_MB_LIB.T6G(SCH_1):GND
CB25    GND VSS_CB25 @T6G_MB_LIB.T6G(SCH_1):GND
CB26    GND VSS_CB26 @T6G_MB_LIB.T6G(SCH_1):GND
CB27    GND VSS_CB27 @T6G_MB_LIB.T6G(SCH_1):GND
CB28    GND VSS_CB28 @T6G_MB_LIB.T6G(SCH_1):GND
CB29    GND VSS_CB29 @T6G_MB_LIB.T6G(SCH_1):GND
CB30    GND VSS_CB30 @T6G_MB_LIB.T6G(SCH_1):GND
CB31    GND VSS_CB31 @T6G_MB_LIB.T6G(SCH_1):GND
CB32    GND VSS_CB32 @T6G_MB_LIB.T6G(SCH_1):GND
CB33    GND VSS_CB33 @T6G_MB_LIB.T6G(SCH_1):GND
CB34    GND VSS_CB34 @T6G_MB_LIB.T6G(SCH_1):GND
CB37    GND VSS_CB37 @T6G_MB_LIB.T6G(SCH_1):GND
CB39    GND VSS_CB39 @T6G_MB_LIB.T6G(SCH_1):GND
CB42    GND VSS_CB42 @T6G_MB_LIB.T6G(SCH_1):GND
CB43    GND VSS_CB43 @T6G_MB_LIB.T6G(SCH_1):GND
CB45    GND VSS_CB45 @T6G_MB_LIB.T6G(SCH_1):GND
CB46    GND VSS_CB46 @T6G_MB_LIB.T6G(SCH_1):GND
CB47    GND VSS_CB47 @T6G_MB_LIB.T6G(SCH_1):GND
CB48    GND VSS_CB48 @T6G_MB_LIB.T6G(SCH_1):GND
CB49    GND VSS_CB49 @T6G_MB_LIB.T6G(SCH_1):GND
CB50    GND VSS_CB50 @T6G_MB_LIB.T6G(SCH_1):GND
CB51    GND VSS_CB51 @T6G_MB_LIB.T6G(SCH_1):GND
CB52    GND VSS_CB52 @T6G_MB_LIB.T6G(SCH_1):GND
CB53    GND VSS_CB53 @T6G_MB_LIB.T6G(SCH_1):GND
CB57    GND VSS_CB57 @T6G_MB_LIB.T6G(SCH_1):GND
CB59    GND VSS_CB59 @T6G_MB_LIB.T6G(SCH_1):GND
CB61    GND VSS_CB61 @T6G_MB_LIB.T6G(SCH_1):GND
CB64    GND VSS_CB64 @T6G_MB_LIB.T6G(SCH_1):GND
CB66    GND VSS_CB66 @T6G_MB_LIB.T6G(SCH_1):GND
CB68    GND VSS_CB68 @T6G_MB_LIB.T6G(SCH_1):GND
CB71    GND VSS_CB71 @T6G_MB_LIB.T6G(SCH_1):GND
CB73    GND VSS_CB73 @T6G_MB_LIB.T6G(SCH_1):GND
 CC1    GND VSS_CC1 @T6G_MB_LIB.T6G(SCH_1):GND
 CC4    GND VSS_CC4 @T6G_MB_LIB.T6G(SCH_1):GND
 CC6    GND VSS_CC6 @T6G_MB_LIB.T6G(SCH_1):GND
 CC8    GND VSS_CC8 @T6G_MB_LIB.T6G(SCH_1):GND
CC11    GND VSS_CC11 @T6G_MB_LIB.T6G(SCH_1):GND
CC13    GND VSS_CC13 @T6G_MB_LIB.T6G(SCH_1):GND
CC15    GND VSS_CC15 @T6G_MB_LIB.T6G(SCH_1):GND
CC18    GND VSS_CC18 @T6G_MB_LIB.T6G(SCH_1):GND
CC20    GND VSS_CC20 @T6G_MB_LIB.T6G(SCH_1):GND
CC25    GND VSS_CC25 @T6G_MB_LIB.T6G(SCH_1):GND
CC28    GND VSS_CC28 @T6G_MB_LIB.T6G(SCH_1):GND
CC31    GND VSS_CC31 @T6G_MB_LIB.T6G(SCH_1):GND
CC34    GND VSS_CC34 @T6G_MB_LIB.T6G(SCH_1):GND
CC42    GND VSS_CC42 @T6G_MB_LIB.T6G(SCH_1):GND
CC45    GND VSS_CC45 @T6G_MB_LIB.T6G(SCH_1):GND
CC48    GND VSS_CC48 @T6G_MB_LIB.T6G(SCH_1):GND
CC51    GND VSS_CC51 @T6G_MB_LIB.T6G(SCH_1):GND
CC54    GND VSS_CC54 @T6G_MB_LIB.T6G(SCH_1):GND
CC56    GND VSS_CC56 @T6G_MB_LIB.T6G(SCH_1):GND
CC58    GND VSS_CC58 @T6G_MB_LIB.T6G(SCH_1):GND
CC61    GND VSS_CC61 @T6G_MB_LIB.T6G(SCH_1):GND
CC63    GND VSS_CC63 @T6G_MB_LIB.T6G(SCH_1):GND
CC65    GND VSS_CC65 @T6G_MB_LIB.T6G(SCH_1):GND
CC68    GND VSS_CC68 @T6G_MB_LIB.T6G(SCH_1):GND
CC70    GND VSS_CC70 @T6G_MB_LIB.T6G(SCH_1):GND
CC72    GND VSS_CC72 @T6G_MB_LIB.T6G(SCH_1):GND
CC75    GND VSS_CC75 @T6G_MB_LIB.T6G(SCH_1):GND
 CD3    GND VSS_CD3 @T6G_MB_LIB.T6G(SCH_1):GND
 CD8    GND VSS_CD8 @T6G_MB_LIB.T6G(SCH_1):GND
CD10    GND VSS_CD10 @T6G_MB_LIB.T6G(SCH_1):GND
CD15    GND VSS_CD15 @T6G_MB_LIB.T6G(SCH_1):GND
CD17    GND VSS_CD17 @T6G_MB_LIB.T6G(SCH_1):GND
CD22    GND VSS_CD22 @T6G_MB_LIB.T6G(SCH_1):GND
CD25    GND VSS_CD25 @T6G_MB_LIB.T6G(SCH_1):GND
CD28    GND VSS_CD28 @T6G_MB_LIB.T6G(SCH_1):GND
CD31    GND VSS_CD31 @T6G_MB_LIB.T6G(SCH_1):GND
CD34    GND VSS_CD34 @T6G_MB_LIB.T6G(SCH_1):GND
CD37    GND VSS_CD37 @T6G_MB_LIB.T6G(SCH_1):GND
CD39    GND VSS_CD39 @T6G_MB_LIB.T6G(SCH_1):GND
CD42    GND VSS_CD42 @T6G_MB_LIB.T6G(SCH_1):GND
CD45    GND VSS_CD45 @T6G_MB_LIB.T6G(SCH_1):GND
CD48    GND VSS_CD48 @T6G_MB_LIB.T6G(SCH_1):GND
CD51    GND VSS_CD51 @T6G_MB_LIB.T6G(SCH_1):GND
CD54    GND VSS_CD54 @T6G_MB_LIB.T6G(SCH_1):GND
CD59    GND VSS_CD59 @T6G_MB_LIB.T6G(SCH_1):GND
CD61    GND VSS_CD61 @T6G_MB_LIB.T6G(SCH_1):GND
CD66    GND VSS_CD66 @T6G_MB_LIB.T6G(SCH_1):GND
CD68    GND VSS_CD68 @T6G_MB_LIB.T6G(SCH_1):GND
CD73    GND VSS_CD73 @T6G_MB_LIB.T6G(SCH_1):GND
 CE1    GND VSS_CE1 @T6G_MB_LIB.T6G(SCH_1):GND
 CE4    GND VSS_CE4 @T6G_MB_LIB.T6G(SCH_1):GND
 CE6    GND VSS_CE6 @T6G_MB_LIB.T6G(SCH_1):GND
 CE8    GND VSS_CE8 @T6G_MB_LIB.T6G(SCH_1):GND
CE11    GND VSS_CE11 @T6G_MB_LIB.T6G(SCH_1):GND
CE13    GND VSS_CE13 @T6G_MB_LIB.T6G(SCH_1):GND
CE15    GND VSS_CE15 @T6G_MB_LIB.T6G(SCH_1):GND
CE18    GND VSS_CE18 @T6G_MB_LIB.T6G(SCH_1):GND
CE20    GND VSS_CE20 @T6G_MB_LIB.T6G(SCH_1):GND
CE22    GND VSS_CE22 @T6G_MB_LIB.T6G(SCH_1):GND
CE25    GND VSS_CE25 @T6G_MB_LIB.T6G(SCH_1):GND
CE28    GND VSS_CE28 @T6G_MB_LIB.T6G(SCH_1):GND
CE31    GND VSS_CE31 @T6G_MB_LIB.T6G(SCH_1):GND
CE34    GND VSS_CE34 @T6G_MB_LIB.T6G(SCH_1):GND
CE35    GND VSS_CE35 @T6G_MB_LIB.T6G(SCH_1):GND
CE36    GND VSS_CE36 @T6G_MB_LIB.T6G(SCH_1):GND
CE40    GND VSS_CE40 @T6G_MB_LIB.T6G(SCH_1):GND
CE41    GND VSS_CE41 @T6G_MB_LIB.T6G(SCH_1):GND
CE42    GND VSS_CE42 @T6G_MB_LIB.T6G(SCH_1):GND
CE45    GND VSS_CE45 @T6G_MB_LIB.T6G(SCH_1):GND
CE48    GND VSS_CE48 @T6G_MB_LIB.T6G(SCH_1):GND
CE51    GND VSS_CE51 @T6G_MB_LIB.T6G(SCH_1):GND
CE54    GND VSS_CE54 @T6G_MB_LIB.T6G(SCH_1):GND
CE56    GND VSS_CE56 @T6G_MB_LIB.T6G(SCH_1):GND
CE58    GND VSS_CE58 @T6G_MB_LIB.T6G(SCH_1):GND
CE61    GND VSS_CE61 @T6G_MB_LIB.T6G(SCH_1):GND
CE63    GND VSS_CE63 @T6G_MB_LIB.T6G(SCH_1):GND
CE65    GND VSS_CE65 @T6G_MB_LIB.T6G(SCH_1):GND
CE68    GND VSS_CE68 @T6G_MB_LIB.T6G(SCH_1):GND
CE70    GND VSS_CE70 @T6G_MB_LIB.T6G(SCH_1):GND
CE72    GND VSS_CE72 @T6G_MB_LIB.T6G(SCH_1):GND
CE75    GND VSS_CE75 @T6G_MB_LIB.T6G(SCH_1):GND
 CF3    GND VSS_CF3 @T6G_MB_LIB.T6G(SCH_1):GND
 CF5    GND VSS_CF5 @T6G_MB_LIB.T6G(SCH_1):GND
 CF8    GND VSS_CF8 @T6G_MB_LIB.T6G(SCH_1):GND
CF10    GND VSS_CF10 @T6G_MB_LIB.T6G(SCH_1):GND
CF12    GND VSS_CF12 @T6G_MB_LIB.T6G(SCH_1):GND
CF15    GND VSS_CF15 @T6G_MB_LIB.T6G(SCH_1):GND
CF17    GND VSS_CF17 @T6G_MB_LIB.T6G(SCH_1):GND
CF19    GND VSS_CF19 @T6G_MB_LIB.T6G(SCH_1):GND
CF23    GND VSS_CF23 @T6G_MB_LIB.T6G(SCH_1):GND
CF24    GND VSS_CF24 @T6G_MB_LIB.T6G(SCH_1):GND
CF25    GND VSS_CF25 @T6G_MB_LIB.T6G(SCH_1):GND
CF26    GND VSS_CF26 @T6G_MB_LIB.T6G(SCH_1):GND
CF27    GND VSS_CF27 @T6G_MB_LIB.T6G(SCH_1):GND
CF28    GND VSS_CF28 @T6G_MB_LIB.T6G(SCH_1):GND
CF29    GND VSS_CF29 @T6G_MB_LIB.T6G(SCH_1):GND
CF30    GND VSS_CF30 @T6G_MB_LIB.T6G(SCH_1):GND
CF31    GND VSS_CF31 @T6G_MB_LIB.T6G(SCH_1):GND
CF32    GND VSS_CF32 @T6G_MB_LIB.T6G(SCH_1):GND
CF33    GND VSS_CF33 @T6G_MB_LIB.T6G(SCH_1):GND

GENOA_SP5-SOCKET6096_13568-001,SMLF,IO,DGA^6000030  I15  U25
CN56    GND VSS_CN56 @T6G_MB_LIB.T6G(SCH_1):GND
CN20    GND VSS_CN20 @T6G_MB_LIB.T6G(SCH_1):GND
CM61    GND VSS_CM61 @T6G_MB_LIB.T6G(SCH_1):GND
CM34    GND VSS_CM34 @T6G_MB_LIB.T6G(SCH_1):GND
CK33    GND VSS_CK33 @T6G_MB_LIB.T6G(SCH_1):GND
CK15    GND VSS_CK15 @T6G_MB_LIB.T6G(SCH_1):GND
CJ58    GND VSS_CJ58 @T6G_MB_LIB.T6G(SCH_1):GND
CJ20    GND VSS_CJ20 @T6G_MB_LIB.T6G(SCH_1):GND
CH68    GND VSS_CH68 @T6G_MB_LIB.T6G(SCH_1):GND
CH39    GND VSS_CH39 @T6G_MB_LIB.T6G(SCH_1):GND
CH10    GND VSS_CH10 @T6G_MB_LIB.T6G(SCH_1):GND
CN22    GND VSS_CN22 @T6G_MB_LIB.T6G(SCH_1):GND
CM64    GND VSS_CM64 @T6G_MB_LIB.T6G(SCH_1):GND
CM37    GND VSS_CM37 @T6G_MB_LIB.T6G(SCH_1):GND
CM24    GND VSS_CM24 @T6G_MB_LIB.T6G(SCH_1):GND
CK17    GND VSS_CK17 @T6G_MB_LIB.T6G(SCH_1):GND
CJ61    GND VSS_CJ61 @T6G_MB_LIB.T6G(SCH_1):GND
CJ23    GND VSS_CJ23 @T6G_MB_LIB.T6G(SCH_1):GND
CH71    GND VSS_CH71 @T6G_MB_LIB.T6G(SCH_1):GND
CH42    GND VSS_CH42 @T6G_MB_LIB.T6G(SCH_1):GND
CH12    GND VSS_CH12 @T6G_MB_LIB.T6G(SCH_1):GND
CM66    GND VSS_CM66 @T6G_MB_LIB.T6G(SCH_1):GND
CM39    GND VSS_CM39 @T6G_MB_LIB.T6G(SCH_1):GND
CM25    GND VSS_CM25 @T6G_MB_LIB.T6G(SCH_1):GND
CL75    GND VSS_CL75 @T6G_MB_LIB.T6G(SCH_1):GND
CJ63    GND VSS_CJ63 @T6G_MB_LIB.T6G(SCH_1):GND
CJ31    GND VSS_CJ31 @T6G_MB_LIB.T6G(SCH_1):GND
CH73    GND VSS_CH73 @T6G_MB_LIB.T6G(SCH_1):GND
CH45    GND VSS_CH45 @T6G_MB_LIB.T6G(SCH_1):GND
CH15    GND VSS_CH15 @T6G_MB_LIB.T6G(SCH_1):GND
CM42    GND VSS_CM42 @T6G_MB_LIB.T6G(SCH_1):GND
CM26    GND VSS_CM26 @T6G_MB_LIB.T6G(SCH_1):GND
 CM3    GND VSS_CM3 @T6G_MB_LIB.T6G(SCH_1):GND
CL51    GND VSS_CL51 @T6G_MB_LIB.T6G(SCH_1):GND
CJ34    GND VSS_CJ34 @T6G_MB_LIB.T6G(SCH_1):GND
 CJ1    GND VSS_CJ1 @T6G_MB_LIB.T6G(SCH_1):GND
CH48    GND VSS_CH48 @T6G_MB_LIB.T6G(SCH_1):GND
CH17    GND VSS_CH17 @T6G_MB_LIB.T6G(SCH_1):GND
CM43    GND VSS_CM43 @T6G_MB_LIB.T6G(SCH_1):GND
CM27    GND VSS_CM27 @T6G_MB_LIB.T6G(SCH_1):GND
 CM5    GND VSS_CM5 @T6G_MB_LIB.T6G(SCH_1):GND
CL54    GND VSS_CL54 @T6G_MB_LIB.T6G(SCH_1):GND
CL28    GND VSS_CL28 @T6G_MB_LIB.T6G(SCH_1):GND
 CJ4    GND VSS_CJ4 @T6G_MB_LIB.T6G(SCH_1):GND
CH51    GND VSS_CH51 @T6G_MB_LIB.T6G(SCH_1):GND
CH19    GND VSS_CH19 @T6G_MB_LIB.T6G(SCH_1):GND
CF34    GND VSS_CF34 @T6G_MB_LIB.T6G(SCH_1):GND
CF37    GND VSS_CF37 @T6G_MB_LIB.T6G(SCH_1):GND
CF39    GND VSS_CF39 @T6G_MB_LIB.T6G(SCH_1):GND
CF42    GND VSS_CF42 @T6G_MB_LIB.T6G(SCH_1):GND
CF43    GND VSS_CF43 @T6G_MB_LIB.T6G(SCH_1):GND
CF44    GND VSS_CF44 @T6G_MB_LIB.T6G(SCH_1):GND
CF45    GND VSS_CF45 @T6G_MB_LIB.T6G(SCH_1):GND
CF47    GND VSS_CF47 @T6G_MB_LIB.T6G(SCH_1):GND
CF48    GND VSS_CF48 @T6G_MB_LIB.T6G(SCH_1):GND
CF49    GND VSS_CF49 @T6G_MB_LIB.T6G(SCH_1):GND
CF50    GND VSS_CF50 @T6G_MB_LIB.T6G(SCH_1):GND
CF51    GND VSS_CF51 @T6G_MB_LIB.T6G(SCH_1):GND
CF52    GND VSS_CF52 @T6G_MB_LIB.T6G(SCH_1):GND
CF53    GND VSS_CF53 @T6G_MB_LIB.T6G(SCH_1):GND
CF57    GND VSS_CF57 @T6G_MB_LIB.T6G(SCH_1):GND
CF59    GND VSS_CF59 @T6G_MB_LIB.T6G(SCH_1):GND
CF61    GND VSS_CF61 @T6G_MB_LIB.T6G(SCH_1):GND
CF64    GND VSS_CF64 @T6G_MB_LIB.T6G(SCH_1):GND
CF66    GND VSS_CF66 @T6G_MB_LIB.T6G(SCH_1):GND
CF68    GND VSS_CF68 @T6G_MB_LIB.T6G(SCH_1):GND
CF71    GND VSS_CF71 @T6G_MB_LIB.T6G(SCH_1):GND
CF73    GND VSS_CF73 @T6G_MB_LIB.T6G(SCH_1):GND
 CG1    GND VSS_CG1 @T6G_MB_LIB.T6G(SCH_1):GND
 CG6    GND VSS_CG6 @T6G_MB_LIB.T6G(SCH_1):GND
 CG8    GND VSS_CG8 @T6G_MB_LIB.T6G(SCH_1):GND
CG13    GND VSS_CG13 @T6G_MB_LIB.T6G(SCH_1):GND
CG15    GND VSS_CG15 @T6G_MB_LIB.T6G(SCH_1):GND
CG20    GND VSS_CG20 @T6G_MB_LIB.T6G(SCH_1):GND
CG22    GND VSS_CG22 @T6G_MB_LIB.T6G(SCH_1):GND
CG25    GND VSS_CG25 @T6G_MB_LIB.T6G(SCH_1):GND
CG28    GND VSS_CG28 @T6G_MB_LIB.T6G(SCH_1):GND
CG31    GND VSS_CG31 @T6G_MB_LIB.T6G(SCH_1):GND
CG34    GND VSS_CG34 @T6G_MB_LIB.T6G(SCH_1):GND
CG45    GND VSS_CG45 @T6G_MB_LIB.T6G(SCH_1):GND
CG48    GND VSS_CG48 @T6G_MB_LIB.T6G(SCH_1):GND
CG51    GND VSS_CG51 @T6G_MB_LIB.T6G(SCH_1):GND
CG54    GND VSS_CG54 @T6G_MB_LIB.T6G(SCH_1):GND
CG56    GND VSS_CG56 @T6G_MB_LIB.T6G(SCH_1):GND
CG61    GND VSS_CG61 @T6G_MB_LIB.T6G(SCH_1):GND
CG63    GND VSS_CG63 @T6G_MB_LIB.T6G(SCH_1):GND
CG68    GND VSS_CG68 @T6G_MB_LIB.T6G(SCH_1):GND
CG70    GND VSS_CG70 @T6G_MB_LIB.T6G(SCH_1):GND
CG75    GND VSS_CG75 @T6G_MB_LIB.T6G(SCH_1):GND
 CH3    GND VSS_CH3 @T6G_MB_LIB.T6G(SCH_1):GND
 CH5    GND VSS_CH5 @T6G_MB_LIB.T6G(SCH_1):GND
 CH8    GND VSS_CH8 @T6G_MB_LIB.T6G(SCH_1):GND
CH22    GND VSS_CH22 @T6G_MB_LIB.T6G(SCH_1):GND
CH25    GND VSS_CH25 @T6G_MB_LIB.T6G(SCH_1):GND
CH28    GND VSS_CH28 @T6G_MB_LIB.T6G(SCH_1):GND
CH31    GND VSS_CH31 @T6G_MB_LIB.T6G(SCH_1):GND
CH34    GND VSS_CH34 @T6G_MB_LIB.T6G(SCH_1):GND
CH37    GND VSS_CH37 @T6G_MB_LIB.T6G(SCH_1):GND
CH54    GND VSS_CH54 @T6G_MB_LIB.T6G(SCH_1):GND
CH57    GND VSS_CH57 @T6G_MB_LIB.T6G(SCH_1):GND
CH59    GND VSS_CH59 @T6G_MB_LIB.T6G(SCH_1):GND
CH61    GND VSS_CH61 @T6G_MB_LIB.T6G(SCH_1):GND
CH64    GND VSS_CH64 @T6G_MB_LIB.T6G(SCH_1):GND
CH66    GND VSS_CH66 @T6G_MB_LIB.T6G(SCH_1):GND
 CJ6    GND VSS_CJ6 @T6G_MB_LIB.T6G(SCH_1):GND
 CJ8    GND VSS_CJ8 @T6G_MB_LIB.T6G(SCH_1):GND
CJ11    GND VSS_CJ11 @T6G_MB_LIB.T6G(SCH_1):GND
CJ13    GND VSS_CJ13 @T6G_MB_LIB.T6G(SCH_1):GND
CJ15    GND VSS_CJ15 @T6G_MB_LIB.T6G(SCH_1):GND
CJ18    GND VSS_CJ18 @T6G_MB_LIB.T6G(SCH_1):GND
CJ35    GND VSS_CJ35 @T6G_MB_LIB.T6G(SCH_1):GND
CJ36    GND VSS_CJ36 @T6G_MB_LIB.T6G(SCH_1):GND
CJ40    GND VSS_CJ40 @T6G_MB_LIB.T6G(SCH_1):GND
CJ41    GND VSS_CJ41 @T6G_MB_LIB.T6G(SCH_1):GND
CJ42    GND VSS_CJ42 @T6G_MB_LIB.T6G(SCH_1):GND
CJ45    GND VSS_CJ45 @T6G_MB_LIB.T6G(SCH_1):GND
CJ56    GND VSS_CJ56 @T6G_MB_LIB.T6G(SCH_1):GND
CJ65    GND VSS_CJ65 @T6G_MB_LIB.T6G(SCH_1):GND
CJ68    GND VSS_CJ68 @T6G_MB_LIB.T6G(SCH_1):GND
CJ70    GND VSS_CJ70 @T6G_MB_LIB.T6G(SCH_1):GND
CJ72    GND VSS_CJ72 @T6G_MB_LIB.T6G(SCH_1):GND
CJ75    GND VSS_CJ75 @T6G_MB_LIB.T6G(SCH_1):GND
 CK3    GND VSS_CK3 @T6G_MB_LIB.T6G(SCH_1):GND
 CK8    GND VSS_CK8 @T6G_MB_LIB.T6G(SCH_1):GND
CK22    GND VSS_CK22 @T6G_MB_LIB.T6G(SCH_1):GND
CK23    GND VSS_CK23 @T6G_MB_LIB.T6G(SCH_1):GND
CK24    GND VSS_CK24 @T6G_MB_LIB.T6G(SCH_1):GND
CK25    GND VSS_CK25 @T6G_MB_LIB.T6G(SCH_1):GND
CK26    GND VSS_CK26 @T6G_MB_LIB.T6G(SCH_1):GND
CK27    GND VSS_CK27 @T6G_MB_LIB.T6G(SCH_1):GND
CK28    GND VSS_CK28 @T6G_MB_LIB.T6G(SCH_1):GND
CK32    GND VSS_CK32 @T6G_MB_LIB.T6G(SCH_1):GND
CK34    GND VSS_CK34 @T6G_MB_LIB.T6G(SCH_1):GND
CK37    GND VSS_CK37 @T6G_MB_LIB.T6G(SCH_1):GND
CK39    GND VSS_CK39 @T6G_MB_LIB.T6G(SCH_1):GND
CK42    GND VSS_CK42 @T6G_MB_LIB.T6G(SCH_1):GND
CK43    GND VSS_CK43 @T6G_MB_LIB.T6G(SCH_1):GND
CK44    GND VSS_CK44 @T6G_MB_LIB.T6G(SCH_1):GND
CK45    GND VSS_CK45 @T6G_MB_LIB.T6G(SCH_1):GND
CK48    GND VSS_CK48 @T6G_MB_LIB.T6G(SCH_1):GND
CK49    GND VSS_CK49 @T6G_MB_LIB.T6G(SCH_1):GND
CK50    GND VSS_CK50 @T6G_MB_LIB.T6G(SCH_1):GND
CK51    GND VSS_CK51 @T6G_MB_LIB.T6G(SCH_1):GND
CK52    GND VSS_CK52 @T6G_MB_LIB.T6G(SCH_1):GND
CK53    GND VSS_CK53 @T6G_MB_LIB.T6G(SCH_1):GND
CK54    GND VSS_CK54 @T6G_MB_LIB.T6G(SCH_1):GND
CK59    GND VSS_CK59 @T6G_MB_LIB.T6G(SCH_1):GND
CK61    GND VSS_CK61 @T6G_MB_LIB.T6G(SCH_1):GND
CK66    GND VSS_CK66 @T6G_MB_LIB.T6G(SCH_1):GND
CK68    GND VSS_CK68 @T6G_MB_LIB.T6G(SCH_1):GND
CK73    GND VSS_CK73 @T6G_MB_LIB.T6G(SCH_1):GND
 CL1    GND VSS_CL1 @T6G_MB_LIB.T6G(SCH_1):GND
 CL4    GND VSS_CL4 @T6G_MB_LIB.T6G(SCH_1):GND
 CL6    GND VSS_CL6 @T6G_MB_LIB.T6G(SCH_1):GND
 CL8    GND VSS_CL8 @T6G_MB_LIB.T6G(SCH_1):GND
CL11    GND VSS_CL11 @T6G_MB_LIB.T6G(SCH_1):GND
CL13    GND VSS_CL13 @T6G_MB_LIB.T6G(SCH_1):GND
CL15    GND VSS_CL15 @T6G_MB_LIB.T6G(SCH_1):GND
CL18    GND VSS_CL18 @T6G_MB_LIB.T6G(SCH_1):GND
CL20    GND VSS_CL20 @T6G_MB_LIB.T6G(SCH_1):GND
CL22    GND VSS_CL22 @T6G_MB_LIB.T6G(SCH_1):GND
CL25    GND VSS_CL25 @T6G_MB_LIB.T6G(SCH_1):GND
CL31    GND VSS_CL31 @T6G_MB_LIB.T6G(SCH_1):GND
CL34    GND VSS_CL34 @T6G_MB_LIB.T6G(SCH_1):GND
CL35    GND VSS_CL35 @T6G_MB_LIB.T6G(SCH_1):GND
CL36    GND VSS_CL36 @T6G_MB_LIB.T6G(SCH_1):GND
CL40    GND VSS_CL40 @T6G_MB_LIB.T6G(SCH_1):GND
CL41    GND VSS_CL41 @T6G_MB_LIB.T6G(SCH_1):GND
CL42    GND VSS_CL42 @T6G_MB_LIB.T6G(SCH_1):GND
CL45    GND VSS_CL45 @T6G_MB_LIB.T6G(SCH_1):GND
CL48    GND VSS_CL48 @T6G_MB_LIB.T6G(SCH_1):GND
CL56    GND VSS_CL56 @T6G_MB_LIB.T6G(SCH_1):GND
CL58    GND VSS_CL58 @T6G_MB_LIB.T6G(SCH_1):GND
CL61    GND VSS_CL61 @T6G_MB_LIB.T6G(SCH_1):GND
CL63    GND VSS_CL63 @T6G_MB_LIB.T6G(SCH_1):GND
CL65    GND VSS_CL65 @T6G_MB_LIB.T6G(SCH_1):GND
CL68    GND VSS_CL68 @T6G_MB_LIB.T6G(SCH_1):GND
CL70    GND VSS_CL70 @T6G_MB_LIB.T6G(SCH_1):GND
CL72    GND VSS_CL72 @T6G_MB_LIB.T6G(SCH_1):GND
 CM8    GND VSS_CM8 @T6G_MB_LIB.T6G(SCH_1):GND
CM10    GND VSS_CM10 @T6G_MB_LIB.T6G(SCH_1):GND
CM12    GND VSS_CM12 @T6G_MB_LIB.T6G(SCH_1):GND
CM15    GND VSS_CM15 @T6G_MB_LIB.T6G(SCH_1):GND
CM17    GND VSS_CM17 @T6G_MB_LIB.T6G(SCH_1):GND
CM19    GND VSS_CM19 @T6G_MB_LIB.T6G(SCH_1):GND
CM23    GND VSS_CM23 @T6G_MB_LIB.T6G(SCH_1):GND
CM28    GND VSS_CM28 @T6G_MB_LIB.T6G(SCH_1):GND
CM29    GND VSS_CM29 @T6G_MB_LIB.T6G(SCH_1):GND
CM30    GND VSS_CM30 @T6G_MB_LIB.T6G(SCH_1):GND
CM31    GND VSS_CM31 @T6G_MB_LIB.T6G(SCH_1):GND
CM32    GND VSS_CM32 @T6G_MB_LIB.T6G(SCH_1):GND
CM33    GND VSS_CM33 @T6G_MB_LIB.T6G(SCH_1):GND
CM44    GND VSS_CM44 @T6G_MB_LIB.T6G(SCH_1):GND
CM45    GND VSS_CM45 @T6G_MB_LIB.T6G(SCH_1):GND
CM46    GND VSS_CM46 @T6G_MB_LIB.T6G(SCH_1):GND
CM47    GND VSS_CM47 @T6G_MB_LIB.T6G(SCH_1):GND
CM48    GND VSS_CM48 @T6G_MB_LIB.T6G(SCH_1):GND
CM49    GND VSS_CM49 @T6G_MB_LIB.T6G(SCH_1):GND
CM51    GND VSS_CM51 @T6G_MB_LIB.T6G(SCH_1):GND
CM52    GND VSS_CM52 @T6G_MB_LIB.T6G(SCH_1):GND
CM53    GND VSS_CM53 @T6G_MB_LIB.T6G(SCH_1):GND
CM57    GND VSS_CM57 @T6G_MB_LIB.T6G(SCH_1):GND
CM59    GND VSS_CM59 @T6G_MB_LIB.T6G(SCH_1):GND
CM68    GND VSS_CM68 @T6G_MB_LIB.T6G(SCH_1):GND
CM71    GND VSS_CM71 @T6G_MB_LIB.T6G(SCH_1):GND
CM73    GND VSS_CM73 @T6G_MB_LIB.T6G(SCH_1):GND
 CN1    GND VSS_CN1 @T6G_MB_LIB.T6G(SCH_1):GND
 CN6    GND VSS_CN6 @T6G_MB_LIB.T6G(SCH_1):GND
 CN8    GND VSS_CN8 @T6G_MB_LIB.T6G(SCH_1):GND
CN13    GND VSS_CN13 @T6G_MB_LIB.T6G(SCH_1):GND
CN15    GND VSS_CN15 @T6G_MB_LIB.T6G(SCH_1):GND
CN25    GND VSS_CN25 @T6G_MB_LIB.T6G(SCH_1):GND
CN28    GND VSS_CN28 @T6G_MB_LIB.T6G(SCH_1):GND
CN31    GND VSS_CN31 @T6G_MB_LIB.T6G(SCH_1):GND
CN34    GND VSS_CN34 @T6G_MB_LIB.T6G(SCH_1):GND
CN42    GND VSS_CN42 @T6G_MB_LIB.T6G(SCH_1):GND
CN45    GND VSS_CN45 @T6G_MB_LIB.T6G(SCH_1):GND
CN48    GND VSS_CN48 @T6G_MB_LIB.T6G(SCH_1):GND
CN51    GND VSS_CN51 @T6G_MB_LIB.T6G(SCH_1):GND
CN61    GND VSS_CN61 @T6G_MB_LIB.T6G(SCH_1):GND
CN63    GND VSS_CN63 @T6G_MB_LIB.T6G(SCH_1):GND
CN68    GND VSS_CN68 @T6G_MB_LIB.T6G(SCH_1):GND
CN70    GND VSS_CN70 @T6G_MB_LIB.T6G(SCH_1):GND
CN75    GND VSS_CN75 @T6G_MB_LIB.T6G(SCH_1):GND
 CP3    GND VSS_CP3 @T6G_MB_LIB.T6G(SCH_1):GND
 CP5    GND VSS_CP5 @T6G_MB_LIB.T6G(SCH_1):GND
 CP8    GND VSS_CP8 @T6G_MB_LIB.T6G(SCH_1):GND
CP10    GND VSS_CP10 @T6G_MB_LIB.T6G(SCH_1):GND
CP12    GND VSS_CP12 @T6G_MB_LIB.T6G(SCH_1):GND
CP15    GND VSS_CP15 @T6G_MB_LIB.T6G(SCH_1):GND
CP17    GND VSS_CP17 @T6G_MB_LIB.T6G(SCH_1):GND
CP19    GND VSS_CP19 @T6G_MB_LIB.T6G(SCH_1):GND

GENOA_SP5-SOCKET6096_13568-001,SMLF,IO,DGA^6000030  I16  U25
CP22    GND VSS_CP22 @T6G_MB_LIB.T6G(SCH_1):GND
CP42    GND VSS_CP42 @T6G_MB_LIB.T6G(SCH_1):GND
CP45    GND VSS_CP45 @T6G_MB_LIB.T6G(SCH_1):GND
CP48    GND VSS_CP48 @T6G_MB_LIB.T6G(SCH_1):GND
CP51    GND VSS_CP51 @T6G_MB_LIB.T6G(SCH_1):GND
CP54    GND VSS_CP54 @T6G_MB_LIB.T6G(SCH_1):GND
CP71    GND VSS_CP71 @T6G_MB_LIB.T6G(SCH_1):GND
CP73    GND VSS_CP73 @T6G_MB_LIB.T6G(SCH_1):GND
 CR1    GND VSS_CR1 @T6G_MB_LIB.T6G(SCH_1):GND
 CR4    GND VSS_CR4 @T6G_MB_LIB.T6G(SCH_1):GND
 CR6    GND VSS_CR6 @T6G_MB_LIB.T6G(SCH_1):GND
CR22    GND VSS_CR22 @T6G_MB_LIB.T6G(SCH_1):GND
CR25    GND VSS_CR25 @T6G_MB_LIB.T6G(SCH_1):GND
CR28    GND VSS_CR28 @T6G_MB_LIB.T6G(SCH_1):GND
CR31    GND VSS_CR31 @T6G_MB_LIB.T6G(SCH_1):GND
CR34    GND VSS_CR34 @T6G_MB_LIB.T6G(SCH_1):GND
CR48    GND VSS_CR48 @T6G_MB_LIB.T6G(SCH_1):GND
CR51    GND VSS_CR51 @T6G_MB_LIB.T6G(SCH_1):GND
CR54    GND VSS_CR54 @T6G_MB_LIB.T6G(SCH_1):GND
CR56    GND VSS_CR56 @T6G_MB_LIB.T6G(SCH_1):GND
CR58    GND VSS_CR58 @T6G_MB_LIB.T6G(SCH_1):GND
CR75    GND VSS_CR75 @T6G_MB_LIB.T6G(SCH_1):GND
 CT3    GND VSS_CT3 @T6G_MB_LIB.T6G(SCH_1):GND
 CT8    GND VSS_CT8 @T6G_MB_LIB.T6G(SCH_1):GND
CT10    GND VSS_CT10 @T6G_MB_LIB.T6G(SCH_1):GND
CT15    GND VSS_CT15 @T6G_MB_LIB.T6G(SCH_1):GND
CT48    GND VSS_CT48 @T6G_MB_LIB.T6G(SCH_1):GND
CT73    GND VSS_CT73 @T6G_MB_LIB.T6G(SCH_1):GND
 CU1    GND VSS_CU1 @T6G_MB_LIB.T6G(SCH_1):GND
CU22    GND VSS_CU22 @T6G_MB_LIB.T6G(SCH_1):GND
CU25    GND VSS_CU25 @T6G_MB_LIB.T6G(SCH_1):GND
CU28    GND VSS_CU28 @T6G_MB_LIB.T6G(SCH_1):GND
CU56    GND VSS_CU56 @T6G_MB_LIB.T6G(SCH_1):GND
CU61    GND VSS_CU61 @T6G_MB_LIB.T6G(SCH_1):GND
CU63    GND VSS_CU63 @T6G_MB_LIB.T6G(SCH_1):GND
 CV5    GND VSS_CV5 @T6G_MB_LIB.T6G(SCH_1):GND
 CV8    GND VSS_CV8 @T6G_MB_LIB.T6G(SCH_1):GND
CV10    GND VSS_CV10 @T6G_MB_LIB.T6G(SCH_1):GND
CV12    GND VSS_CV12 @T6G_MB_LIB.T6G(SCH_1):GND
CV15    GND VSS_CV15 @T6G_MB_LIB.T6G(SCH_1):GND
CV34    GND VSS_CV34 @T6G_MB_LIB.T6G(SCH_1):GND
CV37    GND VSS_CV37 @T6G_MB_LIB.T6G(SCH_1):GND
CV39    GND VSS_CV39 @T6G_MB_LIB.T6G(SCH_1):GND
CV42    GND VSS_CV42 @T6G_MB_LIB.T6G(SCH_1):GND
CV45    GND VSS_CV45 @T6G_MB_LIB.T6G(SCH_1):GND
CV64    GND VSS_CV64 @T6G_MB_LIB.T6G(SCH_1):GND
CV66    GND VSS_CV66 @T6G_MB_LIB.T6G(SCH_1):GND
CV68    GND VSS_CV68 @T6G_MB_LIB.T6G(SCH_1):GND
CV71    GND VSS_CV71 @T6G_MB_LIB.T6G(SCH_1):GND
CV73    GND VSS_CV73 @T6G_MB_LIB.T6G(SCH_1):GND
CW22    GND VSS_CW22 @T6G_MB_LIB.T6G(SCH_1):GND
CW25    GND VSS_CW25 @T6G_MB_LIB.T6G(SCH_1):GND
CW28    GND VSS_CW28 @T6G_MB_LIB.T6G(SCH_1):GND
CW31    GND VSS_CW31 @T6G_MB_LIB.T6G(SCH_1):GND
CW34    GND VSS_CW34 @T6G_MB_LIB.T6G(SCH_1):GND
CY32    GND VSS_CY32 @T6G_MB_LIB.T6G(SCH_1):GND
CY47    GND VSS_CY47 @T6G_MB_LIB.T6G(SCH_1):GND
CY48    GND VSS_CY48 @T6G_MB_LIB.T6G(SCH_1):GND
CY64    GND VSS_CY64 @T6G_MB_LIB.T6G(SCH_1):GND
CY66    GND VSS_CY66 @T6G_MB_LIB.T6G(SCH_1):GND
CY68    GND VSS_CY68 @T6G_MB_LIB.T6G(SCH_1):GND
DA13    GND VSS_DA13 @T6G_MB_LIB.T6G(SCH_1):GND
DA15    GND VSS_DA15 @T6G_MB_LIB.T6G(SCH_1):GND
DA18    GND VSS_DA18 @T6G_MB_LIB.T6G(SCH_1):GND
DA20    GND VSS_DA20 @T6G_MB_LIB.T6G(SCH_1):GND
DA45    GND VSS_DA45 @T6G_MB_LIB.T6G(SCH_1):GND
DA48    GND VSS_DA48 @T6G_MB_LIB.T6G(SCH_1):GND
DA51    GND VSS_DA51 @T6G_MB_LIB.T6G(SCH_1):GND
DA54    GND VSS_DA54 @T6G_MB_LIB.T6G(SCH_1):GND
CP25    GND VSS_CP25 @T6G_MB_LIB.T6G(SCH_1):GND
CP28    GND VSS_CP28 @T6G_MB_LIB.T6G(SCH_1):GND
CP31    GND VSS_CP31 @T6G_MB_LIB.T6G(SCH_1):GND
CP34    GND VSS_CP34 @T6G_MB_LIB.T6G(SCH_1):GND
CP37    GND VSS_CP37 @T6G_MB_LIB.T6G(SCH_1):GND
CP39    GND VSS_CP39 @T6G_MB_LIB.T6G(SCH_1):GND
CP57    GND VSS_CP57 @T6G_MB_LIB.T6G(SCH_1):GND
CP59    GND VSS_CP59 @T6G_MB_LIB.T6G(SCH_1):GND
CP61    GND VSS_CP61 @T6G_MB_LIB.T6G(SCH_1):GND
CP64    GND VSS_CP64 @T6G_MB_LIB.T6G(SCH_1):GND
CP66    GND VSS_CP66 @T6G_MB_LIB.T6G(SCH_1):GND
CP68    GND VSS_CP68 @T6G_MB_LIB.T6G(SCH_1):GND
 CR8    GND VSS_CR8 @T6G_MB_LIB.T6G(SCH_1):GND
CR11    GND VSS_CR11 @T6G_MB_LIB.T6G(SCH_1):GND
CR13    GND VSS_CR13 @T6G_MB_LIB.T6G(SCH_1):GND
CR15    GND VSS_CR15 @T6G_MB_LIB.T6G(SCH_1):GND
CR18    GND VSS_CR18 @T6G_MB_LIB.T6G(SCH_1):GND
CR20    GND VSS_CR20 @T6G_MB_LIB.T6G(SCH_1):GND
CR35    GND VSS_CR35 @T6G_MB_LIB.T6G(SCH_1):GND
CR36    GND VSS_CR36 @T6G_MB_LIB.T6G(SCH_1):GND
CR40    GND VSS_CR40 @T6G_MB_LIB.T6G(SCH_1):GND
CR41    GND VSS_CR41 @T6G_MB_LIB.T6G(SCH_1):GND
CR42    GND VSS_CR42 @T6G_MB_LIB.T6G(SCH_1):GND
CR45    GND VSS_CR45 @T6G_MB_LIB.T6G(SCH_1):GND
CR61    GND VSS_CR61 @T6G_MB_LIB.T6G(SCH_1):GND
CR63    GND VSS_CR63 @T6G_MB_LIB.T6G(SCH_1):GND
CR65    GND VSS_CR65 @T6G_MB_LIB.T6G(SCH_1):GND
CR68    GND VSS_CR68 @T6G_MB_LIB.T6G(SCH_1):GND
CR70    GND VSS_CR70 @T6G_MB_LIB.T6G(SCH_1):GND
CR72    GND VSS_CR72 @T6G_MB_LIB.T6G(SCH_1):GND
CT17    GND VSS_CT17 @T6G_MB_LIB.T6G(SCH_1):GND
CT23    GND VSS_CT23 @T6G_MB_LIB.T6G(SCH_1):GND
CT24    GND VSS_CT24 @T6G_MB_LIB.T6G(SCH_1):GND
CT25    GND VSS_CT25 @T6G_MB_LIB.T6G(SCH_1):GND
CT26    GND VSS_CT26 @T6G_MB_LIB.T6G(SCH_1):GND
CT27    GND VSS_CT27 @T6G_MB_LIB.T6G(SCH_1):GND
CT28    GND VSS_CT28 @T6G_MB_LIB.T6G(SCH_1):GND
CT29    GND VSS_CT29 @T6G_MB_LIB.T6G(SCH_1):GND
CT30    GND VSS_CT30 @T6G_MB_LIB.T6G(SCH_1):GND
CT31    GND VSS_CT31 @T6G_MB_LIB.T6G(SCH_1):GND
CT32    GND VSS_CT32 @T6G_MB_LIB.T6G(SCH_1):GND
CT33    GND VSS_CT33 @T6G_MB_LIB.T6G(SCH_1):GND
CT34    GND VSS_CT34 @T6G_MB_LIB.T6G(SCH_1):GND
CT37    GND VSS_CT37 @T6G_MB_LIB.T6G(SCH_1):GND
CT39    GND VSS_CT39 @T6G_MB_LIB.T6G(SCH_1):GND
CT42    GND VSS_CT42 @T6G_MB_LIB.T6G(SCH_1):GND
CT43    GND VSS_CT43 @T6G_MB_LIB.T6G(SCH_1):GND
CT44    GND VSS_CT44 @T6G_MB_LIB.T6G(SCH_1):GND
CT45    GND VSS_CT45 @T6G_MB_LIB.T6G(SCH_1):GND
CT46    GND VSS_CT46 @T6G_MB_LIB.T6G(SCH_1):GND
CT47    GND VSS_CT47 @T6G_MB_LIB.T6G(SCH_1):GND
CT49    GND VSS_CT49 @T6G_MB_LIB.T6G(SCH_1):GND
CT50    GND VSS_CT50 @T6G_MB_LIB.T6G(SCH_1):GND
CT51    GND VSS_CT51 @T6G_MB_LIB.T6G(SCH_1):GND
CT53    GND VSS_CT53 @T6G_MB_LIB.T6G(SCH_1):GND
CT59    GND VSS_CT59 @T6G_MB_LIB.T6G(SCH_1):GND
CT61    GND VSS_CT61 @T6G_MB_LIB.T6G(SCH_1):GND
CT66    GND VSS_CT66 @T6G_MB_LIB.T6G(SCH_1):GND
CT68    GND VSS_CT68 @T6G_MB_LIB.T6G(SCH_1):GND
 CU4    GND VSS_CU4 @T6G_MB_LIB.T6G(SCH_1):GND
 CU6    GND VSS_CU6 @T6G_MB_LIB.T6G(SCH_1):GND
 CU8    GND VSS_CU8 @T6G_MB_LIB.T6G(SCH_1):GND
CU11    GND VSS_CU11 @T6G_MB_LIB.T6G(SCH_1):GND
CU13    GND VSS_CU13 @T6G_MB_LIB.T6G(SCH_1):GND
CU15    GND VSS_CU15 @T6G_MB_LIB.T6G(SCH_1):GND
CU18    GND VSS_CU18 @T6G_MB_LIB.T6G(SCH_1):GND
CU20    GND VSS_CU20 @T6G_MB_LIB.T6G(SCH_1):GND
CU31    GND VSS_CU31 @T6G_MB_LIB.T6G(SCH_1):GND
CU34    GND VSS_CU34 @T6G_MB_LIB.T6G(SCH_1):GND
CU42    GND VSS_CU42 @T6G_MB_LIB.T6G(SCH_1):GND
CU45    GND VSS_CU45 @T6G_MB_LIB.T6G(SCH_1):GND
CU48    GND VSS_CU48 @T6G_MB_LIB.T6G(SCH_1):GND
CU51    GND VSS_CU51 @T6G_MB_LIB.T6G(SCH_1):GND
CU54    GND VSS_CU54 @T6G_MB_LIB.T6G(SCH_1):GND
CU65    GND VSS_CU65 @T6G_MB_LIB.T6G(SCH_1):GND
CU68    GND VSS_CU68 @T6G_MB_LIB.T6G(SCH_1):GND
CU70    GND VSS_CU70 @T6G_MB_LIB.T6G(SCH_1):GND
CU72    GND VSS_CU72 @T6G_MB_LIB.T6G(SCH_1):GND
CU75    GND VSS_CU75 @T6G_MB_LIB.T6G(SCH_1):GND
 CV3    GND VSS_CV3 @T6G_MB_LIB.T6G(SCH_1):GND
CV17    GND VSS_CV17 @T6G_MB_LIB.T6G(SCH_1):GND
CV19    GND VSS_CV19 @T6G_MB_LIB.T6G(SCH_1):GND
CV22    GND VSS_CV22 @T6G_MB_LIB.T6G(SCH_1):GND
CV25    GND VSS_CV25 @T6G_MB_LIB.T6G(SCH_1):GND
CV28    GND VSS_CV28 @T6G_MB_LIB.T6G(SCH_1):GND
CV31    GND VSS_CV31 @T6G_MB_LIB.T6G(SCH_1):GND
CV48    GND VSS_CV48 @T6G_MB_LIB.T6G(SCH_1):GND
CV51    GND VSS_CV51 @T6G_MB_LIB.T6G(SCH_1):GND
CV54    GND VSS_CV54 @T6G_MB_LIB.T6G(SCH_1):GND
CV57    GND VSS_CV57 @T6G_MB_LIB.T6G(SCH_1):GND
CV59    GND VSS_CV59 @T6G_MB_LIB.T6G(SCH_1):GND
CV61    GND VSS_CV61 @T6G_MB_LIB.T6G(SCH_1):GND
 CW1    GND VSS_CW1 @T6G_MB_LIB.T6G(SCH_1):GND
 CW6    GND VSS_CW6 @T6G_MB_LIB.T6G(SCH_1):GND
 CW8    GND VSS_CW8 @T6G_MB_LIB.T6G(SCH_1):GND
CW13    GND VSS_CW13 @T6G_MB_LIB.T6G(SCH_1):GND
CW15    GND VSS_CW15 @T6G_MB_LIB.T6G(SCH_1):GND
CW20    GND VSS_CW20 @T6G_MB_LIB.T6G(SCH_1):GND
CW35    GND VSS_CW35 @T6G_MB_LIB.T6G(SCH_1):GND
CW36    GND VSS_CW36 @T6G_MB_LIB.T6G(SCH_1):GND
CW40    GND VSS_CW40 @T6G_MB_LIB.T6G(SCH_1):GND
CW41    GND VSS_CW41 @T6G_MB_LIB.T6G(SCH_1):GND
CW42    GND VSS_CW42 @T6G_MB_LIB.T6G(SCH_1):GND
CW45    GND VSS_CW45 @T6G_MB_LIB.T6G(SCH_1):GND
CW48    GND VSS_CW48 @T6G_MB_LIB.T6G(SCH_1):GND
CW51    GND VSS_CW51 @T6G_MB_LIB.T6G(SCH_1):GND
CW54    GND VSS_CW54 @T6G_MB_LIB.T6G(SCH_1):GND
CW56    GND VSS_CW56 @T6G_MB_LIB.T6G(SCH_1):GND
CW61    GND VSS_CW61 @T6G_MB_LIB.T6G(SCH_1):GND
CW63    GND VSS_CW63 @T6G_MB_LIB.T6G(SCH_1):GND
CW68    GND VSS_CW68 @T6G_MB_LIB.T6G(SCH_1):GND
CW70    GND VSS_CW70 @T6G_MB_LIB.T6G(SCH_1):GND
CW75    GND VSS_CW75 @T6G_MB_LIB.T6G(SCH_1):GND
 CY3    GND VSS_CY3 @T6G_MB_LIB.T6G(SCH_1):GND
 CY5    GND VSS_CY5 @T6G_MB_LIB.T6G(SCH_1):GND
 CY8    GND VSS_CY8 @T6G_MB_LIB.T6G(SCH_1):GND
CY10    GND VSS_CY10 @T6G_MB_LIB.T6G(SCH_1):GND
CY12    GND VSS_CY12 @T6G_MB_LIB.T6G(SCH_1):GND
CY15    GND VSS_CY15 @T6G_MB_LIB.T6G(SCH_1):GND
CY17    GND VSS_CY17 @T6G_MB_LIB.T6G(SCH_1):GND
CY19    GND VSS_CY19 @T6G_MB_LIB.T6G(SCH_1):GND
CY23    GND VSS_CY23 @T6G_MB_LIB.T6G(SCH_1):GND
CY24    GND VSS_CY24 @T6G_MB_LIB.T6G(SCH_1):GND
CY25    GND VSS_CY25 @T6G_MB_LIB.T6G(SCH_1):GND
CY26    GND VSS_CY26 @T6G_MB_LIB.T6G(SCH_1):GND
CY27    GND VSS_CY27 @T6G_MB_LIB.T6G(SCH_1):GND
CY28    GND VSS_CY28 @T6G_MB_LIB.T6G(SCH_1):GND
CY29    GND VSS_CY29 @T6G_MB_LIB.T6G(SCH_1):GND
CY30    GND VSS_CY30 @T6G_MB_LIB.T6G(SCH_1):GND
CY31    GND VSS_CY31 @T6G_MB_LIB.T6G(SCH_1):GND
CY33    GND VSS_CY33 @T6G_MB_LIB.T6G(SCH_1):GND
CY34    GND VSS_CY34 @T6G_MB_LIB.T6G(SCH_1):GND
CY37    GND VSS_CY37 @T6G_MB_LIB.T6G(SCH_1):GND
CY39    GND VSS_CY39 @T6G_MB_LIB.T6G(SCH_1):GND
CY42    GND VSS_CY42 @T6G_MB_LIB.T6G(SCH_1):GND
CY43    GND VSS_CY43 @T6G_MB_LIB.T6G(SCH_1):GND
CY44    GND VSS_CY44 @T6G_MB_LIB.T6G(SCH_1):GND
CY45    GND VSS_CY45 @T6G_MB_LIB.T6G(SCH_1):GND
CY46    GND VSS_CY46 @T6G_MB_LIB.T6G(SCH_1):GND
CY49    GND VSS_CY49 @T6G_MB_LIB.T6G(SCH_1):GND
CY50    GND VSS_CY50 @T6G_MB_LIB.T6G(SCH_1):GND
CY51    GND VSS_CY51 @T6G_MB_LIB.T6G(SCH_1):GND
CY52    GND VSS_CY52 @T6G_MB_LIB.T6G(SCH_1):GND
CY53    GND VSS_CY53 @T6G_MB_LIB.T6G(SCH_1):GND
CY59    GND VSS_CY59 @T6G_MB_LIB.T6G(SCH_1):GND
CY61    GND VSS_CY61 @T6G_MB_LIB.T6G(SCH_1):GND
CY71    GND VSS_CY71 @T6G_MB_LIB.T6G(SCH_1):GND
CY73    GND VSS_CY73 @T6G_MB_LIB.T6G(SCH_1):GND
 DA1    GND VSS_DA1 @T6G_MB_LIB.T6G(SCH_1):GND
 DA4    GND VSS_DA4 @T6G_MB_LIB.T6G(SCH_1):GND
 DA6    GND VSS_DA6 @T6G_MB_LIB.T6G(SCH_1):GND
 DA8    GND VSS_DA8 @T6G_MB_LIB.T6G(SCH_1):GND
DA11    GND VSS_DA11 @T6G_MB_LIB.T6G(SCH_1):GND
DA22    GND VSS_DA22 @T6G_MB_LIB.T6G(SCH_1):GND
DA25    GND VSS_DA25 @T6G_MB_LIB.T6G(SCH_1):GND
DA28    GND VSS_DA28 @T6G_MB_LIB.T6G(SCH_1):GND
DA31    GND VSS_DA31 @T6G_MB_LIB.T6G(SCH_1):GND
DA34    GND VSS_DA34 @T6G_MB_LIB.T6G(SCH_1):GND
DA42    GND VSS_DA42 @T6G_MB_LIB.T6G(SCH_1):GND
DA58    GND VSS_DA58 @T6G_MB_LIB.T6G(SCH_1):GND
DA61    GND VSS_DA61 @T6G_MB_LIB.T6G(SCH_1):GND
DA63    GND VSS_DA63 @T6G_MB_LIB.T6G(SCH_1):GND
DA65    GND VSS_DA65 @T6G_MB_LIB.T6G(SCH_1):GND
DA68    GND VSS_DA68 @T6G_MB_LIB.T6G(SCH_1):GND
DA70    GND VSS_DA70 @T6G_MB_LIB.T6G(SCH_1):GND


DRAWING: @T6G_MB_LIB.T6G(SCH_1):PAGE33 

GENOA_SP5-SOCKET6096_13568-001,SMLF,IO,DGA^6000030  I4  U25
DB15    GND VSS_DB15 @T6G_MB_LIB.T6G(SCH_1):GND
DB17    GND VSS_DB17 @T6G_MB_LIB.T6G(SCH_1):GND
DB22    GND VSS_DB22 @T6G_MB_LIB.T6G(SCH_1):GND
DB25    GND VSS_DB25 @T6G_MB_LIB.T6G(SCH_1):GND
DB48    GND VSS_DB48 @T6G_MB_LIB.T6G(SCH_1):GND
DB51    GND VSS_DB51 @T6G_MB_LIB.T6G(SCH_1):GND
DB54    GND VSS_DB54 @T6G_MB_LIB.T6G(SCH_1):GND
DB59    GND VSS_DB59 @T6G_MB_LIB.T6G(SCH_1):GND
DC13    GND VSS_DC13 @T6G_MB_LIB.T6G(SCH_1):GND
DC15    GND VSS_DC15 @T6G_MB_LIB.T6G(SCH_1):GND
DC45    GND VSS_DC45 @T6G_MB_LIB.T6G(SCH_1):GND
DC48    GND VSS_DC48 @T6G_MB_LIB.T6G(SCH_1):GND
DC51    GND VSS_DC51 @T6G_MB_LIB.T6G(SCH_1):GND
DC70    GND VSS_DC70 @T6G_MB_LIB.T6G(SCH_1):GND
DC72    GND VSS_DC72 @T6G_MB_LIB.T6G(SCH_1):GND
DC75    GND VSS_DC75 @T6G_MB_LIB.T6G(SCH_1):GND
 DD3    GND VSS_DD3 @T6G_MB_LIB.T6G(SCH_1):GND
DD23    GND VSS_DD23 @T6G_MB_LIB.T6G(SCH_1):GND
DD24    GND VSS_DD24 @T6G_MB_LIB.T6G(SCH_1):GND
DD26    GND VSS_DD26 @T6G_MB_LIB.T6G(SCH_1):GND
DD27    GND VSS_DD27 @T6G_MB_LIB.T6G(SCH_1):GND
DD39    GND VSS_DD39 @T6G_MB_LIB.T6G(SCH_1):GND
DD40    GND VSS_DD40 @T6G_MB_LIB.T6G(SCH_1):GND
DD41    GND VSS_DD41 @T6G_MB_LIB.T6G(SCH_1):GND
DD43    GND VSS_DD43 @T6G_MB_LIB.T6G(SCH_1):GND
DD57    GND VSS_DD57 @T6G_MB_LIB.T6G(SCH_1):GND
DD59    GND VSS_DD59 @T6G_MB_LIB.T6G(SCH_1):GND
DD61    GND VSS_DD61 @T6G_MB_LIB.T6G(SCH_1):GND
DD64    GND VSS_DD64 @T6G_MB_LIB.T6G(SCH_1):GND
DE13    GND VSS_DE13 @T6G_MB_LIB.T6G(SCH_1):GND
DE15    GND VSS_DE15 @T6G_MB_LIB.T6G(SCH_1):GND
DE20    GND VSS_DE20 @T6G_MB_LIB.T6G(SCH_1):GND
DE23    GND VSS_DE23 @T6G_MB_LIB.T6G(SCH_1):GND
DE70    GND VSS_DE70 @T6G_MB_LIB.T6G(SCH_1):GND
DE75    GND VSS_DE75 @T6G_MB_LIB.T6G(SCH_1):GND
 DF3    GND VSS_DF3 @T6G_MB_LIB.T6G(SCH_1):GND
 DF4    GND VSS_DF4 @T6G_MB_LIB.T6G(SCH_1):GND
DF15    GND VSS_DF15 @T6G_MB_LIB.T6G(SCH_1):GND
DF17    GND VSS_DF17 @T6G_MB_LIB.T6G(SCH_1):GND
DF18    GND VSS_DF18 @T6G_MB_LIB.T6G(SCH_1):GND
DF19    GND VSS_DF19 @T6G_MB_LIB.T6G(SCH_1):GND
DF43    GND VSS_DF43 @T6G_MB_LIB.T6G(SCH_1):GND
DF53    GND VSS_DF53 @T6G_MB_LIB.T6G(SCH_1):GND
DF54    GND VSS_DF54 @T6G_MB_LIB.T6G(SCH_1):GND
DF66    GND VSS_DF66 @T6G_MB_LIB.T6G(SCH_1):GND
DF68    GND VSS_DF68 @T6G_MB_LIB.T6G(SCH_1):GND
DF70    GND VSS_DF70 @T6G_MB_LIB.T6G(SCH_1):GND
 DG8    GND VSS_DG8 @T6G_MB_LIB.T6G(SCH_1):GND
 DG9    GND VSS_DG9 @T6G_MB_LIB.T6G(SCH_1):GND
DG13    GND VSS_DG13 @T6G_MB_LIB.T6G(SCH_1):GND
DG14    GND VSS_DG14 @T6G_MB_LIB.T6G(SCH_1):GND
DG30    GND VSS_DG30 @T6G_MB_LIB.T6G(SCH_1):GND
DG33    GND VSS_DG33 @T6G_MB_LIB.T6G(SCH_1):GND
DG41    GND VSS_DG41 @T6G_MB_LIB.T6G(SCH_1):GND
DG43    GND VSS_DG43 @T6G_MB_LIB.T6G(SCH_1):GND
DG61    GND VSS_DG61 @T6G_MB_LIB.T6G(SCH_1):GND
DG62    GND VSS_DG62 @T6G_MB_LIB.T6G(SCH_1):GND
DG63    GND VSS_DG63 @T6G_MB_LIB.T6G(SCH_1):GND
DG65    GND VSS_DG65 @T6G_MB_LIB.T6G(SCH_1):GND
 DH5    GND VSS_DH5 @T6G_MB_LIB.T6G(SCH_1):GND
DH11    GND VSS_DH11 @T6G_MB_LIB.T6G(SCH_1):GND
DH18    GND VSS_DH18 @T6G_MB_LIB.T6G(SCH_1):GND
DH37    GND VSS_DH37 @T6G_MB_LIB.T6G(SCH_1):GND
DH61    GND VSS_DH61 @T6G_MB_LIB.T6G(SCH_1):GND
DH63    GND VSS_DH63 @T6G_MB_LIB.T6G(SCH_1):GND
DH64    GND VSS_DH64 @T6G_MB_LIB.T6G(SCH_1):GND
DH66    GND VSS_DH66 @T6G_MB_LIB.T6G(SCH_1):GND
DA72    GND VSS_DA72 @T6G_MB_LIB.T6G(SCH_1):GND
DA75    GND VSS_DA75 @T6G_MB_LIB.T6G(SCH_1):GND
 DB3    GND VSS_DB3 @T6G_MB_LIB.T6G(SCH_1):GND
 DB8    GND VSS_DB8 @T6G_MB_LIB.T6G(SCH_1):GND
DB10    GND VSS_DB10 @T6G_MB_LIB.T6G(SCH_1):GND
DB28    GND VSS_DB28 @T6G_MB_LIB.T6G(SCH_1):GND
DB31    GND VSS_DB31 @T6G_MB_LIB.T6G(SCH_1):GND
DB34    GND VSS_DB34 @T6G_MB_LIB.T6G(SCH_1):GND
DB37    GND VSS_DB37 @T6G_MB_LIB.T6G(SCH_1):GND
DB39    GND VSS_DB39 @T6G_MB_LIB.T6G(SCH_1):GND
DB42    GND VSS_DB42 @T6G_MB_LIB.T6G(SCH_1):GND
DB45    GND VSS_DB45 @T6G_MB_LIB.T6G(SCH_1):GND
DB61    GND VSS_DB61 @T6G_MB_LIB.T6G(SCH_1):GND
DB66    GND VSS_DB66 @T6G_MB_LIB.T6G(SCH_1):GND
DB68    GND VSS_DB68 @T6G_MB_LIB.T6G(SCH_1):GND
DB73    GND VSS_DB73 @T6G_MB_LIB.T6G(SCH_1):GND
 DC1    GND VSS_DC1 @T6G_MB_LIB.T6G(SCH_1):GND
 DC4    GND VSS_DC4 @T6G_MB_LIB.T6G(SCH_1):GND
 DC6    GND VSS_DC6 @T6G_MB_LIB.T6G(SCH_1):GND
 DC8    GND VSS_DC8 @T6G_MB_LIB.T6G(SCH_1):GND
DC11    GND VSS_DC11 @T6G_MB_LIB.T6G(SCH_1):GND
DC18    GND VSS_DC18 @T6G_MB_LIB.T6G(SCH_1):GND
DC20    GND VSS_DC20 @T6G_MB_LIB.T6G(SCH_1):GND
DC22    GND VSS_DC22 @T6G_MB_LIB.T6G(SCH_1):GND
DC25    GND VSS_DC25 @T6G_MB_LIB.T6G(SCH_1):GND
DC28    GND VSS_DC28 @T6G_MB_LIB.T6G(SCH_1):GND
DC31    GND VSS_DC31 @T6G_MB_LIB.T6G(SCH_1):GND
DC34    GND VSS_DC34 @T6G_MB_LIB.T6G(SCH_1):GND
DC42    GND VSS_DC42 @T6G_MB_LIB.T6G(SCH_1):GND
DC54    GND VSS_DC54 @T6G_MB_LIB.T6G(SCH_1):GND
DC56    GND VSS_DC56 @T6G_MB_LIB.T6G(SCH_1):GND
DC58    GND VSS_DC58 @T6G_MB_LIB.T6G(SCH_1):GND
DC61    GND VSS_DC61 @T6G_MB_LIB.T6G(SCH_1):GND
DC63    GND VSS_DC63 @T6G_MB_LIB.T6G(SCH_1):GND
DC65    GND VSS_DC65 @T6G_MB_LIB.T6G(SCH_1):GND
DC68    GND VSS_DC68 @T6G_MB_LIB.T6G(SCH_1):GND
 DD5    GND VSS_DD5 @T6G_MB_LIB.T6G(SCH_1):GND
 DD8    GND VSS_DD8 @T6G_MB_LIB.T6G(SCH_1):GND
DD10    GND VSS_DD10 @T6G_MB_LIB.T6G(SCH_1):GND
DD12    GND VSS_DD12 @T6G_MB_LIB.T6G(SCH_1):GND
DD15    GND VSS_DD15 @T6G_MB_LIB.T6G(SCH_1):GND
DD17    GND VSS_DD17 @T6G_MB_LIB.T6G(SCH_1):GND
DD19    GND VSS_DD19 @T6G_MB_LIB.T6G(SCH_1):GND
DD29    GND VSS_DD29 @T6G_MB_LIB.T6G(SCH_1):GND
DD30    GND VSS_DD30 @T6G_MB_LIB.T6G(SCH_1):GND
DD32    GND VSS_DD32 @T6G_MB_LIB.T6G(SCH_1):GND
DD33    GND VSS_DD33 @T6G_MB_LIB.T6G(SCH_1):GND
DD35    GND VSS_DD35 @T6G_MB_LIB.T6G(SCH_1):GND
DD36    GND VSS_DD36 @T6G_MB_LIB.T6G(SCH_1):GND
DD37    GND VSS_DD37 @T6G_MB_LIB.T6G(SCH_1):GND
DD44    GND VSS_DD44 @T6G_MB_LIB.T6G(SCH_1):GND
DD46    GND VSS_DD46 @T6G_MB_LIB.T6G(SCH_1):GND
DD47    GND VSS_DD47 @T6G_MB_LIB.T6G(SCH_1):GND
DD49    GND VSS_DD49 @T6G_MB_LIB.T6G(SCH_1):GND
DD50    GND VSS_DD50 @T6G_MB_LIB.T6G(SCH_1):GND
DD52    GND VSS_DD52 @T6G_MB_LIB.T6G(SCH_1):GND
DD53    GND VSS_DD53 @T6G_MB_LIB.T6G(SCH_1):GND
DD66    GND VSS_DD66 @T6G_MB_LIB.T6G(SCH_1):GND
DD68    GND VSS_DD68 @T6G_MB_LIB.T6G(SCH_1):GND
DD71    GND VSS_DD71 @T6G_MB_LIB.T6G(SCH_1):GND
DD73    GND VSS_DD73 @T6G_MB_LIB.T6G(SCH_1):GND
 DE1    GND VSS_DE1 @T6G_MB_LIB.T6G(SCH_1):GND
 DE6    GND VSS_DE6 @T6G_MB_LIB.T6G(SCH_1):GND
 DE8    GND VSS_DE8 @T6G_MB_LIB.T6G(SCH_1):GND
DE26    GND VSS_DE26 @T6G_MB_LIB.T6G(SCH_1):GND
DE29    GND VSS_DE29 @T6G_MB_LIB.T6G(SCH_1):GND
DE33    GND VSS_DE33 @T6G_MB_LIB.T6G(SCH_1):GND
DE56    GND VSS_DE56 @T6G_MB_LIB.T6G(SCH_1):GND
DE61    GND VSS_DE61 @T6G_MB_LIB.T6G(SCH_1):GND
DE63    GND VSS_DE63 @T6G_MB_LIB.T6G(SCH_1):GND
DE68    GND VSS_DE68 @T6G_MB_LIB.T6G(SCH_1):GND
 DF5    GND VSS_DF5 @T6G_MB_LIB.T6G(SCH_1):GND
 DF6    GND VSS_DF6 @T6G_MB_LIB.T6G(SCH_1):GND
 DF8    GND VSS_DF8 @T6G_MB_LIB.T6G(SCH_1):GND
DF10    GND VSS_DF10 @T6G_MB_LIB.T6G(SCH_1):GND
DF11    GND VSS_DF11 @T6G_MB_LIB.T6G(SCH_1):GND
DF12    GND VSS_DF12 @T6G_MB_LIB.T6G(SCH_1):GND
DF13    GND VSS_DF13 @T6G_MB_LIB.T6G(SCH_1):GND
DF20    GND VSS_DF20 @T6G_MB_LIB.T6G(SCH_1):GND
DF22    GND VSS_DF22 @T6G_MB_LIB.T6G(SCH_1):GND
DF23    GND VSS_DF23 @T6G_MB_LIB.T6G(SCH_1):GND
DF26    GND VSS_DF26 @T6G_MB_LIB.T6G(SCH_1):GND
DF29    GND VSS_DF29 @T6G_MB_LIB.T6G(SCH_1):GND
DF32    GND VSS_DF32 @T6G_MB_LIB.T6G(SCH_1):GND
DF35    GND VSS_DF35 @T6G_MB_LIB.T6G(SCH_1):GND
DF37    GND VSS_DF37 @T6G_MB_LIB.T6G(SCH_1):GND
DF39    GND VSS_DF39 @T6G_MB_LIB.T6G(SCH_1):GND
DF42    GND VSS_DF42 @T6G_MB_LIB.T6G(SCH_1):GND
DF44    GND VSS_DF44 @T6G_MB_LIB.T6G(SCH_1):GND
DF45    GND VSS_DF45 @T6G_MB_LIB.T6G(SCH_1):GND
DF46    GND VSS_DF46 @T6G_MB_LIB.T6G(SCH_1):GND
DF47    GND VSS_DF47 @T6G_MB_LIB.T6G(SCH_1):GND
DF48    GND VSS_DF48 @T6G_MB_LIB.T6G(SCH_1):GND
DF49    GND VSS_DF49 @T6G_MB_LIB.T6G(SCH_1):GND
DF50    GND VSS_DF50 @T6G_MB_LIB.T6G(SCH_1):GND
DF51    GND VSS_DF51 @T6G_MB_LIB.T6G(SCH_1):GND
DF52    GND VSS_DF52 @T6G_MB_LIB.T6G(SCH_1):GND
DF56    GND VSS_DF56 @T6G_MB_LIB.T6G(SCH_1):GND
DF57    GND VSS_DF57 @T6G_MB_LIB.T6G(SCH_1):GND
DF58    GND VSS_DF58 @T6G_MB_LIB.T6G(SCH_1):GND
DF59    GND VSS_DF59 @T6G_MB_LIB.T6G(SCH_1):GND
DF61    GND VSS_DF61 @T6G_MB_LIB.T6G(SCH_1):GND
DF63    GND VSS_DF63 @T6G_MB_LIB.T6G(SCH_1):GND
DF64    GND VSS_DF64 @T6G_MB_LIB.T6G(SCH_1):GND
DF65    GND VSS_DF65 @T6G_MB_LIB.T6G(SCH_1):GND
DF71    GND VSS_DF71 @T6G_MB_LIB.T6G(SCH_1):GND
DF72    GND VSS_DF72 @T6G_MB_LIB.T6G(SCH_1):GND
DF73    GND VSS_DF73 @T6G_MB_LIB.T6G(SCH_1):GND
 DG1    GND VSS_DG1 @T6G_MB_LIB.T6G(SCH_1):GND
 DG2    GND VSS_DG2 @T6G_MB_LIB.T6G(SCH_1):GND
 DG6    GND VSS_DG6 @T6G_MB_LIB.T6G(SCH_1):GND
 DG7    GND VSS_DG7 @T6G_MB_LIB.T6G(SCH_1):GND
DG15    GND VSS_DG15 @T6G_MB_LIB.T6G(SCH_1):GND
DG16    GND VSS_DG16 @T6G_MB_LIB.T6G(SCH_1):GND
DG18    GND VSS_DG18 @T6G_MB_LIB.T6G(SCH_1):GND
DG20    GND VSS_DG20 @T6G_MB_LIB.T6G(SCH_1):GND
DG21    GND VSS_DG21 @T6G_MB_LIB.T6G(SCH_1):GND
DG24    GND VSS_DG24 @T6G_MB_LIB.T6G(SCH_1):GND
DG27    GND VSS_DG27 @T6G_MB_LIB.T6G(SCH_1):GND
DG46    GND VSS_DG46 @T6G_MB_LIB.T6G(SCH_1):GND
DG49    GND VSS_DG49 @T6G_MB_LIB.T6G(SCH_1):GND
DG52    GND VSS_DG52 @T6G_MB_LIB.T6G(SCH_1):GND
DG55    GND VSS_DG55 @T6G_MB_LIB.T6G(SCH_1):GND
DG56    GND VSS_DG56 @T6G_MB_LIB.T6G(SCH_1):GND
DG59    GND VSS_DG59 @T6G_MB_LIB.T6G(SCH_1):GND
DG60    GND VSS_DG60 @T6G_MB_LIB.T6G(SCH_1):GND
DG66    GND VSS_DG66 @T6G_MB_LIB.T6G(SCH_1):GND
DG67    GND VSS_DG67 @T6G_MB_LIB.T6G(SCH_1):GND
DG68    GND VSS_DG68 @T6G_MB_LIB.T6G(SCH_1):GND
DG69    GND VSS_DG69 @T6G_MB_LIB.T6G(SCH_1):GND
DG70    GND VSS_DG70 @T6G_MB_LIB.T6G(SCH_1):GND
DG74    GND VSS_DG74 @T6G_MB_LIB.T6G(SCH_1):GND
DG75    GND VSS_DG75 @T6G_MB_LIB.T6G(SCH_1):GND
DH39    GND VSS_DH39 @T6G_MB_LIB.T6G(SCH_1):GND
DH43    GND VSS_DH43 @T6G_MB_LIB.T6G(SCH_1):GND
DH46    GND VSS_DH46 @T6G_MB_LIB.T6G(SCH_1):GND
DH49    GND VSS_DH49 @T6G_MB_LIB.T6G(SCH_1):GND
DH52    GND VSS_DH52 @T6G_MB_LIB.T6G(SCH_1):GND
DH55    GND VSS_DH55 @T6G_MB_LIB.T6G(SCH_1):GND
DH59    GND VSS_DH59 @T6G_MB_LIB.T6G(SCH_1):GND
DH68    GND VSS_DH68 @T6G_MB_LIB.T6G(SCH_1):GND
DH70    GND VSS_DH70 @T6G_MB_LIB.T6G(SCH_1):GND
 DJ7    GND VSS_DJ7 @T6G_MB_LIB.T6G(SCH_1):GND
DJ15    GND VSS_DJ15 @T6G_MB_LIB.T6G(SCH_1):GND
DJ19    GND VSS_DJ19 @T6G_MB_LIB.T6G(SCH_1):GND
DJ43    GND VSS_DJ43 @T6G_MB_LIB.T6G(SCH_1):GND
DJ49    GND VSS_DJ49 @T6G_MB_LIB.T6G(SCH_1):GND
DJ59    GND VSS_DJ59 @T6G_MB_LIB.T6G(SCH_1):GND
DJ61    GND VSS_DJ61 @T6G_MB_LIB.T6G(SCH_1):GND
DJ63    GND VSS_DJ63 @T6G_MB_LIB.T6G(SCH_1):GND
DJ66    GND VSS_DJ66 @T6G_MB_LIB.T6G(SCH_1):GND
DJ68    GND VSS_DJ68 @T6G_MB_LIB.T6G(SCH_1):GND
DJ73    GND VSS_DJ73 @T6G_MB_LIB.T6G(SCH_1):GND
CY57    GND VSS_CY57 @T6G_MB_LIB.T6G(SCH_1):GND
CK31    GND VSS_CK31 @T6G_MB_LIB.T6G(SCH_1):GND
CB44    GND VSS_CB44 @T6G_MB_LIB.T6G(SCH_1):GND
AM37    GND VSS_AM37 @T6G_MB_LIB.T6G(SCH_1):GND
 K23    GND VSS_K23 @T6G_MB_LIB.T6G(SCH_1):GND
CN54    GND VSS_CN54 @T6G_MB_LIB.T6G(SCH_1):GND
CK10    GND VSS_CK10 @T6G_MB_LIB.T6G(SCH_1):GND
AA72    GND VSS_AA72 @T6G_MB_LIB.T6G(SCH_1):GND
AJ13    GND VSS_AJ13 @T6G_MB_LIB.T6G(SCH_1):GND
AD31    GND VSS_AD31 @T6G_MB_LIB.T6G(SCH_1):GND
AA42    GND VSS_AA42 @T6G_MB_LIB.T6G(SCH_1):GND
 V27    GND VSS_V27 @T6G_MB_LIB.T6G(SCH_1):GND
CF46    GND VSS_CF46 @T6G_MB_LIB.T6G(SCH_1):GND
CC22    GND VSS_CC22 @T6G_MB_LIB.T6G(SCH_1):GND
AN20    GND VSS_AN20 @T6G_MB_LIB.T6G(SCH_1):GND
 P68    GND VSS_P68 @T6G_MB_LIB.T6G(SCH_1):GND
 P25    GND VSS_P25 @T6G_MB_LIB.T6G(SCH_1):GND
CU58    GND VSS_CU58 @T6G_MB_LIB.T6G(SCH_1):GND
BW25    GND VSS_BW25 @T6G_MB_LIB.T6G(SCH_1):GND
AH33    GND VSS_AH33 @T6G_MB_LIB.T6G(SCH_1):GND
 AE4    GND VSS_AE4 @T6G_MB_LIB.T6G(SCH_1):GND
CG42    GND VSS_CG42 @T6G_MB_LIB.T6G(SCH_1):GND
DA56    GND VSS_DA56 @T6G_MB_LIB.T6G(SCH_1):GND
 K59    GND VSS_K59 @T6G_MB_LIB.T6G(SCH_1):GND
CM50    GND VSS_CM50 @T6G_MB_LIB.T6G(SCH_1):GND
CT52    GND VSS_CT52 @T6G_MB_LIB.T6G(SCH_1):GND
BV42    GND VSS_BV42 @T6G_MB_LIB.T6G(SCH_1):GND
 V68    GND VSS_V68 @T6G_MB_LIB.T6G(SCH_1):GND


DRAWING: @T6G_MB_LIB.T6G(SCH_1):PAGE34 

Q_RES_0402LF-4.7K,5%,1/16W,CHIP,CS24702JB10  I4  R499
   1 P3V3_AUX      A @T6G_MB_LIB.T6G(SCH_1):P3V3_AUX
   2 SMB_CPU0_4_XLTR_SCL      B @T6G_MB_LIB.T6G(SCH_1):SMB_CPU0_4_XLTR_SCL

Q_RES_0402LF-4.7K,5%,1/16W,CHIP,CS24702JB10  I5  R590
   1 P3V3_AUX      A @T6G_MB_LIB.T6G(SCH_1):P3V3_AUX
   2 SMB_CPU0_4_XLTR_SDA      B @T6G_MB_LIB.T6G(SCH_1):SMB_CPU0_4_XLTR_SDA

PCA9617ADP-PCA9617ADP,SMLF,IC,AL009617K02  I18  U27
   5 TP_U27_EN     EN @T6G_MB_LIB.T6G(SCH_1):TP_U27_EN
   1 PVDD18_S5_P0   VCCA @T6G_MB_LIB.T6G(SCH_1):PVDD18_S5_P0
   8 P3V3_AUX   VCCB @T6G_MB_LIB.T6G(SCH_1):P3V3_AUX
   2 SMB_CPU0_4_SCL   SCLA @T6G_MB_LIB.T6G(SCH_1):SMB_CPU0_4_SCL
   3 SMB_CPU0_4_SDA   SDAA @T6G_MB_LIB.T6G(SCH_1):SMB_CPU0_4_SDA
   6 SMB_CPU0_4_XLTR_SDA   SDAB @T6G_MB_LIB.T6G(SCH_1):SMB_CPU0_4_XLTR_SDA
   7 SMB_CPU0_4_XLTR_SCL   SCLB @T6G_MB_LIB.T6G(SCH_1):SMB_CPU0_4_XLTR_SCL
   4    GND    GND @T6G_MB_LIB.T6G(SCH_1):GND

Q_CAP_0402-0.1UF,25V,10%,X7R,CH4104K1B00  I44  C42
   1 PVDD18_S5_P0      A @T6G_MB_LIB.T6G(SCH_1):PVDD18_S5_P0
   2    GND      B @T6G_MB_LIB.T6G(SCH_1):GND

Q_CAP_0402-0.1UF,25V,10%,X7R,CH4104K1B00  I47  C43
   1 P3V3_AUX      A @T6G_MB_LIB.T6G(SCH_1):P3V3_AUX
   2    GND      B @T6G_MB_LIB.T6G(SCH_1):GND

Q_RES_0402LF-4.7K,5%,1/16W,CHIP,CS24702JB10  I53  R943
   1 P1V8_AUX      A @T6G_MB_LIB.T6G(SCH_1):P1V8_AUX
   2 FM_BIOS_POST_CMPLT_BUF_R1_N      B @T6G_MB_LIB.T6G(SCH_1):FM_BIOS_POST_CMPLT_BUF_R1_N

SN74LVC1G07DBVR_SMLF-SN74LVC1G07DBVR,IC,AL1G0007024  I55  U101
   2 FM_BIOS_POST_CMPLT_N      A @T6G_MB_LIB.T6G(SCH_1):FM_BIOS_POST_CMPLT_N
   4 FM_BIOS_POST_CMPLT_BUF_R1_N      Y @T6G_MB_LIB.T6G(SCH_1):FM_BIOS_POST_CMPLT_BUF_R1_N
   1     NC     NC     NC
   5 PVDD18_S5_P0    VCC @T6G_MB_LIB.T6G(SCH_1):PVDD18_S5_P0
   3    GND    GND @T6G_MB_LIB.T6G(SCH_1):GND

Q_CAP_0402-0.1UF,25V,10%,X7R,CH4104K1B00  I59  C226
   1 PVDD18_S5_P0      A @T6G_MB_LIB.T6G(SCH_1):PVDD18_S5_P0
   2    GND      B @T6G_MB_LIB.T6G(SCH_1):GND

Q_RES_0402LF-4.7K,5%,1/16W,CHIP,CS24702JB10  I60  R942
   1 PVDD18_S5_P0      A @T6G_MB_LIB.T6G(SCH_1):PVDD18_S5_P0
   2 FM_BIOS_POST_CMPLT_N      B @T6G_MB_LIB.T6G(SCH_1):FM_BIOS_POST_CMPLT_N

Q_RES_0402LF-4.7K,5%,1/16W,CHIP,CS24702JB10  I106  R495
   1 PVDD18_S5_P0      A @T6G_MB_LIB.T6G(SCH_1):PVDD18_S5_P0
   2 SMB_CPU0_4_SCL      B @T6G_MB_LIB.T6G(SCH_1):SMB_CPU0_4_SCL

Q_RES_0402LF-2.2K,5%,1/16W,CHIP,CS22202JB07  I107  R498
   1 PVDD18_S5_P0      A @T6G_MB_LIB.T6G(SCH_1):PVDD18_S5_P0
   2 SMB_CPU0_4_SDA      B @T6G_MB_LIB.T6G(SCH_1):SMB_CPU0_4_SDA

Q_CAP_0402-1000PF,50V,5%,X7R,TMP_QCH21006JB10  I124  C5000
   1 FM_BIOS_POST_CMPLT_BUF_N      A @T6G_MB_LIB.T6G(SCH_1):FM_BIOS_POST_CMPLT_BUF_N
   2    GND      B @T6G_MB_LIB.T6G(SCH_1):GND

Q_RES_0402LF-49.9,1%,1/16W,CHIP,CS04992FB07  I125  R6100
   1 FM_BIOS_POST_CMPLT_BUF_R1_N      A @T6G_MB_LIB.T6G(SCH_1):FM_BIOS_POST_CMPLT_BUF_R1_N
   2 FM_BIOS_POST_CMPLT_BUF_N      B @T6G_MB_LIB.T6G(SCH_1):FM_BIOS_POST_CMPLT_BUF_N


DRAWING: @T6G_MB_LIB.T6G(SCH_1):PAGE37 

GENOA_SP5-SOCKET6096_13568-001,SMLF,IO,DGA^6000030  I167  U26
AR74 M_A_CPU1_ALERT_R_N MA_ALERT_L @T6G_MB_LIB.T6G(SCH_1):M_A_CPU1_ALERT_R_N
AT74 M_A_CPU1_RESET_N MA_RESET_L @T6G_MB_LIB.T6G(SCH_1):M_A_CPU1_RESET_N
CE73 M_A_CPU1_SB_DQS_DN<5> MAB_DQS_L5 @T6G_MB_LIB.T6G(SCH_1):M_A_CPU1_SB_DQS_DN(5)
CK74 M_A_CPU1_SB_DQS_DP<1> MAB_DQS_H1 @T6G_MB_LIB.T6G(SCH_1):M_A_CPU1_SB_DQS_DP(1)
DE73 M_A_CPU1_SB_DQ<29> MAB_DATA29 @T6G_MB_LIB.T6G(SCH_1):M_A_CPU1_SB_DQ(29)
CR74 M_A_CPU1_SB_DQ<18> MAB_DATA18 @T6G_MB_LIB.T6G(SCH_1):M_A_CPU1_SB_DQ(18)
CD72 M_A_CPU1_SB_DQ<3> MAB_DATA3 @T6G_MB_LIB.T6G(SCH_1):M_A_CPU1_SB_DQ(3)
AA73 M_A_CPU1_SA_DQS_DP<7> MAA_DQS_H7 @T6G_MB_LIB.T6G(SCH_1):M_A_CPU1_SA_DQS_DP(7)
 J74 M_A_CPU1_SA_DQ<4> MAA_DATA4 @T6G_MB_LIB.T6G(SCH_1):M_A_CPU1_SA_DQ(4)
AU74     NC MAA1_CS_L0     NC
AW73 M_A_CPU1_SA_CS_N<1> MAA0_CS_L1 @T6G_MB_LIB.T6G(SCH_1):M_A_CPU1_SA_CS_N(1)
CL73 M_A_CPU1_SB_DQS_DN<6> MAB_DQS_L6 @T6G_MB_LIB.T6G(SCH_1):M_A_CPU1_SB_DQS_DN(6)
CT74 M_A_CPU1_SB_DQS_DP<2> MAB_DQS_H2 @T6G_MB_LIB.T6G(SCH_1):M_A_CPU1_SB_DQS_DP(2)
CT72 M_A_CPU1_SB_DQ<19> MAB_DATA19 @T6G_MB_LIB.T6G(SCH_1):M_A_CPU1_SB_DQ(19)
CF74 M_A_CPU1_SB_DQ<4> MAB_DATA4 @T6G_MB_LIB.T6G(SCH_1):M_A_CPU1_SB_DQ(4)
AG73 M_A_CPU1_SA_DQS_DP<8> MAA_DQS_H8 @T6G_MB_LIB.T6G(SCH_1):M_A_CPU1_SA_DQS_DP(8)
AH74 M_A_CPU1_SA_DQ<30> MAA_DATA30 @T6G_MB_LIB.T6G(SCH_1):M_A_CPU1_SA_DQ(30)
 K72 M_A_CPU1_SA_DQ<5> MAA_DATA5 @T6G_MB_LIB.T6G(SCH_1):M_A_CPU1_SA_DQ(5)
AV72     NC MAA1_CS_L1     NC
CU73 M_A_CPU1_SB_DQS_DN<7> MAB_DQS_L7 @T6G_MB_LIB.T6G(SCH_1):M_A_CPU1_SB_DQS_DN(7)
DB74 M_A_CPU1_SB_DQS_DP<3> MAB_DQS_H3 @T6G_MB_LIB.T6G(SCH_1):M_A_CPU1_SB_DQS_DP(3)
CG73 M_A_CPU1_SB_DQ<5> MAB_DATA5 @T6G_MB_LIB.T6G(SCH_1):M_A_CPU1_SB_DQ(5)
AN73 M_A_CPU1_SA_DQS_DP<9> MAA_DQS_H9 @T6G_MB_LIB.T6G(SCH_1):M_A_CPU1_SA_DQS_DP(9)
AJ73 M_A_CPU1_SA_DQ<31> MAA_DATA31 @T6G_MB_LIB.T6G(SCH_1):M_A_CPU1_SA_DQ(31)
AA74 M_A_CPU1_SA_DQ<20> MAA_DATA20 @T6G_MB_LIB.T6G(SCH_1):M_A_CPU1_SA_DQ(20)
 K74 M_A_CPU1_SA_DQ<6> MAA_DATA6 @T6G_MB_LIB.T6G(SCH_1):M_A_CPU1_SA_DQ(6)
AJ74 M_A_CPU1_SA_CB<0> MAA_CHECK0 @T6G_MB_LIB.T6G(SCH_1):M_A_CPU1_SA_CB(0)
DC73 M_A_CPU1_SB_DQS_DN<8> MAB_DQS_L8 @T6G_MB_LIB.T6G(SCH_1):M_A_CPU1_SB_DQS_DN(8)
BY72 M_A_CPU1_SB_DQS_DP<4> MAB_DQS_H4 @T6G_MB_LIB.T6G(SCH_1):M_A_CPU1_SB_DQS_DP(4)
CG74 M_A_CPU1_SB_DQ<6> MAB_DATA6 @T6G_MB_LIB.T6G(SCH_1):M_A_CPU1_SB_DQ(6)
AB72 M_A_CPU1_SA_DQ<21> MAA_DATA21 @T6G_MB_LIB.T6G(SCH_1):M_A_CPU1_SA_DQ(21)
 M74 M_A_CPU1_SA_DQ<10> MAA_DATA10 @T6G_MB_LIB.T6G(SCH_1):M_A_CPU1_SA_DQ(10)
 L73 M_A_CPU1_SA_DQ<7> MAA_DATA7 @T6G_MB_LIB.T6G(SCH_1):M_A_CPU1_SA_DQ(7)
AK72 M_A_CPU1_SA_CB<1> MAA_CHECK1 @T6G_MB_LIB.T6G(SCH_1):M_A_CPU1_SA_CB(1)
BW74 M_A_CPU1_SB_DQS_DN<9> MAB_DQS_L9 @T6G_MB_LIB.T6G(SCH_1):M_A_CPU1_SB_DQS_DN(9)
CF72 M_A_CPU1_SB_DQS_DP<5> MAB_DQS_H5 @T6G_MB_LIB.T6G(SCH_1):M_A_CPU1_SB_DQS_DP(5)
CH72 M_A_CPU1_SB_DQ<7> MAB_DATA7 @T6G_MB_LIB.T6G(SCH_1):M_A_CPU1_SB_DQ(7)
AB74 M_A_CPU1_SA_DQ<22> MAA_DATA22 @T6G_MB_LIB.T6G(SCH_1):M_A_CPU1_SA_DQ(22)
 N73 M_A_CPU1_SA_DQ<11> MAA_DATA11 @T6G_MB_LIB.T6G(SCH_1):M_A_CPU1_SA_DQ(11)
 L74 M_A_CPU1_SA_DQ<8> MAA_DATA8 @T6G_MB_LIB.T6G(SCH_1):M_A_CPU1_SA_DQ(8)
AK74 M_A_CPU1_SA_CB<2> MAA_CHECK2 @T6G_MB_LIB.T6G(SCH_1):M_A_CPU1_SA_CB(2)
CM72 M_A_CPU1_SB_DQS_DP<6> MAB_DQS_H6 @T6G_MB_LIB.T6G(SCH_1):M_A_CPU1_SB_DQS_DP(6)
CH74 M_A_CPU1_SB_DQ<8> MAB_DATA8 @T6G_MB_LIB.T6G(SCH_1):M_A_CPU1_SB_DQ(8)
BM72 M_A_CPU1_SB_CS_N<0> MAB0_CS_L0 @T6G_MB_LIB.T6G(SCH_1):M_A_CPU1_SB_CS_N(0)
AC73 M_A_CPU1_SA_DQ<23> MAA_DATA23 @T6G_MB_LIB.T6G(SCH_1):M_A_CPU1_SA_DQ(23)
 R74 M_A_CPU1_SA_DQ<12> MAA_DATA12 @T6G_MB_LIB.T6G(SCH_1):M_A_CPU1_SA_DQ(12)
 M72 M_A_CPU1_SA_DQ<9> MAA_DATA9 @T6G_MB_LIB.T6G(SCH_1):M_A_CPU1_SA_DQ(9)
AL73 M_A_CPU1_SA_CB<3> MAA_CHECK3 @T6G_MB_LIB.T6G(SCH_1):M_A_CPU1_SA_CB(3)
CV72 M_A_CPU1_SB_DQS_DP<7> MAB_DQS_H7 @T6G_MB_LIB.T6G(SCH_1):M_A_CPU1_SB_DQS_DP(7)
CJ73 M_A_CPU1_SB_DQ<9> MAB_DATA9 @T6G_MB_LIB.T6G(SCH_1):M_A_CPU1_SB_DQ(9)
BL73     NC MAB1_CS_L0     NC
BN74 M_A_CPU1_SB_CS_N<1> MAB0_CS_L1 @T6G_MB_LIB.T6G(SCH_1):M_A_CPU1_SB_CS_N(1)
 H74 M_A_CPU1_SA_DQS_DN<0> MAA_DQS_L0 @T6G_MB_LIB.T6G(SCH_1):M_A_CPU1_SA_DQS_DN(0)
AC74 M_A_CPU1_SA_DQ<24> MAA_DATA24 @T6G_MB_LIB.T6G(SCH_1):M_A_CPU1_SA_DQ(24)
 T72 M_A_CPU1_SA_DQ<13> MAA_DATA13 @T6G_MB_LIB.T6G(SCH_1):M_A_CPU1_SA_DQ(13)
AN74 M_A_CPU1_SA_CB<4> MAA_CHECK4 @T6G_MB_LIB.T6G(SCH_1):M_A_CPU1_SA_CB(4)
DD72 M_A_CPU1_SB_DQS_DP<8> MAB_DQS_H8 @T6G_MB_LIB.T6G(SCH_1):M_A_CPU1_SB_DQS_DP(8)
DE74 M_A_CPU1_SB_DQ<30> MAB_DATA30 @T6G_MB_LIB.T6G(SCH_1):M_A_CPU1_SB_DQ(30)
BM74     NC MAB1_CS_L1     NC
 P74 M_A_CPU1_SA_DQS_DN<1> MAA_DQS_L1 @T6G_MB_LIB.T6G(SCH_1):M_A_CPU1_SA_DQS_DN(1)
AD72 M_A_CPU1_SA_DQ<25> MAA_DATA25 @T6G_MB_LIB.T6G(SCH_1):M_A_CPU1_SA_DQ(25)
 T74 M_A_CPU1_SA_DQ<14> MAA_DATA14 @T6G_MB_LIB.T6G(SCH_1):M_A_CPU1_SA_DQ(14)
AP72 M_A_CPU1_SA_CB<5> MAA_CHECK5 @T6G_MB_LIB.T6G(SCH_1):M_A_CPU1_SA_CB(5)
DF74 M_A_CPU1_SB_DQ<31> MAB_DATA31 @T6G_MB_LIB.T6G(SCH_1):M_A_CPU1_SB_DQ(31)
CV74 M_A_CPU1_SB_DQ<20> MAB_DATA20 @T6G_MB_LIB.T6G(SCH_1):M_A_CPU1_SB_DQ(20)
BY74 M_A_CPU1_SB_CB<0> MAB_CHECK0 @T6G_MB_LIB.T6G(SCH_1):M_A_CPU1_SB_CB(0)
 Y74 M_A_CPU1_SA_DQS_DN<2> MAA_DQS_L2 @T6G_MB_LIB.T6G(SCH_1):M_A_CPU1_SA_DQS_DN(2)
AD74 M_A_CPU1_SA_DQ<26> MAA_DATA26 @T6G_MB_LIB.T6G(SCH_1):M_A_CPU1_SA_DQ(26)
 U73 M_A_CPU1_SA_DQ<15> MAA_DATA15 @T6G_MB_LIB.T6G(SCH_1):M_A_CPU1_SA_DQ(15)
AP74 M_A_CPU1_SA_CB<6> MAA_CHECK6 @T6G_MB_LIB.T6G(SCH_1):M_A_CPU1_SA_CB(6)
BN73 M_A_CPU1_SA_RSP<0> MAA0_RSP_L @T6G_MB_LIB.T6G(SCH_1):M_A_CPU1_SA_RSP(0)
CW73 M_A_CPU1_SB_DQ<21> MAB_DATA21 @T6G_MB_LIB.T6G(SCH_1):M_A_CPU1_SB_DQ(21)
CJ74 M_A_CPU1_SB_DQ<10> MAB_DATA10 @T6G_MB_LIB.T6G(SCH_1):M_A_CPU1_SB_DQ(10)
CA73 M_A_CPU1_SB_CB<1> MAB_CHECK1 @T6G_MB_LIB.T6G(SCH_1):M_A_CPU1_SB_CB(1)
AF74 M_A_CPU1_SA_DQS_DN<3> MAA_DQS_L3 @T6G_MB_LIB.T6G(SCH_1):M_A_CPU1_SA_DQS_DN(3)
AE73 M_A_CPU1_SA_DQ<27> MAA_DATA27 @T6G_MB_LIB.T6G(SCH_1):M_A_CPU1_SA_DQ(27)
 U74 M_A_CPU1_SA_DQ<16> MAA_DATA16 @T6G_MB_LIB.T6G(SCH_1):M_A_CPU1_SA_DQ(16)
AR73 M_A_CPU1_SA_CB<7> MAA_CHECK7 @T6G_MB_LIB.T6G(SCH_1):M_A_CPU1_SA_CB(7)
AW74 M_A_CPU1_SA_CA<0> MAA_CA0 @T6G_MB_LIB.T6G(SCH_1):M_A_CPU1_SA_CA(0)
BP72     NC MAA1_RSP_L     NC
CW74 M_A_CPU1_SB_DQ<22> MAB_DATA22 @T6G_MB_LIB.T6G(SCH_1):M_A_CPU1_SB_DQ(22)
CK72 M_A_CPU1_SB_DQ<11> MAB_DATA11 @T6G_MB_LIB.T6G(SCH_1):M_A_CPU1_SB_DQ(11)
CA74 M_A_CPU1_SB_CB<2> MAB_CHECK2 @T6G_MB_LIB.T6G(SCH_1):M_A_CPU1_SB_CB(2)
BG73 M_A_CPU1_SB_CA<0> MAB_CA0 @T6G_MB_LIB.T6G(SCH_1):M_A_CPU1_SB_CA(0)
AM74 M_A_CPU1_SA_DQS_DN<4> MAA_DQS_L4 @T6G_MB_LIB.T6G(SCH_1):M_A_CPU1_SA_DQS_DN(4)
 G74 M_A_CPU1_SA_DQS_DP<0> MAA_DQS_H0 @T6G_MB_LIB.T6G(SCH_1):M_A_CPU1_SA_DQS_DP(0)
AG74 M_A_CPU1_SA_DQ<28> MAA_DATA28 @T6G_MB_LIB.T6G(SCH_1):M_A_CPU1_SA_DQ(28)
 V72 M_A_CPU1_SA_DQ<17> MAA_DATA17 @T6G_MB_LIB.T6G(SCH_1):M_A_CPU1_SA_DQ(17)
AY74 M_A_CPU1_SA_CA<1> MAA_CA1 @T6G_MB_LIB.T6G(SCH_1):M_A_CPU1_SA_CA(1)
CY72 M_A_CPU1_SB_DQ<23> MAB_DATA23 @T6G_MB_LIB.T6G(SCH_1):M_A_CPU1_SB_DQ(23)
CM74 M_A_CPU1_SB_DQ<12> MAB_DATA12 @T6G_MB_LIB.T6G(SCH_1):M_A_CPU1_SB_DQ(12)
CB72 M_A_CPU1_SB_CB<3> MAB_CHECK3 @T6G_MB_LIB.T6G(SCH_1):M_A_CPU1_SB_CB(3)
BH72 M_A_CPU1_SB_CA<1> MAB_CA1 @T6G_MB_LIB.T6G(SCH_1):M_A_CPU1_SB_CA(1)
 H72 M_A_CPU1_SA_DQS_DN<5> MAA_DQS_L5 @T6G_MB_LIB.T6G(SCH_1):M_A_CPU1_SA_DQS_DN(5)
 N74 M_A_CPU1_SA_DQS_DP<1> MAA_DQS_H1 @T6G_MB_LIB.T6G(SCH_1):M_A_CPU1_SA_DQS_DP(1)
AH72 M_A_CPU1_SA_DQ<29> MAA_DATA29 @T6G_MB_LIB.T6G(SCH_1):M_A_CPU1_SA_DQ(29)
 V74 M_A_CPU1_SA_DQ<18> MAA_DATA18 @T6G_MB_LIB.T6G(SCH_1):M_A_CPU1_SA_DQ(18)
AY72 M_A_CPU1_SA_CA<2> MAA_CA2 @T6G_MB_LIB.T6G(SCH_1):M_A_CPU1_SA_CA(2)
CE74 M_A_CPU1_SB_DQS_DN<0> MAB_DQS_L0 @T6G_MB_LIB.T6G(SCH_1):M_A_CPU1_SB_DQS_DN(0)
CY74 M_A_CPU1_SB_DQ<24> MAB_DATA24 @T6G_MB_LIB.T6G(SCH_1):M_A_CPU1_SB_DQ(24)
CN73 M_A_CPU1_SB_DQ<13> MAB_DATA13 @T6G_MB_LIB.T6G(SCH_1):M_A_CPU1_SB_DQ(13)
BT74 M_A_CPU1_SB_CB<4> MAB_CHECK4 @T6G_MB_LIB.T6G(SCH_1):M_A_CPU1_SB_CB(4)
BH74 M_A_CPU1_SB_CA<2> MAB_CA2 @T6G_MB_LIB.T6G(SCH_1):M_A_CPU1_SB_CA(2)
 P72 M_A_CPU1_SA_DQS_DN<6> MAA_DQS_L6 @T6G_MB_LIB.T6G(SCH_1):M_A_CPU1_SA_DQS_DN(6)
 W74 M_A_CPU1_SA_DQS_DP<2> MAA_DQS_H2 @T6G_MB_LIB.T6G(SCH_1):M_A_CPU1_SA_DQS_DP(2)
 W73 M_A_CPU1_SA_DQ<19> MAA_DATA19 @T6G_MB_LIB.T6G(SCH_1):M_A_CPU1_SA_DQ(19)
BA73 M_A_CPU1_SA_CA<3> MAA_CA3 @T6G_MB_LIB.T6G(SCH_1):M_A_CPU1_SA_CA(3)
CL74 M_A_CPU1_SB_DQS_DN<1> MAB_DQS_L1 @T6G_MB_LIB.T6G(SCH_1):M_A_CPU1_SB_DQS_DN(1)
DA73 M_A_CPU1_SB_DQ<25> MAB_DATA25 @T6G_MB_LIB.T6G(SCH_1):M_A_CPU1_SB_DQ(25)
CN74 M_A_CPU1_SB_DQ<14> MAB_DATA14 @T6G_MB_LIB.T6G(SCH_1):M_A_CPU1_SB_DQ(14)
BU73 M_A_CPU1_SB_CB<5> MAB_CHECK5 @T6G_MB_LIB.T6G(SCH_1):M_A_CPU1_SB_CB(5)
BJ74 M_A_CPU1_SB_CA<3> MAB_CA3 @T6G_MB_LIB.T6G(SCH_1):M_A_CPU1_SB_CA(3)
 Y72 M_A_CPU1_SA_DQS_DN<7> MAA_DQS_L7 @T6G_MB_LIB.T6G(SCH_1):M_A_CPU1_SA_DQS_DN(7)
AE74 M_A_CPU1_SA_DQS_DP<3> MAA_DQS_H3 @T6G_MB_LIB.T6G(SCH_1):M_A_CPU1_SA_DQS_DP(3)
 E74 M_A_CPU1_SA_DQ<0> MAA_DATA0 @T6G_MB_LIB.T6G(SCH_1):M_A_CPU1_SA_DQ(0)
BA74 M_A_CPU1_SA_CA<4> MAA_CA4 @T6G_MB_LIB.T6G(SCH_1):M_A_CPU1_SA_CA(4)
CU74 M_A_CPU1_SB_DQS_DN<2> MAB_DQS_L2 @T6G_MB_LIB.T6G(SCH_1):M_A_CPU1_SB_DQS_DN(2)
DA74 M_A_CPU1_SB_DQ<26> MAB_DATA26 @T6G_MB_LIB.T6G(SCH_1):M_A_CPU1_SB_DQ(26)
CP72 M_A_CPU1_SB_DQ<15> MAB_DATA15 @T6G_MB_LIB.T6G(SCH_1):M_A_CPU1_SB_DQ(15)
CB74 M_A_CPU1_SB_DQ<0> MAB_DATA0 @T6G_MB_LIB.T6G(SCH_1):M_A_CPU1_SB_DQ(0)
BU74 M_A_CPU1_SB_CB<6> MAB_CHECK6 @T6G_MB_LIB.T6G(SCH_1):M_A_CPU1_SB_CB(6)
BJ73 M_A_CPU1_SB_CA<4> MAB_CA4 @T6G_MB_LIB.T6G(SCH_1):M_A_CPU1_SB_CA(4)
BP74 M_A_CPU1_SB_RSP<0> MAB0_RSP_L @T6G_MB_LIB.T6G(SCH_1):M_A_CPU1_SB_RSP(0)
AF72 M_A_CPU1_SA_DQS_DN<8> MAA_DQS_L8 @T6G_MB_LIB.T6G(SCH_1):M_A_CPU1_SA_DQS_DN(8)
AL74 M_A_CPU1_SA_DQS_DP<4> MAA_DQS_H4 @T6G_MB_LIB.T6G(SCH_1):M_A_CPU1_SA_DQS_DP(4)
 F72 M_A_CPU1_SA_DQ<1> MAA_DATA1 @T6G_MB_LIB.T6G(SCH_1):M_A_CPU1_SA_DQ(1)
BB74 M_A_CPU1_SA_CA<5> MAA_CA5 @T6G_MB_LIB.T6G(SCH_1):M_A_CPU1_SA_CA(5)
DC74 M_A_CPU1_SB_DQS_DN<3> MAB_DQS_L3 @T6G_MB_LIB.T6G(SCH_1):M_A_CPU1_SB_DQS_DN(3)
DB72 M_A_CPU1_SB_DQ<27> MAB_DATA27 @T6G_MB_LIB.T6G(SCH_1):M_A_CPU1_SB_DQ(27)
CP74 M_A_CPU1_SB_DQ<16> MAB_DATA16 @T6G_MB_LIB.T6G(SCH_1):M_A_CPU1_SB_DQ(16)
CC73 M_A_CPU1_SB_DQ<1> MAB_DATA1 @T6G_MB_LIB.T6G(SCH_1):M_A_CPU1_SB_DQ(1)
BV72 M_A_CPU1_SB_CB<7> MAB_CHECK7 @T6G_MB_LIB.T6G(SCH_1):M_A_CPU1_SB_CB(7)
BK72 M_A_CPU1_SB_CA<5> MAB_CA5 @T6G_MB_LIB.T6G(SCH_1):M_A_CPU1_SB_CA(5)
BR74     NC MAB1_RSP_L     NC
AM72 M_A_CPU1_SA_DQS_DN<9> MAA_DQS_L9 @T6G_MB_LIB.T6G(SCH_1):M_A_CPU1_SA_DQS_DN(9)
 J73 M_A_CPU1_SA_DQS_DP<5> MAA_DQS_H5 @T6G_MB_LIB.T6G(SCH_1):M_A_CPU1_SA_DQS_DP(5)
 F74 M_A_CPU1_SA_DQ<2> MAA_DATA2 @T6G_MB_LIB.T6G(SCH_1):M_A_CPU1_SA_DQ(2)
BB72 M_A_CPU1_SA_CA<6> MAA_CA6 @T6G_MB_LIB.T6G(SCH_1):M_A_CPU1_SA_CA(6)
BW73 M_A_CPU1_SB_DQS_DN<4> MAB_DQS_L4 @T6G_MB_LIB.T6G(SCH_1):M_A_CPU1_SB_DQS_DN(4)
CD74 M_A_CPU1_SB_DQS_DP<0> MAB_DQS_H0 @T6G_MB_LIB.T6G(SCH_1):M_A_CPU1_SB_DQS_DP(0)
DD74 M_A_CPU1_SB_DQ<28> MAB_DATA28 @T6G_MB_LIB.T6G(SCH_1):M_A_CPU1_SB_DQ(28)
CR73 M_A_CPU1_SB_DQ<17> MAB_DATA17 @T6G_MB_LIB.T6G(SCH_1):M_A_CPU1_SB_DQ(17)
CC74 M_A_CPU1_SB_DQ<2> MAB_DATA2 @T6G_MB_LIB.T6G(SCH_1):M_A_CPU1_SB_DQ(2)
BK74 M_A_CPU1_SB_CA<6> MAB_CA6 @T6G_MB_LIB.T6G(SCH_1):M_A_CPU1_SB_CA(6)
 R73 M_A_CPU1_SA_DQS_DP<6> MAA_DQS_H6 @T6G_MB_LIB.T6G(SCH_1):M_A_CPU1_SA_DQS_DP(6)
 G73 M_A_CPU1_SA_DQ<3> MAA_DATA3 @T6G_MB_LIB.T6G(SCH_1):M_A_CPU1_SA_DQ(3)
AV74 M_A_CPU1_SA_CS_N<0> MAA0_CS_L0 @T6G_MB_LIB.T6G(SCH_1):M_A_CPU1_SA_CS_N(0)
BC73 M_A_CPU1_SA_PAR MAA_PAR @T6G_MB_LIB.T6G(SCH_1):M_A_CPU1_SA_PAR
BL74 M_A_CPU1_SB_PAR MAB_PAR @T6G_MB_LIB.T6G(SCH_1):M_A_CPU1_SB_PAR
BC74 M_A_CPU1_CLK_DP<0> MA0_CLK_H @T6G_MB_LIB.T6G(SCH_1):M_A_CPU1_CLK_DP(0)
BV74 M_A_CPU1_SB_DQS_DP<9> MAB_DQS_H9 @T6G_MB_LIB.T6G(SCH_1):M_A_CPU1_SB_DQS_DP(9)
BF74     NC MA1_CLK_H     NC
BD74 M_A_CPU1_CLK_DN<0> MA0_CLK_L @T6G_MB_LIB.T6G(SCH_1):M_A_CPU1_CLK_DN(0)
BG74     NC MA1_CLK_L     NC
BF72 TP_M_A_CPU1_SA_TEST39A TEST39A @T6G_MB_LIB.T6G(SCH_1):TP_M_A_CPU1_SA_TEST39A
 C60 TP_M_A_CPU1_SA_TEST40 TEST40 @T6G_MB_LIB.T6G(SCH_1):TP_M_A_CPU1_SA_TEST40

Q_RES_0402LF-15,1%,1/16W,CHIP,CS01502FB03  I322  R500
   1 M_A_CPU1_ALERT_N      A @T6G_MB_LIB.T6G(SCH_1):M_A_CPU1_ALERT_N
   2 M_A_CPU1_ALERT_R_N      B @T6G_MB_LIB.T6G(SCH_1):M_A_CPU1_ALERT_R_N


DRAWING: @T6G_MB_LIB.T6G(SCH_1):PAGE38 

GENOA_SP5-SOCKET6096_13568-001,SMLF,IO,DGA^6000030  I159  U26
AT62 M_B_CPU1_ALERT_R_N MB_ALERT_L @T6G_MB_LIB.T6G(SCH_1):M_B_CPU1_ALERT_R_N
AU62 M_B_CPU1_RESET_N MB_RESET_L @T6G_MB_LIB.T6G(SCH_1):M_B_CPU1_RESET_N
BW64 M_B_CPU1_SB_DQS_DN<9> MBB_DQS_L9 @T6G_MB_LIB.T6G(SCH_1):M_B_CPU1_SB_DQS_DN(9)
CF62 M_B_CPU1_SB_DQS_DP<5> MBB_DQS_H5 @T6G_MB_LIB.T6G(SCH_1):M_B_CPU1_SB_DQS_DP(5)
AB63 M_B_CPU1_SA_DQ<22> MBA_DATA22 @T6G_MB_LIB.T6G(SCH_1):M_B_CPU1_SA_DQ(22)
 N62 M_B_CPU1_SA_DQ<11> MBA_DATA11 @T6G_MB_LIB.T6G(SCH_1):M_B_CPU1_SA_DQ(11)
AK63 M_B_CPU1_SA_CB<2> MBA_CHECK2 @T6G_MB_LIB.T6G(SCH_1):M_B_CPU1_SA_CB(2)
CM62 M_B_CPU1_SB_DQS_DP<6> MBB_DQS_H6 @T6G_MB_LIB.T6G(SCH_1):M_B_CPU1_SB_DQS_DP(6)
AC62 M_B_CPU1_SA_DQ<23> MBA_DATA23 @T6G_MB_LIB.T6G(SCH_1):M_B_CPU1_SA_DQ(23)
 R64 M_B_CPU1_SA_DQ<12> MBA_DATA12 @T6G_MB_LIB.T6G(SCH_1):M_B_CPU1_SA_DQ(12)
AL62 M_B_CPU1_SA_CB<3> MBA_CHECK3 @T6G_MB_LIB.T6G(SCH_1):M_B_CPU1_SA_CB(3)
CV62 M_B_CPU1_SB_DQS_DP<7> MBB_DQS_H7 @T6G_MB_LIB.T6G(SCH_1):M_B_CPU1_SB_DQS_DP(7)
BM62 M_B_CPU1_SB_CS_N<0> MBB0_CS_L0 @T6G_MB_LIB.T6G(SCH_1):M_B_CPU1_SB_CS_N(0)
 H63 M_B_CPU1_SA_DQS_DN<0> MBA_DQS_L0 @T6G_MB_LIB.T6G(SCH_1):M_B_CPU1_SA_DQS_DN(0)
 T62 M_B_CPU1_SA_DQ<13> MBA_DATA13 @T6G_MB_LIB.T6G(SCH_1):M_B_CPU1_SA_DQ(13)
 E64 M_B_CPU1_SA_DQ<0> MBA_DATA0 @T6G_MB_LIB.T6G(SCH_1):M_B_CPU1_SA_DQ(0)
AN64 M_B_CPU1_SA_CB<4> MBA_CHECK4 @T6G_MB_LIB.T6G(SCH_1):M_B_CPU1_SA_CB(4)
DD62 M_B_CPU1_SB_DQS_DP<8> MBB_DQS_H8 @T6G_MB_LIB.T6G(SCH_1):M_B_CPU1_SB_DQS_DP(8)
DE64 M_B_CPU1_SB_DQ<30> MBB_DATA30 @T6G_MB_LIB.T6G(SCH_1):M_B_CPU1_SB_DQ(30)
CB63 M_B_CPU1_SB_DQ<0> MBB_DATA0 @T6G_MB_LIB.T6G(SCH_1):M_B_CPU1_SB_DQ(0)
BL62     NC MBB1_CS_L0     NC
BN64 M_B_CPU1_SB_CS_N<1> MBB0_CS_L1 @T6G_MB_LIB.T6G(SCH_1):M_B_CPU1_SB_CS_N(1)
 P63 M_B_CPU1_SA_DQS_DN<1> MBA_DQS_L1 @T6G_MB_LIB.T6G(SCH_1):M_B_CPU1_SA_DQS_DN(1)
AD62 M_B_CPU1_SA_DQ<25> MBA_DATA25 @T6G_MB_LIB.T6G(SCH_1):M_B_CPU1_SA_DQ(25)
 T63 M_B_CPU1_SA_DQ<14> MBA_DATA14 @T6G_MB_LIB.T6G(SCH_1):M_B_CPU1_SA_DQ(14)
 F62 M_B_CPU1_SA_DQ<1> MBA_DATA1 @T6G_MB_LIB.T6G(SCH_1):M_B_CPU1_SA_DQ(1)
AP62 M_B_CPU1_SA_CB<5> MBA_CHECK5 @T6G_MB_LIB.T6G(SCH_1):M_B_CPU1_SA_CB(5)
DF62 M_B_CPU1_SB_DQ<31> MBB_DATA31 @T6G_MB_LIB.T6G(SCH_1):M_B_CPU1_SB_DQ(31)
CC62 M_B_CPU1_SB_DQ<1> MBB_DATA1 @T6G_MB_LIB.T6G(SCH_1):M_B_CPU1_SB_DQ(1)
BY63 M_B_CPU1_SB_CB<0> MBB_CHECK0 @T6G_MB_LIB.T6G(SCH_1):M_B_CPU1_SB_CB(0)
BM63     NC MBB1_CS_L1     NC
 Y63 M_B_CPU1_SA_DQS_DN<2> MBA_DQS_L2 @T6G_MB_LIB.T6G(SCH_1):M_B_CPU1_SA_DQS_DN(2)
AD63 M_B_CPU1_SA_DQ<26> MBA_DATA26 @T6G_MB_LIB.T6G(SCH_1):M_B_CPU1_SA_DQ(26)
 U62 M_B_CPU1_SA_DQ<15> MBA_DATA15 @T6G_MB_LIB.T6G(SCH_1):M_B_CPU1_SA_DQ(15)
 F63 M_B_CPU1_SA_DQ<2> MBA_DATA2 @T6G_MB_LIB.T6G(SCH_1):M_B_CPU1_SA_DQ(2)
AP63 M_B_CPU1_SA_CB<6> MBA_CHECK6 @T6G_MB_LIB.T6G(SCH_1):M_B_CPU1_SA_CB(6)
CW62 M_B_CPU1_SB_DQ<21> MBB_DATA21 @T6G_MB_LIB.T6G(SCH_1):M_B_CPU1_SB_DQ(21)
CJ64 M_B_CPU1_SB_DQ<10> MBB_DATA10 @T6G_MB_LIB.T6G(SCH_1):M_B_CPU1_SB_DQ(10)
CC64 M_B_CPU1_SB_DQ<2> MBB_DATA2 @T6G_MB_LIB.T6G(SCH_1):M_B_CPU1_SB_DQ(2)
CA62 M_B_CPU1_SB_CB<1> MBB_CHECK1 @T6G_MB_LIB.T6G(SCH_1):M_B_CPU1_SB_CB(1)
AF63 M_B_CPU1_SA_DQS_DN<3> MBA_DQS_L3 @T6G_MB_LIB.T6G(SCH_1):M_B_CPU1_SA_DQS_DN(3)
AE62 M_B_CPU1_SA_DQ<27> MBA_DATA27 @T6G_MB_LIB.T6G(SCH_1):M_B_CPU1_SA_DQ(27)
 U64 M_B_CPU1_SA_DQ<16> MBA_DATA16 @T6G_MB_LIB.T6G(SCH_1):M_B_CPU1_SA_DQ(16)
 G62 M_B_CPU1_SA_DQ<3> MBA_DATA3 @T6G_MB_LIB.T6G(SCH_1):M_B_CPU1_SA_DQ(3)
AR62 M_B_CPU1_SA_CB<7> MBA_CHECK7 @T6G_MB_LIB.T6G(SCH_1):M_B_CPU1_SA_CB(7)
BN62 M_B_CPU1_SA_RSP<0> MBA0_RSP_L @T6G_MB_LIB.T6G(SCH_1):M_B_CPU1_SA_RSP(0)
CW64 M_B_CPU1_SB_DQ<22> MBB_DATA22 @T6G_MB_LIB.T6G(SCH_1):M_B_CPU1_SB_DQ(22)
CK62 M_B_CPU1_SB_DQ<11> MBB_DATA11 @T6G_MB_LIB.T6G(SCH_1):M_B_CPU1_SB_DQ(11)
CD62 M_B_CPU1_SB_DQ<3> MBB_DATA3 @T6G_MB_LIB.T6G(SCH_1):M_B_CPU1_SB_DQ(3)
CA64 M_B_CPU1_SB_CB<2> MBB_CHECK2 @T6G_MB_LIB.T6G(SCH_1):M_B_CPU1_SB_CB(2)
AM63 M_B_CPU1_SA_DQS_DN<4> MBA_DQS_L4 @T6G_MB_LIB.T6G(SCH_1):M_B_CPU1_SA_DQS_DN(4)
 G64 M_B_CPU1_SA_DQS_DP<0> MBA_DQS_H0 @T6G_MB_LIB.T6G(SCH_1):M_B_CPU1_SA_DQS_DP(0)
AG64 M_B_CPU1_SA_DQ<28> MBA_DATA28 @T6G_MB_LIB.T6G(SCH_1):M_B_CPU1_SA_DQ(28)
 V62 M_B_CPU1_SA_DQ<17> MBA_DATA17 @T6G_MB_LIB.T6G(SCH_1):M_B_CPU1_SA_DQ(17)
 J64 M_B_CPU1_SA_DQ<4> MBA_DATA4 @T6G_MB_LIB.T6G(SCH_1):M_B_CPU1_SA_DQ(4)
BP62     NC MBA1_RSP_L     NC
CY62 M_B_CPU1_SB_DQ<23> MBB_DATA23 @T6G_MB_LIB.T6G(SCH_1):M_B_CPU1_SB_DQ(23)
CM63 M_B_CPU1_SB_DQ<12> MBB_DATA12 @T6G_MB_LIB.T6G(SCH_1):M_B_CPU1_SB_DQ(12)
CF63 M_B_CPU1_SB_DQ<4> MBB_DATA4 @T6G_MB_LIB.T6G(SCH_1):M_B_CPU1_SB_DQ(4)
CB62 M_B_CPU1_SB_CB<3> MBB_CHECK3 @T6G_MB_LIB.T6G(SCH_1):M_B_CPU1_SB_CB(3)
 H62 M_B_CPU1_SA_DQS_DN<5> MBA_DQS_L5 @T6G_MB_LIB.T6G(SCH_1):M_B_CPU1_SA_DQS_DN(5)
 N64 M_B_CPU1_SA_DQS_DP<1> MBA_DQS_H1 @T6G_MB_LIB.T6G(SCH_1):M_B_CPU1_SA_DQS_DP(1)
AH62 M_B_CPU1_SA_DQ<29> MBA_DATA29 @T6G_MB_LIB.T6G(SCH_1):M_B_CPU1_SA_DQ(29)
 V63 M_B_CPU1_SA_DQ<18> MBA_DATA18 @T6G_MB_LIB.T6G(SCH_1):M_B_CPU1_SA_DQ(18)
 K62 M_B_CPU1_SA_DQ<5> MBA_DATA5 @T6G_MB_LIB.T6G(SCH_1):M_B_CPU1_SA_DQ(5)
CE64 M_B_CPU1_SB_DQS_DN<0> MBB_DQS_L0 @T6G_MB_LIB.T6G(SCH_1):M_B_CPU1_SB_DQS_DN(0)
CY63 M_B_CPU1_SB_DQ<24> MBB_DATA24 @T6G_MB_LIB.T6G(SCH_1):M_B_CPU1_SB_DQ(24)
CN62 M_B_CPU1_SB_DQ<13> MBB_DATA13 @T6G_MB_LIB.T6G(SCH_1):M_B_CPU1_SB_DQ(13)
CG62 M_B_CPU1_SB_DQ<5> MBB_DATA5 @T6G_MB_LIB.T6G(SCH_1):M_B_CPU1_SB_DQ(5)
BT63 M_B_CPU1_SB_CB<4> MBB_CHECK4 @T6G_MB_LIB.T6G(SCH_1):M_B_CPU1_SB_CB(4)
 P62 M_B_CPU1_SA_DQS_DN<6> MBA_DQS_L6 @T6G_MB_LIB.T6G(SCH_1):M_B_CPU1_SA_DQS_DN(6)
 W64 M_B_CPU1_SA_DQS_DP<2> MBA_DQS_H2 @T6G_MB_LIB.T6G(SCH_1):M_B_CPU1_SA_DQS_DP(2)
 W62 M_B_CPU1_SA_DQ<19> MBA_DATA19 @T6G_MB_LIB.T6G(SCH_1):M_B_CPU1_SA_DQ(19)
 K63 M_B_CPU1_SA_DQ<6> MBA_DATA6 @T6G_MB_LIB.T6G(SCH_1):M_B_CPU1_SA_DQ(6)
AW64 M_B_CPU1_SA_CA<0> MBA_CA0 @T6G_MB_LIB.T6G(SCH_1):M_B_CPU1_SA_CA(0)
CL64 M_B_CPU1_SB_DQS_DN<1> MBB_DQS_L1 @T6G_MB_LIB.T6G(SCH_1):M_B_CPU1_SB_DQS_DN(1)
DA62 M_B_CPU1_SB_DQ<25> MBB_DATA25 @T6G_MB_LIB.T6G(SCH_1):M_B_CPU1_SB_DQ(25)
CN64 M_B_CPU1_SB_DQ<14> MBB_DATA14 @T6G_MB_LIB.T6G(SCH_1):M_B_CPU1_SB_DQ(14)
CG64 M_B_CPU1_SB_DQ<6> MBB_DATA6 @T6G_MB_LIB.T6G(SCH_1):M_B_CPU1_SB_DQ(6)
BU62 M_B_CPU1_SB_CB<5> MBB_CHECK5 @T6G_MB_LIB.T6G(SCH_1):M_B_CPU1_SB_CB(5)
BG62 M_B_CPU1_SB_CA<0> MBB_CA0 @T6G_MB_LIB.T6G(SCH_1):M_B_CPU1_SB_CA(0)
 Y62 M_B_CPU1_SA_DQS_DN<7> MBA_DQS_L7 @T6G_MB_LIB.T6G(SCH_1):M_B_CPU1_SA_DQS_DN(7)
AE64 M_B_CPU1_SA_DQS_DP<3> MBA_DQS_H3 @T6G_MB_LIB.T6G(SCH_1):M_B_CPU1_SA_DQS_DP(3)
 L62 M_B_CPU1_SA_DQ<7> MBA_DATA7 @T6G_MB_LIB.T6G(SCH_1):M_B_CPU1_SA_DQ(7)
AY63 M_B_CPU1_SA_CA<1> MBA_CA1 @T6G_MB_LIB.T6G(SCH_1):M_B_CPU1_SA_CA(1)
CU64 M_B_CPU1_SB_DQS_DN<2> MBB_DQS_L2 @T6G_MB_LIB.T6G(SCH_1):M_B_CPU1_SB_DQS_DN(2)
DA64 M_B_CPU1_SB_DQ<26> MBB_DATA26 @T6G_MB_LIB.T6G(SCH_1):M_B_CPU1_SB_DQ(26)
CP62 M_B_CPU1_SB_DQ<15> MBB_DATA15 @T6G_MB_LIB.T6G(SCH_1):M_B_CPU1_SB_DQ(15)
CH62 M_B_CPU1_SB_DQ<7> MBB_DATA7 @T6G_MB_LIB.T6G(SCH_1):M_B_CPU1_SB_DQ(7)
BU64 M_B_CPU1_SB_CB<6> MBB_CHECK6 @T6G_MB_LIB.T6G(SCH_1):M_B_CPU1_SB_CB(6)
BH62 M_B_CPU1_SB_CA<1> MBB_CA1 @T6G_MB_LIB.T6G(SCH_1):M_B_CPU1_SB_CA(1)
AF62 M_B_CPU1_SA_DQS_DN<8> MBA_DQS_L8 @T6G_MB_LIB.T6G(SCH_1):M_B_CPU1_SA_DQS_DN(8)
AL64 M_B_CPU1_SA_DQS_DP<4> MBA_DQS_H4 @T6G_MB_LIB.T6G(SCH_1):M_B_CPU1_SA_DQS_DP(4)
 L64 M_B_CPU1_SA_DQ<8> MBA_DATA8 @T6G_MB_LIB.T6G(SCH_1):M_B_CPU1_SA_DQ(8)
AY62 M_B_CPU1_SA_CA<2> MBA_CA2 @T6G_MB_LIB.T6G(SCH_1):M_B_CPU1_SA_CA(2)
DC64 M_B_CPU1_SB_DQS_DN<3> MBB_DQS_L3 @T6G_MB_LIB.T6G(SCH_1):M_B_CPU1_SB_DQS_DN(3)
DB62 M_B_CPU1_SB_DQ<27> MBB_DATA27 @T6G_MB_LIB.T6G(SCH_1):M_B_CPU1_SB_DQ(27)
CP63 M_B_CPU1_SB_DQ<16> MBB_DATA16 @T6G_MB_LIB.T6G(SCH_1):M_B_CPU1_SB_DQ(16)
CH63 M_B_CPU1_SB_DQ<8> MBB_DATA8 @T6G_MB_LIB.T6G(SCH_1):M_B_CPU1_SB_DQ(8)
BV62 M_B_CPU1_SB_CB<7> MBB_CHECK7 @T6G_MB_LIB.T6G(SCH_1):M_B_CPU1_SB_CB(7)
BH63 M_B_CPU1_SB_CA<2> MBB_CA2 @T6G_MB_LIB.T6G(SCH_1):M_B_CPU1_SB_CA(2)
BP63 M_B_CPU1_SB_RSP<0> MBB0_RSP_L @T6G_MB_LIB.T6G(SCH_1):M_B_CPU1_SB_RSP(0)
AM62 M_B_CPU1_SA_DQS_DN<9> MBA_DQS_L9 @T6G_MB_LIB.T6G(SCH_1):M_B_CPU1_SA_DQS_DN(9)
 J62 M_B_CPU1_SA_DQS_DP<5> MBA_DQS_H5 @T6G_MB_LIB.T6G(SCH_1):M_B_CPU1_SA_DQS_DP(5)
 M62 M_B_CPU1_SA_DQ<9> MBA_DATA9 @T6G_MB_LIB.T6G(SCH_1):M_B_CPU1_SA_DQ(9)
BA62 M_B_CPU1_SA_CA<3> MBA_CA3 @T6G_MB_LIB.T6G(SCH_1):M_B_CPU1_SA_CA(3)
BW62 M_B_CPU1_SB_DQS_DN<4> MBB_DQS_L4 @T6G_MB_LIB.T6G(SCH_1):M_B_CPU1_SB_DQS_DN(4)
CD63 M_B_CPU1_SB_DQS_DP<0> MBB_DQS_H0 @T6G_MB_LIB.T6G(SCH_1):M_B_CPU1_SB_DQS_DP(0)
DD63 M_B_CPU1_SB_DQ<28> MBB_DATA28 @T6G_MB_LIB.T6G(SCH_1):M_B_CPU1_SB_DQ(28)
CR62 M_B_CPU1_SB_DQ<17> MBB_DATA17 @T6G_MB_LIB.T6G(SCH_1):M_B_CPU1_SB_DQ(17)
CJ62 M_B_CPU1_SB_DQ<9> MBB_DATA9 @T6G_MB_LIB.T6G(SCH_1):M_B_CPU1_SB_DQ(9)
BJ64 M_B_CPU1_SB_CA<3> MBB_CA3 @T6G_MB_LIB.T6G(SCH_1):M_B_CPU1_SB_CA(3)
BR64     NC MBB1_RSP_L     NC
 R62 M_B_CPU1_SA_DQS_DP<6> MBA_DQS_H6 @T6G_MB_LIB.T6G(SCH_1):M_B_CPU1_SA_DQS_DP(6)
BA64 M_B_CPU1_SA_CA<4> MBA_CA4 @T6G_MB_LIB.T6G(SCH_1):M_B_CPU1_SA_CA(4)
CE62 M_B_CPU1_SB_DQS_DN<5> MBB_DQS_L5 @T6G_MB_LIB.T6G(SCH_1):M_B_CPU1_SB_DQS_DN(5)
CK63 M_B_CPU1_SB_DQS_DP<1> MBB_DQS_H1 @T6G_MB_LIB.T6G(SCH_1):M_B_CPU1_SB_DQS_DP(1)
DE62 M_B_CPU1_SB_DQ<29> MBB_DATA29 @T6G_MB_LIB.T6G(SCH_1):M_B_CPU1_SB_DQ(29)
CR64 M_B_CPU1_SB_DQ<18> MBB_DATA18 @T6G_MB_LIB.T6G(SCH_1):M_B_CPU1_SB_DQ(18)
BJ62 M_B_CPU1_SB_CA<4> MBB_CA4 @T6G_MB_LIB.T6G(SCH_1):M_B_CPU1_SB_CA(4)
AA62 M_B_CPU1_SA_DQS_DP<7> MBA_DQS_H7 @T6G_MB_LIB.T6G(SCH_1):M_B_CPU1_SA_DQS_DP(7)
BB63 M_B_CPU1_SA_CA<5> MBA_CA5 @T6G_MB_LIB.T6G(SCH_1):M_B_CPU1_SA_CA(5)
AV63 M_B_CPU1_SA_CS_N<0> MBA0_CS_L0 @T6G_MB_LIB.T6G(SCH_1):M_B_CPU1_SA_CS_N(0)
CL62 M_B_CPU1_SB_DQS_DN<6> MBB_DQS_L6 @T6G_MB_LIB.T6G(SCH_1):M_B_CPU1_SB_DQS_DN(6)
CT63 M_B_CPU1_SB_DQS_DP<2> MBB_DQS_H2 @T6G_MB_LIB.T6G(SCH_1):M_B_CPU1_SB_DQS_DP(2)
BK62 M_B_CPU1_SB_CA<5> MBB_CA5 @T6G_MB_LIB.T6G(SCH_1):M_B_CPU1_SB_CA(5)
AG62 M_B_CPU1_SA_DQS_DP<8> MBA_DQS_H8 @T6G_MB_LIB.T6G(SCH_1):M_B_CPU1_SA_DQS_DP(8)
AH63 M_B_CPU1_SA_DQ<30> MBA_DATA30 @T6G_MB_LIB.T6G(SCH_1):M_B_CPU1_SA_DQ(30)
BB62 M_B_CPU1_SA_CA<6> MBA_CA6 @T6G_MB_LIB.T6G(SCH_1):M_B_CPU1_SA_CA(6)
AU64     NC MBA1_CS_L0     NC
AW62 M_B_CPU1_SA_CS_N<1> MBA0_CS_L1 @T6G_MB_LIB.T6G(SCH_1):M_B_CPU1_SA_CS_N(1)
CU62 M_B_CPU1_SB_DQS_DN<7> MBB_DQS_L7 @T6G_MB_LIB.T6G(SCH_1):M_B_CPU1_SB_DQS_DN(7)
DB63 M_B_CPU1_SB_DQS_DP<3> MBB_DQS_H3 @T6G_MB_LIB.T6G(SCH_1):M_B_CPU1_SB_DQS_DP(3)
BK63 M_B_CPU1_SB_CA<6> MBB_CA6 @T6G_MB_LIB.T6G(SCH_1):M_B_CPU1_SB_CA(6)
AN62 M_B_CPU1_SA_DQS_DP<9> MBA_DQS_H9 @T6G_MB_LIB.T6G(SCH_1):M_B_CPU1_SA_DQS_DP(9)
AJ62 M_B_CPU1_SA_DQ<31> MBA_DATA31 @T6G_MB_LIB.T6G(SCH_1):M_B_CPU1_SA_DQ(31)
AA64 M_B_CPU1_SA_DQ<20> MBA_DATA20 @T6G_MB_LIB.T6G(SCH_1):M_B_CPU1_SA_DQ(20)
AJ64 M_B_CPU1_SA_CB<0> MBA_CHECK0 @T6G_MB_LIB.T6G(SCH_1):M_B_CPU1_SA_CB(0)
AV62     NC MBA1_CS_L1     NC
DC62 M_B_CPU1_SB_DQS_DN<8> MBB_DQS_L8 @T6G_MB_LIB.T6G(SCH_1):M_B_CPU1_SB_DQS_DN(8)
BY62 M_B_CPU1_SB_DQS_DP<4> MBB_DQS_H4 @T6G_MB_LIB.T6G(SCH_1):M_B_CPU1_SB_DQS_DP(4)
AB62 M_B_CPU1_SA_DQ<21> MBA_DATA21 @T6G_MB_LIB.T6G(SCH_1):M_B_CPU1_SA_DQ(21)
 M63 M_B_CPU1_SA_DQ<10> MBA_DATA10 @T6G_MB_LIB.T6G(SCH_1):M_B_CPU1_SA_DQ(10)
AK62 M_B_CPU1_SA_CB<1> MBA_CHECK1 @T6G_MB_LIB.T6G(SCH_1):M_B_CPU1_SA_CB(1)
BV63 M_B_CPU1_SB_DQS_DP<9> MBB_DQS_H9 @T6G_MB_LIB.T6G(SCH_1):M_B_CPU1_SB_DQS_DP(9)
BC62 M_B_CPU1_SA_PAR MBA_PAR @T6G_MB_LIB.T6G(SCH_1):M_B_CPU1_SA_PAR
BL64 M_B_CPU1_SB_PAR MBB_PAR @T6G_MB_LIB.T6G(SCH_1):M_B_CPU1_SB_PAR
BC64 M_B_CPU1_CLK_DP<0> MB0_CLK_H @T6G_MB_LIB.T6G(SCH_1):M_B_CPU1_CLK_DP(0)
BD63 M_B_CPU1_CLK_DN<0> MB0_CLK_L @T6G_MB_LIB.T6G(SCH_1):M_B_CPU1_CLK_DN(0)
BF63     NC MB1_CLK_H     NC
BG64     NC MB1_CLK_L     NC
CT62 M_B_CPU1_SB_DQ<19> MBB_DATA19 @T6G_MB_LIB.T6G(SCH_1):M_B_CPU1_SB_DQ(19)
AC64 M_B_CPU1_SA_DQ<24> MBA_DATA24 @T6G_MB_LIB.T6G(SCH_1):M_B_CPU1_SA_DQ(24)
CV63 M_B_CPU1_SB_DQ<20> MBB_DATA20 @T6G_MB_LIB.T6G(SCH_1):M_B_CPU1_SB_DQ(20)
BF62 TP_M_B_CPU1_SA_TEST39B TEST39B @T6G_MB_LIB.T6G(SCH_1):TP_M_B_CPU1_SA_TEST39B

Q_RES_0402LF-15,1%,1/16W,CHIP,CS01502FB03  I314  R501
   1 M_B_CPU1_ALERT_N      A @T6G_MB_LIB.T6G(SCH_1):M_B_CPU1_ALERT_N
   2 M_B_CPU1_ALERT_R_N      B @T6G_MB_LIB.T6G(SCH_1):M_B_CPU1_ALERT_R_N


DRAWING: @T6G_MB_LIB.T6G(SCH_1):PAGE39 

GENOA_SP5-SOCKET6096_13568-001,SMLF,IO,DGA^6000030  I159  U26
AT55 M_C_CPU1_ALERT_R_N MC_ALERT_L @T6G_MB_LIB.T6G(SCH_1):M_C_CPU1_ALERT_R_N
AU55 M_C_CPU1_RESET_N MC_RESET_L @T6G_MB_LIB.T6G(SCH_1):M_C_CPU1_RESET_N
DD55 M_C_CPU1_SB_DQS_DP<8> MCB_DQS_H8 @T6G_MB_LIB.T6G(SCH_1):M_C_CPU1_SB_DQS_DP(8)
DE57 M_C_CPU1_SB_DQ<30> MCB_DATA30 @T6G_MB_LIB.T6G(SCH_1):M_C_CPU1_SB_DQ(30)
CH56 M_C_CPU1_SB_DQ<8> MCB_DATA8 @T6G_MB_LIB.T6G(SCH_1):M_C_CPU1_SB_DQ(8)
BM56     NC MCB1_CS_L1     NC
BN57 M_C_CPU1_SB_CS_N<1> MCB0_CS_L1 @T6G_MB_LIB.T6G(SCH_1):M_C_CPU1_SB_CS_N(1)
 P56 M_C_CPU1_SA_DQS_DN<1> MCA_DQS_L1 @T6G_MB_LIB.T6G(SCH_1):M_C_CPU1_SA_DQS_DN(1)
AD55 M_C_CPU1_SA_DQ<25> MCA_DATA25 @T6G_MB_LIB.T6G(SCH_1):M_C_CPU1_SA_DQ(25)
 T56 M_C_CPU1_SA_DQ<14> MCA_DATA14 @T6G_MB_LIB.T6G(SCH_1):M_C_CPU1_SA_DQ(14)
 M55 M_C_CPU1_SA_DQ<9> MCA_DATA9 @T6G_MB_LIB.T6G(SCH_1):M_C_CPU1_SA_DQ(9)
AP55 M_C_CPU1_SA_CB<5> MCA_CHECK5 @T6G_MB_LIB.T6G(SCH_1):M_C_CPU1_SA_CB(5)
DF55 M_C_CPU1_SB_DQ<31> MCB_DATA31 @T6G_MB_LIB.T6G(SCH_1):M_C_CPU1_SB_DQ(31)
CV56 M_C_CPU1_SB_DQ<20> MCB_DATA20 @T6G_MB_LIB.T6G(SCH_1):M_C_CPU1_SB_DQ(20)
CJ55 M_C_CPU1_SB_DQ<9> MCB_DATA9 @T6G_MB_LIB.T6G(SCH_1):M_C_CPU1_SB_DQ(9)
BY56 M_C_CPU1_SB_CB<0> MCB_CHECK0 @T6G_MB_LIB.T6G(SCH_1):M_C_CPU1_SB_CB(0)
 Y56 M_C_CPU1_SA_DQS_DN<2> MCA_DQS_L2 @T6G_MB_LIB.T6G(SCH_1):M_C_CPU1_SA_DQS_DN(2)
AD56 M_C_CPU1_SA_DQ<26> MCA_DATA26 @T6G_MB_LIB.T6G(SCH_1):M_C_CPU1_SA_DQ(26)
 U55 M_C_CPU1_SA_DQ<15> MCA_DATA15 @T6G_MB_LIB.T6G(SCH_1):M_C_CPU1_SA_DQ(15)
AP56 M_C_CPU1_SA_CB<6> MCA_CHECK6 @T6G_MB_LIB.T6G(SCH_1):M_C_CPU1_SA_CB(6)
BN55 M_C_CPU1_SA_RSP<0> MCA0_RSP_L @T6G_MB_LIB.T6G(SCH_1):M_C_CPU1_SA_RSP(0)
CW55 M_C_CPU1_SB_DQ<21> MCB_DATA21 @T6G_MB_LIB.T6G(SCH_1):M_C_CPU1_SB_DQ(21)
CJ57 M_C_CPU1_SB_DQ<10> MCB_DATA10 @T6G_MB_LIB.T6G(SCH_1):M_C_CPU1_SB_DQ(10)
CA55 M_C_CPU1_SB_CB<1> MCB_CHECK1 @T6G_MB_LIB.T6G(SCH_1):M_C_CPU1_SB_CB(1)
AF56 M_C_CPU1_SA_DQS_DN<3> MCA_DQS_L3 @T6G_MB_LIB.T6G(SCH_1):M_C_CPU1_SA_DQS_DN(3)
AE55 M_C_CPU1_SA_DQ<27> MCA_DATA27 @T6G_MB_LIB.T6G(SCH_1):M_C_CPU1_SA_DQ(27)
 U57 M_C_CPU1_SA_DQ<16> MCA_DATA16 @T6G_MB_LIB.T6G(SCH_1):M_C_CPU1_SA_DQ(16)
AR55 M_C_CPU1_SA_CB<7> MCA_CHECK7 @T6G_MB_LIB.T6G(SCH_1):M_C_CPU1_SA_CB(7)
BP55     NC MCA1_RSP_L     NC
CW57 M_C_CPU1_SB_DQ<22> MCB_DATA22 @T6G_MB_LIB.T6G(SCH_1):M_C_CPU1_SB_DQ(22)
CK55 M_C_CPU1_SB_DQ<11> MCB_DATA11 @T6G_MB_LIB.T6G(SCH_1):M_C_CPU1_SB_DQ(11)
CA57 M_C_CPU1_SB_CB<2> MCB_CHECK2 @T6G_MB_LIB.T6G(SCH_1):M_C_CPU1_SB_CB(2)
AM56 M_C_CPU1_SA_DQS_DN<4> MCA_DQS_L4 @T6G_MB_LIB.T6G(SCH_1):M_C_CPU1_SA_DQS_DN(4)
 G57 M_C_CPU1_SA_DQS_DP<0> MCA_DQS_H0 @T6G_MB_LIB.T6G(SCH_1):M_C_CPU1_SA_DQS_DP(0)
AG57 M_C_CPU1_SA_DQ<28> MCA_DATA28 @T6G_MB_LIB.T6G(SCH_1):M_C_CPU1_SA_DQ(28)
 V55 M_C_CPU1_SA_DQ<17> MCA_DATA17 @T6G_MB_LIB.T6G(SCH_1):M_C_CPU1_SA_DQ(17)
CY55 M_C_CPU1_SB_DQ<23> MCB_DATA23 @T6G_MB_LIB.T6G(SCH_1):M_C_CPU1_SB_DQ(23)
CM56 M_C_CPU1_SB_DQ<12> MCB_DATA12 @T6G_MB_LIB.T6G(SCH_1):M_C_CPU1_SB_DQ(12)
CB55 M_C_CPU1_SB_CB<3> MCB_CHECK3 @T6G_MB_LIB.T6G(SCH_1):M_C_CPU1_SB_CB(3)
 H55 M_C_CPU1_SA_DQS_DN<5> MCA_DQS_L5 @T6G_MB_LIB.T6G(SCH_1):M_C_CPU1_SA_DQS_DN(5)
 N57 M_C_CPU1_SA_DQS_DP<1> MCA_DQS_H1 @T6G_MB_LIB.T6G(SCH_1):M_C_CPU1_SA_DQS_DP(1)
AH55 M_C_CPU1_SA_DQ<29> MCA_DATA29 @T6G_MB_LIB.T6G(SCH_1):M_C_CPU1_SA_DQ(29)
 V56 M_C_CPU1_SA_DQ<18> MCA_DATA18 @T6G_MB_LIB.T6G(SCH_1):M_C_CPU1_SA_DQ(18)
CE57 M_C_CPU1_SB_DQS_DN<0> MCB_DQS_L0 @T6G_MB_LIB.T6G(SCH_1):M_C_CPU1_SB_DQS_DN(0)
CY56 M_C_CPU1_SB_DQ<24> MCB_DATA24 @T6G_MB_LIB.T6G(SCH_1):M_C_CPU1_SB_DQ(24)
CN55 M_C_CPU1_SB_DQ<13> MCB_DATA13 @T6G_MB_LIB.T6G(SCH_1):M_C_CPU1_SB_DQ(13)
BT56 M_C_CPU1_SB_CB<4> MCB_CHECK4 @T6G_MB_LIB.T6G(SCH_1):M_C_CPU1_SB_CB(4)
 P55 M_C_CPU1_SA_DQS_DN<6> MCA_DQS_L6 @T6G_MB_LIB.T6G(SCH_1):M_C_CPU1_SA_DQS_DN(6)
 W57 M_C_CPU1_SA_DQS_DP<2> MCA_DQS_H2 @T6G_MB_LIB.T6G(SCH_1):M_C_CPU1_SA_DQS_DP(2)
 W55 M_C_CPU1_SA_DQ<19> MCA_DATA19 @T6G_MB_LIB.T6G(SCH_1):M_C_CPU1_SA_DQ(19)
CL57 M_C_CPU1_SB_DQS_DN<1> MCB_DQS_L1 @T6G_MB_LIB.T6G(SCH_1):M_C_CPU1_SB_DQS_DN(1)
DA55 M_C_CPU1_SB_DQ<25> MCB_DATA25 @T6G_MB_LIB.T6G(SCH_1):M_C_CPU1_SB_DQ(25)
CN57 M_C_CPU1_SB_DQ<14> MCB_DATA14 @T6G_MB_LIB.T6G(SCH_1):M_C_CPU1_SB_DQ(14)
BU55 M_C_CPU1_SB_CB<5> MCB_CHECK5 @T6G_MB_LIB.T6G(SCH_1):M_C_CPU1_SB_CB(5)
 Y55 M_C_CPU1_SA_DQS_DN<7> MCA_DQS_L7 @T6G_MB_LIB.T6G(SCH_1):M_C_CPU1_SA_DQS_DN(7)
AE57 M_C_CPU1_SA_DQS_DP<3> MCA_DQS_H3 @T6G_MB_LIB.T6G(SCH_1):M_C_CPU1_SA_DQS_DP(3)
CU57 M_C_CPU1_SB_DQS_DN<2> MCB_DQS_L2 @T6G_MB_LIB.T6G(SCH_1):M_C_CPU1_SB_DQS_DN(2)
DA57 M_C_CPU1_SB_DQ<26> MCB_DATA26 @T6G_MB_LIB.T6G(SCH_1):M_C_CPU1_SB_DQ(26)
CP55 M_C_CPU1_SB_DQ<15> MCB_DATA15 @T6G_MB_LIB.T6G(SCH_1):M_C_CPU1_SB_DQ(15)
BU57 M_C_CPU1_SB_CB<6> MCB_CHECK6 @T6G_MB_LIB.T6G(SCH_1):M_C_CPU1_SB_CB(6)
AF55 M_C_CPU1_SA_DQS_DN<8> MCA_DQS_L8 @T6G_MB_LIB.T6G(SCH_1):M_C_CPU1_SA_DQS_DN(8)
AL57 M_C_CPU1_SA_DQS_DP<4> MCA_DQS_H4 @T6G_MB_LIB.T6G(SCH_1):M_C_CPU1_SA_DQS_DP(4)
AW57 M_C_CPU1_SA_CA<0> MCA_CA0 @T6G_MB_LIB.T6G(SCH_1):M_C_CPU1_SA_CA(0)
DC57 M_C_CPU1_SB_DQS_DN<3> MCB_DQS_L3 @T6G_MB_LIB.T6G(SCH_1):M_C_CPU1_SB_DQS_DN(3)
DB55 M_C_CPU1_SB_DQ<27> MCB_DATA27 @T6G_MB_LIB.T6G(SCH_1):M_C_CPU1_SB_DQ(27)
CP56 M_C_CPU1_SB_DQ<16> MCB_DATA16 @T6G_MB_LIB.T6G(SCH_1):M_C_CPU1_SB_DQ(16)
BV55 M_C_CPU1_SB_CB<7> MCB_CHECK7 @T6G_MB_LIB.T6G(SCH_1):M_C_CPU1_SB_CB(7)
BG55 M_C_CPU1_SB_CA<0> MCB_CA0 @T6G_MB_LIB.T6G(SCH_1):M_C_CPU1_SB_CA(0)
BR57     NC MCB1_RSP_L     NC
BP56 M_C_CPU1_SB_RSP<0> MCB0_RSP_L @T6G_MB_LIB.T6G(SCH_1):M_C_CPU1_SB_RSP(0)
AM55 M_C_CPU1_SA_DQS_DN<9> MCA_DQS_L9 @T6G_MB_LIB.T6G(SCH_1):M_C_CPU1_SA_DQS_DN(9)
 J55 M_C_CPU1_SA_DQS_DP<5> MCA_DQS_H5 @T6G_MB_LIB.T6G(SCH_1):M_C_CPU1_SA_DQS_DP(5)
 E57 M_C_CPU1_SA_DQ<0> MCA_DATA0 @T6G_MB_LIB.T6G(SCH_1):M_C_CPU1_SA_DQ(0)
AY56 M_C_CPU1_SA_CA<1> MCA_CA1 @T6G_MB_LIB.T6G(SCH_1):M_C_CPU1_SA_CA(1)
BW55 M_C_CPU1_SB_DQS_DN<4> MCB_DQS_L4 @T6G_MB_LIB.T6G(SCH_1):M_C_CPU1_SB_DQS_DN(4)
CD56 M_C_CPU1_SB_DQS_DP<0> MCB_DQS_H0 @T6G_MB_LIB.T6G(SCH_1):M_C_CPU1_SB_DQS_DP(0)
DD56 M_C_CPU1_SB_DQ<28> MCB_DATA28 @T6G_MB_LIB.T6G(SCH_1):M_C_CPU1_SB_DQ(28)
CR55 M_C_CPU1_SB_DQ<17> MCB_DATA17 @T6G_MB_LIB.T6G(SCH_1):M_C_CPU1_SB_DQ(17)
CB56 M_C_CPU1_SB_DQ<0> MCB_DATA0 @T6G_MB_LIB.T6G(SCH_1):M_C_CPU1_SB_DQ(0)
BH55 M_C_CPU1_SB_CA<1> MCB_CA1 @T6G_MB_LIB.T6G(SCH_1):M_C_CPU1_SB_CA(1)
 R55 M_C_CPU1_SA_DQS_DP<6> MCA_DQS_H6 @T6G_MB_LIB.T6G(SCH_1):M_C_CPU1_SA_DQS_DP(6)
 F55 M_C_CPU1_SA_DQ<1> MCA_DATA1 @T6G_MB_LIB.T6G(SCH_1):M_C_CPU1_SA_DQ(1)
AY55 M_C_CPU1_SA_CA<2> MCA_CA2 @T6G_MB_LIB.T6G(SCH_1):M_C_CPU1_SA_CA(2)
AV56 M_C_CPU1_SA_CS_N<0> MCA0_CS_L0 @T6G_MB_LIB.T6G(SCH_1):M_C_CPU1_SA_CS_N(0)
CE55 M_C_CPU1_SB_DQS_DN<5> MCB_DQS_L5 @T6G_MB_LIB.T6G(SCH_1):M_C_CPU1_SB_DQS_DN(5)
CK56 M_C_CPU1_SB_DQS_DP<1> MCB_DQS_H1 @T6G_MB_LIB.T6G(SCH_1):M_C_CPU1_SB_DQS_DP(1)
DE55 M_C_CPU1_SB_DQ<29> MCB_DATA29 @T6G_MB_LIB.T6G(SCH_1):M_C_CPU1_SB_DQ(29)
CR57 M_C_CPU1_SB_DQ<18> MCB_DATA18 @T6G_MB_LIB.T6G(SCH_1):M_C_CPU1_SB_DQ(18)
CC55 M_C_CPU1_SB_DQ<1> MCB_DATA1 @T6G_MB_LIB.T6G(SCH_1):M_C_CPU1_SB_DQ(1)
BH56 M_C_CPU1_SB_CA<2> MCB_CA2 @T6G_MB_LIB.T6G(SCH_1):M_C_CPU1_SB_CA(2)
AA55 M_C_CPU1_SA_DQS_DP<7> MCA_DQS_H7 @T6G_MB_LIB.T6G(SCH_1):M_C_CPU1_SA_DQS_DP(7)
 F56 M_C_CPU1_SA_DQ<2> MCA_DATA2 @T6G_MB_LIB.T6G(SCH_1):M_C_CPU1_SA_DQ(2)
BA55 M_C_CPU1_SA_CA<3> MCA_CA3 @T6G_MB_LIB.T6G(SCH_1):M_C_CPU1_SA_CA(3)
AU57     NC MCA1_CS_L0     NC
AW55 M_C_CPU1_SA_CS_N<1> MCA0_CS_L1 @T6G_MB_LIB.T6G(SCH_1):M_C_CPU1_SA_CS_N(1)
CL55 M_C_CPU1_SB_DQS_DN<6> MCB_DQS_L6 @T6G_MB_LIB.T6G(SCH_1):M_C_CPU1_SB_DQS_DN(6)
CT56 M_C_CPU1_SB_DQS_DP<2> MCB_DQS_H2 @T6G_MB_LIB.T6G(SCH_1):M_C_CPU1_SB_DQS_DP(2)
CT55 M_C_CPU1_SB_DQ<19> MCB_DATA19 @T6G_MB_LIB.T6G(SCH_1):M_C_CPU1_SB_DQ(19)
CC57 M_C_CPU1_SB_DQ<2> MCB_DATA2 @T6G_MB_LIB.T6G(SCH_1):M_C_CPU1_SB_DQ(2)
BJ57 M_C_CPU1_SB_CA<3> MCB_CA3 @T6G_MB_LIB.T6G(SCH_1):M_C_CPU1_SB_CA(3)
AG55 M_C_CPU1_SA_DQS_DP<8> MCA_DQS_H8 @T6G_MB_LIB.T6G(SCH_1):M_C_CPU1_SA_DQS_DP(8)
AH56 M_C_CPU1_SA_DQ<30> MCA_DATA30 @T6G_MB_LIB.T6G(SCH_1):M_C_CPU1_SA_DQ(30)
 G55 M_C_CPU1_SA_DQ<3> MCA_DATA3 @T6G_MB_LIB.T6G(SCH_1):M_C_CPU1_SA_DQ(3)
BA57 M_C_CPU1_SA_CA<4> MCA_CA4 @T6G_MB_LIB.T6G(SCH_1):M_C_CPU1_SA_CA(4)
AV55     NC MCA1_CS_L1     NC
CU55 M_C_CPU1_SB_DQS_DN<7> MCB_DQS_L7 @T6G_MB_LIB.T6G(SCH_1):M_C_CPU1_SB_DQS_DN(7)
DB56 M_C_CPU1_SB_DQS_DP<3> MCB_DQS_H3 @T6G_MB_LIB.T6G(SCH_1):M_C_CPU1_SB_DQS_DP(3)
CD55 M_C_CPU1_SB_DQ<3> MCB_DATA3 @T6G_MB_LIB.T6G(SCH_1):M_C_CPU1_SB_DQ(3)
BJ55 M_C_CPU1_SB_CA<4> MCB_CA4 @T6G_MB_LIB.T6G(SCH_1):M_C_CPU1_SB_CA(4)
AN55 M_C_CPU1_SA_DQS_DP<9> MCA_DQS_H9 @T6G_MB_LIB.T6G(SCH_1):M_C_CPU1_SA_DQS_DP(9)
AJ55 M_C_CPU1_SA_DQ<31> MCA_DATA31 @T6G_MB_LIB.T6G(SCH_1):M_C_CPU1_SA_DQ(31)
AA57 M_C_CPU1_SA_DQ<20> MCA_DATA20 @T6G_MB_LIB.T6G(SCH_1):M_C_CPU1_SA_DQ(20)
 J57 M_C_CPU1_SA_DQ<4> MCA_DATA4 @T6G_MB_LIB.T6G(SCH_1):M_C_CPU1_SA_DQ(4)
AJ57 M_C_CPU1_SA_CB<0> MCA_CHECK0 @T6G_MB_LIB.T6G(SCH_1):M_C_CPU1_SA_CB(0)
BB56 M_C_CPU1_SA_CA<5> MCA_CA5 @T6G_MB_LIB.T6G(SCH_1):M_C_CPU1_SA_CA(5)
DC55 M_C_CPU1_SB_DQS_DN<8> MCB_DQS_L8 @T6G_MB_LIB.T6G(SCH_1):M_C_CPU1_SB_DQS_DN(8)
BY55 M_C_CPU1_SB_DQS_DP<4> MCB_DQS_H4 @T6G_MB_LIB.T6G(SCH_1):M_C_CPU1_SB_DQS_DP(4)
CF56 M_C_CPU1_SB_DQ<4> MCB_DATA4 @T6G_MB_LIB.T6G(SCH_1):M_C_CPU1_SB_DQ(4)
BK55 M_C_CPU1_SB_CA<5> MCB_CA5 @T6G_MB_LIB.T6G(SCH_1):M_C_CPU1_SB_CA(5)
AB55 M_C_CPU1_SA_DQ<21> MCA_DATA21 @T6G_MB_LIB.T6G(SCH_1):M_C_CPU1_SA_DQ(21)
 M56 M_C_CPU1_SA_DQ<10> MCA_DATA10 @T6G_MB_LIB.T6G(SCH_1):M_C_CPU1_SA_DQ(10)
 K55 M_C_CPU1_SA_DQ<5> MCA_DATA5 @T6G_MB_LIB.T6G(SCH_1):M_C_CPU1_SA_DQ(5)
AK55 M_C_CPU1_SA_CB<1> MCA_CHECK1 @T6G_MB_LIB.T6G(SCH_1):M_C_CPU1_SA_CB(1)
BB55 M_C_CPU1_SA_CA<6> MCA_CA6 @T6G_MB_LIB.T6G(SCH_1):M_C_CPU1_SA_CA(6)
BW57 M_C_CPU1_SB_DQS_DN<9> MCB_DQS_L9 @T6G_MB_LIB.T6G(SCH_1):M_C_CPU1_SB_DQS_DN(9)
CF55 M_C_CPU1_SB_DQS_DP<5> MCB_DQS_H5 @T6G_MB_LIB.T6G(SCH_1):M_C_CPU1_SB_DQS_DP(5)
CG55 M_C_CPU1_SB_DQ<5> MCB_DATA5 @T6G_MB_LIB.T6G(SCH_1):M_C_CPU1_SB_DQ(5)
BK56 M_C_CPU1_SB_CA<6> MCB_CA6 @T6G_MB_LIB.T6G(SCH_1):M_C_CPU1_SB_CA(6)
AB56 M_C_CPU1_SA_DQ<22> MCA_DATA22 @T6G_MB_LIB.T6G(SCH_1):M_C_CPU1_SA_DQ(22)
 N55 M_C_CPU1_SA_DQ<11> MCA_DATA11 @T6G_MB_LIB.T6G(SCH_1):M_C_CPU1_SA_DQ(11)
 K56 M_C_CPU1_SA_DQ<6> MCA_DATA6 @T6G_MB_LIB.T6G(SCH_1):M_C_CPU1_SA_DQ(6)
AK56 M_C_CPU1_SA_CB<2> MCA_CHECK2 @T6G_MB_LIB.T6G(SCH_1):M_C_CPU1_SA_CB(2)
CM55 M_C_CPU1_SB_DQS_DP<6> MCB_DQS_H6 @T6G_MB_LIB.T6G(SCH_1):M_C_CPU1_SB_DQS_DP(6)
CG57 M_C_CPU1_SB_DQ<6> MCB_DATA6 @T6G_MB_LIB.T6G(SCH_1):M_C_CPU1_SB_DQ(6)
AC55 M_C_CPU1_SA_DQ<23> MCA_DATA23 @T6G_MB_LIB.T6G(SCH_1):M_C_CPU1_SA_DQ(23)
 R57 M_C_CPU1_SA_DQ<12> MCA_DATA12 @T6G_MB_LIB.T6G(SCH_1):M_C_CPU1_SA_DQ(12)
 L55 M_C_CPU1_SA_DQ<7> MCA_DATA7 @T6G_MB_LIB.T6G(SCH_1):M_C_CPU1_SA_DQ(7)
AL55 M_C_CPU1_SA_CB<3> MCA_CHECK3 @T6G_MB_LIB.T6G(SCH_1):M_C_CPU1_SA_CB(3)
CV55 M_C_CPU1_SB_DQS_DP<7> MCB_DQS_H7 @T6G_MB_LIB.T6G(SCH_1):M_C_CPU1_SB_DQS_DP(7)
CH55 M_C_CPU1_SB_DQ<7> MCB_DATA7 @T6G_MB_LIB.T6G(SCH_1):M_C_CPU1_SB_DQ(7)
BL55     NC MCB1_CS_L0     NC
BM55 M_C_CPU1_SB_CS_N<0> MCB0_CS_L0 @T6G_MB_LIB.T6G(SCH_1):M_C_CPU1_SB_CS_N(0)
 H56 M_C_CPU1_SA_DQS_DN<0> MCA_DQS_L0 @T6G_MB_LIB.T6G(SCH_1):M_C_CPU1_SA_DQS_DN(0)
AC57 M_C_CPU1_SA_DQ<24> MCA_DATA24 @T6G_MB_LIB.T6G(SCH_1):M_C_CPU1_SA_DQ(24)
 T55 M_C_CPU1_SA_DQ<13> MCA_DATA13 @T6G_MB_LIB.T6G(SCH_1):M_C_CPU1_SA_DQ(13)
 L57 M_C_CPU1_SA_DQ<8> MCA_DATA8 @T6G_MB_LIB.T6G(SCH_1):M_C_CPU1_SA_DQ(8)
AN57 M_C_CPU1_SA_CB<4> MCA_CHECK4 @T6G_MB_LIB.T6G(SCH_1):M_C_CPU1_SA_CB(4)
BV56 M_C_CPU1_SB_DQS_DP<9> MCB_DQS_H9 @T6G_MB_LIB.T6G(SCH_1):M_C_CPU1_SB_DQS_DP(9)
BC55 M_C_CPU1_SA_PAR MCA_PAR @T6G_MB_LIB.T6G(SCH_1):M_C_CPU1_SA_PAR
BL57 M_C_CPU1_SB_PAR MCB_PAR @T6G_MB_LIB.T6G(SCH_1):M_C_CPU1_SB_PAR
BC57 M_C_CPU1_CLK_DP<0> MC0_CLK_H @T6G_MB_LIB.T6G(SCH_1):M_C_CPU1_CLK_DP(0)
BD56 M_C_CPU1_CLK_DN<0> MC0_CLK_L @T6G_MB_LIB.T6G(SCH_1):M_C_CPU1_CLK_DN(0)
BF56     NC MC1_CLK_H     NC
BG57     NC MC1_CLK_L     NC
BF55 TP_M_C_CPU1_SA_TEST39C TEST39C @T6G_MB_LIB.T6G(SCH_1):TP_M_C_CPU1_SA_TEST39C

Q_RES_0402LF-15,1%,1/16W,CHIP,CS01502FB03  I313  R502
   1 M_C_CPU1_ALERT_N      A @T6G_MB_LIB.T6G(SCH_1):M_C_CPU1_ALERT_N
   2 M_C_CPU1_ALERT_R_N      B @T6G_MB_LIB.T6G(SCH_1):M_C_CPU1_ALERT_R_N


DRAWING: @T6G_MB_LIB.T6G(SCH_1):PAGE40 

GENOA_SP5-SOCKET6096_13568-001,SMLF,IO,DGA^6000030  I159  U26
AT58 M_D_CPU1_ALERT_R_N MD_ALERT_L @T6G_MB_LIB.T6G(SCH_1):M_D_CPU1_ALERT_R_N
AU59 M_D_CPU1_RESET_N MD_RESET_L @T6G_MB_LIB.T6G(SCH_1):M_D_CPU1_RESET_N
CY58 M_D_CPU1_SB_DQ<23> MDB_DATA23 @T6G_MB_LIB.T6G(SCH_1):M_D_CPU1_SB_DQ(23)
CM60 M_D_CPU1_SB_DQ<12> MDB_DATA12 @T6G_MB_LIB.T6G(SCH_1):M_D_CPU1_SB_DQ(12)
CC60 M_D_CPU1_SB_DQ<2> MDB_DATA2 @T6G_MB_LIB.T6G(SCH_1):M_D_CPU1_SB_DQ(2)
CB58 M_D_CPU1_SB_CB<3> MDB_CHECK3 @T6G_MB_LIB.T6G(SCH_1):M_D_CPU1_SB_CB(3)
 H58 M_D_CPU1_SA_DQS_DN<5> MDA_DQS_L5 @T6G_MB_LIB.T6G(SCH_1):M_D_CPU1_SA_DQS_DN(5)
 N60 M_D_CPU1_SA_DQS_DP<1> MDA_DQS_H1 @T6G_MB_LIB.T6G(SCH_1):M_D_CPU1_SA_DQS_DP(1)
AH58 M_D_CPU1_SA_DQ<29> MDA_DATA29 @T6G_MB_LIB.T6G(SCH_1):M_D_CPU1_SA_DQ(29)
 V60 M_D_CPU1_SA_DQ<18> MDA_DATA18 @T6G_MB_LIB.T6G(SCH_1):M_D_CPU1_SA_DQ(18)
 G59 M_D_CPU1_SA_DQ<3> MDA_DATA3 @T6G_MB_LIB.T6G(SCH_1):M_D_CPU1_SA_DQ(3)
CE60 M_D_CPU1_SB_DQS_DN<0> MDB_DQS_L0 @T6G_MB_LIB.T6G(SCH_1):M_D_CPU1_SB_DQS_DN(0)
CY60 M_D_CPU1_SB_DQ<24> MDB_DATA24 @T6G_MB_LIB.T6G(SCH_1):M_D_CPU1_SB_DQ(24)
CN59 M_D_CPU1_SB_DQ<13> MDB_DATA13 @T6G_MB_LIB.T6G(SCH_1):M_D_CPU1_SB_DQ(13)
CD58 M_D_CPU1_SB_DQ<3> MDB_DATA3 @T6G_MB_LIB.T6G(SCH_1):M_D_CPU1_SB_DQ(3)
BT60 M_D_CPU1_SB_CB<4> MDB_CHECK4 @T6G_MB_LIB.T6G(SCH_1):M_D_CPU1_SB_CB(4)
 P58 M_D_CPU1_SA_DQS_DN<6> MDA_DQS_L6 @T6G_MB_LIB.T6G(SCH_1):M_D_CPU1_SA_DQS_DN(6)
 W60 M_D_CPU1_SA_DQS_DP<2> MDA_DQS_H2 @T6G_MB_LIB.T6G(SCH_1):M_D_CPU1_SA_DQS_DP(2)
 W59 M_D_CPU1_SA_DQ<19> MDA_DATA19 @T6G_MB_LIB.T6G(SCH_1):M_D_CPU1_SA_DQ(19)
 J60 M_D_CPU1_SA_DQ<4> MDA_DATA4 @T6G_MB_LIB.T6G(SCH_1):M_D_CPU1_SA_DQ(4)
CL60 M_D_CPU1_SB_DQS_DN<1> MDB_DQS_L1 @T6G_MB_LIB.T6G(SCH_1):M_D_CPU1_SB_DQS_DN(1)
DA59 M_D_CPU1_SB_DQ<25> MDB_DATA25 @T6G_MB_LIB.T6G(SCH_1):M_D_CPU1_SB_DQ(25)
CN60 M_D_CPU1_SB_DQ<14> MDB_DATA14 @T6G_MB_LIB.T6G(SCH_1):M_D_CPU1_SB_DQ(14)
CF60 M_D_CPU1_SB_DQ<4> MDB_DATA4 @T6G_MB_LIB.T6G(SCH_1):M_D_CPU1_SB_DQ(4)
BU59 M_D_CPU1_SB_CB<5> MDB_CHECK5 @T6G_MB_LIB.T6G(SCH_1):M_D_CPU1_SB_CB(5)
 Y58 M_D_CPU1_SA_DQS_DN<7> MDA_DQS_L7 @T6G_MB_LIB.T6G(SCH_1):M_D_CPU1_SA_DQS_DN(7)
AE60 M_D_CPU1_SA_DQS_DP<3> MDA_DQS_H3 @T6G_MB_LIB.T6G(SCH_1):M_D_CPU1_SA_DQS_DP(3)
 K58 M_D_CPU1_SA_DQ<5> MDA_DATA5 @T6G_MB_LIB.T6G(SCH_1):M_D_CPU1_SA_DQ(5)
CU60 M_D_CPU1_SB_DQS_DN<2> MDB_DQS_L2 @T6G_MB_LIB.T6G(SCH_1):M_D_CPU1_SB_DQS_DN(2)
DA60 M_D_CPU1_SB_DQ<26> MDB_DATA26 @T6G_MB_LIB.T6G(SCH_1):M_D_CPU1_SB_DQ(26)
CP58 M_D_CPU1_SB_DQ<15> MDB_DATA15 @T6G_MB_LIB.T6G(SCH_1):M_D_CPU1_SB_DQ(15)
CG59 M_D_CPU1_SB_DQ<5> MDB_DATA5 @T6G_MB_LIB.T6G(SCH_1):M_D_CPU1_SB_DQ(5)
BU60 M_D_CPU1_SB_CB<6> MDB_CHECK6 @T6G_MB_LIB.T6G(SCH_1):M_D_CPU1_SB_CB(6)
AF58 M_D_CPU1_SA_DQS_DN<8> MDA_DQS_L8 @T6G_MB_LIB.T6G(SCH_1):M_D_CPU1_SA_DQS_DN(8)
AL60 M_D_CPU1_SA_DQS_DP<4> MDA_DQS_H4 @T6G_MB_LIB.T6G(SCH_1):M_D_CPU1_SA_DQS_DP(4)
 K60 M_D_CPU1_SA_DQ<6> MDA_DATA6 @T6G_MB_LIB.T6G(SCH_1):M_D_CPU1_SA_DQ(6)
DC60 M_D_CPU1_SB_DQS_DN<3> MDB_DQS_L3 @T6G_MB_LIB.T6G(SCH_1):M_D_CPU1_SB_DQS_DN(3)
DB58 M_D_CPU1_SB_DQ<27> MDB_DATA27 @T6G_MB_LIB.T6G(SCH_1):M_D_CPU1_SB_DQ(27)
CP60 M_D_CPU1_SB_DQ<16> MDB_DATA16 @T6G_MB_LIB.T6G(SCH_1):M_D_CPU1_SB_DQ(16)
CG60 M_D_CPU1_SB_DQ<6> MDB_DATA6 @T6G_MB_LIB.T6G(SCH_1):M_D_CPU1_SB_DQ(6)
BV58 M_D_CPU1_SB_CB<7> MDB_CHECK7 @T6G_MB_LIB.T6G(SCH_1):M_D_CPU1_SB_CB(7)
BP60 M_D_CPU1_SB_RSP<0> MDB0_RSP_L @T6G_MB_LIB.T6G(SCH_1):M_D_CPU1_SB_RSP(0)
AM58 M_D_CPU1_SA_DQS_DN<9> MDA_DQS_L9 @T6G_MB_LIB.T6G(SCH_1):M_D_CPU1_SA_DQS_DN(9)
 J59 M_D_CPU1_SA_DQS_DP<5> MDA_DQS_H5 @T6G_MB_LIB.T6G(SCH_1):M_D_CPU1_SA_DQS_DP(5)
 L59 M_D_CPU1_SA_DQ<7> MDA_DATA7 @T6G_MB_LIB.T6G(SCH_1):M_D_CPU1_SA_DQ(7)
BW59 M_D_CPU1_SB_DQS_DN<4> MDB_DQS_L4 @T6G_MB_LIB.T6G(SCH_1):M_D_CPU1_SB_DQS_DN(4)
CD60 M_D_CPU1_SB_DQS_DP<0> MDB_DQS_H0 @T6G_MB_LIB.T6G(SCH_1):M_D_CPU1_SB_DQS_DP(0)
DD60 M_D_CPU1_SB_DQ<28> MDB_DATA28 @T6G_MB_LIB.T6G(SCH_1):M_D_CPU1_SB_DQ(28)
CR59 M_D_CPU1_SB_DQ<17> MDB_DATA17 @T6G_MB_LIB.T6G(SCH_1):M_D_CPU1_SB_DQ(17)
CH58 M_D_CPU1_SB_DQ<7> MDB_DATA7 @T6G_MB_LIB.T6G(SCH_1):M_D_CPU1_SB_DQ(7)
BR60     NC MDB1_RSP_L     NC
 R59 M_D_CPU1_SA_DQS_DP<6> MDA_DQS_H6 @T6G_MB_LIB.T6G(SCH_1):M_D_CPU1_SA_DQS_DP(6)
 L60 M_D_CPU1_SA_DQ<8> MDA_DATA8 @T6G_MB_LIB.T6G(SCH_1):M_D_CPU1_SA_DQ(8)
CE59 M_D_CPU1_SB_DQS_DN<5> MDB_DQS_L5 @T6G_MB_LIB.T6G(SCH_1):M_D_CPU1_SB_DQS_DN(5)
CK60 M_D_CPU1_SB_DQS_DP<1> MDB_DQS_H1 @T6G_MB_LIB.T6G(SCH_1):M_D_CPU1_SB_DQS_DP(1)
DE59 M_D_CPU1_SB_DQ<29> MDB_DATA29 @T6G_MB_LIB.T6G(SCH_1):M_D_CPU1_SB_DQ(29)
CR60 M_D_CPU1_SB_DQ<18> MDB_DATA18 @T6G_MB_LIB.T6G(SCH_1):M_D_CPU1_SB_DQ(18)
CH60 M_D_CPU1_SB_DQ<8> MDB_DATA8 @T6G_MB_LIB.T6G(SCH_1):M_D_CPU1_SB_DQ(8)
AA59 M_D_CPU1_SA_DQS_DP<7> MDA_DQS_H7 @T6G_MB_LIB.T6G(SCH_1):M_D_CPU1_SA_DQS_DP(7)
 M58 M_D_CPU1_SA_DQ<9> MDA_DATA9 @T6G_MB_LIB.T6G(SCH_1):M_D_CPU1_SA_DQ(9)
AW60 M_D_CPU1_SA_CA<0> MDA_CA0 @T6G_MB_LIB.T6G(SCH_1):M_D_CPU1_SA_CA(0)
AV60 M_D_CPU1_SA_CS_N<0> MDA0_CS_L0 @T6G_MB_LIB.T6G(SCH_1):M_D_CPU1_SA_CS_N(0)
CL59 M_D_CPU1_SB_DQS_DN<6> MDB_DQS_L6 @T6G_MB_LIB.T6G(SCH_1):M_D_CPU1_SB_DQS_DN(6)
CT60 M_D_CPU1_SB_DQS_DP<2> MDB_DQS_H2 @T6G_MB_LIB.T6G(SCH_1):M_D_CPU1_SB_DQS_DP(2)
CT58 M_D_CPU1_SB_DQ<19> MDB_DATA19 @T6G_MB_LIB.T6G(SCH_1):M_D_CPU1_SB_DQ(19)
CJ59 M_D_CPU1_SB_DQ<9> MDB_DATA9 @T6G_MB_LIB.T6G(SCH_1):M_D_CPU1_SB_DQ(9)
BG59 M_D_CPU1_SB_CA<0> MDB_CA0 @T6G_MB_LIB.T6G(SCH_1):M_D_CPU1_SB_CA(0)
AG59 M_D_CPU1_SA_DQS_DP<8> MDA_DQS_H8 @T6G_MB_LIB.T6G(SCH_1):M_D_CPU1_SA_DQS_DP(8)
AH60 M_D_CPU1_SA_DQ<30> MDA_DATA30 @T6G_MB_LIB.T6G(SCH_1):M_D_CPU1_SA_DQ(30)
AY60 M_D_CPU1_SA_CA<1> MDA_CA1 @T6G_MB_LIB.T6G(SCH_1):M_D_CPU1_SA_CA(1)
AU60     NC MDA1_CS_L0     NC
AW59 M_D_CPU1_SA_CS_N<1> MDA0_CS_L1 @T6G_MB_LIB.T6G(SCH_1):M_D_CPU1_SA_CS_N(1)
CU59 M_D_CPU1_SB_DQS_DN<7> MDB_DQS_L7 @T6G_MB_LIB.T6G(SCH_1):M_D_CPU1_SB_DQS_DN(7)
DB60 M_D_CPU1_SB_DQS_DP<3> MDB_DQS_H3 @T6G_MB_LIB.T6G(SCH_1):M_D_CPU1_SB_DQS_DP(3)
BH58 M_D_CPU1_SB_CA<1> MDB_CA1 @T6G_MB_LIB.T6G(SCH_1):M_D_CPU1_SB_CA(1)
AN59 M_D_CPU1_SA_DQS_DP<9> MDA_DQS_H9 @T6G_MB_LIB.T6G(SCH_1):M_D_CPU1_SA_DQS_DP(9)
AJ59 M_D_CPU1_SA_DQ<31> MDA_DATA31 @T6G_MB_LIB.T6G(SCH_1):M_D_CPU1_SA_DQ(31)
AA60 M_D_CPU1_SA_DQ<20> MDA_DATA20 @T6G_MB_LIB.T6G(SCH_1):M_D_CPU1_SA_DQ(20)
AJ60 M_D_CPU1_SA_CB<0> MDA_CHECK0 @T6G_MB_LIB.T6G(SCH_1):M_D_CPU1_SA_CB(0)
AY58 M_D_CPU1_SA_CA<2> MDA_CA2 @T6G_MB_LIB.T6G(SCH_1):M_D_CPU1_SA_CA(2)
AV58     NC MDA1_CS_L1     NC
DC59 M_D_CPU1_SB_DQS_DN<8> MDB_DQS_L8 @T6G_MB_LIB.T6G(SCH_1):M_D_CPU1_SB_DQS_DN(8)
BY58 M_D_CPU1_SB_DQS_DP<4> MDB_DQS_H4 @T6G_MB_LIB.T6G(SCH_1):M_D_CPU1_SB_DQS_DP(4)
BH60 M_D_CPU1_SB_CA<2> MDB_CA2 @T6G_MB_LIB.T6G(SCH_1):M_D_CPU1_SB_CA(2)
AB58 M_D_CPU1_SA_DQ<21> MDA_DATA21 @T6G_MB_LIB.T6G(SCH_1):M_D_CPU1_SA_DQ(21)
 M60 M_D_CPU1_SA_DQ<10> MDA_DATA10 @T6G_MB_LIB.T6G(SCH_1):M_D_CPU1_SA_DQ(10)
AK58 M_D_CPU1_SA_CB<1> MDA_CHECK1 @T6G_MB_LIB.T6G(SCH_1):M_D_CPU1_SA_CB(1)
BA59 M_D_CPU1_SA_CA<3> MDA_CA3 @T6G_MB_LIB.T6G(SCH_1):M_D_CPU1_SA_CA(3)
BW60 M_D_CPU1_SB_DQS_DN<9> MDB_DQS_L9 @T6G_MB_LIB.T6G(SCH_1):M_D_CPU1_SB_DQS_DN(9)
CF58 M_D_CPU1_SB_DQS_DP<5> MDB_DQS_H5 @T6G_MB_LIB.T6G(SCH_1):M_D_CPU1_SB_DQS_DP(5)
AB60 M_D_CPU1_SA_DQ<22> MDA_DATA22 @T6G_MB_LIB.T6G(SCH_1):M_D_CPU1_SA_DQ(22)
 N59 M_D_CPU1_SA_DQ<11> MDA_DATA11 @T6G_MB_LIB.T6G(SCH_1):M_D_CPU1_SA_DQ(11)
AK60 M_D_CPU1_SA_CB<2> MDA_CHECK2 @T6G_MB_LIB.T6G(SCH_1):M_D_CPU1_SA_CB(2)
BA60 M_D_CPU1_SA_CA<4> MDA_CA4 @T6G_MB_LIB.T6G(SCH_1):M_D_CPU1_SA_CA(4)
CM58 M_D_CPU1_SB_DQS_DP<6> MDB_DQS_H6 @T6G_MB_LIB.T6G(SCH_1):M_D_CPU1_SB_DQS_DP(6)
BJ59 M_D_CPU1_SB_CA<4> MDB_CA4 @T6G_MB_LIB.T6G(SCH_1):M_D_CPU1_SB_CA(4)
AC59 M_D_CPU1_SA_DQ<23> MDA_DATA23 @T6G_MB_LIB.T6G(SCH_1):M_D_CPU1_SA_DQ(23)
 R60 M_D_CPU1_SA_DQ<12> MDA_DATA12 @T6G_MB_LIB.T6G(SCH_1):M_D_CPU1_SA_DQ(12)
AL59 M_D_CPU1_SA_CB<3> MDA_CHECK3 @T6G_MB_LIB.T6G(SCH_1):M_D_CPU1_SA_CB(3)
BB60 M_D_CPU1_SA_CA<5> MDA_CA5 @T6G_MB_LIB.T6G(SCH_1):M_D_CPU1_SA_CA(5)
CV58 M_D_CPU1_SB_DQS_DP<7> MDB_DQS_H7 @T6G_MB_LIB.T6G(SCH_1):M_D_CPU1_SB_DQS_DP(7)
BK58 M_D_CPU1_SB_CA<5> MDB_CA5 @T6G_MB_LIB.T6G(SCH_1):M_D_CPU1_SB_CA(5)
BM58 M_D_CPU1_SB_CS_N<0> MDB0_CS_L0 @T6G_MB_LIB.T6G(SCH_1):M_D_CPU1_SB_CS_N(0)
 H60 M_D_CPU1_SA_DQS_DN<0> MDA_DQS_L0 @T6G_MB_LIB.T6G(SCH_1):M_D_CPU1_SA_DQS_DN(0)
AC60 M_D_CPU1_SA_DQ<24> MDA_DATA24 @T6G_MB_LIB.T6G(SCH_1):M_D_CPU1_SA_DQ(24)
 T58 M_D_CPU1_SA_DQ<13> MDA_DATA13 @T6G_MB_LIB.T6G(SCH_1):M_D_CPU1_SA_DQ(13)
AN60 M_D_CPU1_SA_CB<4> MDA_CHECK4 @T6G_MB_LIB.T6G(SCH_1):M_D_CPU1_SA_CB(4)
BB58 M_D_CPU1_SA_CA<6> MDA_CA6 @T6G_MB_LIB.T6G(SCH_1):M_D_CPU1_SA_CA(6)
DD58 M_D_CPU1_SB_DQS_DP<8> MDB_DQS_H8 @T6G_MB_LIB.T6G(SCH_1):M_D_CPU1_SB_DQS_DP(8)
DE60 M_D_CPU1_SB_DQ<30> MDB_DATA30 @T6G_MB_LIB.T6G(SCH_1):M_D_CPU1_SB_DQ(30)
BK60 M_D_CPU1_SB_CA<6> MDB_CA6 @T6G_MB_LIB.T6G(SCH_1):M_D_CPU1_SB_CA(6)
BL59     NC MDB1_CS_L0     NC
BN60 M_D_CPU1_SB_CS_N<1> MDB0_CS_L1 @T6G_MB_LIB.T6G(SCH_1):M_D_CPU1_SB_CS_N(1)
 P60 M_D_CPU1_SA_DQS_DN<1> MDA_DQS_L1 @T6G_MB_LIB.T6G(SCH_1):M_D_CPU1_SA_DQS_DN(1)
AD58 M_D_CPU1_SA_DQ<25> MDA_DATA25 @T6G_MB_LIB.T6G(SCH_1):M_D_CPU1_SA_DQ(25)
 T60 M_D_CPU1_SA_DQ<14> MDA_DATA14 @T6G_MB_LIB.T6G(SCH_1):M_D_CPU1_SA_DQ(14)
AP58 M_D_CPU1_SA_CB<5> MDA_CHECK5 @T6G_MB_LIB.T6G(SCH_1):M_D_CPU1_SA_CB(5)
DF60 M_D_CPU1_SB_DQ<31> MDB_DATA31 @T6G_MB_LIB.T6G(SCH_1):M_D_CPU1_SB_DQ(31)
CV60 M_D_CPU1_SB_DQ<20> MDB_DATA20 @T6G_MB_LIB.T6G(SCH_1):M_D_CPU1_SB_DQ(20)
BY60 M_D_CPU1_SB_CB<0> MDB_CHECK0 @T6G_MB_LIB.T6G(SCH_1):M_D_CPU1_SB_CB(0)
BM60     NC MDB1_CS_L1     NC
 Y60 M_D_CPU1_SA_DQS_DN<2> MDA_DQS_L2 @T6G_MB_LIB.T6G(SCH_1):M_D_CPU1_SA_DQS_DN(2)
AD60 M_D_CPU1_SA_DQ<26> MDA_DATA26 @T6G_MB_LIB.T6G(SCH_1):M_D_CPU1_SA_DQ(26)
 U59 M_D_CPU1_SA_DQ<15> MDA_DATA15 @T6G_MB_LIB.T6G(SCH_1):M_D_CPU1_SA_DQ(15)
 E60 M_D_CPU1_SA_DQ<0> MDA_DATA0 @T6G_MB_LIB.T6G(SCH_1):M_D_CPU1_SA_DQ(0)
AP60 M_D_CPU1_SA_CB<6> MDA_CHECK6 @T6G_MB_LIB.T6G(SCH_1):M_D_CPU1_SA_CB(6)
CW59 M_D_CPU1_SB_DQ<21> MDB_DATA21 @T6G_MB_LIB.T6G(SCH_1):M_D_CPU1_SB_DQ(21)
CJ60 M_D_CPU1_SB_DQ<10> MDB_DATA10 @T6G_MB_LIB.T6G(SCH_1):M_D_CPU1_SB_DQ(10)
CB60 M_D_CPU1_SB_DQ<0> MDB_DATA0 @T6G_MB_LIB.T6G(SCH_1):M_D_CPU1_SB_DQ(0)
CA59 M_D_CPU1_SB_CB<1> MDB_CHECK1 @T6G_MB_LIB.T6G(SCH_1):M_D_CPU1_SB_CB(1)
AF60 M_D_CPU1_SA_DQS_DN<3> MDA_DQS_L3 @T6G_MB_LIB.T6G(SCH_1):M_D_CPU1_SA_DQS_DN(3)
AE59 M_D_CPU1_SA_DQ<27> MDA_DATA27 @T6G_MB_LIB.T6G(SCH_1):M_D_CPU1_SA_DQ(27)
 U60 M_D_CPU1_SA_DQ<16> MDA_DATA16 @T6G_MB_LIB.T6G(SCH_1):M_D_CPU1_SA_DQ(16)
 F58 M_D_CPU1_SA_DQ<1> MDA_DATA1 @T6G_MB_LIB.T6G(SCH_1):M_D_CPU1_SA_DQ(1)
AR59 M_D_CPU1_SA_CB<7> MDA_CHECK7 @T6G_MB_LIB.T6G(SCH_1):M_D_CPU1_SA_CB(7)
BN59 M_D_CPU1_SA_RSP<0> MDA0_RSP_L @T6G_MB_LIB.T6G(SCH_1):M_D_CPU1_SA_RSP(0)
CW60 M_D_CPU1_SB_DQ<22> MDB_DATA22 @T6G_MB_LIB.T6G(SCH_1):M_D_CPU1_SB_DQ(22)
CK58 M_D_CPU1_SB_DQ<11> MDB_DATA11 @T6G_MB_LIB.T6G(SCH_1):M_D_CPU1_SB_DQ(11)
CC59 M_D_CPU1_SB_DQ<1> MDB_DATA1 @T6G_MB_LIB.T6G(SCH_1):M_D_CPU1_SB_DQ(1)
CA60 M_D_CPU1_SB_CB<2> MDB_CHECK2 @T6G_MB_LIB.T6G(SCH_1):M_D_CPU1_SB_CB(2)
AM60 M_D_CPU1_SA_DQS_DN<4> MDA_DQS_L4 @T6G_MB_LIB.T6G(SCH_1):M_D_CPU1_SA_DQS_DN(4)
 G60 M_D_CPU1_SA_DQS_DP<0> MDA_DQS_H0 @T6G_MB_LIB.T6G(SCH_1):M_D_CPU1_SA_DQS_DP(0)
AG60 M_D_CPU1_SA_DQ<28> MDA_DATA28 @T6G_MB_LIB.T6G(SCH_1):M_D_CPU1_SA_DQ(28)
 V58 M_D_CPU1_SA_DQ<17> MDA_DATA17 @T6G_MB_LIB.T6G(SCH_1):M_D_CPU1_SA_DQ(17)
 F60 M_D_CPU1_SA_DQ<2> MDA_DATA2 @T6G_MB_LIB.T6G(SCH_1):M_D_CPU1_SA_DQ(2)
BP58     NC MDA1_RSP_L     NC
BC59 M_D_CPU1_SA_PAR MDA_PAR @T6G_MB_LIB.T6G(SCH_1):M_D_CPU1_SA_PAR
BL60 M_D_CPU1_SB_PAR MDB_PAR @T6G_MB_LIB.T6G(SCH_1):M_D_CPU1_SB_PAR
BJ60 M_D_CPU1_SB_CA<3> MDB_CA3 @T6G_MB_LIB.T6G(SCH_1):M_D_CPU1_SB_CA(3)
BV60 M_D_CPU1_SB_DQS_DP<9> MDB_DQS_H9 @T6G_MB_LIB.T6G(SCH_1):M_D_CPU1_SB_DQS_DP(9)
BC60 M_D_CPU1_CLK_DP<0> MD0_CLK_H @T6G_MB_LIB.T6G(SCH_1):M_D_CPU1_CLK_DP(0)
BD60 M_D_CPU1_CLK_DN<0> MD0_CLK_L @T6G_MB_LIB.T6G(SCH_1):M_D_CPU1_CLK_DN(0)
BF60     NC MD1_CLK_H     NC
BG60     NC MD1_CLK_L     NC
BF58 TP_M_D_CPU1_SA_TEST39D TEST39D @T6G_MB_LIB.T6G(SCH_1):TP_M_D_CPU1_SA_TEST39D

Q_RES_0402LF-15,1%,1/16W,CHIP,CS01502FB03  I314  R503
   1 M_D_CPU1_ALERT_N      A @T6G_MB_LIB.T6G(SCH_1):M_D_CPU1_ALERT_N
   2 M_D_CPU1_ALERT_R_N      B @T6G_MB_LIB.T6G(SCH_1):M_D_CPU1_ALERT_R_N


DRAWING: @T6G_MB_LIB.T6G(SCH_1):PAGE41 

GENOA_SP5-SOCKET6096_13568-001,SMLF,IO,DGA^6000030  I159  U26
AT69 M_E_CPU1_ALERT_R_N ME_ALERT_L @T6G_MB_LIB.T6G(SCH_1):M_E_CPU1_ALERT_R_N
AU69 M_E_CPU1_RESET_N ME_RESET_L @T6G_MB_LIB.T6G(SCH_1):M_E_CPU1_RESET_N
CU71 M_E_CPU1_SB_DQS_DN<2> MEB_DQS_L2 @T6G_MB_LIB.T6G(SCH_1):M_E_CPU1_SB_DQS_DN(2)
DA71 M_E_CPU1_SB_DQ<26> MEB_DATA26 @T6G_MB_LIB.T6G(SCH_1):M_E_CPU1_SB_DQ(26)
CP69 M_E_CPU1_SB_DQ<15> MEB_DATA15 @T6G_MB_LIB.T6G(SCH_1):M_E_CPU1_SB_DQ(15)
BU71 M_E_CPU1_SB_CB<6> MEB_CHECK6 @T6G_MB_LIB.T6G(SCH_1):M_E_CPU1_SB_CB(6)
AF69 M_E_CPU1_SA_DQS_DN<8> MEA_DQS_L8 @T6G_MB_LIB.T6G(SCH_1):M_E_CPU1_SA_DQS_DN(8)
AL71 M_E_CPU1_SA_DQS_DP<4> MEA_DQS_H4 @T6G_MB_LIB.T6G(SCH_1):M_E_CPU1_SA_DQS_DP(4)
DC71 M_E_CPU1_SB_DQS_DN<3> MEB_DQS_L3 @T6G_MB_LIB.T6G(SCH_1):M_E_CPU1_SB_DQS_DN(3)
DB69 M_E_CPU1_SB_DQ<27> MEB_DATA27 @T6G_MB_LIB.T6G(SCH_1):M_E_CPU1_SB_DQ(27)
CP70 M_E_CPU1_SB_DQ<16> MEB_DATA16 @T6G_MB_LIB.T6G(SCH_1):M_E_CPU1_SB_DQ(16)
BV69 M_E_CPU1_SB_CB<7> MEB_CHECK7 @T6G_MB_LIB.T6G(SCH_1):M_E_CPU1_SB_CB(7)
BR71     NC MEB1_RSP_L     NC
BP70 M_E_CPU1_SB_RSP<0> MEB0_RSP_L @T6G_MB_LIB.T6G(SCH_1):M_E_CPU1_SB_RSP(0)
AM69 M_E_CPU1_SA_DQS_DN<9> MEA_DQS_L9 @T6G_MB_LIB.T6G(SCH_1):M_E_CPU1_SA_DQS_DN(9)
 J69 M_E_CPU1_SA_DQS_DP<5> MEA_DQS_H5 @T6G_MB_LIB.T6G(SCH_1):M_E_CPU1_SA_DQS_DP(5)
BW69 M_E_CPU1_SB_DQS_DN<4> MEB_DQS_L4 @T6G_MB_LIB.T6G(SCH_1):M_E_CPU1_SB_DQS_DN(4)
CD70 M_E_CPU1_SB_DQS_DP<0> MEB_DQS_H0 @T6G_MB_LIB.T6G(SCH_1):M_E_CPU1_SB_DQS_DP(0)
DD70 M_E_CPU1_SB_DQ<28> MEB_DATA28 @T6G_MB_LIB.T6G(SCH_1):M_E_CPU1_SB_DQ(28)
CR69 M_E_CPU1_SB_DQ<17> MEB_DATA17 @T6G_MB_LIB.T6G(SCH_1):M_E_CPU1_SB_DQ(17)
 R69 M_E_CPU1_SA_DQS_DP<6> MEA_DQS_H6 @T6G_MB_LIB.T6G(SCH_1):M_E_CPU1_SA_DQS_DP(6)
CE69 M_E_CPU1_SB_DQS_DN<5> MEB_DQS_L5 @T6G_MB_LIB.T6G(SCH_1):M_E_CPU1_SB_DQS_DN(5)
CK70 M_E_CPU1_SB_DQS_DP<1> MEB_DQS_H1 @T6G_MB_LIB.T6G(SCH_1):M_E_CPU1_SB_DQS_DP(1)
DE69 M_E_CPU1_SB_DQ<29> MEB_DATA29 @T6G_MB_LIB.T6G(SCH_1):M_E_CPU1_SB_DQ(29)
CR71 M_E_CPU1_SB_DQ<18> MEB_DATA18 @T6G_MB_LIB.T6G(SCH_1):M_E_CPU1_SB_DQ(18)
AA69 M_E_CPU1_SA_DQS_DP<7> MEA_DQS_H7 @T6G_MB_LIB.T6G(SCH_1):M_E_CPU1_SA_DQS_DP(7)
 E71 M_E_CPU1_SA_DQ<0> MEA_DATA0 @T6G_MB_LIB.T6G(SCH_1):M_E_CPU1_SA_DQ(0)
AU71     NC MEA1_CS_L0     NC
AV70 M_E_CPU1_SA_CS_N<0> MEA0_CS_L0 @T6G_MB_LIB.T6G(SCH_1):M_E_CPU1_SA_CS_N(0)
CL69 M_E_CPU1_SB_DQS_DN<6> MEB_DQS_L6 @T6G_MB_LIB.T6G(SCH_1):M_E_CPU1_SB_DQS_DN(6)
CT70 M_E_CPU1_SB_DQS_DP<2> MEB_DQS_H2 @T6G_MB_LIB.T6G(SCH_1):M_E_CPU1_SB_DQS_DP(2)
CT69 M_E_CPU1_SB_DQ<19> MEB_DATA19 @T6G_MB_LIB.T6G(SCH_1):M_E_CPU1_SB_DQ(19)
CB70 M_E_CPU1_SB_DQ<0> MEB_DATA0 @T6G_MB_LIB.T6G(SCH_1):M_E_CPU1_SB_DQ(0)
AG69 M_E_CPU1_SA_DQS_DP<8> MEA_DQS_H8 @T6G_MB_LIB.T6G(SCH_1):M_E_CPU1_SA_DQS_DP(8)
AH70 M_E_CPU1_SA_DQ<30> MEA_DATA30 @T6G_MB_LIB.T6G(SCH_1):M_E_CPU1_SA_DQ(30)
 F69 M_E_CPU1_SA_DQ<1> MEA_DATA1 @T6G_MB_LIB.T6G(SCH_1):M_E_CPU1_SA_DQ(1)
AV69     NC MEA1_CS_L1     NC
AW69 M_E_CPU1_SA_CS_N<1> MEA0_CS_L1 @T6G_MB_LIB.T6G(SCH_1):M_E_CPU1_SA_CS_N(1)
CU69 M_E_CPU1_SB_DQS_DN<7> MEB_DQS_L7 @T6G_MB_LIB.T6G(SCH_1):M_E_CPU1_SB_DQS_DN(7)
DB70 M_E_CPU1_SB_DQS_DP<3> MEB_DQS_H3 @T6G_MB_LIB.T6G(SCH_1):M_E_CPU1_SB_DQS_DP(3)
CC69 M_E_CPU1_SB_DQ<1> MEB_DATA1 @T6G_MB_LIB.T6G(SCH_1):M_E_CPU1_SB_DQ(1)
AN69 M_E_CPU1_SA_DQS_DP<9> MEA_DQS_H9 @T6G_MB_LIB.T6G(SCH_1):M_E_CPU1_SA_DQS_DP(9)
AJ69 M_E_CPU1_SA_DQ<31> MEA_DATA31 @T6G_MB_LIB.T6G(SCH_1):M_E_CPU1_SA_DQ(31)
AA71 M_E_CPU1_SA_DQ<20> MEA_DATA20 @T6G_MB_LIB.T6G(SCH_1):M_E_CPU1_SA_DQ(20)
 F70 M_E_CPU1_SA_DQ<2> MEA_DATA2 @T6G_MB_LIB.T6G(SCH_1):M_E_CPU1_SA_DQ(2)
AJ71 M_E_CPU1_SA_CB<0> MEA_CHECK0 @T6G_MB_LIB.T6G(SCH_1):M_E_CPU1_SA_CB(0)
AW71 M_E_CPU1_SA_CA<0> MEA_CA0 @T6G_MB_LIB.T6G(SCH_1):M_E_CPU1_SA_CA(0)
DC69 M_E_CPU1_SB_DQS_DN<8> MEB_DQS_L8 @T6G_MB_LIB.T6G(SCH_1):M_E_CPU1_SB_DQS_DN(8)
BY69 M_E_CPU1_SB_DQS_DP<4> MEB_DQS_H4 @T6G_MB_LIB.T6G(SCH_1):M_E_CPU1_SB_DQS_DP(4)
CC71 M_E_CPU1_SB_DQ<2> MEB_DATA2 @T6G_MB_LIB.T6G(SCH_1):M_E_CPU1_SB_DQ(2)
BG69 M_E_CPU1_SB_CA<0> MEB_CA0 @T6G_MB_LIB.T6G(SCH_1):M_E_CPU1_SB_CA(0)
AB69 M_E_CPU1_SA_DQ<21> MEA_DATA21 @T6G_MB_LIB.T6G(SCH_1):M_E_CPU1_SA_DQ(21)
 M70 M_E_CPU1_SA_DQ<10> MEA_DATA10 @T6G_MB_LIB.T6G(SCH_1):M_E_CPU1_SA_DQ(10)
 G69 M_E_CPU1_SA_DQ<3> MEA_DATA3 @T6G_MB_LIB.T6G(SCH_1):M_E_CPU1_SA_DQ(3)
AK69 M_E_CPU1_SA_CB<1> MEA_CHECK1 @T6G_MB_LIB.T6G(SCH_1):M_E_CPU1_SA_CB(1)
AY70 M_E_CPU1_SA_CA<1> MEA_CA1 @T6G_MB_LIB.T6G(SCH_1):M_E_CPU1_SA_CA(1)
BW71 M_E_CPU1_SB_DQS_DN<9> MEB_DQS_L9 @T6G_MB_LIB.T6G(SCH_1):M_E_CPU1_SB_DQS_DN(9)
CF69 M_E_CPU1_SB_DQS_DP<5> MEB_DQS_H5 @T6G_MB_LIB.T6G(SCH_1):M_E_CPU1_SB_DQS_DP(5)
CD69 M_E_CPU1_SB_DQ<3> MEB_DATA3 @T6G_MB_LIB.T6G(SCH_1):M_E_CPU1_SB_DQ(3)
BH69 M_E_CPU1_SB_CA<1> MEB_CA1 @T6G_MB_LIB.T6G(SCH_1):M_E_CPU1_SB_CA(1)
AB70 M_E_CPU1_SA_DQ<22> MEA_DATA22 @T6G_MB_LIB.T6G(SCH_1):M_E_CPU1_SA_DQ(22)
 N69 M_E_CPU1_SA_DQ<11> MEA_DATA11 @T6G_MB_LIB.T6G(SCH_1):M_E_CPU1_SA_DQ(11)
 J71 M_E_CPU1_SA_DQ<4> MEA_DATA4 @T6G_MB_LIB.T6G(SCH_1):M_E_CPU1_SA_DQ(4)
AK70 M_E_CPU1_SA_CB<2> MEA_CHECK2 @T6G_MB_LIB.T6G(SCH_1):M_E_CPU1_SA_CB(2)
AY69 M_E_CPU1_SA_CA<2> MEA_CA2 @T6G_MB_LIB.T6G(SCH_1):M_E_CPU1_SA_CA(2)
CM69 M_E_CPU1_SB_DQS_DP<6> MEB_DQS_H6 @T6G_MB_LIB.T6G(SCH_1):M_E_CPU1_SB_DQS_DP(6)
CF70 M_E_CPU1_SB_DQ<4> MEB_DATA4 @T6G_MB_LIB.T6G(SCH_1):M_E_CPU1_SB_DQ(4)
BH70 M_E_CPU1_SB_CA<2> MEB_CA2 @T6G_MB_LIB.T6G(SCH_1):M_E_CPU1_SB_CA(2)
AC69 M_E_CPU1_SA_DQ<23> MEA_DATA23 @T6G_MB_LIB.T6G(SCH_1):M_E_CPU1_SA_DQ(23)
 R71 M_E_CPU1_SA_DQ<12> MEA_DATA12 @T6G_MB_LIB.T6G(SCH_1):M_E_CPU1_SA_DQ(12)
 K69 M_E_CPU1_SA_DQ<5> MEA_DATA5 @T6G_MB_LIB.T6G(SCH_1):M_E_CPU1_SA_DQ(5)
AL69 M_E_CPU1_SA_CB<3> MEA_CHECK3 @T6G_MB_LIB.T6G(SCH_1):M_E_CPU1_SA_CB(3)
BA69 M_E_CPU1_SA_CA<3> MEA_CA3 @T6G_MB_LIB.T6G(SCH_1):M_E_CPU1_SA_CA(3)
CV69 M_E_CPU1_SB_DQS_DP<7> MEB_DQS_H7 @T6G_MB_LIB.T6G(SCH_1):M_E_CPU1_SB_DQS_DP(7)
CG69 M_E_CPU1_SB_DQ<5> MEB_DATA5 @T6G_MB_LIB.T6G(SCH_1):M_E_CPU1_SB_DQ(5)
BJ71 M_E_CPU1_SB_CA<3> MEB_CA3 @T6G_MB_LIB.T6G(SCH_1):M_E_CPU1_SB_CA(3)
BL69     NC MEB1_CS_L0     NC
BM69 M_E_CPU1_SB_CS_N<0> MEB0_CS_L0 @T6G_MB_LIB.T6G(SCH_1):M_E_CPU1_SB_CS_N(0)
 H70 M_E_CPU1_SA_DQS_DN<0> MEA_DQS_L0 @T6G_MB_LIB.T6G(SCH_1):M_E_CPU1_SA_DQS_DN(0)
AC71 M_E_CPU1_SA_DQ<24> MEA_DATA24 @T6G_MB_LIB.T6G(SCH_1):M_E_CPU1_SA_DQ(24)
 T69 M_E_CPU1_SA_DQ<13> MEA_DATA13 @T6G_MB_LIB.T6G(SCH_1):M_E_CPU1_SA_DQ(13)
 K70 M_E_CPU1_SA_DQ<6> MEA_DATA6 @T6G_MB_LIB.T6G(SCH_1):M_E_CPU1_SA_DQ(6)
AN71 M_E_CPU1_SA_CB<4> MEA_CHECK4 @T6G_MB_LIB.T6G(SCH_1):M_E_CPU1_SA_CB(4)
BA71 M_E_CPU1_SA_CA<4> MEA_CA4 @T6G_MB_LIB.T6G(SCH_1):M_E_CPU1_SA_CA(4)
DD69 M_E_CPU1_SB_DQS_DP<8> MEB_DQS_H8 @T6G_MB_LIB.T6G(SCH_1):M_E_CPU1_SB_DQS_DP(8)
DE71 M_E_CPU1_SB_DQ<30> MEB_DATA30 @T6G_MB_LIB.T6G(SCH_1):M_E_CPU1_SB_DQ(30)
CG71 M_E_CPU1_SB_DQ<6> MEB_DATA6 @T6G_MB_LIB.T6G(SCH_1):M_E_CPU1_SB_DQ(6)
BJ69 M_E_CPU1_SB_CA<4> MEB_CA4 @T6G_MB_LIB.T6G(SCH_1):M_E_CPU1_SB_CA(4)
BM70     NC MEB1_CS_L1     NC
BN71 M_E_CPU1_SB_CS_N<1> MEB0_CS_L1 @T6G_MB_LIB.T6G(SCH_1):M_E_CPU1_SB_CS_N(1)
 P70 M_E_CPU1_SA_DQS_DN<1> MEA_DQS_L1 @T6G_MB_LIB.T6G(SCH_1):M_E_CPU1_SA_DQS_DN(1)
AD69 M_E_CPU1_SA_DQ<25> MEA_DATA25 @T6G_MB_LIB.T6G(SCH_1):M_E_CPU1_SA_DQ(25)
 T70 M_E_CPU1_SA_DQ<14> MEA_DATA14 @T6G_MB_LIB.T6G(SCH_1):M_E_CPU1_SA_DQ(14)
 L69 M_E_CPU1_SA_DQ<7> MEA_DATA7 @T6G_MB_LIB.T6G(SCH_1):M_E_CPU1_SA_DQ(7)
AP69 M_E_CPU1_SA_CB<5> MEA_CHECK5 @T6G_MB_LIB.T6G(SCH_1):M_E_CPU1_SA_CB(5)
BB70 M_E_CPU1_SA_CA<5> MEA_CA5 @T6G_MB_LIB.T6G(SCH_1):M_E_CPU1_SA_CA(5)
DF69 M_E_CPU1_SB_DQ<31> MEB_DATA31 @T6G_MB_LIB.T6G(SCH_1):M_E_CPU1_SB_DQ(31)
CV70 M_E_CPU1_SB_DQ<20> MEB_DATA20 @T6G_MB_LIB.T6G(SCH_1):M_E_CPU1_SB_DQ(20)
CH69 M_E_CPU1_SB_DQ<7> MEB_DATA7 @T6G_MB_LIB.T6G(SCH_1):M_E_CPU1_SB_DQ(7)
BY70 M_E_CPU1_SB_CB<0> MEB_CHECK0 @T6G_MB_LIB.T6G(SCH_1):M_E_CPU1_SB_CB(0)
BK69 M_E_CPU1_SB_CA<5> MEB_CA5 @T6G_MB_LIB.T6G(SCH_1):M_E_CPU1_SB_CA(5)
 Y70 M_E_CPU1_SA_DQS_DN<2> MEA_DQS_L2 @T6G_MB_LIB.T6G(SCH_1):M_E_CPU1_SA_DQS_DN(2)
AD70 M_E_CPU1_SA_DQ<26> MEA_DATA26 @T6G_MB_LIB.T6G(SCH_1):M_E_CPU1_SA_DQ(26)
 U69 M_E_CPU1_SA_DQ<15> MEA_DATA15 @T6G_MB_LIB.T6G(SCH_1):M_E_CPU1_SA_DQ(15)
 L71 M_E_CPU1_SA_DQ<8> MEA_DATA8 @T6G_MB_LIB.T6G(SCH_1):M_E_CPU1_SA_DQ(8)
AP70 M_E_CPU1_SA_CB<6> MEA_CHECK6 @T6G_MB_LIB.T6G(SCH_1):M_E_CPU1_SA_CB(6)
BB69 M_E_CPU1_SA_CA<6> MEA_CA6 @T6G_MB_LIB.T6G(SCH_1):M_E_CPU1_SA_CA(6)
CW69 M_E_CPU1_SB_DQ<21> MEB_DATA21 @T6G_MB_LIB.T6G(SCH_1):M_E_CPU1_SB_DQ(21)
CJ71 M_E_CPU1_SB_DQ<10> MEB_DATA10 @T6G_MB_LIB.T6G(SCH_1):M_E_CPU1_SB_DQ(10)
CH70 M_E_CPU1_SB_DQ<8> MEB_DATA8 @T6G_MB_LIB.T6G(SCH_1):M_E_CPU1_SB_DQ(8)
CA69 M_E_CPU1_SB_CB<1> MEB_CHECK1 @T6G_MB_LIB.T6G(SCH_1):M_E_CPU1_SB_CB(1)
BK70 M_E_CPU1_SB_CA<6> MEB_CA6 @T6G_MB_LIB.T6G(SCH_1):M_E_CPU1_SB_CA(6)
AF70 M_E_CPU1_SA_DQS_DN<3> MEA_DQS_L3 @T6G_MB_LIB.T6G(SCH_1):M_E_CPU1_SA_DQS_DN(3)
AE69 M_E_CPU1_SA_DQ<27> MEA_DATA27 @T6G_MB_LIB.T6G(SCH_1):M_E_CPU1_SA_DQ(27)
 U71 M_E_CPU1_SA_DQ<16> MEA_DATA16 @T6G_MB_LIB.T6G(SCH_1):M_E_CPU1_SA_DQ(16)
 M69 M_E_CPU1_SA_DQ<9> MEA_DATA9 @T6G_MB_LIB.T6G(SCH_1):M_E_CPU1_SA_DQ(9)
AR69 M_E_CPU1_SA_CB<7> MEA_CHECK7 @T6G_MB_LIB.T6G(SCH_1):M_E_CPU1_SA_CB(7)
BP69     NC MEA1_RSP_L     NC
BN69 M_E_CPU1_SA_RSP<0> MEA0_RSP_L @T6G_MB_LIB.T6G(SCH_1):M_E_CPU1_SA_RSP(0)
CW71 M_E_CPU1_SB_DQ<22> MEB_DATA22 @T6G_MB_LIB.T6G(SCH_1):M_E_CPU1_SB_DQ(22)
CK69 M_E_CPU1_SB_DQ<11> MEB_DATA11 @T6G_MB_LIB.T6G(SCH_1):M_E_CPU1_SB_DQ(11)
CJ69 M_E_CPU1_SB_DQ<9> MEB_DATA9 @T6G_MB_LIB.T6G(SCH_1):M_E_CPU1_SB_DQ(9)
CA71 M_E_CPU1_SB_CB<2> MEB_CHECK2 @T6G_MB_LIB.T6G(SCH_1):M_E_CPU1_SB_CB(2)
AM70 M_E_CPU1_SA_DQS_DN<4> MEA_DQS_L4 @T6G_MB_LIB.T6G(SCH_1):M_E_CPU1_SA_DQS_DN(4)
 G71 M_E_CPU1_SA_DQS_DP<0> MEA_DQS_H0 @T6G_MB_LIB.T6G(SCH_1):M_E_CPU1_SA_DQS_DP(0)
AG71 M_E_CPU1_SA_DQ<28> MEA_DATA28 @T6G_MB_LIB.T6G(SCH_1):M_E_CPU1_SA_DQ(28)
 V69 M_E_CPU1_SA_DQ<17> MEA_DATA17 @T6G_MB_LIB.T6G(SCH_1):M_E_CPU1_SA_DQ(17)
CY69 M_E_CPU1_SB_DQ<23> MEB_DATA23 @T6G_MB_LIB.T6G(SCH_1):M_E_CPU1_SB_DQ(23)
CM70 M_E_CPU1_SB_DQ<12> MEB_DATA12 @T6G_MB_LIB.T6G(SCH_1):M_E_CPU1_SB_DQ(12)
CB69 M_E_CPU1_SB_CB<3> MEB_CHECK3 @T6G_MB_LIB.T6G(SCH_1):M_E_CPU1_SB_CB(3)
 H69 M_E_CPU1_SA_DQS_DN<5> MEA_DQS_L5 @T6G_MB_LIB.T6G(SCH_1):M_E_CPU1_SA_DQS_DN(5)
 N71 M_E_CPU1_SA_DQS_DP<1> MEA_DQS_H1 @T6G_MB_LIB.T6G(SCH_1):M_E_CPU1_SA_DQS_DP(1)
AH69 M_E_CPU1_SA_DQ<29> MEA_DATA29 @T6G_MB_LIB.T6G(SCH_1):M_E_CPU1_SA_DQ(29)
 V70 M_E_CPU1_SA_DQ<18> MEA_DATA18 @T6G_MB_LIB.T6G(SCH_1):M_E_CPU1_SA_DQ(18)
CE71 M_E_CPU1_SB_DQS_DN<0> MEB_DQS_L0 @T6G_MB_LIB.T6G(SCH_1):M_E_CPU1_SB_DQS_DN(0)
CY70 M_E_CPU1_SB_DQ<24> MEB_DATA24 @T6G_MB_LIB.T6G(SCH_1):M_E_CPU1_SB_DQ(24)
CN69 M_E_CPU1_SB_DQ<13> MEB_DATA13 @T6G_MB_LIB.T6G(SCH_1):M_E_CPU1_SB_DQ(13)
BT70 M_E_CPU1_SB_CB<4> MEB_CHECK4 @T6G_MB_LIB.T6G(SCH_1):M_E_CPU1_SB_CB(4)
 P69 M_E_CPU1_SA_DQS_DN<6> MEA_DQS_L6 @T6G_MB_LIB.T6G(SCH_1):M_E_CPU1_SA_DQS_DN(6)
 W71 M_E_CPU1_SA_DQS_DP<2> MEA_DQS_H2 @T6G_MB_LIB.T6G(SCH_1):M_E_CPU1_SA_DQS_DP(2)
 W69 M_E_CPU1_SA_DQ<19> MEA_DATA19 @T6G_MB_LIB.T6G(SCH_1):M_E_CPU1_SA_DQ(19)
CL71 M_E_CPU1_SB_DQS_DN<1> MEB_DQS_L1 @T6G_MB_LIB.T6G(SCH_1):M_E_CPU1_SB_DQS_DN(1)
DA69 M_E_CPU1_SB_DQ<25> MEB_DATA25 @T6G_MB_LIB.T6G(SCH_1):M_E_CPU1_SB_DQ(25)
CN71 M_E_CPU1_SB_DQ<14> MEB_DATA14 @T6G_MB_LIB.T6G(SCH_1):M_E_CPU1_SB_DQ(14)
BU69 M_E_CPU1_SB_CB<5> MEB_CHECK5 @T6G_MB_LIB.T6G(SCH_1):M_E_CPU1_SB_CB(5)
 Y69 M_E_CPU1_SA_DQS_DN<7> MEA_DQS_L7 @T6G_MB_LIB.T6G(SCH_1):M_E_CPU1_SA_DQS_DN(7)
AE71 M_E_CPU1_SA_DQS_DP<3> MEA_DQS_H3 @T6G_MB_LIB.T6G(SCH_1):M_E_CPU1_SA_DQS_DP(3)
BC69 M_E_CPU1_SA_PAR MEA_PAR @T6G_MB_LIB.T6G(SCH_1):M_E_CPU1_SA_PAR
BL71 M_E_CPU1_SB_PAR MEB_PAR @T6G_MB_LIB.T6G(SCH_1):M_E_CPU1_SB_PAR
BV70 M_E_CPU1_SB_DQS_DP<9> MEB_DQS_H9 @T6G_MB_LIB.T6G(SCH_1):M_E_CPU1_SB_DQS_DP(9)
BC71 M_E_CPU1_CLK_DP<0> ME0_CLK_H @T6G_MB_LIB.T6G(SCH_1):M_E_CPU1_CLK_DP(0)
BD70 M_E_CPU1_CLK_DN<0> ME0_CLK_L @T6G_MB_LIB.T6G(SCH_1):M_E_CPU1_CLK_DN(0)
BF70     NC ME1_CLK_H     NC
BG71     NC ME1_CLK_L     NC
BF69 TP_M_E_CPU1_SA_TEST39E TEST39E @T6G_MB_LIB.T6G(SCH_1):TP_M_E_CPU1_SA_TEST39E

Q_RES_0402LF-15,1%,1/16W,CHIP,CS01502FB03  I314  R504
   1 M_E_CPU1_ALERT_N      A @T6G_MB_LIB.T6G(SCH_1):M_E_CPU1_ALERT_N
   2 M_E_CPU1_ALERT_R_N      B @T6G_MB_LIB.T6G(SCH_1):M_E_CPU1_ALERT_R_N


DRAWING: @T6G_MB_LIB.T6G(SCH_1):PAGE42 

GENOA_SP5-SOCKET6096_13568-001,SMLF,IO,DGA^6000030  I159  U26
AT65 M_F_CPU1_ALERT_R_N MF_ALERT_L @T6G_MB_LIB.T6G(SCH_1):M_F_CPU1_ALERT_R_N
AU66 M_F_CPU1_RESET_N MF_RESET_L @T6G_MB_LIB.T6G(SCH_1):M_F_CPU1_RESET_N
CL66 M_F_CPU1_SB_DQS_DN<6> MFB_DQS_L6 @T6G_MB_LIB.T6G(SCH_1):M_F_CPU1_SB_DQS_DN(6)
CT67 M_F_CPU1_SB_DQS_DP<2> MFB_DQS_H2 @T6G_MB_LIB.T6G(SCH_1):M_F_CPU1_SB_DQS_DP(2)
CT65 M_F_CPU1_SB_DQ<19> MFB_DATA19 @T6G_MB_LIB.T6G(SCH_1):M_F_CPU1_SB_DQ(19)
CH65 M_F_CPU1_SB_DQ<7> MFB_DATA7 @T6G_MB_LIB.T6G(SCH_1):M_F_CPU1_SB_DQ(7)
AG66 M_F_CPU1_SA_DQS_DP<8> MFA_DQS_H8 @T6G_MB_LIB.T6G(SCH_1):M_F_CPU1_SA_DQS_DP(8)
AH67 M_F_CPU1_SA_DQ<30> MFA_DATA30 @T6G_MB_LIB.T6G(SCH_1):M_F_CPU1_SA_DQ(30)
 L67 M_F_CPU1_SA_DQ<8> MFA_DATA8 @T6G_MB_LIB.T6G(SCH_1):M_F_CPU1_SA_DQ(8)
AU67     NC MFA1_CS_L0     NC
AW66 M_F_CPU1_SA_CS_N<1> MFA0_CS_L1 @T6G_MB_LIB.T6G(SCH_1):M_F_CPU1_SA_CS_N(1)
CU66 M_F_CPU1_SB_DQS_DN<7> MFB_DQS_L7 @T6G_MB_LIB.T6G(SCH_1):M_F_CPU1_SB_DQS_DN(7)
DB67 M_F_CPU1_SB_DQS_DP<3> MFB_DQS_H3 @T6G_MB_LIB.T6G(SCH_1):M_F_CPU1_SB_DQS_DP(3)
CH67 M_F_CPU1_SB_DQ<8> MFB_DATA8 @T6G_MB_LIB.T6G(SCH_1):M_F_CPU1_SB_DQ(8)
AN66 M_F_CPU1_SA_DQS_DP<9> MFA_DQS_H9 @T6G_MB_LIB.T6G(SCH_1):M_F_CPU1_SA_DQS_DP(9)
AJ66 M_F_CPU1_SA_DQ<31> MFA_DATA31 @T6G_MB_LIB.T6G(SCH_1):M_F_CPU1_SA_DQ(31)
AA67 M_F_CPU1_SA_DQ<20> MFA_DATA20 @T6G_MB_LIB.T6G(SCH_1):M_F_CPU1_SA_DQ(20)
 M65 M_F_CPU1_SA_DQ<9> MFA_DATA9 @T6G_MB_LIB.T6G(SCH_1):M_F_CPU1_SA_DQ(9)
AJ67 M_F_CPU1_SA_CB<0> MFA_CHECK0 @T6G_MB_LIB.T6G(SCH_1):M_F_CPU1_SA_CB(0)
AV65     NC MFA1_CS_L1     NC
DC66 M_F_CPU1_SB_DQS_DN<8> MFB_DQS_L8 @T6G_MB_LIB.T6G(SCH_1):M_F_CPU1_SB_DQS_DN(8)
BY65 M_F_CPU1_SB_DQS_DP<4> MFB_DQS_H4 @T6G_MB_LIB.T6G(SCH_1):M_F_CPU1_SB_DQS_DP(4)
CJ66 M_F_CPU1_SB_DQ<9> MFB_DATA9 @T6G_MB_LIB.T6G(SCH_1):M_F_CPU1_SB_DQ(9)
AB65 M_F_CPU1_SA_DQ<21> MFA_DATA21 @T6G_MB_LIB.T6G(SCH_1):M_F_CPU1_SA_DQ(21)
 M67 M_F_CPU1_SA_DQ<10> MFA_DATA10 @T6G_MB_LIB.T6G(SCH_1):M_F_CPU1_SA_DQ(10)
AK65 M_F_CPU1_SA_CB<1> MFA_CHECK1 @T6G_MB_LIB.T6G(SCH_1):M_F_CPU1_SA_CB(1)
BW67 M_F_CPU1_SB_DQS_DN<9> MFB_DQS_L9 @T6G_MB_LIB.T6G(SCH_1):M_F_CPU1_SB_DQS_DN(9)
CF65 M_F_CPU1_SB_DQS_DP<5> MFB_DQS_H5 @T6G_MB_LIB.T6G(SCH_1):M_F_CPU1_SB_DQS_DP(5)
AB67 M_F_CPU1_SA_DQ<22> MFA_DATA22 @T6G_MB_LIB.T6G(SCH_1):M_F_CPU1_SA_DQ(22)
 N66 M_F_CPU1_SA_DQ<11> MFA_DATA11 @T6G_MB_LIB.T6G(SCH_1):M_F_CPU1_SA_DQ(11)
AK67 M_F_CPU1_SA_CB<2> MFA_CHECK2 @T6G_MB_LIB.T6G(SCH_1):M_F_CPU1_SA_CB(2)
CM65 M_F_CPU1_SB_DQS_DP<6> MFB_DQS_H6 @T6G_MB_LIB.T6G(SCH_1):M_F_CPU1_SB_DQS_DP(6)
AC66 M_F_CPU1_SA_DQ<23> MFA_DATA23 @T6G_MB_LIB.T6G(SCH_1):M_F_CPU1_SA_DQ(23)
 R67 M_F_CPU1_SA_DQ<12> MFA_DATA12 @T6G_MB_LIB.T6G(SCH_1):M_F_CPU1_SA_DQ(12)
AL66 M_F_CPU1_SA_CB<3> MFA_CHECK3 @T6G_MB_LIB.T6G(SCH_1):M_F_CPU1_SA_CB(3)
AW67 M_F_CPU1_SA_CA<0> MFA_CA0 @T6G_MB_LIB.T6G(SCH_1):M_F_CPU1_SA_CA(0)
CV65 M_F_CPU1_SB_DQS_DP<7> MFB_DQS_H7 @T6G_MB_LIB.T6G(SCH_1):M_F_CPU1_SB_DQS_DP(7)
BG66 M_F_CPU1_SB_CA<0> MFB_CA0 @T6G_MB_LIB.T6G(SCH_1):M_F_CPU1_SB_CA(0)
BM65 M_F_CPU1_SB_CS_N<0> MFB0_CS_L0 @T6G_MB_LIB.T6G(SCH_1):M_F_CPU1_SB_CS_N(0)
 H67 M_F_CPU1_SA_DQS_DN<0> MFA_DQS_L0 @T6G_MB_LIB.T6G(SCH_1):M_F_CPU1_SA_DQS_DN(0)
AC67 M_F_CPU1_SA_DQ<24> MFA_DATA24 @T6G_MB_LIB.T6G(SCH_1):M_F_CPU1_SA_DQ(24)
 T65 M_F_CPU1_SA_DQ<13> MFA_DATA13 @T6G_MB_LIB.T6G(SCH_1):M_F_CPU1_SA_DQ(13)
AN67 M_F_CPU1_SA_CB<4> MFA_CHECK4 @T6G_MB_LIB.T6G(SCH_1):M_F_CPU1_SA_CB(4)
AY67 M_F_CPU1_SA_CA<1> MFA_CA1 @T6G_MB_LIB.T6G(SCH_1):M_F_CPU1_SA_CA(1)
DD65 M_F_CPU1_SB_DQS_DP<8> MFB_DQS_H8 @T6G_MB_LIB.T6G(SCH_1):M_F_CPU1_SB_DQS_DP(8)
DE67 M_F_CPU1_SB_DQ<30> MFB_DATA30 @T6G_MB_LIB.T6G(SCH_1):M_F_CPU1_SB_DQ(30)
BH65 M_F_CPU1_SB_CA<1> MFB_CA1 @T6G_MB_LIB.T6G(SCH_1):M_F_CPU1_SB_CA(1)
BL66     NC MFB1_CS_L0     NC
BN67 M_F_CPU1_SB_CS_N<1> MFB0_CS_L1 @T6G_MB_LIB.T6G(SCH_1):M_F_CPU1_SB_CS_N(1)
 P67 M_F_CPU1_SA_DQS_DN<1> MFA_DQS_L1 @T6G_MB_LIB.T6G(SCH_1):M_F_CPU1_SA_DQS_DN(1)
AD65 M_F_CPU1_SA_DQ<25> MFA_DATA25 @T6G_MB_LIB.T6G(SCH_1):M_F_CPU1_SA_DQ(25)
 T67 M_F_CPU1_SA_DQ<14> MFA_DATA14 @T6G_MB_LIB.T6G(SCH_1):M_F_CPU1_SA_DQ(14)
AP65 M_F_CPU1_SA_CB<5> MFA_CHECK5 @T6G_MB_LIB.T6G(SCH_1):M_F_CPU1_SA_CB(5)
AY65 M_F_CPU1_SA_CA<2> MFA_CA2 @T6G_MB_LIB.T6G(SCH_1):M_F_CPU1_SA_CA(2)
DF67 M_F_CPU1_SB_DQ<31> MFB_DATA31 @T6G_MB_LIB.T6G(SCH_1):M_F_CPU1_SB_DQ(31)
CV67 M_F_CPU1_SB_DQ<20> MFB_DATA20 @T6G_MB_LIB.T6G(SCH_1):M_F_CPU1_SB_DQ(20)
BY67 M_F_CPU1_SB_CB<0> MFB_CHECK0 @T6G_MB_LIB.T6G(SCH_1):M_F_CPU1_SB_CB(0)
BH67 M_F_CPU1_SB_CA<2> MFB_CA2 @T6G_MB_LIB.T6G(SCH_1):M_F_CPU1_SB_CA(2)
BM67     NC MFB1_CS_L1     NC
 Y67 M_F_CPU1_SA_DQS_DN<2> MFA_DQS_L2 @T6G_MB_LIB.T6G(SCH_1):M_F_CPU1_SA_DQS_DN(2)
AD67 M_F_CPU1_SA_DQ<26> MFA_DATA26 @T6G_MB_LIB.T6G(SCH_1):M_F_CPU1_SA_DQ(26)
 U66 M_F_CPU1_SA_DQ<15> MFA_DATA15 @T6G_MB_LIB.T6G(SCH_1):M_F_CPU1_SA_DQ(15)
AP67 M_F_CPU1_SA_CB<6> MFA_CHECK6 @T6G_MB_LIB.T6G(SCH_1):M_F_CPU1_SA_CB(6)
BA66 M_F_CPU1_SA_CA<3> MFA_CA3 @T6G_MB_LIB.T6G(SCH_1):M_F_CPU1_SA_CA(3)
CW66 M_F_CPU1_SB_DQ<21> MFB_DATA21 @T6G_MB_LIB.T6G(SCH_1):M_F_CPU1_SB_DQ(21)
CJ67 M_F_CPU1_SB_DQ<10> MFB_DATA10 @T6G_MB_LIB.T6G(SCH_1):M_F_CPU1_SB_DQ(10)
CA66 M_F_CPU1_SB_CB<1> MFB_CHECK1 @T6G_MB_LIB.T6G(SCH_1):M_F_CPU1_SB_CB(1)
BJ67 M_F_CPU1_SB_CA<3> MFB_CA3 @T6G_MB_LIB.T6G(SCH_1):M_F_CPU1_SB_CA(3)
AF67 M_F_CPU1_SA_DQS_DN<3> MFA_DQS_L3 @T6G_MB_LIB.T6G(SCH_1):M_F_CPU1_SA_DQS_DN(3)
AE66 M_F_CPU1_SA_DQ<27> MFA_DATA27 @T6G_MB_LIB.T6G(SCH_1):M_F_CPU1_SA_DQ(27)
 U67 M_F_CPU1_SA_DQ<16> MFA_DATA16 @T6G_MB_LIB.T6G(SCH_1):M_F_CPU1_SA_DQ(16)
AR66 M_F_CPU1_SA_CB<7> MFA_CHECK7 @T6G_MB_LIB.T6G(SCH_1):M_F_CPU1_SA_CB(7)
BA67 M_F_CPU1_SA_CA<4> MFA_CA4 @T6G_MB_LIB.T6G(SCH_1):M_F_CPU1_SA_CA(4)
BN66 M_F_CPU1_SA_RSP<0> MFA0_RSP_L @T6G_MB_LIB.T6G(SCH_1):M_F_CPU1_SA_RSP(0)
CW67 M_F_CPU1_SB_DQ<22> MFB_DATA22 @T6G_MB_LIB.T6G(SCH_1):M_F_CPU1_SB_DQ(22)
CK65 M_F_CPU1_SB_DQ<11> MFB_DATA11 @T6G_MB_LIB.T6G(SCH_1):M_F_CPU1_SB_DQ(11)
CA67 M_F_CPU1_SB_CB<2> MFB_CHECK2 @T6G_MB_LIB.T6G(SCH_1):M_F_CPU1_SB_CB(2)
BJ66 M_F_CPU1_SB_CA<4> MFB_CA4 @T6G_MB_LIB.T6G(SCH_1):M_F_CPU1_SB_CA(4)
AM67 M_F_CPU1_SA_DQS_DN<4> MFA_DQS_L4 @T6G_MB_LIB.T6G(SCH_1):M_F_CPU1_SA_DQS_DN(4)
 G67 M_F_CPU1_SA_DQS_DP<0> MFA_DQS_H0 @T6G_MB_LIB.T6G(SCH_1):M_F_CPU1_SA_DQS_DP(0)
AG67 M_F_CPU1_SA_DQ<28> MFA_DATA28 @T6G_MB_LIB.T6G(SCH_1):M_F_CPU1_SA_DQ(28)
 V65 M_F_CPU1_SA_DQ<17> MFA_DATA17 @T6G_MB_LIB.T6G(SCH_1):M_F_CPU1_SA_DQ(17)
 E67 M_F_CPU1_SA_DQ<0> MFA_DATA0 @T6G_MB_LIB.T6G(SCH_1):M_F_CPU1_SA_DQ(0)
BB67 M_F_CPU1_SA_CA<5> MFA_CA5 @T6G_MB_LIB.T6G(SCH_1):M_F_CPU1_SA_CA(5)
BP65     NC MFA1_RSP_L     NC
CY65 M_F_CPU1_SB_DQ<23> MFB_DATA23 @T6G_MB_LIB.T6G(SCH_1):M_F_CPU1_SB_DQ(23)
CM67 M_F_CPU1_SB_DQ<12> MFB_DATA12 @T6G_MB_LIB.T6G(SCH_1):M_F_CPU1_SB_DQ(12)
CB67 M_F_CPU1_SB_DQ<0> MFB_DATA0 @T6G_MB_LIB.T6G(SCH_1):M_F_CPU1_SB_DQ(0)
CB65 M_F_CPU1_SB_CB<3> MFB_CHECK3 @T6G_MB_LIB.T6G(SCH_1):M_F_CPU1_SB_CB(3)
BK65 M_F_CPU1_SB_CA<5> MFB_CA5 @T6G_MB_LIB.T6G(SCH_1):M_F_CPU1_SB_CA(5)
 H65 M_F_CPU1_SA_DQS_DN<5> MFA_DQS_L5 @T6G_MB_LIB.T6G(SCH_1):M_F_CPU1_SA_DQS_DN(5)
 N67 M_F_CPU1_SA_DQS_DP<1> MFA_DQS_H1 @T6G_MB_LIB.T6G(SCH_1):M_F_CPU1_SA_DQS_DP(1)
AH65 M_F_CPU1_SA_DQ<29> MFA_DATA29 @T6G_MB_LIB.T6G(SCH_1):M_F_CPU1_SA_DQ(29)
 V67 M_F_CPU1_SA_DQ<18> MFA_DATA18 @T6G_MB_LIB.T6G(SCH_1):M_F_CPU1_SA_DQ(18)
 F65 M_F_CPU1_SA_DQ<1> MFA_DATA1 @T6G_MB_LIB.T6G(SCH_1):M_F_CPU1_SA_DQ(1)
BB65 M_F_CPU1_SA_CA<6> MFA_CA6 @T6G_MB_LIB.T6G(SCH_1):M_F_CPU1_SA_CA(6)
CE67 M_F_CPU1_SB_DQS_DN<0> MFB_DQS_L0 @T6G_MB_LIB.T6G(SCH_1):M_F_CPU1_SB_DQS_DN(0)
CY67 M_F_CPU1_SB_DQ<24> MFB_DATA24 @T6G_MB_LIB.T6G(SCH_1):M_F_CPU1_SB_DQ(24)
CN66 M_F_CPU1_SB_DQ<13> MFB_DATA13 @T6G_MB_LIB.T6G(SCH_1):M_F_CPU1_SB_DQ(13)
CC66 M_F_CPU1_SB_DQ<1> MFB_DATA1 @T6G_MB_LIB.T6G(SCH_1):M_F_CPU1_SB_DQ(1)
BT67 M_F_CPU1_SB_CB<4> MFB_CHECK4 @T6G_MB_LIB.T6G(SCH_1):M_F_CPU1_SB_CB(4)
BK67 M_F_CPU1_SB_CA<6> MFB_CA6 @T6G_MB_LIB.T6G(SCH_1):M_F_CPU1_SB_CA(6)
 P65 M_F_CPU1_SA_DQS_DN<6> MFA_DQS_L6 @T6G_MB_LIB.T6G(SCH_1):M_F_CPU1_SA_DQS_DN(6)
 W67 M_F_CPU1_SA_DQS_DP<2> MFA_DQS_H2 @T6G_MB_LIB.T6G(SCH_1):M_F_CPU1_SA_DQS_DP(2)
 W66 M_F_CPU1_SA_DQ<19> MFA_DATA19 @T6G_MB_LIB.T6G(SCH_1):M_F_CPU1_SA_DQ(19)
 F67 M_F_CPU1_SA_DQ<2> MFA_DATA2 @T6G_MB_LIB.T6G(SCH_1):M_F_CPU1_SA_DQ(2)
CL67 M_F_CPU1_SB_DQS_DN<1> MFB_DQS_L1 @T6G_MB_LIB.T6G(SCH_1):M_F_CPU1_SB_DQS_DN(1)
DA66 M_F_CPU1_SB_DQ<25> MFB_DATA25 @T6G_MB_LIB.T6G(SCH_1):M_F_CPU1_SB_DQ(25)
CN67 M_F_CPU1_SB_DQ<14> MFB_DATA14 @T6G_MB_LIB.T6G(SCH_1):M_F_CPU1_SB_DQ(14)
CC67 M_F_CPU1_SB_DQ<2> MFB_DATA2 @T6G_MB_LIB.T6G(SCH_1):M_F_CPU1_SB_DQ(2)
BU66 M_F_CPU1_SB_CB<5> MFB_CHECK5 @T6G_MB_LIB.T6G(SCH_1):M_F_CPU1_SB_CB(5)
 Y65 M_F_CPU1_SA_DQS_DN<7> MFA_DQS_L7 @T6G_MB_LIB.T6G(SCH_1):M_F_CPU1_SA_DQS_DN(7)
AE67 M_F_CPU1_SA_DQS_DP<3> MFA_DQS_H3 @T6G_MB_LIB.T6G(SCH_1):M_F_CPU1_SA_DQS_DP(3)
 G66 M_F_CPU1_SA_DQ<3> MFA_DATA3 @T6G_MB_LIB.T6G(SCH_1):M_F_CPU1_SA_DQ(3)
CU67 M_F_CPU1_SB_DQS_DN<2> MFB_DQS_L2 @T6G_MB_LIB.T6G(SCH_1):M_F_CPU1_SB_DQS_DN(2)
DA67 M_F_CPU1_SB_DQ<26> MFB_DATA26 @T6G_MB_LIB.T6G(SCH_1):M_F_CPU1_SB_DQ(26)
CP65 M_F_CPU1_SB_DQ<15> MFB_DATA15 @T6G_MB_LIB.T6G(SCH_1):M_F_CPU1_SB_DQ(15)
CD65 M_F_CPU1_SB_DQ<3> MFB_DATA3 @T6G_MB_LIB.T6G(SCH_1):M_F_CPU1_SB_DQ(3)
BU67 M_F_CPU1_SB_CB<6> MFB_CHECK6 @T6G_MB_LIB.T6G(SCH_1):M_F_CPU1_SB_CB(6)
AF65 M_F_CPU1_SA_DQS_DN<8> MFA_DQS_L8 @T6G_MB_LIB.T6G(SCH_1):M_F_CPU1_SA_DQS_DN(8)
AL67 M_F_CPU1_SA_DQS_DP<4> MFA_DQS_H4 @T6G_MB_LIB.T6G(SCH_1):M_F_CPU1_SA_DQS_DP(4)
 J67 M_F_CPU1_SA_DQ<4> MFA_DATA4 @T6G_MB_LIB.T6G(SCH_1):M_F_CPU1_SA_DQ(4)
DC67 M_F_CPU1_SB_DQS_DN<3> MFB_DQS_L3 @T6G_MB_LIB.T6G(SCH_1):M_F_CPU1_SB_DQS_DN(3)
DB65 M_F_CPU1_SB_DQ<27> MFB_DATA27 @T6G_MB_LIB.T6G(SCH_1):M_F_CPU1_SB_DQ(27)
CP67 M_F_CPU1_SB_DQ<16> MFB_DATA16 @T6G_MB_LIB.T6G(SCH_1):M_F_CPU1_SB_DQ(16)
CF67 M_F_CPU1_SB_DQ<4> MFB_DATA4 @T6G_MB_LIB.T6G(SCH_1):M_F_CPU1_SB_DQ(4)
BV65 M_F_CPU1_SB_CB<7> MFB_CHECK7 @T6G_MB_LIB.T6G(SCH_1):M_F_CPU1_SB_CB(7)
BP67 M_F_CPU1_SB_RSP<0> MFB0_RSP_L @T6G_MB_LIB.T6G(SCH_1):M_F_CPU1_SB_RSP(0)
AM65 M_F_CPU1_SA_DQS_DN<9> MFA_DQS_L9 @T6G_MB_LIB.T6G(SCH_1):M_F_CPU1_SA_DQS_DN(9)
 J66 M_F_CPU1_SA_DQS_DP<5> MFA_DQS_H5 @T6G_MB_LIB.T6G(SCH_1):M_F_CPU1_SA_DQS_DP(5)
 K65 M_F_CPU1_SA_DQ<5> MFA_DATA5 @T6G_MB_LIB.T6G(SCH_1):M_F_CPU1_SA_DQ(5)
BW66 M_F_CPU1_SB_DQS_DN<4> MFB_DQS_L4 @T6G_MB_LIB.T6G(SCH_1):M_F_CPU1_SB_DQS_DN(4)
CD67 M_F_CPU1_SB_DQS_DP<0> MFB_DQS_H0 @T6G_MB_LIB.T6G(SCH_1):M_F_CPU1_SB_DQS_DP(0)
DD67 M_F_CPU1_SB_DQ<28> MFB_DATA28 @T6G_MB_LIB.T6G(SCH_1):M_F_CPU1_SB_DQ(28)
CR66 M_F_CPU1_SB_DQ<17> MFB_DATA17 @T6G_MB_LIB.T6G(SCH_1):M_F_CPU1_SB_DQ(17)
CG66 M_F_CPU1_SB_DQ<5> MFB_DATA5 @T6G_MB_LIB.T6G(SCH_1):M_F_CPU1_SB_DQ(5)
BR67     NC MFB1_RSP_L     NC
 R66 M_F_CPU1_SA_DQS_DP<6> MFA_DQS_H6 @T6G_MB_LIB.T6G(SCH_1):M_F_CPU1_SA_DQS_DP(6)
 K67 M_F_CPU1_SA_DQ<6> MFA_DATA6 @T6G_MB_LIB.T6G(SCH_1):M_F_CPU1_SA_DQ(6)
CE66 M_F_CPU1_SB_DQS_DN<5> MFB_DQS_L5 @T6G_MB_LIB.T6G(SCH_1):M_F_CPU1_SB_DQS_DN(5)
CK67 M_F_CPU1_SB_DQS_DP<1> MFB_DQS_H1 @T6G_MB_LIB.T6G(SCH_1):M_F_CPU1_SB_DQS_DP(1)
DE66 M_F_CPU1_SB_DQ<29> MFB_DATA29 @T6G_MB_LIB.T6G(SCH_1):M_F_CPU1_SB_DQ(29)
CR67 M_F_CPU1_SB_DQ<18> MFB_DATA18 @T6G_MB_LIB.T6G(SCH_1):M_F_CPU1_SB_DQ(18)
CG67 M_F_CPU1_SB_DQ<6> MFB_DATA6 @T6G_MB_LIB.T6G(SCH_1):M_F_CPU1_SB_DQ(6)
AA66 M_F_CPU1_SA_DQS_DP<7> MFA_DQS_H7 @T6G_MB_LIB.T6G(SCH_1):M_F_CPU1_SA_DQS_DP(7)
 L66 M_F_CPU1_SA_DQ<7> MFA_DATA7 @T6G_MB_LIB.T6G(SCH_1):M_F_CPU1_SA_DQ(7)
AV67 M_F_CPU1_SA_CS_N<0> MFA0_CS_L0 @T6G_MB_LIB.T6G(SCH_1):M_F_CPU1_SA_CS_N(0)
BC66 M_F_CPU1_SA_PAR MFA_PAR @T6G_MB_LIB.T6G(SCH_1):M_F_CPU1_SA_PAR
BL67 M_F_CPU1_SB_PAR MFB_PAR @T6G_MB_LIB.T6G(SCH_1):M_F_CPU1_SB_PAR
BV67 M_F_CPU1_SB_DQS_DP<9> MFB_DQS_H9 @T6G_MB_LIB.T6G(SCH_1):M_F_CPU1_SB_DQS_DP(9)
BC67 M_F_CPU1_CLK_DP<0> MF0_CLK_H @T6G_MB_LIB.T6G(SCH_1):M_F_CPU1_CLK_DP(0)
BD67 M_F_CPU1_CLK_DN<0> MF0_CLK_L @T6G_MB_LIB.T6G(SCH_1):M_F_CPU1_CLK_DN(0)
BF67     NC MF1_CLK_H     NC
BG67     NC MF1_CLK_L     NC
BF65 TP_M_F_CPU1_SA_TEST39F TEST39F @T6G_MB_LIB.T6G(SCH_1):TP_M_F_CPU1_SA_TEST39F

Q_RES_0402LF-15,1%,1/16W,CHIP,CS01502FB03  I314  R505
   1 M_F_CPU1_ALERT_N      A @T6G_MB_LIB.T6G(SCH_1):M_F_CPU1_ALERT_N
   2 M_F_CPU1_ALERT_R_N      B @T6G_MB_LIB.T6G(SCH_1):M_F_CPU1_ALERT_R_N


DRAWING: @T6G_MB_LIB.T6G(SCH_1):PAGE43 

GENOA_SP5-SOCKET6096_13568-001,SMLF,IO,DGA^6000030  I167  U26
 AR2 M_G_CPU1_ALERT_R_N MG_ALERT_L @T6G_MB_LIB.T6G(SCH_1):M_G_CPU1_ALERT_R_N
 AT2 M_G_CPU1_RESET_N MG_RESET_L @T6G_MB_LIB.T6G(SCH_1):M_G_CPU1_RESET_N
 BW2 M_G_CPU1_SB_DQS_DN<9> MGB_DQS_L9 @T6G_MB_LIB.T6G(SCH_1):M_G_CPU1_SB_DQS_DN(9)
 CF4 M_G_CPU1_SB_DQS_DP<5> MGB_DQS_H5 @T6G_MB_LIB.T6G(SCH_1):M_G_CPU1_SB_DQS_DP(5)
 CC3 M_G_CPU1_SB_DQ<1> MGB_DATA1 @T6G_MB_LIB.T6G(SCH_1):M_G_CPU1_SB_DQ(1)
 AB2 M_G_CPU1_SA_DQ<22> MGA_DATA22 @T6G_MB_LIB.T6G(SCH_1):M_G_CPU1_SA_DQ(22)
  N3 M_G_CPU1_SA_DQ<11> MGA_DATA11 @T6G_MB_LIB.T6G(SCH_1):M_G_CPU1_SA_DQ(11)
  F4 M_G_CPU1_SA_DQ<1> MGA_DATA1 @T6G_MB_LIB.T6G(SCH_1):M_G_CPU1_SA_DQ(1)
 AK2 M_G_CPU1_SA_CB<2> MGA_CHECK2 @T6G_MB_LIB.T6G(SCH_1):M_G_CPU1_SA_CB(2)
 CM4 M_G_CPU1_SB_DQS_DP<6> MGB_DQS_H6 @T6G_MB_LIB.T6G(SCH_1):M_G_CPU1_SB_DQS_DP(6)
 CC2 M_G_CPU1_SB_DQ<2> MGB_DATA2 @T6G_MB_LIB.T6G(SCH_1):M_G_CPU1_SB_DQ(2)
 AC3 M_G_CPU1_SA_DQ<23> MGA_DATA23 @T6G_MB_LIB.T6G(SCH_1):M_G_CPU1_SA_DQ(23)
  R2 M_G_CPU1_SA_DQ<12> MGA_DATA12 @T6G_MB_LIB.T6G(SCH_1):M_G_CPU1_SA_DQ(12)
  F2 M_G_CPU1_SA_DQ<2> MGA_DATA2 @T6G_MB_LIB.T6G(SCH_1):M_G_CPU1_SA_DQ(2)
 AL3 M_G_CPU1_SA_CB<3> MGA_CHECK3 @T6G_MB_LIB.T6G(SCH_1):M_G_CPU1_SA_CB(3)
 CV4 M_G_CPU1_SB_DQS_DP<7> MGB_DQS_H7 @T6G_MB_LIB.T6G(SCH_1):M_G_CPU1_SB_DQS_DP(7)
 CD4 M_G_CPU1_SB_DQ<3> MGB_DATA3 @T6G_MB_LIB.T6G(SCH_1):M_G_CPU1_SB_DQ(3)
 BL2     NC MGB1_CS_L0     NC
 BM4 M_G_CPU1_SB_CS_N<0> MGB0_CS_L0 @T6G_MB_LIB.T6G(SCH_1):M_G_CPU1_SB_CS_N(0)
  H2 M_G_CPU1_SA_DQS_DN<0> MGA_DQS_L0 @T6G_MB_LIB.T6G(SCH_1):M_G_CPU1_SA_DQS_DN(0)
 AC2 M_G_CPU1_SA_DQ<24> MGA_DATA24 @T6G_MB_LIB.T6G(SCH_1):M_G_CPU1_SA_DQ(24)
  T4 M_G_CPU1_SA_DQ<13> MGA_DATA13 @T6G_MB_LIB.T6G(SCH_1):M_G_CPU1_SA_DQ(13)
  G3 M_G_CPU1_SA_DQ<3> MGA_DATA3 @T6G_MB_LIB.T6G(SCH_1):M_G_CPU1_SA_DQ(3)
 AN2 M_G_CPU1_SA_CB<4> MGA_CHECK4 @T6G_MB_LIB.T6G(SCH_1):M_G_CPU1_SA_CB(4)
 DD4 M_G_CPU1_SB_DQS_DP<8> MGB_DQS_H8 @T6G_MB_LIB.T6G(SCH_1):M_G_CPU1_SB_DQS_DP(8)
 DE2 M_G_CPU1_SB_DQ<30> MGB_DATA30 @T6G_MB_LIB.T6G(SCH_1):M_G_CPU1_SB_DQ(30)
 CF2 M_G_CPU1_SB_DQ<4> MGB_DATA4 @T6G_MB_LIB.T6G(SCH_1):M_G_CPU1_SB_DQ(4)
 BM2     NC MGB1_CS_L1     NC
 BN2 M_G_CPU1_SB_CS_N<1> MGB0_CS_L1 @T6G_MB_LIB.T6G(SCH_1):M_G_CPU1_SB_CS_N(1)
  P2 M_G_CPU1_SA_DQS_DN<1> MGA_DQS_L1 @T6G_MB_LIB.T6G(SCH_1):M_G_CPU1_SA_DQS_DN(1)
 AD4 M_G_CPU1_SA_DQ<25> MGA_DATA25 @T6G_MB_LIB.T6G(SCH_1):M_G_CPU1_SA_DQ(25)
  T2 M_G_CPU1_SA_DQ<14> MGA_DATA14 @T6G_MB_LIB.T6G(SCH_1):M_G_CPU1_SA_DQ(14)
  J2 M_G_CPU1_SA_DQ<4> MGA_DATA4 @T6G_MB_LIB.T6G(SCH_1):M_G_CPU1_SA_DQ(4)
 AP4 M_G_CPU1_SA_CB<5> MGA_CHECK5 @T6G_MB_LIB.T6G(SCH_1):M_G_CPU1_SA_CB(5)
 AW2 M_G_CPU1_SA_CA<0> MGA_CA0 @T6G_MB_LIB.T6G(SCH_1):M_G_CPU1_SA_CA(0)
 DF2 M_G_CPU1_SB_DQ<31> MGB_DATA31 @T6G_MB_LIB.T6G(SCH_1):M_G_CPU1_SB_DQ(31)
 CV2 M_G_CPU1_SB_DQ<20> MGB_DATA20 @T6G_MB_LIB.T6G(SCH_1):M_G_CPU1_SB_DQ(20)
 CG3 M_G_CPU1_SB_DQ<5> MGB_DATA5 @T6G_MB_LIB.T6G(SCH_1):M_G_CPU1_SB_DQ(5)
 BY2 M_G_CPU1_SB_CB<0> MGB_CHECK0 @T6G_MB_LIB.T6G(SCH_1):M_G_CPU1_SB_CB(0)
 BG3 M_G_CPU1_SB_CA<0> MGB_CA0 @T6G_MB_LIB.T6G(SCH_1):M_G_CPU1_SB_CA(0)
  Y2 M_G_CPU1_SA_DQS_DN<2> MGA_DQS_L2 @T6G_MB_LIB.T6G(SCH_1):M_G_CPU1_SA_DQS_DN(2)
 AD2 M_G_CPU1_SA_DQ<26> MGA_DATA26 @T6G_MB_LIB.T6G(SCH_1):M_G_CPU1_SA_DQ(26)
  U3 M_G_CPU1_SA_DQ<15> MGA_DATA15 @T6G_MB_LIB.T6G(SCH_1):M_G_CPU1_SA_DQ(15)
  K4 M_G_CPU1_SA_DQ<5> MGA_DATA5 @T6G_MB_LIB.T6G(SCH_1):M_G_CPU1_SA_DQ(5)
 AP2 M_G_CPU1_SA_CB<6> MGA_CHECK6 @T6G_MB_LIB.T6G(SCH_1):M_G_CPU1_SA_CB(6)
 AY2 M_G_CPU1_SA_CA<1> MGA_CA1 @T6G_MB_LIB.T6G(SCH_1):M_G_CPU1_SA_CA(1)
 CW3 M_G_CPU1_SB_DQ<21> MGB_DATA21 @T6G_MB_LIB.T6G(SCH_1):M_G_CPU1_SB_DQ(21)
 CJ2 M_G_CPU1_SB_DQ<10> MGB_DATA10 @T6G_MB_LIB.T6G(SCH_1):M_G_CPU1_SB_DQ(10)
 CG2 M_G_CPU1_SB_DQ<6> MGB_DATA6 @T6G_MB_LIB.T6G(SCH_1):M_G_CPU1_SB_DQ(6)
 CA3 M_G_CPU1_SB_CB<1> MGB_CHECK1 @T6G_MB_LIB.T6G(SCH_1):M_G_CPU1_SB_CB(1)
 BH4 M_G_CPU1_SB_CA<1> MGB_CA1 @T6G_MB_LIB.T6G(SCH_1):M_G_CPU1_SB_CA(1)
 AF2 M_G_CPU1_SA_DQS_DN<3> MGA_DQS_L3 @T6G_MB_LIB.T6G(SCH_1):M_G_CPU1_SA_DQS_DN(3)
 AE3 M_G_CPU1_SA_DQ<27> MGA_DATA27 @T6G_MB_LIB.T6G(SCH_1):M_G_CPU1_SA_DQ(27)
  U2 M_G_CPU1_SA_DQ<16> MGA_DATA16 @T6G_MB_LIB.T6G(SCH_1):M_G_CPU1_SA_DQ(16)
  K2 M_G_CPU1_SA_DQ<6> MGA_DATA6 @T6G_MB_LIB.T6G(SCH_1):M_G_CPU1_SA_DQ(6)
 AR3 M_G_CPU1_SA_CB<7> MGA_CHECK7 @T6G_MB_LIB.T6G(SCH_1):M_G_CPU1_SA_CB(7)
 AY4 M_G_CPU1_SA_CA<2> MGA_CA2 @T6G_MB_LIB.T6G(SCH_1):M_G_CPU1_SA_CA(2)
 BP4     NC MGA1_RSP_L     NC
 BN3 M_G_CPU1_SA_RSP<0> MGA0_RSP_L @T6G_MB_LIB.T6G(SCH_1):M_G_CPU1_SA_RSP(0)
 CW2 M_G_CPU1_SB_DQ<22> MGB_DATA22 @T6G_MB_LIB.T6G(SCH_1):M_G_CPU1_SB_DQ(22)
 CK4 M_G_CPU1_SB_DQ<11> MGB_DATA11 @T6G_MB_LIB.T6G(SCH_1):M_G_CPU1_SB_DQ(11)
 CH4 M_G_CPU1_SB_DQ<7> MGB_DATA7 @T6G_MB_LIB.T6G(SCH_1):M_G_CPU1_SB_DQ(7)
 CA2 M_G_CPU1_SB_CB<2> MGB_CHECK2 @T6G_MB_LIB.T6G(SCH_1):M_G_CPU1_SB_CB(2)
 BH2 M_G_CPU1_SB_CA<2> MGB_CA2 @T6G_MB_LIB.T6G(SCH_1):M_G_CPU1_SB_CA(2)
 AM2 M_G_CPU1_SA_DQS_DN<4> MGA_DQS_L4 @T6G_MB_LIB.T6G(SCH_1):M_G_CPU1_SA_DQS_DN(4)
  G2 M_G_CPU1_SA_DQS_DP<0> MGA_DQS_H0 @T6G_MB_LIB.T6G(SCH_1):M_G_CPU1_SA_DQS_DP(0)
 AG2 M_G_CPU1_SA_DQ<28> MGA_DATA28 @T6G_MB_LIB.T6G(SCH_1):M_G_CPU1_SA_DQ(28)
  V4 M_G_CPU1_SA_DQ<17> MGA_DATA17 @T6G_MB_LIB.T6G(SCH_1):M_G_CPU1_SA_DQ(17)
  L3 M_G_CPU1_SA_DQ<7> MGA_DATA7 @T6G_MB_LIB.T6G(SCH_1):M_G_CPU1_SA_DQ(7)
 BA3 M_G_CPU1_SA_CA<3> MGA_CA3 @T6G_MB_LIB.T6G(SCH_1):M_G_CPU1_SA_CA(3)
 CY4 M_G_CPU1_SB_DQ<23> MGB_DATA23 @T6G_MB_LIB.T6G(SCH_1):M_G_CPU1_SB_DQ(23)
 CM2 M_G_CPU1_SB_DQ<12> MGB_DATA12 @T6G_MB_LIB.T6G(SCH_1):M_G_CPU1_SB_DQ(12)
 CH2 M_G_CPU1_SB_DQ<8> MGB_DATA8 @T6G_MB_LIB.T6G(SCH_1):M_G_CPU1_SB_DQ(8)
 CB4 M_G_CPU1_SB_CB<3> MGB_CHECK3 @T6G_MB_LIB.T6G(SCH_1):M_G_CPU1_SB_CB(3)
 BJ2 M_G_CPU1_SB_CA<3> MGB_CA3 @T6G_MB_LIB.T6G(SCH_1):M_G_CPU1_SB_CA(3)
  H4 M_G_CPU1_SA_DQS_DN<5> MGA_DQS_L5 @T6G_MB_LIB.T6G(SCH_1):M_G_CPU1_SA_DQS_DN(5)
  N2 M_G_CPU1_SA_DQS_DP<1> MGA_DQS_H1 @T6G_MB_LIB.T6G(SCH_1):M_G_CPU1_SA_DQS_DP(1)
 AH4 M_G_CPU1_SA_DQ<29> MGA_DATA29 @T6G_MB_LIB.T6G(SCH_1):M_G_CPU1_SA_DQ(29)
  V2 M_G_CPU1_SA_DQ<18> MGA_DATA18 @T6G_MB_LIB.T6G(SCH_1):M_G_CPU1_SA_DQ(18)
  L2 M_G_CPU1_SA_DQ<8> MGA_DATA8 @T6G_MB_LIB.T6G(SCH_1):M_G_CPU1_SA_DQ(8)
 BA2 M_G_CPU1_SA_CA<4> MGA_CA4 @T6G_MB_LIB.T6G(SCH_1):M_G_CPU1_SA_CA(4)
 CE2 M_G_CPU1_SB_DQS_DN<0> MGB_DQS_L0 @T6G_MB_LIB.T6G(SCH_1):M_G_CPU1_SB_DQS_DN(0)
 CY2 M_G_CPU1_SB_DQ<24> MGB_DATA24 @T6G_MB_LIB.T6G(SCH_1):M_G_CPU1_SB_DQ(24)
 CN3 M_G_CPU1_SB_DQ<13> MGB_DATA13 @T6G_MB_LIB.T6G(SCH_1):M_G_CPU1_SB_DQ(13)
 CJ3 M_G_CPU1_SB_DQ<9> MGB_DATA9 @T6G_MB_LIB.T6G(SCH_1):M_G_CPU1_SB_DQ(9)
 BT2 M_G_CPU1_SB_CB<4> MGB_CHECK4 @T6G_MB_LIB.T6G(SCH_1):M_G_CPU1_SB_CB(4)
 BJ3 M_G_CPU1_SB_CA<4> MGB_CA4 @T6G_MB_LIB.T6G(SCH_1):M_G_CPU1_SB_CA(4)
  P4 M_G_CPU1_SA_DQS_DN<6> MGA_DQS_L6 @T6G_MB_LIB.T6G(SCH_1):M_G_CPU1_SA_DQS_DN(6)
  W2 M_G_CPU1_SA_DQS_DP<2> MGA_DQS_H2 @T6G_MB_LIB.T6G(SCH_1):M_G_CPU1_SA_DQS_DP(2)
  W3 M_G_CPU1_SA_DQ<19> MGA_DATA19 @T6G_MB_LIB.T6G(SCH_1):M_G_CPU1_SA_DQ(19)
  M4 M_G_CPU1_SA_DQ<9> MGA_DATA9 @T6G_MB_LIB.T6G(SCH_1):M_G_CPU1_SA_DQ(9)
 BB2 M_G_CPU1_SA_CA<5> MGA_CA5 @T6G_MB_LIB.T6G(SCH_1):M_G_CPU1_SA_CA(5)
 CL2 M_G_CPU1_SB_DQS_DN<1> MGB_DQS_L1 @T6G_MB_LIB.T6G(SCH_1):M_G_CPU1_SB_DQS_DN(1)
 DA3 M_G_CPU1_SB_DQ<25> MGB_DATA25 @T6G_MB_LIB.T6G(SCH_1):M_G_CPU1_SB_DQ(25)
 CN2 M_G_CPU1_SB_DQ<14> MGB_DATA14 @T6G_MB_LIB.T6G(SCH_1):M_G_CPU1_SB_DQ(14)
 BU3 M_G_CPU1_SB_CB<5> MGB_CHECK5 @T6G_MB_LIB.T6G(SCH_1):M_G_CPU1_SB_CB(5)
 BK4 M_G_CPU1_SB_CA<5> MGB_CA5 @T6G_MB_LIB.T6G(SCH_1):M_G_CPU1_SB_CA(5)
  Y4 M_G_CPU1_SA_DQS_DN<7> MGA_DQS_L7 @T6G_MB_LIB.T6G(SCH_1):M_G_CPU1_SA_DQS_DN(7)
 AE2 M_G_CPU1_SA_DQS_DP<3> MGA_DQS_H3 @T6G_MB_LIB.T6G(SCH_1):M_G_CPU1_SA_DQS_DP(3)
 BB4 M_G_CPU1_SA_CA<6> MGA_CA6 @T6G_MB_LIB.T6G(SCH_1):M_G_CPU1_SA_CA(6)
 CU2 M_G_CPU1_SB_DQS_DN<2> MGB_DQS_L2 @T6G_MB_LIB.T6G(SCH_1):M_G_CPU1_SB_DQS_DN(2)
 DA2 M_G_CPU1_SB_DQ<26> MGB_DATA26 @T6G_MB_LIB.T6G(SCH_1):M_G_CPU1_SB_DQ(26)
 CP4 M_G_CPU1_SB_DQ<15> MGB_DATA15 @T6G_MB_LIB.T6G(SCH_1):M_G_CPU1_SB_DQ(15)
 BU2 M_G_CPU1_SB_CB<6> MGB_CHECK6 @T6G_MB_LIB.T6G(SCH_1):M_G_CPU1_SB_CB(6)
 BK2 M_G_CPU1_SB_CA<6> MGB_CA6 @T6G_MB_LIB.T6G(SCH_1):M_G_CPU1_SB_CA(6)
 AF4 M_G_CPU1_SA_DQS_DN<8> MGA_DQS_L8 @T6G_MB_LIB.T6G(SCH_1):M_G_CPU1_SA_DQS_DN(8)
 AL2 M_G_CPU1_SA_DQS_DP<4> MGA_DQS_H4 @T6G_MB_LIB.T6G(SCH_1):M_G_CPU1_SA_DQS_DP(4)
 DC2 M_G_CPU1_SB_DQS_DN<3> MGB_DQS_L3 @T6G_MB_LIB.T6G(SCH_1):M_G_CPU1_SB_DQS_DN(3)
 DB4 M_G_CPU1_SB_DQ<27> MGB_DATA27 @T6G_MB_LIB.T6G(SCH_1):M_G_CPU1_SB_DQ(27)
 CP2 M_G_CPU1_SB_DQ<16> MGB_DATA16 @T6G_MB_LIB.T6G(SCH_1):M_G_CPU1_SB_DQ(16)
 BV4 M_G_CPU1_SB_CB<7> MGB_CHECK7 @T6G_MB_LIB.T6G(SCH_1):M_G_CPU1_SB_CB(7)
 BR2     NC MGB1_RSP_L     NC
 BP2 M_G_CPU1_SB_RSP<0> MGB0_RSP_L @T6G_MB_LIB.T6G(SCH_1):M_G_CPU1_SB_RSP(0)
 AM4 M_G_CPU1_SA_DQS_DN<9> MGA_DQS_L9 @T6G_MB_LIB.T6G(SCH_1):M_G_CPU1_SA_DQS_DN(9)
  J3 M_G_CPU1_SA_DQS_DP<5> MGA_DQS_H5 @T6G_MB_LIB.T6G(SCH_1):M_G_CPU1_SA_DQS_DP(5)
 BW3 M_G_CPU1_SB_DQS_DN<4> MGB_DQS_L4 @T6G_MB_LIB.T6G(SCH_1):M_G_CPU1_SB_DQS_DN(4)
 CD2 M_G_CPU1_SB_DQS_DP<0> MGB_DQS_H0 @T6G_MB_LIB.T6G(SCH_1):M_G_CPU1_SB_DQS_DP(0)
 DD2 M_G_CPU1_SB_DQ<28> MGB_DATA28 @T6G_MB_LIB.T6G(SCH_1):M_G_CPU1_SB_DQ(28)
 CR3 M_G_CPU1_SB_DQ<17> MGB_DATA17 @T6G_MB_LIB.T6G(SCH_1):M_G_CPU1_SB_DQ(17)
  R3 M_G_CPU1_SA_DQS_DP<6> MGA_DQS_H6 @T6G_MB_LIB.T6G(SCH_1):M_G_CPU1_SA_DQS_DP(6)
 CE3 M_G_CPU1_SB_DQS_DN<5> MGB_DQS_L5 @T6G_MB_LIB.T6G(SCH_1):M_G_CPU1_SB_DQS_DN(5)
 CK2 M_G_CPU1_SB_DQS_DP<1> MGB_DQS_H1 @T6G_MB_LIB.T6G(SCH_1):M_G_CPU1_SB_DQS_DP(1)
 DE3 M_G_CPU1_SB_DQ<29> MGB_DATA29 @T6G_MB_LIB.T6G(SCH_1):M_G_CPU1_SB_DQ(29)
 CR2 M_G_CPU1_SB_DQ<18> MGB_DATA18 @T6G_MB_LIB.T6G(SCH_1):M_G_CPU1_SB_DQ(18)
 AA3 M_G_CPU1_SA_DQS_DP<7> MGA_DQS_H7 @T6G_MB_LIB.T6G(SCH_1):M_G_CPU1_SA_DQS_DP(7)
 AV2     NC MGA1_CS_L0     NC
 AU2 M_G_CPU1_SA_CS_N<0> MGA0_CS_L0 @T6G_MB_LIB.T6G(SCH_1):M_G_CPU1_SA_CS_N(0)
 CL3 M_G_CPU1_SB_DQS_DN<6> MGB_DQS_L6 @T6G_MB_LIB.T6G(SCH_1):M_G_CPU1_SB_DQS_DN(6)
 CT2 M_G_CPU1_SB_DQS_DP<2> MGB_DQS_H2 @T6G_MB_LIB.T6G(SCH_1):M_G_CPU1_SB_DQS_DP(2)
 CT4 M_G_CPU1_SB_DQ<19> MGB_DATA19 @T6G_MB_LIB.T6G(SCH_1):M_G_CPU1_SB_DQ(19)
 AG3 M_G_CPU1_SA_DQS_DP<8> MGA_DQS_H8 @T6G_MB_LIB.T6G(SCH_1):M_G_CPU1_SA_DQS_DP(8)
 AH2 M_G_CPU1_SA_DQ<30> MGA_DATA30 @T6G_MB_LIB.T6G(SCH_1):M_G_CPU1_SA_DQ(30)
 AW3     NC MGA1_CS_L1     NC
 AV4 M_G_CPU1_SA_CS_N<1> MGA0_CS_L1 @T6G_MB_LIB.T6G(SCH_1):M_G_CPU1_SA_CS_N(1)
 CU3 M_G_CPU1_SB_DQS_DN<7> MGB_DQS_L7 @T6G_MB_LIB.T6G(SCH_1):M_G_CPU1_SB_DQS_DN(7)
 DB2 M_G_CPU1_SB_DQS_DP<3> MGB_DQS_H3 @T6G_MB_LIB.T6G(SCH_1):M_G_CPU1_SB_DQS_DP(3)
 AN3 M_G_CPU1_SA_DQS_DP<9> MGA_DQS_H9 @T6G_MB_LIB.T6G(SCH_1):M_G_CPU1_SA_DQS_DP(9)
 AJ3 M_G_CPU1_SA_DQ<31> MGA_DATA31 @T6G_MB_LIB.T6G(SCH_1):M_G_CPU1_SA_DQ(31)
 AA2 M_G_CPU1_SA_DQ<20> MGA_DATA20 @T6G_MB_LIB.T6G(SCH_1):M_G_CPU1_SA_DQ(20)
 AJ2 M_G_CPU1_SA_CB<0> MGA_CHECK0 @T6G_MB_LIB.T6G(SCH_1):M_G_CPU1_SA_CB(0)
 DC3 M_G_CPU1_SB_DQS_DN<8> MGB_DQS_L8 @T6G_MB_LIB.T6G(SCH_1):M_G_CPU1_SB_DQS_DN(8)
 BY4 M_G_CPU1_SB_DQS_DP<4> MGB_DQS_H4 @T6G_MB_LIB.T6G(SCH_1):M_G_CPU1_SB_DQS_DP(4)
 CB2 M_G_CPU1_SB_DQ<0> MGB_DATA0 @T6G_MB_LIB.T6G(SCH_1):M_G_CPU1_SB_DQ(0)
 AB4 M_G_CPU1_SA_DQ<21> MGA_DATA21 @T6G_MB_LIB.T6G(SCH_1):M_G_CPU1_SA_DQ(21)
  M2 M_G_CPU1_SA_DQ<10> MGA_DATA10 @T6G_MB_LIB.T6G(SCH_1):M_G_CPU1_SA_DQ(10)
  E2 M_G_CPU1_SA_DQ<0> MGA_DATA0 @T6G_MB_LIB.T6G(SCH_1):M_G_CPU1_SA_DQ(0)
 AK4 M_G_CPU1_SA_CB<1> MGA_CHECK1 @T6G_MB_LIB.T6G(SCH_1):M_G_CPU1_SA_CB(1)
 BL3 M_G_CPU1_SB_PAR MGB_PAR @T6G_MB_LIB.T6G(SCH_1):M_G_CPU1_SB_PAR
 BV2 M_G_CPU1_SB_DQS_DP<9> MGB_DQS_H9 @T6G_MB_LIB.T6G(SCH_1):M_G_CPU1_SB_DQS_DP(9)
 BC3 M_G_CPU1_SA_PAR MGA_PAR @T6G_MB_LIB.T6G(SCH_1):M_G_CPU1_SA_PAR
 BC2 M_G_CPU1_CLK_DP<0> MG0_CLK_H @T6G_MB_LIB.T6G(SCH_1):M_G_CPU1_CLK_DP(0)
 BD2 M_G_CPU1_CLK_DN<0> MG0_CLK_L @T6G_MB_LIB.T6G(SCH_1):M_G_CPU1_CLK_DN(0)
 BF2     NC MG1_CLK_H     NC
 BG2     NC MG1_CLK_L     NC
 BF4 TP_M_G_CPU1_SA_TEST39G TEST39G @T6G_MB_LIB.T6G(SCH_1):TP_M_G_CPU1_SA_TEST39G

Q_RES_0402LF-15,1%,1/16W,CHIP,CS01502FB03  I322  R506
   1 M_G_CPU1_ALERT_N      A @T6G_MB_LIB.T6G(SCH_1):M_G_CPU1_ALERT_N
   2 M_G_CPU1_ALERT_R_N      B @T6G_MB_LIB.T6G(SCH_1):M_G_CPU1_ALERT_R_N


DRAWING: @T6G_MB_LIB.T6G(SCH_1):PAGE44 

GENOA_SP5-SOCKET6096_13568-001,SMLF,IO,DGA^6000030  I159  U26
AT14 M_H_CPU1_ALERT_R_N MH_ALERT_L @T6G_MB_LIB.T6G(SCH_1):M_H_CPU1_ALERT_R_N
AU14 M_H_CPU1_RESET_N MH_RESET_L @T6G_MB_LIB.T6G(SCH_1):M_H_CPU1_RESET_N
DF14 M_H_CPU1_SB_DQ<31> MHB_DATA31 @T6G_MB_LIB.T6G(SCH_1):M_H_CPU1_SB_DQ(31)
CV13 M_H_CPU1_SB_DQ<20> MHB_DATA20 @T6G_MB_LIB.T6G(SCH_1):M_H_CPU1_SB_DQ(20)
BY13 M_H_CPU1_SB_CB<0> MHB_CHECK0 @T6G_MB_LIB.T6G(SCH_1):M_H_CPU1_SB_CB(0)
BM13     NC MHB1_CS_L1     NC
 Y13 M_H_CPU1_SA_DQS_DN<2> MHA_DQS_L2 @T6G_MB_LIB.T6G(SCH_1):M_H_CPU1_SA_DQS_DN(2)
AD13 M_H_CPU1_SA_DQ<26> MHA_DATA26 @T6G_MB_LIB.T6G(SCH_1):M_H_CPU1_SA_DQ(26)
 U14 M_H_CPU1_SA_DQ<15> MHA_DATA15 @T6G_MB_LIB.T6G(SCH_1):M_H_CPU1_SA_DQ(15)
AP13 M_H_CPU1_SA_CB<6> MHA_CHECK6 @T6G_MB_LIB.T6G(SCH_1):M_H_CPU1_SA_CB(6)
CW14 M_H_CPU1_SB_DQ<21> MHB_DATA21 @T6G_MB_LIB.T6G(SCH_1):M_H_CPU1_SB_DQ(21)
CJ12 M_H_CPU1_SB_DQ<10> MHB_DATA10 @T6G_MB_LIB.T6G(SCH_1):M_H_CPU1_SB_DQ(10)
CA14 M_H_CPU1_SB_CB<1> MHB_CHECK1 @T6G_MB_LIB.T6G(SCH_1):M_H_CPU1_SB_CB(1)
AF13 M_H_CPU1_SA_DQS_DN<3> MHA_DQS_L3 @T6G_MB_LIB.T6G(SCH_1):M_H_CPU1_SA_DQS_DN(3)
AE14 M_H_CPU1_SA_DQ<27> MHA_DATA27 @T6G_MB_LIB.T6G(SCH_1):M_H_CPU1_SA_DQ(27)
 U12 M_H_CPU1_SA_DQ<16> MHA_DATA16 @T6G_MB_LIB.T6G(SCH_1):M_H_CPU1_SA_DQ(16)
AR14 M_H_CPU1_SA_CB<7> MHA_CHECK7 @T6G_MB_LIB.T6G(SCH_1):M_H_CPU1_SA_CB(7)
BN14 M_H_CPU1_SA_RSP<0> MHA0_RSP_L @T6G_MB_LIB.T6G(SCH_1):M_H_CPU1_SA_RSP(0)
CW12 M_H_CPU1_SB_DQ<22> MHB_DATA22 @T6G_MB_LIB.T6G(SCH_1):M_H_CPU1_SB_DQ(22)
CK14 M_H_CPU1_SB_DQ<11> MHB_DATA11 @T6G_MB_LIB.T6G(SCH_1):M_H_CPU1_SB_DQ(11)
CA12 M_H_CPU1_SB_CB<2> MHB_CHECK2 @T6G_MB_LIB.T6G(SCH_1):M_H_CPU1_SB_CB(2)
AM13 M_H_CPU1_SA_DQS_DN<4> MHA_DQS_L4 @T6G_MB_LIB.T6G(SCH_1):M_H_CPU1_SA_DQS_DN(4)
 G12 M_H_CPU1_SA_DQS_DP<0> MHA_DQS_H0 @T6G_MB_LIB.T6G(SCH_1):M_H_CPU1_SA_DQS_DP(0)
AG12 M_H_CPU1_SA_DQ<28> MHA_DATA28 @T6G_MB_LIB.T6G(SCH_1):M_H_CPU1_SA_DQ(28)
 V14 M_H_CPU1_SA_DQ<17> MHA_DATA17 @T6G_MB_LIB.T6G(SCH_1):M_H_CPU1_SA_DQ(17)
AW12 M_H_CPU1_SA_CA<0> MHA_CA0 @T6G_MB_LIB.T6G(SCH_1):M_H_CPU1_SA_CA(0)
BP14     NC MHA1_RSP_L     NC
CY14 M_H_CPU1_SB_DQ<23> MHB_DATA23 @T6G_MB_LIB.T6G(SCH_1):M_H_CPU1_SB_DQ(23)
CM13 M_H_CPU1_SB_DQ<12> MHB_DATA12 @T6G_MB_LIB.T6G(SCH_1):M_H_CPU1_SB_DQ(12)
CB14 M_H_CPU1_SB_CB<3> MHB_CHECK3 @T6G_MB_LIB.T6G(SCH_1):M_H_CPU1_SB_CB(3)
BG14 M_H_CPU1_SB_CA<0> MHB_CA0 @T6G_MB_LIB.T6G(SCH_1):M_H_CPU1_SB_CA(0)
 H14 M_H_CPU1_SA_DQS_DN<5> MHA_DQS_L5 @T6G_MB_LIB.T6G(SCH_1):M_H_CPU1_SA_DQS_DN(5)
 N12 M_H_CPU1_SA_DQS_DP<1> MHA_DQS_H1 @T6G_MB_LIB.T6G(SCH_1):M_H_CPU1_SA_DQS_DP(1)
AH14 M_H_CPU1_SA_DQ<29> MHA_DATA29 @T6G_MB_LIB.T6G(SCH_1):M_H_CPU1_SA_DQ(29)
 V13 M_H_CPU1_SA_DQ<18> MHA_DATA18 @T6G_MB_LIB.T6G(SCH_1):M_H_CPU1_SA_DQ(18)
AY13 M_H_CPU1_SA_CA<1> MHA_CA1 @T6G_MB_LIB.T6G(SCH_1):M_H_CPU1_SA_CA(1)
CE12 M_H_CPU1_SB_DQS_DN<0> MHB_DQS_L0 @T6G_MB_LIB.T6G(SCH_1):M_H_CPU1_SB_DQS_DN(0)
CY13 M_H_CPU1_SB_DQ<24> MHB_DATA24 @T6G_MB_LIB.T6G(SCH_1):M_H_CPU1_SB_DQ(24)
CN14 M_H_CPU1_SB_DQ<13> MHB_DATA13 @T6G_MB_LIB.T6G(SCH_1):M_H_CPU1_SB_DQ(13)
BT13 M_H_CPU1_SB_CB<4> MHB_CHECK4 @T6G_MB_LIB.T6G(SCH_1):M_H_CPU1_SB_CB(4)
BH14 M_H_CPU1_SB_CA<1> MHB_CA1 @T6G_MB_LIB.T6G(SCH_1):M_H_CPU1_SB_CA(1)
 P14 M_H_CPU1_SA_DQS_DN<6> MHA_DQS_L6 @T6G_MB_LIB.T6G(SCH_1):M_H_CPU1_SA_DQS_DN(6)
 W12 M_H_CPU1_SA_DQS_DP<2> MHA_DQS_H2 @T6G_MB_LIB.T6G(SCH_1):M_H_CPU1_SA_DQS_DP(2)
 W14 M_H_CPU1_SA_DQ<19> MHA_DATA19 @T6G_MB_LIB.T6G(SCH_1):M_H_CPU1_SA_DQ(19)
AY14 M_H_CPU1_SA_CA<2> MHA_CA2 @T6G_MB_LIB.T6G(SCH_1):M_H_CPU1_SA_CA(2)
CL12 M_H_CPU1_SB_DQS_DN<1> MHB_DQS_L1 @T6G_MB_LIB.T6G(SCH_1):M_H_CPU1_SB_DQS_DN(1)
DA14 M_H_CPU1_SB_DQ<25> MHB_DATA25 @T6G_MB_LIB.T6G(SCH_1):M_H_CPU1_SB_DQ(25)
CN12 M_H_CPU1_SB_DQ<14> MHB_DATA14 @T6G_MB_LIB.T6G(SCH_1):M_H_CPU1_SB_DQ(14)
CB13 M_H_CPU1_SB_DQ<0> MHB_DATA0 @T6G_MB_LIB.T6G(SCH_1):M_H_CPU1_SB_DQ(0)
BU14 M_H_CPU1_SB_CB<5> MHB_CHECK5 @T6G_MB_LIB.T6G(SCH_1):M_H_CPU1_SB_CB(5)
BH13 M_H_CPU1_SB_CA<2> MHB_CA2 @T6G_MB_LIB.T6G(SCH_1):M_H_CPU1_SB_CA(2)
 Y14 M_H_CPU1_SA_DQS_DN<7> MHA_DQS_L7 @T6G_MB_LIB.T6G(SCH_1):M_H_CPU1_SA_DQS_DN(7)
AE12 M_H_CPU1_SA_DQS_DP<3> MHA_DQS_H3 @T6G_MB_LIB.T6G(SCH_1):M_H_CPU1_SA_DQS_DP(3)
 E12 M_H_CPU1_SA_DQ<0> MHA_DATA0 @T6G_MB_LIB.T6G(SCH_1):M_H_CPU1_SA_DQ(0)
BA14 M_H_CPU1_SA_CA<3> MHA_CA3 @T6G_MB_LIB.T6G(SCH_1):M_H_CPU1_SA_CA(3)
CU12 M_H_CPU1_SB_DQS_DN<2> MHB_DQS_L2 @T6G_MB_LIB.T6G(SCH_1):M_H_CPU1_SB_DQS_DN(2)
DA12 M_H_CPU1_SB_DQ<26> MHB_DATA26 @T6G_MB_LIB.T6G(SCH_1):M_H_CPU1_SB_DQ(26)
CP14 M_H_CPU1_SB_DQ<15> MHB_DATA15 @T6G_MB_LIB.T6G(SCH_1):M_H_CPU1_SB_DQ(15)
CC14 M_H_CPU1_SB_DQ<1> MHB_DATA1 @T6G_MB_LIB.T6G(SCH_1):M_H_CPU1_SB_DQ(1)
BU12 M_H_CPU1_SB_CB<6> MHB_CHECK6 @T6G_MB_LIB.T6G(SCH_1):M_H_CPU1_SB_CB(6)
BJ12 M_H_CPU1_SB_CA<3> MHB_CA3 @T6G_MB_LIB.T6G(SCH_1):M_H_CPU1_SB_CA(3)
AF14 M_H_CPU1_SA_DQS_DN<8> MHA_DQS_L8 @T6G_MB_LIB.T6G(SCH_1):M_H_CPU1_SA_DQS_DN(8)
AL12 M_H_CPU1_SA_DQS_DP<4> MHA_DQS_H4 @T6G_MB_LIB.T6G(SCH_1):M_H_CPU1_SA_DQS_DP(4)
 F14 M_H_CPU1_SA_DQ<1> MHA_DATA1 @T6G_MB_LIB.T6G(SCH_1):M_H_CPU1_SA_DQ(1)
BA12 M_H_CPU1_SA_CA<4> MHA_CA4 @T6G_MB_LIB.T6G(SCH_1):M_H_CPU1_SA_CA(4)
DC12 M_H_CPU1_SB_DQS_DN<3> MHB_DQS_L3 @T6G_MB_LIB.T6G(SCH_1):M_H_CPU1_SB_DQS_DN(3)
DB14 M_H_CPU1_SB_DQ<27> MHB_DATA27 @T6G_MB_LIB.T6G(SCH_1):M_H_CPU1_SB_DQ(27)
CP13 M_H_CPU1_SB_DQ<16> MHB_DATA16 @T6G_MB_LIB.T6G(SCH_1):M_H_CPU1_SB_DQ(16)
CC12 M_H_CPU1_SB_DQ<2> MHB_DATA2 @T6G_MB_LIB.T6G(SCH_1):M_H_CPU1_SB_DQ(2)
BV14 M_H_CPU1_SB_CB<7> MHB_CHECK7 @T6G_MB_LIB.T6G(SCH_1):M_H_CPU1_SB_CB(7)
BJ14 M_H_CPU1_SB_CA<4> MHB_CA4 @T6G_MB_LIB.T6G(SCH_1):M_H_CPU1_SB_CA(4)
BP13 M_H_CPU1_SB_RSP<0> MHB0_RSP_L @T6G_MB_LIB.T6G(SCH_1):M_H_CPU1_SB_RSP(0)
AM14 M_H_CPU1_SA_DQS_DN<9> MHA_DQS_L9 @T6G_MB_LIB.T6G(SCH_1):M_H_CPU1_SA_DQS_DN(9)
 J14 M_H_CPU1_SA_DQS_DP<5> MHA_DQS_H5 @T6G_MB_LIB.T6G(SCH_1):M_H_CPU1_SA_DQS_DP(5)
 F13 M_H_CPU1_SA_DQ<2> MHA_DATA2 @T6G_MB_LIB.T6G(SCH_1):M_H_CPU1_SA_DQ(2)
BB13 M_H_CPU1_SA_CA<5> MHA_CA5 @T6G_MB_LIB.T6G(SCH_1):M_H_CPU1_SA_CA(5)
BW14 M_H_CPU1_SB_DQS_DN<4> MHB_DQS_L4 @T6G_MB_LIB.T6G(SCH_1):M_H_CPU1_SB_DQS_DN(4)
CD13 M_H_CPU1_SB_DQS_DP<0> MHB_DQS_H0 @T6G_MB_LIB.T6G(SCH_1):M_H_CPU1_SB_DQS_DP(0)
DD13 M_H_CPU1_SB_DQ<28> MHB_DATA28 @T6G_MB_LIB.T6G(SCH_1):M_H_CPU1_SB_DQ(28)
CR14 M_H_CPU1_SB_DQ<17> MHB_DATA17 @T6G_MB_LIB.T6G(SCH_1):M_H_CPU1_SB_DQ(17)
CD14 M_H_CPU1_SB_DQ<3> MHB_DATA3 @T6G_MB_LIB.T6G(SCH_1):M_H_CPU1_SB_DQ(3)
BK14 M_H_CPU1_SB_CA<5> MHB_CA5 @T6G_MB_LIB.T6G(SCH_1):M_H_CPU1_SB_CA(5)
BR12     NC MHB1_RSP_L     NC
 R14 M_H_CPU1_SA_DQS_DP<6> MHA_DQS_H6 @T6G_MB_LIB.T6G(SCH_1):M_H_CPU1_SA_DQS_DP(6)
 G14 M_H_CPU1_SA_DQ<3> MHA_DATA3 @T6G_MB_LIB.T6G(SCH_1):M_H_CPU1_SA_DQ(3)
BB14 M_H_CPU1_SA_CA<6> MHA_CA6 @T6G_MB_LIB.T6G(SCH_1):M_H_CPU1_SA_CA(6)
CE14 M_H_CPU1_SB_DQS_DN<5> MHB_DQS_L5 @T6G_MB_LIB.T6G(SCH_1):M_H_CPU1_SB_DQS_DN(5)
CK13 M_H_CPU1_SB_DQS_DP<1> MHB_DQS_H1 @T6G_MB_LIB.T6G(SCH_1):M_H_CPU1_SB_DQS_DP(1)
DE14 M_H_CPU1_SB_DQ<29> MHB_DATA29 @T6G_MB_LIB.T6G(SCH_1):M_H_CPU1_SB_DQ(29)
CR12 M_H_CPU1_SB_DQ<18> MHB_DATA18 @T6G_MB_LIB.T6G(SCH_1):M_H_CPU1_SB_DQ(18)
CF13 M_H_CPU1_SB_DQ<4> MHB_DATA4 @T6G_MB_LIB.T6G(SCH_1):M_H_CPU1_SB_DQ(4)
BK13 M_H_CPU1_SB_CA<6> MHB_CA6 @T6G_MB_LIB.T6G(SCH_1):M_H_CPU1_SB_CA(6)
AA14 M_H_CPU1_SA_DQS_DP<7> MHA_DQS_H7 @T6G_MB_LIB.T6G(SCH_1):M_H_CPU1_SA_DQS_DP(7)
 J12 M_H_CPU1_SA_DQ<4> MHA_DATA4 @T6G_MB_LIB.T6G(SCH_1):M_H_CPU1_SA_DQ(4)
AU12 M_H_CPU1_SA_CS_N<0> MHA0_CS_L0 @T6G_MB_LIB.T6G(SCH_1):M_H_CPU1_SA_CS_N(0)
CL14 M_H_CPU1_SB_DQS_DN<6> MHB_DQS_L6 @T6G_MB_LIB.T6G(SCH_1):M_H_CPU1_SB_DQS_DN(6)
CT13 M_H_CPU1_SB_DQS_DP<2> MHB_DQS_H2 @T6G_MB_LIB.T6G(SCH_1):M_H_CPU1_SB_DQS_DP(2)
CT14 M_H_CPU1_SB_DQ<19> MHB_DATA19 @T6G_MB_LIB.T6G(SCH_1):M_H_CPU1_SB_DQ(19)
CG14 M_H_CPU1_SB_DQ<5> MHB_DATA5 @T6G_MB_LIB.T6G(SCH_1):M_H_CPU1_SB_DQ(5)
AG14 M_H_CPU1_SA_DQS_DP<8> MHA_DQS_H8 @T6G_MB_LIB.T6G(SCH_1):M_H_CPU1_SA_DQS_DP(8)
AH13 M_H_CPU1_SA_DQ<30> MHA_DATA30 @T6G_MB_LIB.T6G(SCH_1):M_H_CPU1_SA_DQ(30)
 K14 M_H_CPU1_SA_DQ<5> MHA_DATA5 @T6G_MB_LIB.T6G(SCH_1):M_H_CPU1_SA_DQ(5)
AV13     NC MHA1_CS_L0     NC
AV14 M_H_CPU1_SA_CS_N<1> MHA0_CS_L1 @T6G_MB_LIB.T6G(SCH_1):M_H_CPU1_SA_CS_N(1)
CU14 M_H_CPU1_SB_DQS_DN<7> MHB_DQS_L7 @T6G_MB_LIB.T6G(SCH_1):M_H_CPU1_SB_DQS_DN(7)
DB13 M_H_CPU1_SB_DQS_DP<3> MHB_DQS_H3 @T6G_MB_LIB.T6G(SCH_1):M_H_CPU1_SB_DQS_DP(3)
CG12 M_H_CPU1_SB_DQ<6> MHB_DATA6 @T6G_MB_LIB.T6G(SCH_1):M_H_CPU1_SB_DQ(6)
AN14 M_H_CPU1_SA_DQS_DP<9> MHA_DQS_H9 @T6G_MB_LIB.T6G(SCH_1):M_H_CPU1_SA_DQS_DP(9)
AJ14 M_H_CPU1_SA_DQ<31> MHA_DATA31 @T6G_MB_LIB.T6G(SCH_1):M_H_CPU1_SA_DQ(31)
AA12 M_H_CPU1_SA_DQ<20> MHA_DATA20 @T6G_MB_LIB.T6G(SCH_1):M_H_CPU1_SA_DQ(20)
 K13 M_H_CPU1_SA_DQ<6> MHA_DATA6 @T6G_MB_LIB.T6G(SCH_1):M_H_CPU1_SA_DQ(6)
AJ12 M_H_CPU1_SA_CB<0> MHA_CHECK0 @T6G_MB_LIB.T6G(SCH_1):M_H_CPU1_SA_CB(0)
AW14     NC MHA1_CS_L1     NC
DC14 M_H_CPU1_SB_DQS_DN<8> MHB_DQS_L8 @T6G_MB_LIB.T6G(SCH_1):M_H_CPU1_SB_DQS_DN(8)
BY14 M_H_CPU1_SB_DQS_DP<4> MHB_DQS_H4 @T6G_MB_LIB.T6G(SCH_1):M_H_CPU1_SB_DQS_DP(4)
CH14 M_H_CPU1_SB_DQ<7> MHB_DATA7 @T6G_MB_LIB.T6G(SCH_1):M_H_CPU1_SB_DQ(7)
AB14 M_H_CPU1_SA_DQ<21> MHA_DATA21 @T6G_MB_LIB.T6G(SCH_1):M_H_CPU1_SA_DQ(21)
 M13 M_H_CPU1_SA_DQ<10> MHA_DATA10 @T6G_MB_LIB.T6G(SCH_1):M_H_CPU1_SA_DQ(10)
 L14 M_H_CPU1_SA_DQ<7> MHA_DATA7 @T6G_MB_LIB.T6G(SCH_1):M_H_CPU1_SA_DQ(7)
AK14 M_H_CPU1_SA_CB<1> MHA_CHECK1 @T6G_MB_LIB.T6G(SCH_1):M_H_CPU1_SA_CB(1)
BW12 M_H_CPU1_SB_DQS_DN<9> MHB_DQS_L9 @T6G_MB_LIB.T6G(SCH_1):M_H_CPU1_SB_DQS_DN(9)
CF14 M_H_CPU1_SB_DQS_DP<5> MHB_DQS_H5 @T6G_MB_LIB.T6G(SCH_1):M_H_CPU1_SB_DQS_DP(5)
CH13 M_H_CPU1_SB_DQ<8> MHB_DATA8 @T6G_MB_LIB.T6G(SCH_1):M_H_CPU1_SB_DQ(8)
AB13 M_H_CPU1_SA_DQ<22> MHA_DATA22 @T6G_MB_LIB.T6G(SCH_1):M_H_CPU1_SA_DQ(22)
 N14 M_H_CPU1_SA_DQ<11> MHA_DATA11 @T6G_MB_LIB.T6G(SCH_1):M_H_CPU1_SA_DQ(11)
 L12 M_H_CPU1_SA_DQ<8> MHA_DATA8 @T6G_MB_LIB.T6G(SCH_1):M_H_CPU1_SA_DQ(8)
AK13 M_H_CPU1_SA_CB<2> MHA_CHECK2 @T6G_MB_LIB.T6G(SCH_1):M_H_CPU1_SA_CB(2)
CM14 M_H_CPU1_SB_DQS_DP<6> MHB_DQS_H6 @T6G_MB_LIB.T6G(SCH_1):M_H_CPU1_SB_DQS_DP(6)
CJ14 M_H_CPU1_SB_DQ<9> MHB_DATA9 @T6G_MB_LIB.T6G(SCH_1):M_H_CPU1_SB_DQ(9)
AC14 M_H_CPU1_SA_DQ<23> MHA_DATA23 @T6G_MB_LIB.T6G(SCH_1):M_H_CPU1_SA_DQ(23)
 R12 M_H_CPU1_SA_DQ<12> MHA_DATA12 @T6G_MB_LIB.T6G(SCH_1):M_H_CPU1_SA_DQ(12)
 M14 M_H_CPU1_SA_DQ<9> MHA_DATA9 @T6G_MB_LIB.T6G(SCH_1):M_H_CPU1_SA_DQ(9)
AL14 M_H_CPU1_SA_CB<3> MHA_CHECK3 @T6G_MB_LIB.T6G(SCH_1):M_H_CPU1_SA_CB(3)
CV14 M_H_CPU1_SB_DQS_DP<7> MHB_DQS_H7 @T6G_MB_LIB.T6G(SCH_1):M_H_CPU1_SB_DQS_DP(7)
BM14 M_H_CPU1_SB_CS_N<0> MHB0_CS_L0 @T6G_MB_LIB.T6G(SCH_1):M_H_CPU1_SB_CS_N(0)
 H13 M_H_CPU1_SA_DQS_DN<0> MHA_DQS_L0 @T6G_MB_LIB.T6G(SCH_1):M_H_CPU1_SA_DQS_DN(0)
AC12 M_H_CPU1_SA_DQ<24> MHA_DATA24 @T6G_MB_LIB.T6G(SCH_1):M_H_CPU1_SA_DQ(24)
 T14 M_H_CPU1_SA_DQ<13> MHA_DATA13 @T6G_MB_LIB.T6G(SCH_1):M_H_CPU1_SA_DQ(13)
AN12 M_H_CPU1_SA_CB<4> MHA_CHECK4 @T6G_MB_LIB.T6G(SCH_1):M_H_CPU1_SA_CB(4)
DD14 M_H_CPU1_SB_DQS_DP<8> MHB_DQS_H8 @T6G_MB_LIB.T6G(SCH_1):M_H_CPU1_SB_DQS_DP(8)
DE12 M_H_CPU1_SB_DQ<30> MHB_DATA30 @T6G_MB_LIB.T6G(SCH_1):M_H_CPU1_SB_DQ(30)
BL12     NC MHB1_CS_L0     NC
BN12 M_H_CPU1_SB_CS_N<1> MHB0_CS_L1 @T6G_MB_LIB.T6G(SCH_1):M_H_CPU1_SB_CS_N(1)
 P13 M_H_CPU1_SA_DQS_DN<1> MHA_DQS_L1 @T6G_MB_LIB.T6G(SCH_1):M_H_CPU1_SA_DQS_DN(1)
AD14 M_H_CPU1_SA_DQ<25> MHA_DATA25 @T6G_MB_LIB.T6G(SCH_1):M_H_CPU1_SA_DQ(25)
 T13 M_H_CPU1_SA_DQ<14> MHA_DATA14 @T6G_MB_LIB.T6G(SCH_1):M_H_CPU1_SA_DQ(14)
AP14 M_H_CPU1_SA_CB<5> MHA_CHECK5 @T6G_MB_LIB.T6G(SCH_1):M_H_CPU1_SA_CB(5)
BV13 M_H_CPU1_SB_DQS_DP<9> MHB_DQS_H9 @T6G_MB_LIB.T6G(SCH_1):M_H_CPU1_SB_DQS_DP(9)
BC14 M_H_CPU1_SA_PAR MHA_PAR @T6G_MB_LIB.T6G(SCH_1):M_H_CPU1_SA_PAR
BL14 M_H_CPU1_SB_PAR MHB_PAR @T6G_MB_LIB.T6G(SCH_1):M_H_CPU1_SB_PAR
BC12 M_H_CPU1_CLK_DP<0> MH0_CLK_H @T6G_MB_LIB.T6G(SCH_1):M_H_CPU1_CLK_DP(0)
BD13 M_H_CPU1_CLK_DN<0> MH0_CLK_L @T6G_MB_LIB.T6G(SCH_1):M_H_CPU1_CLK_DN(0)
BF13     NC MH1_CLK_H     NC
BG12     NC MH1_CLK_L     NC
BF14 TP_M_H_CPU1_SA_TEST39H TEST39H @T6G_MB_LIB.T6G(SCH_1):TP_M_H_CPU1_SA_TEST39H

Q_RES_0402LF-15,1%,1/16W,CHIP,CS01502FB03  I314  R507
   1 M_H_CPU1_ALERT_N      A @T6G_MB_LIB.T6G(SCH_1):M_H_CPU1_ALERT_N
   2 M_H_CPU1_ALERT_R_N      B @T6G_MB_LIB.T6G(SCH_1):M_H_CPU1_ALERT_R_N


DRAWING: @T6G_MB_LIB.T6G(SCH_1):PAGE45 

GENOA_SP5-SOCKET6096_13568-001,SMLF,IO,DGA^6000030  I159  U26
CY21 M_I_CPU1_SB_DQ<23> MIB_DATA23 @T6G_MB_LIB.T6G(SCH_1):M_I_CPU1_SB_DQ(23)
CM20 M_I_CPU1_SB_DQ<12> MIB_DATA12 @T6G_MB_LIB.T6G(SCH_1):M_I_CPU1_SB_DQ(12)
CG19 M_I_CPU1_SB_DQ<6> MIB_DATA6 @T6G_MB_LIB.T6G(SCH_1):M_I_CPU1_SB_DQ(6)
CB21 M_I_CPU1_SB_CB<3> MIB_CHECK3 @T6G_MB_LIB.T6G(SCH_1):M_I_CPU1_SB_CB(3)
 H21 M_I_CPU1_SA_DQS_DN<5> MIA_DQS_L5 @T6G_MB_LIB.T6G(SCH_1):M_I_CPU1_SA_DQS_DN(5)
 N19 M_I_CPU1_SA_DQS_DP<1> MIA_DQS_H1 @T6G_MB_LIB.T6G(SCH_1):M_I_CPU1_SA_DQS_DP(1)
AH21 M_I_CPU1_SA_DQ<29> MIA_DATA29 @T6G_MB_LIB.T6G(SCH_1):M_I_CPU1_SA_DQ(29)
 V20 M_I_CPU1_SA_DQ<18> MIA_DATA18 @T6G_MB_LIB.T6G(SCH_1):M_I_CPU1_SA_DQ(18)
 K20 M_I_CPU1_SA_DQ<6> MIA_DATA6 @T6G_MB_LIB.T6G(SCH_1):M_I_CPU1_SA_DQ(6)
CE19 M_I_CPU1_SB_DQS_DN<0> MIB_DQS_L0 @T6G_MB_LIB.T6G(SCH_1):M_I_CPU1_SB_DQS_DN(0)
CY20 M_I_CPU1_SB_DQ<24> MIB_DATA24 @T6G_MB_LIB.T6G(SCH_1):M_I_CPU1_SB_DQ(24)
CN21 M_I_CPU1_SB_DQ<13> MIB_DATA13 @T6G_MB_LIB.T6G(SCH_1):M_I_CPU1_SB_DQ(13)
CH21 M_I_CPU1_SB_DQ<7> MIB_DATA7 @T6G_MB_LIB.T6G(SCH_1):M_I_CPU1_SB_DQ(7)
BT20 M_I_CPU1_SB_CB<4> MIB_CHECK4 @T6G_MB_LIB.T6G(SCH_1):M_I_CPU1_SB_CB(4)
 P21 M_I_CPU1_SA_DQS_DN<6> MIA_DQS_L6 @T6G_MB_LIB.T6G(SCH_1):M_I_CPU1_SA_DQS_DN(6)
 W19 M_I_CPU1_SA_DQS_DP<2> MIA_DQS_H2 @T6G_MB_LIB.T6G(SCH_1):M_I_CPU1_SA_DQS_DP(2)
 W21 M_I_CPU1_SA_DQ<19> MIA_DATA19 @T6G_MB_LIB.T6G(SCH_1):M_I_CPU1_SA_DQ(19)
 L21 M_I_CPU1_SA_DQ<7> MIA_DATA7 @T6G_MB_LIB.T6G(SCH_1):M_I_CPU1_SA_DQ(7)
AW19 M_I_CPU1_SA_CA<0> MIA_CA0 @T6G_MB_LIB.T6G(SCH_1):M_I_CPU1_SA_CA(0)
CL19 M_I_CPU1_SB_DQS_DN<1> MIB_DQS_L1 @T6G_MB_LIB.T6G(SCH_1):M_I_CPU1_SB_DQS_DN(1)
DA21 M_I_CPU1_SB_DQ<25> MIB_DATA25 @T6G_MB_LIB.T6G(SCH_1):M_I_CPU1_SB_DQ(25)
CN19 M_I_CPU1_SB_DQ<14> MIB_DATA14 @T6G_MB_LIB.T6G(SCH_1):M_I_CPU1_SB_DQ(14)
CH20 M_I_CPU1_SB_DQ<8> MIB_DATA8 @T6G_MB_LIB.T6G(SCH_1):M_I_CPU1_SB_DQ(8)
BU21 M_I_CPU1_SB_CB<5> MIB_CHECK5 @T6G_MB_LIB.T6G(SCH_1):M_I_CPU1_SB_CB(5)
BG21 M_I_CPU1_SB_CA<0> MIB_CA0 @T6G_MB_LIB.T6G(SCH_1):M_I_CPU1_SB_CA(0)
 Y21 M_I_CPU1_SA_DQS_DN<7> MIA_DQS_L7 @T6G_MB_LIB.T6G(SCH_1):M_I_CPU1_SA_DQS_DN(7)
AE19 M_I_CPU1_SA_DQS_DP<3> MIA_DQS_H3 @T6G_MB_LIB.T6G(SCH_1):M_I_CPU1_SA_DQS_DP(3)
 L19 M_I_CPU1_SA_DQ<8> MIA_DATA8 @T6G_MB_LIB.T6G(SCH_1):M_I_CPU1_SA_DQ(8)
AY20 M_I_CPU1_SA_CA<1> MIA_CA1 @T6G_MB_LIB.T6G(SCH_1):M_I_CPU1_SA_CA(1)
CU19 M_I_CPU1_SB_DQS_DN<2> MIB_DQS_L2 @T6G_MB_LIB.T6G(SCH_1):M_I_CPU1_SB_DQS_DN(2)
DA19 M_I_CPU1_SB_DQ<26> MIB_DATA26 @T6G_MB_LIB.T6G(SCH_1):M_I_CPU1_SB_DQ(26)
CP21 M_I_CPU1_SB_DQ<15> MIB_DATA15 @T6G_MB_LIB.T6G(SCH_1):M_I_CPU1_SB_DQ(15)
CJ21 M_I_CPU1_SB_DQ<9> MIB_DATA9 @T6G_MB_LIB.T6G(SCH_1):M_I_CPU1_SB_DQ(9)
BU19 M_I_CPU1_SB_CB<6> MIB_CHECK6 @T6G_MB_LIB.T6G(SCH_1):M_I_CPU1_SB_CB(6)
BH21 M_I_CPU1_SB_CA<1> MIB_CA1 @T6G_MB_LIB.T6G(SCH_1):M_I_CPU1_SB_CA(1)
AF21 M_I_CPU1_SA_DQS_DN<8> MIA_DQS_L8 @T6G_MB_LIB.T6G(SCH_1):M_I_CPU1_SA_DQS_DN(8)
AL19 M_I_CPU1_SA_DQS_DP<4> MIA_DQS_H4 @T6G_MB_LIB.T6G(SCH_1):M_I_CPU1_SA_DQS_DP(4)
 M21 M_I_CPU1_SA_DQ<9> MIA_DATA9 @T6G_MB_LIB.T6G(SCH_1):M_I_CPU1_SA_DQ(9)
AY21 M_I_CPU1_SA_CA<2> MIA_CA2 @T6G_MB_LIB.T6G(SCH_1):M_I_CPU1_SA_CA(2)
DC19 M_I_CPU1_SB_DQS_DN<3> MIB_DQS_L3 @T6G_MB_LIB.T6G(SCH_1):M_I_CPU1_SB_DQS_DN(3)
DB21 M_I_CPU1_SB_DQ<27> MIB_DATA27 @T6G_MB_LIB.T6G(SCH_1):M_I_CPU1_SB_DQ(27)
CP20 M_I_CPU1_SB_DQ<16> MIB_DATA16 @T6G_MB_LIB.T6G(SCH_1):M_I_CPU1_SB_DQ(16)
BV21 M_I_CPU1_SB_CB<7> MIB_CHECK7 @T6G_MB_LIB.T6G(SCH_1):M_I_CPU1_SB_CB(7)
BH20 M_I_CPU1_SB_CA<2> MIB_CA2 @T6G_MB_LIB.T6G(SCH_1):M_I_CPU1_SB_CA(2)
BP20 M_I_CPU1_SB_RSP<0> MIB0_RSP_L @T6G_MB_LIB.T6G(SCH_1):M_I_CPU1_SB_RSP(0)
AM21 M_I_CPU1_SA_DQS_DN<9> MIA_DQS_L9 @T6G_MB_LIB.T6G(SCH_1):M_I_CPU1_SA_DQS_DN(9)
 J21 M_I_CPU1_SA_DQS_DP<5> MIA_DQS_H5 @T6G_MB_LIB.T6G(SCH_1):M_I_CPU1_SA_DQS_DP(5)
BA21 M_I_CPU1_SA_CA<3> MIA_CA3 @T6G_MB_LIB.T6G(SCH_1):M_I_CPU1_SA_CA(3)
BW21 M_I_CPU1_SB_DQS_DN<4> MIB_DQS_L4 @T6G_MB_LIB.T6G(SCH_1):M_I_CPU1_SB_DQS_DN(4)
CD20 M_I_CPU1_SB_DQS_DP<0> MIB_DQS_H0 @T6G_MB_LIB.T6G(SCH_1):M_I_CPU1_SB_DQS_DP(0)
DD20 M_I_CPU1_SB_DQ<28> MIB_DATA28 @T6G_MB_LIB.T6G(SCH_1):M_I_CPU1_SB_DQ(28)
CR21 M_I_CPU1_SB_DQ<17> MIB_DATA17 @T6G_MB_LIB.T6G(SCH_1):M_I_CPU1_SB_DQ(17)
BJ19 M_I_CPU1_SB_CA<3> MIB_CA3 @T6G_MB_LIB.T6G(SCH_1):M_I_CPU1_SB_CA(3)
BR19     NC MIB1_RSP_L     NC
 R21 M_I_CPU1_SA_DQS_DP<6> MIA_DQS_H6 @T6G_MB_LIB.T6G(SCH_1):M_I_CPU1_SA_DQS_DP(6)
BA19 M_I_CPU1_SA_CA<4> MIA_CA4 @T6G_MB_LIB.T6G(SCH_1):M_I_CPU1_SA_CA(4)
CE21 M_I_CPU1_SB_DQS_DN<5> MIB_DQS_L5 @T6G_MB_LIB.T6G(SCH_1):M_I_CPU1_SB_DQS_DN(5)
CK20 M_I_CPU1_SB_DQS_DP<1> MIB_DQS_H1 @T6G_MB_LIB.T6G(SCH_1):M_I_CPU1_SB_DQS_DP(1)
DE21 M_I_CPU1_SB_DQ<29> MIB_DATA29 @T6G_MB_LIB.T6G(SCH_1):M_I_CPU1_SB_DQ(29)
CR19 M_I_CPU1_SB_DQ<18> MIB_DATA18 @T6G_MB_LIB.T6G(SCH_1):M_I_CPU1_SB_DQ(18)
BJ21 M_I_CPU1_SB_CA<4> MIB_CA4 @T6G_MB_LIB.T6G(SCH_1):M_I_CPU1_SB_CA(4)
AA21 M_I_CPU1_SA_DQS_DP<7> MIA_DQS_H7 @T6G_MB_LIB.T6G(SCH_1):M_I_CPU1_SA_DQS_DP(7)
BB20 M_I_CPU1_SA_CA<5> MIA_CA5 @T6G_MB_LIB.T6G(SCH_1):M_I_CPU1_SA_CA(5)
AV20     NC MIA1_CS_L0     NC
AU19 M_I_CPU1_SA_CS_N<0> MIA0_CS_L0 @T6G_MB_LIB.T6G(SCH_1):M_I_CPU1_SA_CS_N(0)
BF20     NC MI1_CLK_H     NC
BC19 M_I_CPU1_CLK_DP<0> MI0_CLK_H @T6G_MB_LIB.T6G(SCH_1):M_I_CPU1_CLK_DP(0)
CL21 M_I_CPU1_SB_DQS_DN<6> MIB_DQS_L6 @T6G_MB_LIB.T6G(SCH_1):M_I_CPU1_SB_DQS_DN(6)
CT20 M_I_CPU1_SB_DQS_DP<2> MIB_DQS_H2 @T6G_MB_LIB.T6G(SCH_1):M_I_CPU1_SB_DQS_DP(2)
CT21 M_I_CPU1_SB_DQ<19> MIB_DATA19 @T6G_MB_LIB.T6G(SCH_1):M_I_CPU1_SB_DQ(19)
BK21 M_I_CPU1_SB_CA<5> MIB_CA5 @T6G_MB_LIB.T6G(SCH_1):M_I_CPU1_SB_CA(5)
AG21 M_I_CPU1_SA_DQS_DP<8> MIA_DQS_H8 @T6G_MB_LIB.T6G(SCH_1):M_I_CPU1_SA_DQS_DP(8)
AH20 M_I_CPU1_SA_DQ<30> MIA_DATA30 @T6G_MB_LIB.T6G(SCH_1):M_I_CPU1_SA_DQ(30)
BB21 M_I_CPU1_SA_CA<6> MIA_CA6 @T6G_MB_LIB.T6G(SCH_1):M_I_CPU1_SA_CA(6)
AW21     NC MIA1_CS_L1     NC
AV21 M_I_CPU1_SA_CS_N<1> MIA0_CS_L1 @T6G_MB_LIB.T6G(SCH_1):M_I_CPU1_SA_CS_N(1)
CU21 M_I_CPU1_SB_DQS_DN<7> MIB_DQS_L7 @T6G_MB_LIB.T6G(SCH_1):M_I_CPU1_SB_DQS_DN(7)
DB20 M_I_CPU1_SB_DQS_DP<3> MIB_DQS_H3 @T6G_MB_LIB.T6G(SCH_1):M_I_CPU1_SB_DQS_DP(3)
BK20 M_I_CPU1_SB_CA<6> MIB_CA6 @T6G_MB_LIB.T6G(SCH_1):M_I_CPU1_SB_CA(6)
AN21 M_I_CPU1_SA_DQS_DP<9> MIA_DQS_H9 @T6G_MB_LIB.T6G(SCH_1):M_I_CPU1_SA_DQS_DP(9)
AJ21 M_I_CPU1_SA_DQ<31> MIA_DATA31 @T6G_MB_LIB.T6G(SCH_1):M_I_CPU1_SA_DQ(31)
AA19 M_I_CPU1_SA_DQ<20> MIA_DATA20 @T6G_MB_LIB.T6G(SCH_1):M_I_CPU1_SA_DQ(20)
AJ19 M_I_CPU1_SA_CB<0> MIA_CHECK0 @T6G_MB_LIB.T6G(SCH_1):M_I_CPU1_SA_CB(0)
DC21 M_I_CPU1_SB_DQS_DN<8> MIB_DQS_L8 @T6G_MB_LIB.T6G(SCH_1):M_I_CPU1_SB_DQS_DN(8)
BY21 M_I_CPU1_SB_DQS_DP<4> MIB_DQS_H4 @T6G_MB_LIB.T6G(SCH_1):M_I_CPU1_SB_DQS_DP(4)
AB21 M_I_CPU1_SA_DQ<21> MIA_DATA21 @T6G_MB_LIB.T6G(SCH_1):M_I_CPU1_SA_DQ(21)
 M20 M_I_CPU1_SA_DQ<10> MIA_DATA10 @T6G_MB_LIB.T6G(SCH_1):M_I_CPU1_SA_DQ(10)
AK21 M_I_CPU1_SA_CB<1> MIA_CHECK1 @T6G_MB_LIB.T6G(SCH_1):M_I_CPU1_SA_CB(1)
BW19 M_I_CPU1_SB_DQS_DN<9> MIB_DQS_L9 @T6G_MB_LIB.T6G(SCH_1):M_I_CPU1_SB_DQS_DN(9)
CF21 M_I_CPU1_SB_DQS_DP<5> MIB_DQS_H5 @T6G_MB_LIB.T6G(SCH_1):M_I_CPU1_SB_DQS_DP(5)
AB20 M_I_CPU1_SA_DQ<22> MIA_DATA22 @T6G_MB_LIB.T6G(SCH_1):M_I_CPU1_SA_DQ(22)
 N21 M_I_CPU1_SA_DQ<11> MIA_DATA11 @T6G_MB_LIB.T6G(SCH_1):M_I_CPU1_SA_DQ(11)
AK20 M_I_CPU1_SA_CB<2> MIA_CHECK2 @T6G_MB_LIB.T6G(SCH_1):M_I_CPU1_SA_CB(2)
BG19     NC MI1_CLK_L     NC
BD20 M_I_CPU1_CLK_DN<0> MI0_CLK_L @T6G_MB_LIB.T6G(SCH_1):M_I_CPU1_CLK_DN(0)
AU21 M_I_CPU1_RESET_N MI_RESET_L @T6G_MB_LIB.T6G(SCH_1):M_I_CPU1_RESET_N
CM21 M_I_CPU1_SB_DQS_DP<6> MIB_DQS_H6 @T6G_MB_LIB.T6G(SCH_1):M_I_CPU1_SB_DQS_DP(6)
CB20 M_I_CPU1_SB_DQ<0> MIB_DATA0 @T6G_MB_LIB.T6G(SCH_1):M_I_CPU1_SB_DQ(0)
AC21 M_I_CPU1_SA_DQ<23> MIA_DATA23 @T6G_MB_LIB.T6G(SCH_1):M_I_CPU1_SA_DQ(23)
 R19 M_I_CPU1_SA_DQ<12> MIA_DATA12 @T6G_MB_LIB.T6G(SCH_1):M_I_CPU1_SA_DQ(12)
 E19 M_I_CPU1_SA_DQ<0> MIA_DATA0 @T6G_MB_LIB.T6G(SCH_1):M_I_CPU1_SA_DQ(0)
AL21 M_I_CPU1_SA_CB<3> MIA_CHECK3 @T6G_MB_LIB.T6G(SCH_1):M_I_CPU1_SA_CB(3)
CV21 M_I_CPU1_SB_DQS_DP<7> MIB_DQS_H7 @T6G_MB_LIB.T6G(SCH_1):M_I_CPU1_SB_DQS_DP(7)
CC21 M_I_CPU1_SB_DQ<1> MIB_DATA1 @T6G_MB_LIB.T6G(SCH_1):M_I_CPU1_SB_DQ(1)
BM21 M_I_CPU1_SB_CS_N<0> MIB0_CS_L0 @T6G_MB_LIB.T6G(SCH_1):M_I_CPU1_SB_CS_N(0)
 H20 M_I_CPU1_SA_DQS_DN<0> MIA_DQS_L0 @T6G_MB_LIB.T6G(SCH_1):M_I_CPU1_SA_DQS_DN(0)
AC19 M_I_CPU1_SA_DQ<24> MIA_DATA24 @T6G_MB_LIB.T6G(SCH_1):M_I_CPU1_SA_DQ(24)
 T21 M_I_CPU1_SA_DQ<13> MIA_DATA13 @T6G_MB_LIB.T6G(SCH_1):M_I_CPU1_SA_DQ(13)
 F21 M_I_CPU1_SA_DQ<1> MIA_DATA1 @T6G_MB_LIB.T6G(SCH_1):M_I_CPU1_SA_DQ(1)
AN19 M_I_CPU1_SA_CB<4> MIA_CHECK4 @T6G_MB_LIB.T6G(SCH_1):M_I_CPU1_SA_CB(4)
DD21 M_I_CPU1_SB_DQS_DP<8> MIB_DQS_H8 @T6G_MB_LIB.T6G(SCH_1):M_I_CPU1_SB_DQS_DP(8)
DE19 M_I_CPU1_SB_DQ<30> MIB_DATA30 @T6G_MB_LIB.T6G(SCH_1):M_I_CPU1_SB_DQ(30)
CC19 M_I_CPU1_SB_DQ<2> MIB_DATA2 @T6G_MB_LIB.T6G(SCH_1):M_I_CPU1_SB_DQ(2)
BL19     NC MIB1_CS_L0     NC
BN19 M_I_CPU1_SB_CS_N<1> MIB0_CS_L1 @T6G_MB_LIB.T6G(SCH_1):M_I_CPU1_SB_CS_N(1)
 P20 M_I_CPU1_SA_DQS_DN<1> MIA_DQS_L1 @T6G_MB_LIB.T6G(SCH_1):M_I_CPU1_SA_DQS_DN(1)
AD21 M_I_CPU1_SA_DQ<25> MIA_DATA25 @T6G_MB_LIB.T6G(SCH_1):M_I_CPU1_SA_DQ(25)
 T20 M_I_CPU1_SA_DQ<14> MIA_DATA14 @T6G_MB_LIB.T6G(SCH_1):M_I_CPU1_SA_DQ(14)
 F20 M_I_CPU1_SA_DQ<2> MIA_DATA2 @T6G_MB_LIB.T6G(SCH_1):M_I_CPU1_SA_DQ(2)
AP21 M_I_CPU1_SA_CB<5> MIA_CHECK5 @T6G_MB_LIB.T6G(SCH_1):M_I_CPU1_SA_CB(5)
BV20 M_I_CPU1_SB_DQS_DP<9> MIB_DQS_H9 @T6G_MB_LIB.T6G(SCH_1):M_I_CPU1_SB_DQS_DP(9)
DF21 M_I_CPU1_SB_DQ<31> MIB_DATA31 @T6G_MB_LIB.T6G(SCH_1):M_I_CPU1_SB_DQ(31)
CV20 M_I_CPU1_SB_DQ<20> MIB_DATA20 @T6G_MB_LIB.T6G(SCH_1):M_I_CPU1_SB_DQ(20)
CD21 M_I_CPU1_SB_DQ<3> MIB_DATA3 @T6G_MB_LIB.T6G(SCH_1):M_I_CPU1_SB_DQ(3)
BY20 M_I_CPU1_SB_CB<0> MIB_CHECK0 @T6G_MB_LIB.T6G(SCH_1):M_I_CPU1_SB_CB(0)
BM20     NC MIB1_CS_L1     NC
BC21 M_I_CPU1_SA_PAR MIA_PAR @T6G_MB_LIB.T6G(SCH_1):M_I_CPU1_SA_PAR
 Y20 M_I_CPU1_SA_DQS_DN<2> MIA_DQS_L2 @T6G_MB_LIB.T6G(SCH_1):M_I_CPU1_SA_DQS_DN(2)
AD20 M_I_CPU1_SA_DQ<26> MIA_DATA26 @T6G_MB_LIB.T6G(SCH_1):M_I_CPU1_SA_DQ(26)
 U21 M_I_CPU1_SA_DQ<15> MIA_DATA15 @T6G_MB_LIB.T6G(SCH_1):M_I_CPU1_SA_DQ(15)
 G21 M_I_CPU1_SA_DQ<3> MIA_DATA3 @T6G_MB_LIB.T6G(SCH_1):M_I_CPU1_SA_DQ(3)
AP20 M_I_CPU1_SA_CB<6> MIA_CHECK6 @T6G_MB_LIB.T6G(SCH_1):M_I_CPU1_SA_CB(6)
BL21 M_I_CPU1_SB_PAR MIB_PAR @T6G_MB_LIB.T6G(SCH_1):M_I_CPU1_SB_PAR
CW21 M_I_CPU1_SB_DQ<21> MIB_DATA21 @T6G_MB_LIB.T6G(SCH_1):M_I_CPU1_SB_DQ(21)
CJ19 M_I_CPU1_SB_DQ<10> MIB_DATA10 @T6G_MB_LIB.T6G(SCH_1):M_I_CPU1_SB_DQ(10)
CF20 M_I_CPU1_SB_DQ<4> MIB_DATA4 @T6G_MB_LIB.T6G(SCH_1):M_I_CPU1_SB_DQ(4)
CA21 M_I_CPU1_SB_CB<1> MIB_CHECK1 @T6G_MB_LIB.T6G(SCH_1):M_I_CPU1_SB_CB(1)
AF20 M_I_CPU1_SA_DQS_DN<3> MIA_DQS_L3 @T6G_MB_LIB.T6G(SCH_1):M_I_CPU1_SA_DQS_DN(3)
AE21 M_I_CPU1_SA_DQ<27> MIA_DATA27 @T6G_MB_LIB.T6G(SCH_1):M_I_CPU1_SA_DQ(27)
 U19 M_I_CPU1_SA_DQ<16> MIA_DATA16 @T6G_MB_LIB.T6G(SCH_1):M_I_CPU1_SA_DQ(16)
 J19 M_I_CPU1_SA_DQ<4> MIA_DATA4 @T6G_MB_LIB.T6G(SCH_1):M_I_CPU1_SA_DQ(4)
AR21 M_I_CPU1_SA_CB<7> MIA_CHECK7 @T6G_MB_LIB.T6G(SCH_1):M_I_CPU1_SA_CB(7)
BP21     NC MIA1_RSP_L     NC
BN21 M_I_CPU1_SA_RSP<0> MIA0_RSP_L @T6G_MB_LIB.T6G(SCH_1):M_I_CPU1_SA_RSP(0)
AT21 M_I_CPU1_ALERT_R_N MI_ALERT_L @T6G_MB_LIB.T6G(SCH_1):M_I_CPU1_ALERT_R_N
CW19 M_I_CPU1_SB_DQ<22> MIB_DATA22 @T6G_MB_LIB.T6G(SCH_1):M_I_CPU1_SB_DQ(22)
CK21 M_I_CPU1_SB_DQ<11> MIB_DATA11 @T6G_MB_LIB.T6G(SCH_1):M_I_CPU1_SB_DQ(11)
CG21 M_I_CPU1_SB_DQ<5> MIB_DATA5 @T6G_MB_LIB.T6G(SCH_1):M_I_CPU1_SB_DQ(5)
CA19 M_I_CPU1_SB_CB<2> MIB_CHECK2 @T6G_MB_LIB.T6G(SCH_1):M_I_CPU1_SB_CB(2)
AM20 M_I_CPU1_SA_DQS_DN<4> MIA_DQS_L4 @T6G_MB_LIB.T6G(SCH_1):M_I_CPU1_SA_DQS_DN(4)
 G19 M_I_CPU1_SA_DQS_DP<0> MIA_DQS_H0 @T6G_MB_LIB.T6G(SCH_1):M_I_CPU1_SA_DQS_DP(0)
AG19 M_I_CPU1_SA_DQ<28> MIA_DATA28 @T6G_MB_LIB.T6G(SCH_1):M_I_CPU1_SA_DQ(28)
 V21 M_I_CPU1_SA_DQ<17> MIA_DATA17 @T6G_MB_LIB.T6G(SCH_1):M_I_CPU1_SA_DQ(17)
 K21 M_I_CPU1_SA_DQ<5> MIA_DATA5 @T6G_MB_LIB.T6G(SCH_1):M_I_CPU1_SA_DQ(5)
BF21 TP_M_I_CPU1_SA_TEST39I TEST39I @T6G_MB_LIB.T6G(SCH_1):TP_M_I_CPU1_SA_TEST39I

Q_RES_0402LF-15,1%,1/16W,CHIP,CS01502FB03  I314  R508
   1 M_I_CPU1_ALERT_N      A @T6G_MB_LIB.T6G(SCH_1):M_I_CPU1_ALERT_N
   2 M_I_CPU1_ALERT_R_N      B @T6G_MB_LIB.T6G(SCH_1):M_I_CPU1_ALERT_R_N


DRAWING: @T6G_MB_LIB.T6G(SCH_1):PAGE46 

GENOA_SP5-SOCKET6096_13568-001,SMLF,IO,DGA^6000030  I159  U26
AU17 M_J_CPU1_RESET_N MJ_RESET_L @T6G_MB_LIB.T6G(SCH_1):M_J_CPU1_RESET_N
AT18 M_J_CPU1_ALERT_R_N MJ_ALERT_L @T6G_MB_LIB.T6G(SCH_1):M_J_CPU1_ALERT_R_N
BL17 M_J_CPU1_SB_PAR MJB_PAR @T6G_MB_LIB.T6G(SCH_1):M_J_CPU1_SB_PAR
BW16 M_J_CPU1_SB_DQS_DN<9> MJB_DQS_L9 @T6G_MB_LIB.T6G(SCH_1):M_J_CPU1_SB_DQS_DN(9)
DC17 M_J_CPU1_SB_DQS_DN<8> MJB_DQS_L8 @T6G_MB_LIB.T6G(SCH_1):M_J_CPU1_SB_DQS_DN(8)
CU17 M_J_CPU1_SB_DQS_DN<7> MJB_DQS_L7 @T6G_MB_LIB.T6G(SCH_1):M_J_CPU1_SB_DQS_DN(7)
CL17 M_J_CPU1_SB_DQS_DN<6> MJB_DQS_L6 @T6G_MB_LIB.T6G(SCH_1):M_J_CPU1_SB_DQS_DN(6)
CE17 M_J_CPU1_SB_DQS_DN<5> MJB_DQS_L5 @T6G_MB_LIB.T6G(SCH_1):M_J_CPU1_SB_DQS_DN(5)
DC16 M_J_CPU1_SB_DQS_DN<3> MJB_DQS_L3 @T6G_MB_LIB.T6G(SCH_1):M_J_CPU1_SB_DQS_DN(3)
CU16 M_J_CPU1_SB_DQS_DN<2> MJB_DQS_L2 @T6G_MB_LIB.T6G(SCH_1):M_J_CPU1_SB_DQS_DN(2)
CL16 M_J_CPU1_SB_DQS_DN<1> MJB_DQS_L1 @T6G_MB_LIB.T6G(SCH_1):M_J_CPU1_SB_DQS_DN(1)
BV16 M_J_CPU1_SB_DQS_DP<9> MJB_DQS_H9 @T6G_MB_LIB.T6G(SCH_1):M_J_CPU1_SB_DQS_DP(9)
DD18 M_J_CPU1_SB_DQS_DP<8> MJB_DQS_H8 @T6G_MB_LIB.T6G(SCH_1):M_J_CPU1_SB_DQS_DP(8)
CV18 M_J_CPU1_SB_DQS_DP<7> MJB_DQS_H7 @T6G_MB_LIB.T6G(SCH_1):M_J_CPU1_SB_DQS_DP(7)
CM18 M_J_CPU1_SB_DQS_DP<6> MJB_DQS_H6 @T6G_MB_LIB.T6G(SCH_1):M_J_CPU1_SB_DQS_DP(6)
BY18 M_J_CPU1_SB_DQS_DP<4> MJB_DQS_H4 @T6G_MB_LIB.T6G(SCH_1):M_J_CPU1_SB_DQS_DP(4)
DB16 M_J_CPU1_SB_DQS_DP<3> MJB_DQS_H3 @T6G_MB_LIB.T6G(SCH_1):M_J_CPU1_SB_DQS_DP(3)
CT16 M_J_CPU1_SB_DQS_DP<2> MJB_DQS_H2 @T6G_MB_LIB.T6G(SCH_1):M_J_CPU1_SB_DQS_DP(2)
CK16 M_J_CPU1_SB_DQS_DP<1> MJB_DQS_H1 @T6G_MB_LIB.T6G(SCH_1):M_J_CPU1_SB_DQS_DP(1)
CD16 M_J_CPU1_SB_DQS_DP<0> MJB_DQS_H0 @T6G_MB_LIB.T6G(SCH_1):M_J_CPU1_SB_DQS_DP(0)
DF16 M_J_CPU1_SB_DQ<31> MJB_DATA31 @T6G_MB_LIB.T6G(SCH_1):M_J_CPU1_SB_DQ(31)
DE16 M_J_CPU1_SB_DQ<30> MJB_DATA30 @T6G_MB_LIB.T6G(SCH_1):M_J_CPU1_SB_DQ(30)
DE17 M_J_CPU1_SB_DQ<29> MJB_DATA29 @T6G_MB_LIB.T6G(SCH_1):M_J_CPU1_SB_DQ(29)
DD16 M_J_CPU1_SB_DQ<28> MJB_DATA28 @T6G_MB_LIB.T6G(SCH_1):M_J_CPU1_SB_DQ(28)
DB18 M_J_CPU1_SB_DQ<27> MJB_DATA27 @T6G_MB_LIB.T6G(SCH_1):M_J_CPU1_SB_DQ(27)
DA16 M_J_CPU1_SB_DQ<26> MJB_DATA26 @T6G_MB_LIB.T6G(SCH_1):M_J_CPU1_SB_DQ(26)
DA17 M_J_CPU1_SB_DQ<25> MJB_DATA25 @T6G_MB_LIB.T6G(SCH_1):M_J_CPU1_SB_DQ(25)
CY16 M_J_CPU1_SB_DQ<24> MJB_DATA24 @T6G_MB_LIB.T6G(SCH_1):M_J_CPU1_SB_DQ(24)
CY18 M_J_CPU1_SB_DQ<23> MJB_DATA23 @T6G_MB_LIB.T6G(SCH_1):M_J_CPU1_SB_DQ(23)
CW16 M_J_CPU1_SB_DQ<22> MJB_DATA22 @T6G_MB_LIB.T6G(SCH_1):M_J_CPU1_SB_DQ(22)
CW17 M_J_CPU1_SB_DQ<21> MJB_DATA21 @T6G_MB_LIB.T6G(SCH_1):M_J_CPU1_SB_DQ(21)
CV16 M_J_CPU1_SB_DQ<20> MJB_DATA20 @T6G_MB_LIB.T6G(SCH_1):M_J_CPU1_SB_DQ(20)
CT18 M_J_CPU1_SB_DQ<19> MJB_DATA19 @T6G_MB_LIB.T6G(SCH_1):M_J_CPU1_SB_DQ(19)
CR16 M_J_CPU1_SB_DQ<18> MJB_DATA18 @T6G_MB_LIB.T6G(SCH_1):M_J_CPU1_SB_DQ(18)
CR17 M_J_CPU1_SB_DQ<17> MJB_DATA17 @T6G_MB_LIB.T6G(SCH_1):M_J_CPU1_SB_DQ(17)
CP16 M_J_CPU1_SB_DQ<16> MJB_DATA16 @T6G_MB_LIB.T6G(SCH_1):M_J_CPU1_SB_DQ(16)
CP18 M_J_CPU1_SB_DQ<15> MJB_DATA15 @T6G_MB_LIB.T6G(SCH_1):M_J_CPU1_SB_DQ(15)
CN16 M_J_CPU1_SB_DQ<14> MJB_DATA14 @T6G_MB_LIB.T6G(SCH_1):M_J_CPU1_SB_DQ(14)
CN17 M_J_CPU1_SB_DQ<13> MJB_DATA13 @T6G_MB_LIB.T6G(SCH_1):M_J_CPU1_SB_DQ(13)
CM16 M_J_CPU1_SB_DQ<12> MJB_DATA12 @T6G_MB_LIB.T6G(SCH_1):M_J_CPU1_SB_DQ(12)
CK18 M_J_CPU1_SB_DQ<11> MJB_DATA11 @T6G_MB_LIB.T6G(SCH_1):M_J_CPU1_SB_DQ(11)
CJ16 M_J_CPU1_SB_DQ<10> MJB_DATA10 @T6G_MB_LIB.T6G(SCH_1):M_J_CPU1_SB_DQ(10)
CJ17 M_J_CPU1_SB_DQ<9> MJB_DATA9 @T6G_MB_LIB.T6G(SCH_1):M_J_CPU1_SB_DQ(9)
CH16 M_J_CPU1_SB_DQ<8> MJB_DATA8 @T6G_MB_LIB.T6G(SCH_1):M_J_CPU1_SB_DQ(8)
CC16 M_J_CPU1_SB_DQ<2> MJB_DATA2 @T6G_MB_LIB.T6G(SCH_1):M_J_CPU1_SB_DQ(2)
CC17 M_J_CPU1_SB_DQ<1> MJB_DATA1 @T6G_MB_LIB.T6G(SCH_1):M_J_CPU1_SB_DQ(1)
BV18 M_J_CPU1_SB_CB<7> MJB_CHECK7 @T6G_MB_LIB.T6G(SCH_1):M_J_CPU1_SB_CB(7)
BU16 M_J_CPU1_SB_CB<6> MJB_CHECK6 @T6G_MB_LIB.T6G(SCH_1):M_J_CPU1_SB_CB(6)
BU17 M_J_CPU1_SB_CB<5> MJB_CHECK5 @T6G_MB_LIB.T6G(SCH_1):M_J_CPU1_SB_CB(5)
BT16 M_J_CPU1_SB_CB<4> MJB_CHECK4 @T6G_MB_LIB.T6G(SCH_1):M_J_CPU1_SB_CB(4)
CB18 M_J_CPU1_SB_CB<3> MJB_CHECK3 @T6G_MB_LIB.T6G(SCH_1):M_J_CPU1_SB_CB(3)
CA16 M_J_CPU1_SB_CB<2> MJB_CHECK2 @T6G_MB_LIB.T6G(SCH_1):M_J_CPU1_SB_CB(2)
CA17 M_J_CPU1_SB_CB<1> MJB_CHECK1 @T6G_MB_LIB.T6G(SCH_1):M_J_CPU1_SB_CB(1)
BY16 M_J_CPU1_SB_CB<0> MJB_CHECK0 @T6G_MB_LIB.T6G(SCH_1):M_J_CPU1_SB_CB(0)
BK16 M_J_CPU1_SB_CA<6> MJB_CA6 @T6G_MB_LIB.T6G(SCH_1):M_J_CPU1_SB_CA(6)
BK18 M_J_CPU1_SB_CA<5> MJB_CA5 @T6G_MB_LIB.T6G(SCH_1):M_J_CPU1_SB_CA(5)
BJ17 M_J_CPU1_SB_CA<4> MJB_CA4 @T6G_MB_LIB.T6G(SCH_1):M_J_CPU1_SB_CA(4)
BJ16 M_J_CPU1_SB_CA<3> MJB_CA3 @T6G_MB_LIB.T6G(SCH_1):M_J_CPU1_SB_CA(3)
BH16 M_J_CPU1_SB_CA<2> MJB_CA2 @T6G_MB_LIB.T6G(SCH_1):M_J_CPU1_SB_CA(2)
BH18 M_J_CPU1_SB_CA<1> MJB_CA1 @T6G_MB_LIB.T6G(SCH_1):M_J_CPU1_SB_CA(1)
BG17 M_J_CPU1_SB_CA<0> MJB_CA0 @T6G_MB_LIB.T6G(SCH_1):M_J_CPU1_SB_CA(0)
BR16     NC MJB1_RSP_L     NC
BM16     NC MJB1_CS_L1     NC
BL16     NC MJB1_CS_L0     NC
BP16 M_J_CPU1_SB_RSP<0> MJB0_RSP_L @T6G_MB_LIB.T6G(SCH_1):M_J_CPU1_SB_RSP(0)
BN16 M_J_CPU1_SB_CS_N<1> MJB0_CS_L1 @T6G_MB_LIB.T6G(SCH_1):M_J_CPU1_SB_CS_N(1)
BM18 M_J_CPU1_SB_CS_N<0> MJB0_CS_L0 @T6G_MB_LIB.T6G(SCH_1):M_J_CPU1_SB_CS_N(0)
BC17 M_J_CPU1_SA_PAR MJA_PAR @T6G_MB_LIB.T6G(SCH_1):M_J_CPU1_SA_PAR
AM18 M_J_CPU1_SA_DQS_DN<9> MJA_DQS_L9 @T6G_MB_LIB.T6G(SCH_1):M_J_CPU1_SA_DQS_DN(9)
AF18 M_J_CPU1_SA_DQS_DN<8> MJA_DQS_L8 @T6G_MB_LIB.T6G(SCH_1):M_J_CPU1_SA_DQS_DN(8)
 P18 M_J_CPU1_SA_DQS_DN<6> MJA_DQS_L6 @T6G_MB_LIB.T6G(SCH_1):M_J_CPU1_SA_DQS_DN(6)
AF16 M_J_CPU1_SA_DQS_DN<3> MJA_DQS_L3 @T6G_MB_LIB.T6G(SCH_1):M_J_CPU1_SA_DQS_DN(3)
 Y16 M_J_CPU1_SA_DQS_DN<2> MJA_DQS_L2 @T6G_MB_LIB.T6G(SCH_1):M_J_CPU1_SA_DQS_DN(2)
 P16 M_J_CPU1_SA_DQS_DN<1> MJA_DQS_L1 @T6G_MB_LIB.T6G(SCH_1):M_J_CPU1_SA_DQS_DN(1)
 H16 M_J_CPU1_SA_DQS_DN<0> MJA_DQS_L0 @T6G_MB_LIB.T6G(SCH_1):M_J_CPU1_SA_DQS_DN(0)
AN17 M_J_CPU1_SA_DQS_DP<9> MJA_DQS_H9 @T6G_MB_LIB.T6G(SCH_1):M_J_CPU1_SA_DQS_DP(9)
AA17 M_J_CPU1_SA_DQS_DP<7> MJA_DQS_H7 @T6G_MB_LIB.T6G(SCH_1):M_J_CPU1_SA_DQS_DP(7)
 R17 M_J_CPU1_SA_DQS_DP<6> MJA_DQS_H6 @T6G_MB_LIB.T6G(SCH_1):M_J_CPU1_SA_DQS_DP(6)
 J17 M_J_CPU1_SA_DQS_DP<5> MJA_DQS_H5 @T6G_MB_LIB.T6G(SCH_1):M_J_CPU1_SA_DQS_DP(5)
AE16 M_J_CPU1_SA_DQS_DP<3> MJA_DQS_H3 @T6G_MB_LIB.T6G(SCH_1):M_J_CPU1_SA_DQS_DP(3)
 W16 M_J_CPU1_SA_DQS_DP<2> MJA_DQS_H2 @T6G_MB_LIB.T6G(SCH_1):M_J_CPU1_SA_DQS_DP(2)
 N16 M_J_CPU1_SA_DQS_DP<1> MJA_DQS_H1 @T6G_MB_LIB.T6G(SCH_1):M_J_CPU1_SA_DQS_DP(1)
 G16 M_J_CPU1_SA_DQS_DP<0> MJA_DQS_H0 @T6G_MB_LIB.T6G(SCH_1):M_J_CPU1_SA_DQS_DP(0)
AH16 M_J_CPU1_SA_DQ<30> MJA_DATA30 @T6G_MB_LIB.T6G(SCH_1):M_J_CPU1_SA_DQ(30)
AH18 M_J_CPU1_SA_DQ<29> MJA_DATA29 @T6G_MB_LIB.T6G(SCH_1):M_J_CPU1_SA_DQ(29)
AG16 M_J_CPU1_SA_DQ<28> MJA_DATA28 @T6G_MB_LIB.T6G(SCH_1):M_J_CPU1_SA_DQ(28)
AE17 M_J_CPU1_SA_DQ<27> MJA_DATA27 @T6G_MB_LIB.T6G(SCH_1):M_J_CPU1_SA_DQ(27)
AD16 M_J_CPU1_SA_DQ<26> MJA_DATA26 @T6G_MB_LIB.T6G(SCH_1):M_J_CPU1_SA_DQ(26)
AD18 M_J_CPU1_SA_DQ<25> MJA_DATA25 @T6G_MB_LIB.T6G(SCH_1):M_J_CPU1_SA_DQ(25)
AC16 M_J_CPU1_SA_DQ<24> MJA_DATA24 @T6G_MB_LIB.T6G(SCH_1):M_J_CPU1_SA_DQ(24)
AC17 M_J_CPU1_SA_DQ<23> MJA_DATA23 @T6G_MB_LIB.T6G(SCH_1):M_J_CPU1_SA_DQ(23)
AB18 M_J_CPU1_SA_DQ<21> MJA_DATA21 @T6G_MB_LIB.T6G(SCH_1):M_J_CPU1_SA_DQ(21)
AA16 M_J_CPU1_SA_DQ<20> MJA_DATA20 @T6G_MB_LIB.T6G(SCH_1):M_J_CPU1_SA_DQ(20)
 W17 M_J_CPU1_SA_DQ<19> MJA_DATA19 @T6G_MB_LIB.T6G(SCH_1):M_J_CPU1_SA_DQ(19)
 V16 M_J_CPU1_SA_DQ<18> MJA_DATA18 @T6G_MB_LIB.T6G(SCH_1):M_J_CPU1_SA_DQ(18)
 V18 M_J_CPU1_SA_DQ<17> MJA_DATA17 @T6G_MB_LIB.T6G(SCH_1):M_J_CPU1_SA_DQ(17)
 U16 M_J_CPU1_SA_DQ<16> MJA_DATA16 @T6G_MB_LIB.T6G(SCH_1):M_J_CPU1_SA_DQ(16)
 U17 M_J_CPU1_SA_DQ<15> MJA_DATA15 @T6G_MB_LIB.T6G(SCH_1):M_J_CPU1_SA_DQ(15)
 T16 M_J_CPU1_SA_DQ<14> MJA_DATA14 @T6G_MB_LIB.T6G(SCH_1):M_J_CPU1_SA_DQ(14)
 T18 M_J_CPU1_SA_DQ<13> MJA_DATA13 @T6G_MB_LIB.T6G(SCH_1):M_J_CPU1_SA_DQ(13)
 R16 M_J_CPU1_SA_DQ<12> MJA_DATA12 @T6G_MB_LIB.T6G(SCH_1):M_J_CPU1_SA_DQ(12)
 N17 M_J_CPU1_SA_DQ<11> MJA_DATA11 @T6G_MB_LIB.T6G(SCH_1):M_J_CPU1_SA_DQ(11)
 M16 M_J_CPU1_SA_DQ<10> MJA_DATA10 @T6G_MB_LIB.T6G(SCH_1):M_J_CPU1_SA_DQ(10)
 M18 M_J_CPU1_SA_DQ<9> MJA_DATA9 @T6G_MB_LIB.T6G(SCH_1):M_J_CPU1_SA_DQ(9)
 L16 M_J_CPU1_SA_DQ<8> MJA_DATA8 @T6G_MB_LIB.T6G(SCH_1):M_J_CPU1_SA_DQ(8)
 L17 M_J_CPU1_SA_DQ<7> MJA_DATA7 @T6G_MB_LIB.T6G(SCH_1):M_J_CPU1_SA_DQ(7)
 K16 M_J_CPU1_SA_DQ<6> MJA_DATA6 @T6G_MB_LIB.T6G(SCH_1):M_J_CPU1_SA_DQ(6)
 K18 M_J_CPU1_SA_DQ<5> MJA_DATA5 @T6G_MB_LIB.T6G(SCH_1):M_J_CPU1_SA_DQ(5)
 J16 M_J_CPU1_SA_DQ<4> MJA_DATA4 @T6G_MB_LIB.T6G(SCH_1):M_J_CPU1_SA_DQ(4)
 G17 M_J_CPU1_SA_DQ<3> MJA_DATA3 @T6G_MB_LIB.T6G(SCH_1):M_J_CPU1_SA_DQ(3)
 F16 M_J_CPU1_SA_DQ<2> MJA_DATA2 @T6G_MB_LIB.T6G(SCH_1):M_J_CPU1_SA_DQ(2)
 F18 M_J_CPU1_SA_DQ<1> MJA_DATA1 @T6G_MB_LIB.T6G(SCH_1):M_J_CPU1_SA_DQ(1)
 E16 M_J_CPU1_SA_DQ<0> MJA_DATA0 @T6G_MB_LIB.T6G(SCH_1):M_J_CPU1_SA_DQ(0)
AR17 M_J_CPU1_SA_CB<7> MJA_CHECK7 @T6G_MB_LIB.T6G(SCH_1):M_J_CPU1_SA_CB(7)
AP16 M_J_CPU1_SA_CB<6> MJA_CHECK6 @T6G_MB_LIB.T6G(SCH_1):M_J_CPU1_SA_CB(6)
AP18 M_J_CPU1_SA_CB<5> MJA_CHECK5 @T6G_MB_LIB.T6G(SCH_1):M_J_CPU1_SA_CB(5)
AN16 M_J_CPU1_SA_CB<4> MJA_CHECK4 @T6G_MB_LIB.T6G(SCH_1):M_J_CPU1_SA_CB(4)
AL17 M_J_CPU1_SA_CB<3> MJA_CHECK3 @T6G_MB_LIB.T6G(SCH_1):M_J_CPU1_SA_CB(3)
AK16 M_J_CPU1_SA_CB<2> MJA_CHECK2 @T6G_MB_LIB.T6G(SCH_1):M_J_CPU1_SA_CB(2)
AK18 M_J_CPU1_SA_CB<1> MJA_CHECK1 @T6G_MB_LIB.T6G(SCH_1):M_J_CPU1_SA_CB(1)
AJ16 M_J_CPU1_SA_CB<0> MJA_CHECK0 @T6G_MB_LIB.T6G(SCH_1):M_J_CPU1_SA_CB(0)
BA16 M_J_CPU1_SA_CA<4> MJA_CA4 @T6G_MB_LIB.T6G(SCH_1):M_J_CPU1_SA_CA(4)
BA17 M_J_CPU1_SA_CA<3> MJA_CA3 @T6G_MB_LIB.T6G(SCH_1):M_J_CPU1_SA_CA(3)
AY18 M_J_CPU1_SA_CA<2> MJA_CA2 @T6G_MB_LIB.T6G(SCH_1):M_J_CPU1_SA_CA(2)
AY16 M_J_CPU1_SA_CA<1> MJA_CA1 @T6G_MB_LIB.T6G(SCH_1):M_J_CPU1_SA_CA(1)
AW16 M_J_CPU1_SA_CA<0> MJA_CA0 @T6G_MB_LIB.T6G(SCH_1):M_J_CPU1_SA_CA(0)
BP18     NC MJA1_RSP_L     NC
AW17     NC MJA1_CS_L1     NC
AV16     NC MJA1_CS_L0     NC
BN17 M_J_CPU1_SA_RSP<0> MJA0_RSP_L @T6G_MB_LIB.T6G(SCH_1):M_J_CPU1_SA_RSP(0)
AV18 M_J_CPU1_SA_CS_N<1> MJA0_CS_L1 @T6G_MB_LIB.T6G(SCH_1):M_J_CPU1_SA_CS_N(1)
AU16 M_J_CPU1_SA_CS_N<0> MJA0_CS_L0 @T6G_MB_LIB.T6G(SCH_1):M_J_CPU1_SA_CS_N(0)
BG16     NC MJ1_CLK_L     NC
BF16     NC MJ1_CLK_H     NC
BD16 M_J_CPU1_CLK_DN<0> MJ0_CLK_L @T6G_MB_LIB.T6G(SCH_1):M_J_CPU1_CLK_DN(0)
BC16 M_J_CPU1_CLK_DP<0> MJ0_CLK_H @T6G_MB_LIB.T6G(SCH_1):M_J_CPU1_CLK_DP(0)
BB18 M_J_CPU1_SA_CA<6> MJA_CA6 @T6G_MB_LIB.T6G(SCH_1):M_J_CPU1_SA_CA(6)
BB16 M_J_CPU1_SA_CA<5> MJA_CA5 @T6G_MB_LIB.T6G(SCH_1):M_J_CPU1_SA_CA(5)
AB16 M_J_CPU1_SA_DQ<22> MJA_DATA22 @T6G_MB_LIB.T6G(SCH_1):M_J_CPU1_SA_DQ(22)
 Y18 M_J_CPU1_SA_DQS_DN<7> MJA_DQS_L7 @T6G_MB_LIB.T6G(SCH_1):M_J_CPU1_SA_DQS_DN(7)
 H18 M_J_CPU1_SA_DQS_DN<5> MJA_DQS_L5 @T6G_MB_LIB.T6G(SCH_1):M_J_CPU1_SA_DQS_DN(5)
AM16 M_J_CPU1_SA_DQS_DN<4> MJA_DQS_L4 @T6G_MB_LIB.T6G(SCH_1):M_J_CPU1_SA_DQS_DN(4)
AG17 M_J_CPU1_SA_DQS_DP<8> MJA_DQS_H8 @T6G_MB_LIB.T6G(SCH_1):M_J_CPU1_SA_DQS_DP(8)
AL16 M_J_CPU1_SA_DQS_DP<4> MJA_DQS_H4 @T6G_MB_LIB.T6G(SCH_1):M_J_CPU1_SA_DQS_DP(4)
CF16 M_J_CPU1_SB_DQ<4> MJB_DATA4 @T6G_MB_LIB.T6G(SCH_1):M_J_CPU1_SB_DQ(4)
CD18 M_J_CPU1_SB_DQ<3> MJB_DATA3 @T6G_MB_LIB.T6G(SCH_1):M_J_CPU1_SB_DQ(3)
CB16 M_J_CPU1_SB_DQ<0> MJB_DATA0 @T6G_MB_LIB.T6G(SCH_1):M_J_CPU1_SB_DQ(0)
AJ17 M_J_CPU1_SA_DQ<31> MJA_DATA31 @T6G_MB_LIB.T6G(SCH_1):M_J_CPU1_SA_DQ(31)
CE16 M_J_CPU1_SB_DQS_DN<0> MJB_DQS_L0 @T6G_MB_LIB.T6G(SCH_1):M_J_CPU1_SB_DQS_DN(0)
BW17 M_J_CPU1_SB_DQS_DN<4> MJB_DQS_L4 @T6G_MB_LIB.T6G(SCH_1):M_J_CPU1_SB_DQS_DN(4)
CF18 M_J_CPU1_SB_DQS_DP<5> MJB_DQS_H5 @T6G_MB_LIB.T6G(SCH_1):M_J_CPU1_SB_DQS_DP(5)
CG17 M_J_CPU1_SB_DQ<5> MJB_DATA5 @T6G_MB_LIB.T6G(SCH_1):M_J_CPU1_SB_DQ(5)
CG16 M_J_CPU1_SB_DQ<6> MJB_DATA6 @T6G_MB_LIB.T6G(SCH_1):M_J_CPU1_SB_DQ(6)
CH18 M_J_CPU1_SB_DQ<7> MJB_DATA7 @T6G_MB_LIB.T6G(SCH_1):M_J_CPU1_SB_DQ(7)
BF18 TP_M_J_CPU1_SA_TEST39J TEST39J @T6G_MB_LIB.T6G(SCH_1):TP_M_J_CPU1_SA_TEST39J

Q_RES_0402LF-15,1%,1/16W,CHIP,CS01502FB03  I314  R509
   1 M_J_CPU1_ALERT_N      A @T6G_MB_LIB.T6G(SCH_1):M_J_CPU1_ALERT_N
   2 M_J_CPU1_ALERT_R_N      B @T6G_MB_LIB.T6G(SCH_1):M_J_CPU1_ALERT_R_N


DRAWING: @T6G_MB_LIB.T6G(SCH_1):PAGE47 

GENOA_SP5-SOCKET6096_13568-001,SMLF,IO,DGA^6000030  I159  U26
 CL7 M_K_CPU1_SB_DQS_DN<6> MKB_DQS_L6 @T6G_MB_LIB.T6G(SCH_1):M_K_CPU1_SB_DQS_DN(6)
 CT6 M_K_CPU1_SB_DQS_DP<2> MKB_DQS_H2 @T6G_MB_LIB.T6G(SCH_1):M_K_CPU1_SB_DQS_DP(2)
 CT7 M_K_CPU1_SB_DQ<19> MKB_DATA19 @T6G_MB_LIB.T6G(SCH_1):M_K_CPU1_SB_DQ(19)
 BG7 M_K_CPU1_SB_CA<0> MKB_CA0 @T6G_MB_LIB.T6G(SCH_1):M_K_CPU1_SB_CA(0)
 AG7 M_K_CPU1_SA_DQS_DP<8> MKA_DQS_H8 @T6G_MB_LIB.T6G(SCH_1):M_K_CPU1_SA_DQS_DP(8)
 AH6 M_K_CPU1_SA_DQ<30> MKA_DATA30 @T6G_MB_LIB.T6G(SCH_1):M_K_CPU1_SA_DQ(30)
 AY6 M_K_CPU1_SA_CA<1> MKA_CA1 @T6G_MB_LIB.T6G(SCH_1):M_K_CPU1_SA_CA(1)
 AV6     NC MKA1_CS_L0     NC
 AV7 M_K_CPU1_SA_CS_N<1> MKA0_CS_L1 @T6G_MB_LIB.T6G(SCH_1):M_K_CPU1_SA_CS_N(1)
 CU7 M_K_CPU1_SB_DQS_DN<7> MKB_DQS_L7 @T6G_MB_LIB.T6G(SCH_1):M_K_CPU1_SB_DQS_DN(7)
 DB6 M_K_CPU1_SB_DQS_DP<3> MKB_DQS_H3 @T6G_MB_LIB.T6G(SCH_1):M_K_CPU1_SB_DQS_DP(3)
 BH7 M_K_CPU1_SB_CA<1> MKB_CA1 @T6G_MB_LIB.T6G(SCH_1):M_K_CPU1_SB_CA(1)
 AN7 M_K_CPU1_SA_DQS_DP<9> MKA_DQS_H9 @T6G_MB_LIB.T6G(SCH_1):M_K_CPU1_SA_DQS_DP(9)
 AJ7 M_K_CPU1_SA_DQ<31> MKA_DATA31 @T6G_MB_LIB.T6G(SCH_1):M_K_CPU1_SA_DQ(31)
 AA5 M_K_CPU1_SA_DQ<20> MKA_DATA20 @T6G_MB_LIB.T6G(SCH_1):M_K_CPU1_SA_DQ(20)
 AJ5 M_K_CPU1_SA_CB<0> MKA_CHECK0 @T6G_MB_LIB.T6G(SCH_1):M_K_CPU1_SA_CB(0)
 AY7 M_K_CPU1_SA_CA<2> MKA_CA2 @T6G_MB_LIB.T6G(SCH_1):M_K_CPU1_SA_CA(2)
 AW7     NC MKA1_CS_L1     NC
 BC5 M_K_CPU1_CLK_DP<0> MK0_CLK_H @T6G_MB_LIB.T6G(SCH_1):M_K_CPU1_CLK_DP(0)
 DC7 M_K_CPU1_SB_DQS_DN<8> MKB_DQS_L8 @T6G_MB_LIB.T6G(SCH_1):M_K_CPU1_SB_DQS_DN(8)
 BY7 M_K_CPU1_SB_DQS_DP<4> MKB_DQS_H4 @T6G_MB_LIB.T6G(SCH_1):M_K_CPU1_SB_DQS_DP(4)
 BH6 M_K_CPU1_SB_CA<2> MKB_CA2 @T6G_MB_LIB.T6G(SCH_1):M_K_CPU1_SB_CA(2)
 AB7 M_K_CPU1_SA_DQ<21> MKA_DATA21 @T6G_MB_LIB.T6G(SCH_1):M_K_CPU1_SA_DQ(21)
  M6 M_K_CPU1_SA_DQ<10> MKA_DATA10 @T6G_MB_LIB.T6G(SCH_1):M_K_CPU1_SA_DQ(10)
 AK7 M_K_CPU1_SA_CB<1> MKA_CHECK1 @T6G_MB_LIB.T6G(SCH_1):M_K_CPU1_SA_CB(1)
 BA7 M_K_CPU1_SA_CA<3> MKA_CA3 @T6G_MB_LIB.T6G(SCH_1):M_K_CPU1_SA_CA(3)
 BF6     NC MK1_CLK_H     NC
 BW5 M_K_CPU1_SB_DQS_DN<9> MKB_DQS_L9 @T6G_MB_LIB.T6G(SCH_1):M_K_CPU1_SB_DQS_DN(9)
 CF7 M_K_CPU1_SB_DQS_DP<5> MKB_DQS_H5 @T6G_MB_LIB.T6G(SCH_1):M_K_CPU1_SB_DQS_DP(5)
 BJ5 M_K_CPU1_SB_CA<3> MKB_CA3 @T6G_MB_LIB.T6G(SCH_1):M_K_CPU1_SB_CA(3)
 AB6 M_K_CPU1_SA_DQ<22> MKA_DATA22 @T6G_MB_LIB.T6G(SCH_1):M_K_CPU1_SA_DQ(22)
  N7 M_K_CPU1_SA_DQ<11> MKA_DATA11 @T6G_MB_LIB.T6G(SCH_1):M_K_CPU1_SA_DQ(11)
 AK6 M_K_CPU1_SA_CB<2> MKA_CHECK2 @T6G_MB_LIB.T6G(SCH_1):M_K_CPU1_SA_CB(2)
 BA5 M_K_CPU1_SA_CA<4> MKA_CA4 @T6G_MB_LIB.T6G(SCH_1):M_K_CPU1_SA_CA(4)
 AU7 M_K_CPU1_RESET_N MK_RESET_L @T6G_MB_LIB.T6G(SCH_1):M_K_CPU1_RESET_N
 CM7 M_K_CPU1_SB_DQS_DP<6> MKB_DQS_H6 @T6G_MB_LIB.T6G(SCH_1):M_K_CPU1_SB_DQS_DP(6)
 BJ7 M_K_CPU1_SB_CA<4> MKB_CA4 @T6G_MB_LIB.T6G(SCH_1):M_K_CPU1_SB_CA(4)
 AC7 M_K_CPU1_SA_DQ<23> MKA_DATA23 @T6G_MB_LIB.T6G(SCH_1):M_K_CPU1_SA_DQ(23)
  R5 M_K_CPU1_SA_DQ<12> MKA_DATA12 @T6G_MB_LIB.T6G(SCH_1):M_K_CPU1_SA_DQ(12)
 AL7 M_K_CPU1_SA_CB<3> MKA_CHECK3 @T6G_MB_LIB.T6G(SCH_1):M_K_CPU1_SA_CB(3)
 BB6 M_K_CPU1_SA_CA<5> MKA_CA5 @T6G_MB_LIB.T6G(SCH_1):M_K_CPU1_SA_CA(5)
 CV7 M_K_CPU1_SB_DQS_DP<7> MKB_DQS_H7 @T6G_MB_LIB.T6G(SCH_1):M_K_CPU1_SB_DQS_DP(7)
 BK7 M_K_CPU1_SB_CA<5> MKB_CA5 @T6G_MB_LIB.T6G(SCH_1):M_K_CPU1_SB_CA(5)
 BM7 M_K_CPU1_SB_CS_N<0> MKB0_CS_L0 @T6G_MB_LIB.T6G(SCH_1):M_K_CPU1_SB_CS_N(0)
  H6 M_K_CPU1_SA_DQS_DN<0> MKA_DQS_L0 @T6G_MB_LIB.T6G(SCH_1):M_K_CPU1_SA_DQS_DN(0)
 AC5 M_K_CPU1_SA_DQ<24> MKA_DATA24 @T6G_MB_LIB.T6G(SCH_1):M_K_CPU1_SA_DQ(24)
  T7 M_K_CPU1_SA_DQ<13> MKA_DATA13 @T6G_MB_LIB.T6G(SCH_1):M_K_CPU1_SA_DQ(13)
 AN5 M_K_CPU1_SA_CB<4> MKA_CHECK4 @T6G_MB_LIB.T6G(SCH_1):M_K_CPU1_SA_CB(4)
 BB7 M_K_CPU1_SA_CA<6> MKA_CA6 @T6G_MB_LIB.T6G(SCH_1):M_K_CPU1_SA_CA(6)
 BD6 M_K_CPU1_CLK_DN<0> MK0_CLK_L @T6G_MB_LIB.T6G(SCH_1):M_K_CPU1_CLK_DN(0)
 DD7 M_K_CPU1_SB_DQS_DP<8> MKB_DQS_H8 @T6G_MB_LIB.T6G(SCH_1):M_K_CPU1_SB_DQS_DP(8)
 DE5 M_K_CPU1_SB_DQ<30> MKB_DATA30 @T6G_MB_LIB.T6G(SCH_1):M_K_CPU1_SB_DQ(30)
 BK6 M_K_CPU1_SB_CA<6> MKB_CA6 @T6G_MB_LIB.T6G(SCH_1):M_K_CPU1_SB_CA(6)
 BL5     NC MKB1_CS_L0     NC
 BN5 M_K_CPU1_SB_CS_N<1> MKB0_CS_L1 @T6G_MB_LIB.T6G(SCH_1):M_K_CPU1_SB_CS_N(1)
  P6 M_K_CPU1_SA_DQS_DN<1> MKA_DQS_L1 @T6G_MB_LIB.T6G(SCH_1):M_K_CPU1_SA_DQS_DN(1)
 AD7 M_K_CPU1_SA_DQ<25> MKA_DATA25 @T6G_MB_LIB.T6G(SCH_1):M_K_CPU1_SA_DQ(25)
  T6 M_K_CPU1_SA_DQ<14> MKA_DATA14 @T6G_MB_LIB.T6G(SCH_1):M_K_CPU1_SA_DQ(14)
  E5 M_K_CPU1_SA_DQ<0> MKA_DATA0 @T6G_MB_LIB.T6G(SCH_1):M_K_CPU1_SA_DQ(0)
 AP7 M_K_CPU1_SA_CB<5> MKA_CHECK5 @T6G_MB_LIB.T6G(SCH_1):M_K_CPU1_SA_CB(5)
 BG5     NC MK1_CLK_L     NC
 BV6 M_K_CPU1_SB_DQS_DP<9> MKB_DQS_H9 @T6G_MB_LIB.T6G(SCH_1):M_K_CPU1_SB_DQS_DP(9)
 DF7 M_K_CPU1_SB_DQ<31> MKB_DATA31 @T6G_MB_LIB.T6G(SCH_1):M_K_CPU1_SB_DQ(31)
 CV6 M_K_CPU1_SB_DQ<20> MKB_DATA20 @T6G_MB_LIB.T6G(SCH_1):M_K_CPU1_SB_DQ(20)
 CB6 M_K_CPU1_SB_DQ<0> MKB_DATA0 @T6G_MB_LIB.T6G(SCH_1):M_K_CPU1_SB_DQ(0)
 BY6 M_K_CPU1_SB_CB<0> MKB_CHECK0 @T6G_MB_LIB.T6G(SCH_1):M_K_CPU1_SB_CB(0)
 BM6     NC MKB1_CS_L1     NC
  Y6 M_K_CPU1_SA_DQS_DN<2> MKA_DQS_L2 @T6G_MB_LIB.T6G(SCH_1):M_K_CPU1_SA_DQS_DN(2)
 AD6 M_K_CPU1_SA_DQ<26> MKA_DATA26 @T6G_MB_LIB.T6G(SCH_1):M_K_CPU1_SA_DQ(26)
  U7 M_K_CPU1_SA_DQ<15> MKA_DATA15 @T6G_MB_LIB.T6G(SCH_1):M_K_CPU1_SA_DQ(15)
  F7 M_K_CPU1_SA_DQ<1> MKA_DATA1 @T6G_MB_LIB.T6G(SCH_1):M_K_CPU1_SA_DQ(1)
 AP6 M_K_CPU1_SA_CB<6> MKA_CHECK6 @T6G_MB_LIB.T6G(SCH_1):M_K_CPU1_SA_CB(6)
 CW7 M_K_CPU1_SB_DQ<21> MKB_DATA21 @T6G_MB_LIB.T6G(SCH_1):M_K_CPU1_SB_DQ(21)
 CJ5 M_K_CPU1_SB_DQ<10> MKB_DATA10 @T6G_MB_LIB.T6G(SCH_1):M_K_CPU1_SB_DQ(10)
 CC7 M_K_CPU1_SB_DQ<1> MKB_DATA1 @T6G_MB_LIB.T6G(SCH_1):M_K_CPU1_SB_DQ(1)
 CA7 M_K_CPU1_SB_CB<1> MKB_CHECK1 @T6G_MB_LIB.T6G(SCH_1):M_K_CPU1_SB_CB(1)
 AF6 M_K_CPU1_SA_DQS_DN<3> MKA_DQS_L3 @T6G_MB_LIB.T6G(SCH_1):M_K_CPU1_SA_DQS_DN(3)
 AE7 M_K_CPU1_SA_DQ<27> MKA_DATA27 @T6G_MB_LIB.T6G(SCH_1):M_K_CPU1_SA_DQ(27)
  U5 M_K_CPU1_SA_DQ<16> MKA_DATA16 @T6G_MB_LIB.T6G(SCH_1):M_K_CPU1_SA_DQ(16)
  F6 M_K_CPU1_SA_DQ<2> MKA_DATA2 @T6G_MB_LIB.T6G(SCH_1):M_K_CPU1_SA_DQ(2)
 AR7 M_K_CPU1_SA_CB<7> MKA_CHECK7 @T6G_MB_LIB.T6G(SCH_1):M_K_CPU1_SA_CB(7)
 BN7 M_K_CPU1_SA_RSP<0> MKA0_RSP_L @T6G_MB_LIB.T6G(SCH_1):M_K_CPU1_SA_RSP(0)
 AT7 M_K_CPU1_ALERT_R_N MK_ALERT_L @T6G_MB_LIB.T6G(SCH_1):M_K_CPU1_ALERT_R_N
 CW5 M_K_CPU1_SB_DQ<22> MKB_DATA22 @T6G_MB_LIB.T6G(SCH_1):M_K_CPU1_SB_DQ(22)
 CK7 M_K_CPU1_SB_DQ<11> MKB_DATA11 @T6G_MB_LIB.T6G(SCH_1):M_K_CPU1_SB_DQ(11)
 CC5 M_K_CPU1_SB_DQ<2> MKB_DATA2 @T6G_MB_LIB.T6G(SCH_1):M_K_CPU1_SB_DQ(2)
 CA5 M_K_CPU1_SB_CB<2> MKB_CHECK2 @T6G_MB_LIB.T6G(SCH_1):M_K_CPU1_SB_CB(2)
 AM6 M_K_CPU1_SA_DQS_DN<4> MKA_DQS_L4 @T6G_MB_LIB.T6G(SCH_1):M_K_CPU1_SA_DQS_DN(4)
  G5 M_K_CPU1_SA_DQS_DP<0> MKA_DQS_H0 @T6G_MB_LIB.T6G(SCH_1):M_K_CPU1_SA_DQS_DP(0)
 AG5 M_K_CPU1_SA_DQ<28> MKA_DATA28 @T6G_MB_LIB.T6G(SCH_1):M_K_CPU1_SA_DQ(28)
  V7 M_K_CPU1_SA_DQ<17> MKA_DATA17 @T6G_MB_LIB.T6G(SCH_1):M_K_CPU1_SA_DQ(17)
  G7 M_K_CPU1_SA_DQ<3> MKA_DATA3 @T6G_MB_LIB.T6G(SCH_1):M_K_CPU1_SA_DQ(3)
 BP7     NC MKA1_RSP_L     NC
 CY7 M_K_CPU1_SB_DQ<23> MKB_DATA23 @T6G_MB_LIB.T6G(SCH_1):M_K_CPU1_SB_DQ(23)
 CM6 M_K_CPU1_SB_DQ<12> MKB_DATA12 @T6G_MB_LIB.T6G(SCH_1):M_K_CPU1_SB_DQ(12)
 CD7 M_K_CPU1_SB_DQ<3> MKB_DATA3 @T6G_MB_LIB.T6G(SCH_1):M_K_CPU1_SB_DQ(3)
 CB7 M_K_CPU1_SB_CB<3> MKB_CHECK3 @T6G_MB_LIB.T6G(SCH_1):M_K_CPU1_SB_CB(3)
  H7 M_K_CPU1_SA_DQS_DN<5> MKA_DQS_L5 @T6G_MB_LIB.T6G(SCH_1):M_K_CPU1_SA_DQS_DN(5)
  N5 M_K_CPU1_SA_DQS_DP<1> MKA_DQS_H1 @T6G_MB_LIB.T6G(SCH_1):M_K_CPU1_SA_DQS_DP(1)
 AH7 M_K_CPU1_SA_DQ<29> MKA_DATA29 @T6G_MB_LIB.T6G(SCH_1):M_K_CPU1_SA_DQ(29)
  V6 M_K_CPU1_SA_DQ<18> MKA_DATA18 @T6G_MB_LIB.T6G(SCH_1):M_K_CPU1_SA_DQ(18)
  J5 M_K_CPU1_SA_DQ<4> MKA_DATA4 @T6G_MB_LIB.T6G(SCH_1):M_K_CPU1_SA_DQ(4)
 CE5 M_K_CPU1_SB_DQS_DN<0> MKB_DQS_L0 @T6G_MB_LIB.T6G(SCH_1):M_K_CPU1_SB_DQS_DN(0)
 CY6 M_K_CPU1_SB_DQ<24> MKB_DATA24 @T6G_MB_LIB.T6G(SCH_1):M_K_CPU1_SB_DQ(24)
 CN7 M_K_CPU1_SB_DQ<13> MKB_DATA13 @T6G_MB_LIB.T6G(SCH_1):M_K_CPU1_SB_DQ(13)
 CF6 M_K_CPU1_SB_DQ<4> MKB_DATA4 @T6G_MB_LIB.T6G(SCH_1):M_K_CPU1_SB_DQ(4)
 BT6 M_K_CPU1_SB_CB<4> MKB_CHECK4 @T6G_MB_LIB.T6G(SCH_1):M_K_CPU1_SB_CB(4)
  P7 M_K_CPU1_SA_DQS_DN<6> MKA_DQS_L6 @T6G_MB_LIB.T6G(SCH_1):M_K_CPU1_SA_DQS_DN(6)
  W5 M_K_CPU1_SA_DQS_DP<2> MKA_DQS_H2 @T6G_MB_LIB.T6G(SCH_1):M_K_CPU1_SA_DQS_DP(2)
  W7 M_K_CPU1_SA_DQ<19> MKA_DATA19 @T6G_MB_LIB.T6G(SCH_1):M_K_CPU1_SA_DQ(19)
  K7 M_K_CPU1_SA_DQ<5> MKA_DATA5 @T6G_MB_LIB.T6G(SCH_1):M_K_CPU1_SA_DQ(5)
 CL5 M_K_CPU1_SB_DQS_DN<1> MKB_DQS_L1 @T6G_MB_LIB.T6G(SCH_1):M_K_CPU1_SB_DQS_DN(1)
 DA7 M_K_CPU1_SB_DQ<25> MKB_DATA25 @T6G_MB_LIB.T6G(SCH_1):M_K_CPU1_SB_DQ(25)
 CN5 M_K_CPU1_SB_DQ<14> MKB_DATA14 @T6G_MB_LIB.T6G(SCH_1):M_K_CPU1_SB_DQ(14)
 CG7 M_K_CPU1_SB_DQ<5> MKB_DATA5 @T6G_MB_LIB.T6G(SCH_1):M_K_CPU1_SB_DQ(5)
 BU7 M_K_CPU1_SB_CB<5> MKB_CHECK5 @T6G_MB_LIB.T6G(SCH_1):M_K_CPU1_SB_CB(5)
 BC7 M_K_CPU1_SA_PAR MKA_PAR @T6G_MB_LIB.T6G(SCH_1):M_K_CPU1_SA_PAR
  Y7 M_K_CPU1_SA_DQS_DN<7> MKA_DQS_L7 @T6G_MB_LIB.T6G(SCH_1):M_K_CPU1_SA_DQS_DN(7)
 AE5 M_K_CPU1_SA_DQS_DP<3> MKA_DQS_H3 @T6G_MB_LIB.T6G(SCH_1):M_K_CPU1_SA_DQS_DP(3)
  K6 M_K_CPU1_SA_DQ<6> MKA_DATA6 @T6G_MB_LIB.T6G(SCH_1):M_K_CPU1_SA_DQ(6)
 BL7 M_K_CPU1_SB_PAR MKB_PAR @T6G_MB_LIB.T6G(SCH_1):M_K_CPU1_SB_PAR
 CU5 M_K_CPU1_SB_DQS_DN<2> MKB_DQS_L2 @T6G_MB_LIB.T6G(SCH_1):M_K_CPU1_SB_DQS_DN(2)
 DA5 M_K_CPU1_SB_DQ<26> MKB_DATA26 @T6G_MB_LIB.T6G(SCH_1):M_K_CPU1_SB_DQ(26)
 CP7 M_K_CPU1_SB_DQ<15> MKB_DATA15 @T6G_MB_LIB.T6G(SCH_1):M_K_CPU1_SB_DQ(15)
 CG5 M_K_CPU1_SB_DQ<6> MKB_DATA6 @T6G_MB_LIB.T6G(SCH_1):M_K_CPU1_SB_DQ(6)
 BU5 M_K_CPU1_SB_CB<6> MKB_CHECK6 @T6G_MB_LIB.T6G(SCH_1):M_K_CPU1_SB_CB(6)
 AF7 M_K_CPU1_SA_DQS_DN<8> MKA_DQS_L8 @T6G_MB_LIB.T6G(SCH_1):M_K_CPU1_SA_DQS_DN(8)
 AL5 M_K_CPU1_SA_DQS_DP<4> MKA_DQS_H4 @T6G_MB_LIB.T6G(SCH_1):M_K_CPU1_SA_DQS_DP(4)
  L7 M_K_CPU1_SA_DQ<7> MKA_DATA7 @T6G_MB_LIB.T6G(SCH_1):M_K_CPU1_SA_DQ(7)
 DC5 M_K_CPU1_SB_DQS_DN<3> MKB_DQS_L3 @T6G_MB_LIB.T6G(SCH_1):M_K_CPU1_SB_DQS_DN(3)
 DB7 M_K_CPU1_SB_DQ<27> MKB_DATA27 @T6G_MB_LIB.T6G(SCH_1):M_K_CPU1_SB_DQ(27)
 CP6 M_K_CPU1_SB_DQ<16> MKB_DATA16 @T6G_MB_LIB.T6G(SCH_1):M_K_CPU1_SB_DQ(16)
 CH7 M_K_CPU1_SB_DQ<7> MKB_DATA7 @T6G_MB_LIB.T6G(SCH_1):M_K_CPU1_SB_DQ(7)
 BV7 M_K_CPU1_SB_CB<7> MKB_CHECK7 @T6G_MB_LIB.T6G(SCH_1):M_K_CPU1_SB_CB(7)
 BP6 M_K_CPU1_SB_RSP<0> MKB0_RSP_L @T6G_MB_LIB.T6G(SCH_1):M_K_CPU1_SB_RSP(0)
 AM7 M_K_CPU1_SA_DQS_DN<9> MKA_DQS_L9 @T6G_MB_LIB.T6G(SCH_1):M_K_CPU1_SA_DQS_DN(9)
  J7 M_K_CPU1_SA_DQS_DP<5> MKA_DQS_H5 @T6G_MB_LIB.T6G(SCH_1):M_K_CPU1_SA_DQS_DP(5)
  L5 M_K_CPU1_SA_DQ<8> MKA_DATA8 @T6G_MB_LIB.T6G(SCH_1):M_K_CPU1_SA_DQ(8)
 BW7 M_K_CPU1_SB_DQS_DN<4> MKB_DQS_L4 @T6G_MB_LIB.T6G(SCH_1):M_K_CPU1_SB_DQS_DN(4)
 CD6 M_K_CPU1_SB_DQS_DP<0> MKB_DQS_H0 @T6G_MB_LIB.T6G(SCH_1):M_K_CPU1_SB_DQS_DP(0)
 DD6 M_K_CPU1_SB_DQ<28> MKB_DATA28 @T6G_MB_LIB.T6G(SCH_1):M_K_CPU1_SB_DQ(28)
 CR7 M_K_CPU1_SB_DQ<17> MKB_DATA17 @T6G_MB_LIB.T6G(SCH_1):M_K_CPU1_SB_DQ(17)
 CH6 M_K_CPU1_SB_DQ<8> MKB_DATA8 @T6G_MB_LIB.T6G(SCH_1):M_K_CPU1_SB_DQ(8)
 BR5     NC MKB1_RSP_L     NC
  R7 M_K_CPU1_SA_DQS_DP<6> MKA_DQS_H6 @T6G_MB_LIB.T6G(SCH_1):M_K_CPU1_SA_DQS_DP(6)
  M7 M_K_CPU1_SA_DQ<9> MKA_DATA9 @T6G_MB_LIB.T6G(SCH_1):M_K_CPU1_SA_DQ(9)
 CE7 M_K_CPU1_SB_DQS_DN<5> MKB_DQS_L5 @T6G_MB_LIB.T6G(SCH_1):M_K_CPU1_SB_DQS_DN(5)
 CK6 M_K_CPU1_SB_DQS_DP<1> MKB_DQS_H1 @T6G_MB_LIB.T6G(SCH_1):M_K_CPU1_SB_DQS_DP(1)
 DE7 M_K_CPU1_SB_DQ<29> MKB_DATA29 @T6G_MB_LIB.T6G(SCH_1):M_K_CPU1_SB_DQ(29)
 CR5 M_K_CPU1_SB_DQ<18> MKB_DATA18 @T6G_MB_LIB.T6G(SCH_1):M_K_CPU1_SB_DQ(18)
 CJ7 M_K_CPU1_SB_DQ<9> MKB_DATA9 @T6G_MB_LIB.T6G(SCH_1):M_K_CPU1_SB_DQ(9)
 AA7 M_K_CPU1_SA_DQS_DP<7> MKA_DQS_H7 @T6G_MB_LIB.T6G(SCH_1):M_K_CPU1_SA_DQS_DP(7)
 AW5 M_K_CPU1_SA_CA<0> MKA_CA0 @T6G_MB_LIB.T6G(SCH_1):M_K_CPU1_SA_CA(0)
 AU5 M_K_CPU1_SA_CS_N<0> MKA0_CS_L0 @T6G_MB_LIB.T6G(SCH_1):M_K_CPU1_SA_CS_N(0)
 BF7 TP_M_K_CPU1_SA_TEST39K TEST39K @T6G_MB_LIB.T6G(SCH_1):TP_M_K_CPU1_SA_TEST39K

Q_RES_0402LF-15,1%,1/16W,CHIP,CS01502FB03  I314  R510
   1 M_K_CPU1_ALERT_N      A @T6G_MB_LIB.T6G(SCH_1):M_K_CPU1_ALERT_N
   2 M_K_CPU1_ALERT_R_N      B @T6G_MB_LIB.T6G(SCH_1):M_K_CPU1_ALERT_R_N


DRAWING: @T6G_MB_LIB.T6G(SCH_1):PAGE48 

GENOA_SP5-SOCKET6096_13568-001,SMLF,IO,DGA^6000030  I159  U26
 BW9 M_L_CPU1_SB_DQS_DN<9> MLB_DQS_L9 @T6G_MB_LIB.T6G(SCH_1):M_L_CPU1_SB_DQS_DN(9)
CF11 M_L_CPU1_SB_DQS_DP<5> MLB_DQS_H5 @T6G_MB_LIB.T6G(SCH_1):M_L_CPU1_SB_DQS_DP(5)
 CF9 M_L_CPU1_SB_DQ<4> MLB_DATA4 @T6G_MB_LIB.T6G(SCH_1):M_L_CPU1_SB_DQ(4)
BH11 M_L_CPU1_SB_CA<1> MLB_CA1 @T6G_MB_LIB.T6G(SCH_1):M_L_CPU1_SB_CA(1)
 AB9 M_L_CPU1_SA_DQ<22> MLA_DATA22 @T6G_MB_LIB.T6G(SCH_1):M_L_CPU1_SA_DQ(22)
 N10 M_L_CPU1_SA_DQ<11> MLA_DATA11 @T6G_MB_LIB.T6G(SCH_1):M_L_CPU1_SA_DQ(11)
 K11 M_L_CPU1_SA_DQ<5> MLA_DATA5 @T6G_MB_LIB.T6G(SCH_1):M_L_CPU1_SA_DQ(5)
 AK9 M_L_CPU1_SA_CB<2> MLA_CHECK2 @T6G_MB_LIB.T6G(SCH_1):M_L_CPU1_SA_CB(2)
AY11 M_L_CPU1_SA_CA<2> MLA_CA2 @T6G_MB_LIB.T6G(SCH_1):M_L_CPU1_SA_CA(2)
AU10 M_L_CPU1_RESET_N ML_RESET_L @T6G_MB_LIB.T6G(SCH_1):M_L_CPU1_RESET_N
CM11 M_L_CPU1_SB_DQS_DP<6> MLB_DQS_H6 @T6G_MB_LIB.T6G(SCH_1):M_L_CPU1_SB_DQS_DP(6)
CG10 M_L_CPU1_SB_DQ<5> MLB_DATA5 @T6G_MB_LIB.T6G(SCH_1):M_L_CPU1_SB_DQ(5)
 BH9 M_L_CPU1_SB_CA<2> MLB_CA2 @T6G_MB_LIB.T6G(SCH_1):M_L_CPU1_SB_CA(2)
BM11 M_L_CPU1_SB_CS_N<0> MLB0_CS_L0 @T6G_MB_LIB.T6G(SCH_1):M_L_CPU1_SB_CS_N(0)
AC10 M_L_CPU1_SA_DQ<23> MLA_DATA23 @T6G_MB_LIB.T6G(SCH_1):M_L_CPU1_SA_DQ(23)
  R9 M_L_CPU1_SA_DQ<12> MLA_DATA12 @T6G_MB_LIB.T6G(SCH_1):M_L_CPU1_SA_DQ(12)
  K9 M_L_CPU1_SA_DQ<6> MLA_DATA6 @T6G_MB_LIB.T6G(SCH_1):M_L_CPU1_SA_DQ(6)
AL10 M_L_CPU1_SA_CB<3> MLA_CHECK3 @T6G_MB_LIB.T6G(SCH_1):M_L_CPU1_SA_CB(3)
BA10 M_L_CPU1_SA_CA<3> MLA_CA3 @T6G_MB_LIB.T6G(SCH_1):M_L_CPU1_SA_CA(3)
CV11 M_L_CPU1_SB_DQS_DP<7> MLB_DQS_H7 @T6G_MB_LIB.T6G(SCH_1):M_L_CPU1_SB_DQS_DP(7)
 CG9 M_L_CPU1_SB_DQ<6> MLB_DATA6 @T6G_MB_LIB.T6G(SCH_1):M_L_CPU1_SB_DQ(6)
 BJ9 M_L_CPU1_SB_CA<3> MLB_CA3 @T6G_MB_LIB.T6G(SCH_1):M_L_CPU1_SB_CA(3)
 BL9     NC MLB1_CS_L0     NC
 BN9 M_L_CPU1_SB_CS_N<1> MLB0_CS_L1 @T6G_MB_LIB.T6G(SCH_1):M_L_CPU1_SB_CS_N(1)
  H9 M_L_CPU1_SA_DQS_DN<0> MLA_DQS_L0 @T6G_MB_LIB.T6G(SCH_1):M_L_CPU1_SA_DQS_DN(0)
 AC9 M_L_CPU1_SA_DQ<24> MLA_DATA24 @T6G_MB_LIB.T6G(SCH_1):M_L_CPU1_SA_DQ(24)
 T11 M_L_CPU1_SA_DQ<13> MLA_DATA13 @T6G_MB_LIB.T6G(SCH_1):M_L_CPU1_SA_DQ(13)
 L10 M_L_CPU1_SA_DQ<7> MLA_DATA7 @T6G_MB_LIB.T6G(SCH_1):M_L_CPU1_SA_DQ(7)
 AN9 M_L_CPU1_SA_CB<4> MLA_CHECK4 @T6G_MB_LIB.T6G(SCH_1):M_L_CPU1_SA_CB(4)
 BA9 M_L_CPU1_SA_CA<4> MLA_CA4 @T6G_MB_LIB.T6G(SCH_1):M_L_CPU1_SA_CA(4)
DD11 M_L_CPU1_SB_DQS_DP<8> MLB_DQS_H8 @T6G_MB_LIB.T6G(SCH_1):M_L_CPU1_SB_DQS_DP(8)
 DE9 M_L_CPU1_SB_DQ<30> MLB_DATA30 @T6G_MB_LIB.T6G(SCH_1):M_L_CPU1_SB_DQ(30)
CH11 M_L_CPU1_SB_DQ<7> MLB_DATA7 @T6G_MB_LIB.T6G(SCH_1):M_L_CPU1_SB_DQ(7)
BJ10 M_L_CPU1_SB_CA<4> MLB_CA4 @T6G_MB_LIB.T6G(SCH_1):M_L_CPU1_SB_CA(4)
 BM9     NC MLB1_CS_L1     NC
  P9 M_L_CPU1_SA_DQS_DN<1> MLA_DQS_L1 @T6G_MB_LIB.T6G(SCH_1):M_L_CPU1_SA_DQS_DN(1)
AD11 M_L_CPU1_SA_DQ<25> MLA_DATA25 @T6G_MB_LIB.T6G(SCH_1):M_L_CPU1_SA_DQ(25)
  T9 M_L_CPU1_SA_DQ<14> MLA_DATA14 @T6G_MB_LIB.T6G(SCH_1):M_L_CPU1_SA_DQ(14)
  L9 M_L_CPU1_SA_DQ<8> MLA_DATA8 @T6G_MB_LIB.T6G(SCH_1):M_L_CPU1_SA_DQ(8)
AP11 M_L_CPU1_SA_CB<5> MLA_CHECK5 @T6G_MB_LIB.T6G(SCH_1):M_L_CPU1_SA_CB(5)
 BB9 M_L_CPU1_SA_CA<5> MLA_CA5 @T6G_MB_LIB.T6G(SCH_1):M_L_CPU1_SA_CA(5)
 BV9 M_L_CPU1_SB_DQS_DP<9> MLB_DQS_H9 @T6G_MB_LIB.T6G(SCH_1):M_L_CPU1_SB_DQS_DP(9)
 DF9 M_L_CPU1_SB_DQ<31> MLB_DATA31 @T6G_MB_LIB.T6G(SCH_1):M_L_CPU1_SB_DQ(31)
 CV9 M_L_CPU1_SB_DQ<20> MLB_DATA20 @T6G_MB_LIB.T6G(SCH_1):M_L_CPU1_SB_DQ(20)
 CH9 M_L_CPU1_SB_DQ<8> MLB_DATA8 @T6G_MB_LIB.T6G(SCH_1):M_L_CPU1_SB_DQ(8)
 BY9 M_L_CPU1_SB_CB<0> MLB_CHECK0 @T6G_MB_LIB.T6G(SCH_1):M_L_CPU1_SB_CB(0)
BK11 M_L_CPU1_SB_CA<5> MLB_CA5 @T6G_MB_LIB.T6G(SCH_1):M_L_CPU1_SB_CA(5)
  Y9 M_L_CPU1_SA_DQS_DN<2> MLA_DQS_L2 @T6G_MB_LIB.T6G(SCH_1):M_L_CPU1_SA_DQS_DN(2)
 AD9 M_L_CPU1_SA_DQ<26> MLA_DATA26 @T6G_MB_LIB.T6G(SCH_1):M_L_CPU1_SA_DQ(26)
 U10 M_L_CPU1_SA_DQ<15> MLA_DATA15 @T6G_MB_LIB.T6G(SCH_1):M_L_CPU1_SA_DQ(15)
 M11 M_L_CPU1_SA_DQ<9> MLA_DATA9 @T6G_MB_LIB.T6G(SCH_1):M_L_CPU1_SA_DQ(9)
 AP9 M_L_CPU1_SA_CB<6> MLA_CHECK6 @T6G_MB_LIB.T6G(SCH_1):M_L_CPU1_SA_CB(6)
BB11 M_L_CPU1_SA_CA<6> MLA_CA6 @T6G_MB_LIB.T6G(SCH_1):M_L_CPU1_SA_CA(6)
BN10 M_L_CPU1_SA_RSP<0> MLA0_RSP_L @T6G_MB_LIB.T6G(SCH_1):M_L_CPU1_SA_RSP(0)
CW10 M_L_CPU1_SB_DQ<21> MLB_DATA21 @T6G_MB_LIB.T6G(SCH_1):M_L_CPU1_SB_DQ(21)
 CJ9 M_L_CPU1_SB_DQ<10> MLB_DATA10 @T6G_MB_LIB.T6G(SCH_1):M_L_CPU1_SB_DQ(10)
CJ10 M_L_CPU1_SB_DQ<9> MLB_DATA9 @T6G_MB_LIB.T6G(SCH_1):M_L_CPU1_SB_DQ(9)
CA10 M_L_CPU1_SB_CB<1> MLB_CHECK1 @T6G_MB_LIB.T6G(SCH_1):M_L_CPU1_SB_CB(1)
 BK9 M_L_CPU1_SB_CA<6> MLB_CA6 @T6G_MB_LIB.T6G(SCH_1):M_L_CPU1_SB_CA(6)
 AF9 M_L_CPU1_SA_DQS_DN<3> MLA_DQS_L3 @T6G_MB_LIB.T6G(SCH_1):M_L_CPU1_SA_DQS_DN(3)
AE10 M_L_CPU1_SA_DQ<27> MLA_DATA27 @T6G_MB_LIB.T6G(SCH_1):M_L_CPU1_SA_DQ(27)
  U9 M_L_CPU1_SA_DQ<16> MLA_DATA16 @T6G_MB_LIB.T6G(SCH_1):M_L_CPU1_SA_DQ(16)
AR10 M_L_CPU1_SA_CB<7> MLA_CHECK7 @T6G_MB_LIB.T6G(SCH_1):M_L_CPU1_SA_CB(7)
BP11     NC MLA1_RSP_L     NC
AT11 M_L_CPU1_ALERT_R_N ML_ALERT_L @T6G_MB_LIB.T6G(SCH_1):M_L_CPU1_ALERT_R_N
 CW9 M_L_CPU1_SB_DQ<22> MLB_DATA22 @T6G_MB_LIB.T6G(SCH_1):M_L_CPU1_SB_DQ(22)
CK11 M_L_CPU1_SB_DQ<11> MLB_DATA11 @T6G_MB_LIB.T6G(SCH_1):M_L_CPU1_SB_DQ(11)
 CA9 M_L_CPU1_SB_CB<2> MLB_CHECK2 @T6G_MB_LIB.T6G(SCH_1):M_L_CPU1_SB_CB(2)
 AM9 M_L_CPU1_SA_DQS_DN<4> MLA_DQS_L4 @T6G_MB_LIB.T6G(SCH_1):M_L_CPU1_SA_DQS_DN(4)
  G9 M_L_CPU1_SA_DQS_DP<0> MLA_DQS_H0 @T6G_MB_LIB.T6G(SCH_1):M_L_CPU1_SA_DQS_DP(0)
 AG9 M_L_CPU1_SA_DQ<28> MLA_DATA28 @T6G_MB_LIB.T6G(SCH_1):M_L_CPU1_SA_DQ(28)
 V11 M_L_CPU1_SA_DQ<17> MLA_DATA17 @T6G_MB_LIB.T6G(SCH_1):M_L_CPU1_SA_DQ(17)
CY11 M_L_CPU1_SB_DQ<23> MLB_DATA23 @T6G_MB_LIB.T6G(SCH_1):M_L_CPU1_SB_DQ(23)
 CM9 M_L_CPU1_SB_DQ<12> MLB_DATA12 @T6G_MB_LIB.T6G(SCH_1):M_L_CPU1_SB_DQ(12)
CB11 M_L_CPU1_SB_CB<3> MLB_CHECK3 @T6G_MB_LIB.T6G(SCH_1):M_L_CPU1_SB_CB(3)
 H11 M_L_CPU1_SA_DQS_DN<5> MLA_DQS_L5 @T6G_MB_LIB.T6G(SCH_1):M_L_CPU1_SA_DQS_DN(5)
  N9 M_L_CPU1_SA_DQS_DP<1> MLA_DQS_H1 @T6G_MB_LIB.T6G(SCH_1):M_L_CPU1_SA_DQS_DP(1)
AH11 M_L_CPU1_SA_DQ<29> MLA_DATA29 @T6G_MB_LIB.T6G(SCH_1):M_L_CPU1_SA_DQ(29)
  V9 M_L_CPU1_SA_DQ<18> MLA_DATA18 @T6G_MB_LIB.T6G(SCH_1):M_L_CPU1_SA_DQ(18)
 BC9 M_L_CPU1_CLK_DP<0> ML0_CLK_H @T6G_MB_LIB.T6G(SCH_1):M_L_CPU1_CLK_DP(0)
 CE9 M_L_CPU1_SB_DQS_DN<0> MLB_DQS_L0 @T6G_MB_LIB.T6G(SCH_1):M_L_CPU1_SB_DQS_DN(0)
 CY9 M_L_CPU1_SB_DQ<24> MLB_DATA24 @T6G_MB_LIB.T6G(SCH_1):M_L_CPU1_SB_DQ(24)
CN10 M_L_CPU1_SB_DQ<13> MLB_DATA13 @T6G_MB_LIB.T6G(SCH_1):M_L_CPU1_SB_DQ(13)
 BT9 M_L_CPU1_SB_CB<4> MLB_CHECK4 @T6G_MB_LIB.T6G(SCH_1):M_L_CPU1_SB_CB(4)
 P11 M_L_CPU1_SA_DQS_DN<6> MLA_DQS_L6 @T6G_MB_LIB.T6G(SCH_1):M_L_CPU1_SA_DQS_DN(6)
  W9 M_L_CPU1_SA_DQS_DP<2> MLA_DQS_H2 @T6G_MB_LIB.T6G(SCH_1):M_L_CPU1_SA_DQS_DP(2)
 W10 M_L_CPU1_SA_DQ<19> MLA_DATA19 @T6G_MB_LIB.T6G(SCH_1):M_L_CPU1_SA_DQ(19)
 BF9     NC ML1_CLK_H     NC
 CL9 M_L_CPU1_SB_DQS_DN<1> MLB_DQS_L1 @T6G_MB_LIB.T6G(SCH_1):M_L_CPU1_SB_DQS_DN(1)
DA10 M_L_CPU1_SB_DQ<25> MLB_DATA25 @T6G_MB_LIB.T6G(SCH_1):M_L_CPU1_SB_DQ(25)
 CN9 M_L_CPU1_SB_DQ<14> MLB_DATA14 @T6G_MB_LIB.T6G(SCH_1):M_L_CPU1_SB_DQ(14)
BU10 M_L_CPU1_SB_CB<5> MLB_CHECK5 @T6G_MB_LIB.T6G(SCH_1):M_L_CPU1_SB_CB(5)
 Y11 M_L_CPU1_SA_DQS_DN<7> MLA_DQS_L7 @T6G_MB_LIB.T6G(SCH_1):M_L_CPU1_SA_DQS_DN(7)
 AE9 M_L_CPU1_SA_DQS_DP<3> MLA_DQS_H3 @T6G_MB_LIB.T6G(SCH_1):M_L_CPU1_SA_DQS_DP(3)
 CU9 M_L_CPU1_SB_DQS_DN<2> MLB_DQS_L2 @T6G_MB_LIB.T6G(SCH_1):M_L_CPU1_SB_DQS_DN(2)
 DA9 M_L_CPU1_SB_DQ<26> MLB_DATA26 @T6G_MB_LIB.T6G(SCH_1):M_L_CPU1_SB_DQ(26)
CP11 M_L_CPU1_SB_DQ<15> MLB_DATA15 @T6G_MB_LIB.T6G(SCH_1):M_L_CPU1_SB_DQ(15)
 BU9 M_L_CPU1_SB_CB<6> MLB_CHECK6 @T6G_MB_LIB.T6G(SCH_1):M_L_CPU1_SB_CB(6)
 BP9 M_L_CPU1_SB_RSP<0> MLB0_RSP_L @T6G_MB_LIB.T6G(SCH_1):M_L_CPU1_SB_RSP(0)
AF11 M_L_CPU1_SA_DQS_DN<8> MLA_DQS_L8 @T6G_MB_LIB.T6G(SCH_1):M_L_CPU1_SA_DQS_DN(8)
 AL9 M_L_CPU1_SA_DQS_DP<4> MLA_DQS_H4 @T6G_MB_LIB.T6G(SCH_1):M_L_CPU1_SA_DQS_DP(4)
 DC9 M_L_CPU1_SB_DQS_DN<3> MLB_DQS_L3 @T6G_MB_LIB.T6G(SCH_1):M_L_CPU1_SB_DQS_DN(3)
DB11 M_L_CPU1_SB_DQ<27> MLB_DATA27 @T6G_MB_LIB.T6G(SCH_1):M_L_CPU1_SB_DQ(27)
 CP9 M_L_CPU1_SB_DQ<16> MLB_DATA16 @T6G_MB_LIB.T6G(SCH_1):M_L_CPU1_SB_DQ(16)
BV11 M_L_CPU1_SB_CB<7> MLB_CHECK7 @T6G_MB_LIB.T6G(SCH_1):M_L_CPU1_SB_CB(7)
 BR9     NC MLB1_RSP_L     NC
BC10 M_L_CPU1_SA_PAR MLA_PAR @T6G_MB_LIB.T6G(SCH_1):M_L_CPU1_SA_PAR
AM11 M_L_CPU1_SA_DQS_DN<9> MLA_DQS_L9 @T6G_MB_LIB.T6G(SCH_1):M_L_CPU1_SA_DQS_DN(9)
 J10 M_L_CPU1_SA_DQS_DP<5> MLA_DQS_H5 @T6G_MB_LIB.T6G(SCH_1):M_L_CPU1_SA_DQS_DP(5)
 BD9 M_L_CPU1_CLK_DN<0> ML0_CLK_L @T6G_MB_LIB.T6G(SCH_1):M_L_CPU1_CLK_DN(0)
BL10 M_L_CPU1_SB_PAR MLB_PAR @T6G_MB_LIB.T6G(SCH_1):M_L_CPU1_SB_PAR
BW10 M_L_CPU1_SB_DQS_DN<4> MLB_DQS_L4 @T6G_MB_LIB.T6G(SCH_1):M_L_CPU1_SB_DQS_DN(4)
 CD9 M_L_CPU1_SB_DQS_DP<0> MLB_DQS_H0 @T6G_MB_LIB.T6G(SCH_1):M_L_CPU1_SB_DQS_DP(0)
 DD9 M_L_CPU1_SB_DQ<28> MLB_DATA28 @T6G_MB_LIB.T6G(SCH_1):M_L_CPU1_SB_DQ(28)
CR10 M_L_CPU1_SB_DQ<17> MLB_DATA17 @T6G_MB_LIB.T6G(SCH_1):M_L_CPU1_SB_DQ(17)
 R10 M_L_CPU1_SA_DQS_DP<6> MLA_DQS_H6 @T6G_MB_LIB.T6G(SCH_1):M_L_CPU1_SA_DQS_DP(6)
  E9 M_L_CPU1_SA_DQ<0> MLA_DATA0 @T6G_MB_LIB.T6G(SCH_1):M_L_CPU1_SA_DQ(0)
 AU9 M_L_CPU1_SA_CS_N<0> MLA0_CS_L0 @T6G_MB_LIB.T6G(SCH_1):M_L_CPU1_SA_CS_N(0)
 BG9     NC ML1_CLK_L     NC
CE10 M_L_CPU1_SB_DQS_DN<5> MLB_DQS_L5 @T6G_MB_LIB.T6G(SCH_1):M_L_CPU1_SB_DQS_DN(5)
 CK9 M_L_CPU1_SB_DQS_DP<1> MLB_DQS_H1 @T6G_MB_LIB.T6G(SCH_1):M_L_CPU1_SB_DQS_DP(1)
DE10 M_L_CPU1_SB_DQ<29> MLB_DATA29 @T6G_MB_LIB.T6G(SCH_1):M_L_CPU1_SB_DQ(29)
 CR9 M_L_CPU1_SB_DQ<18> MLB_DATA18 @T6G_MB_LIB.T6G(SCH_1):M_L_CPU1_SB_DQ(18)
 CB9 M_L_CPU1_SB_DQ<0> MLB_DATA0 @T6G_MB_LIB.T6G(SCH_1):M_L_CPU1_SB_DQ(0)
AA10 M_L_CPU1_SA_DQS_DP<7> MLA_DQS_H7 @T6G_MB_LIB.T6G(SCH_1):M_L_CPU1_SA_DQS_DP(7)
 F11 M_L_CPU1_SA_DQ<1> MLA_DATA1 @T6G_MB_LIB.T6G(SCH_1):M_L_CPU1_SA_DQ(1)
 AV9     NC MLA1_CS_L0     NC
AV11 M_L_CPU1_SA_CS_N<1> MLA0_CS_L1 @T6G_MB_LIB.T6G(SCH_1):M_L_CPU1_SA_CS_N(1)
CL10 M_L_CPU1_SB_DQS_DN<6> MLB_DQS_L6 @T6G_MB_LIB.T6G(SCH_1):M_L_CPU1_SB_DQS_DN(6)
 CT9 M_L_CPU1_SB_DQS_DP<2> MLB_DQS_H2 @T6G_MB_LIB.T6G(SCH_1):M_L_CPU1_SB_DQS_DP(2)
CT11 M_L_CPU1_SB_DQ<19> MLB_DATA19 @T6G_MB_LIB.T6G(SCH_1):M_L_CPU1_SB_DQ(19)
CC10 M_L_CPU1_SB_DQ<1> MLB_DATA1 @T6G_MB_LIB.T6G(SCH_1):M_L_CPU1_SB_DQ(1)
AG10 M_L_CPU1_SA_DQS_DP<8> MLA_DQS_H8 @T6G_MB_LIB.T6G(SCH_1):M_L_CPU1_SA_DQS_DP(8)
 AH9 M_L_CPU1_SA_DQ<30> MLA_DATA30 @T6G_MB_LIB.T6G(SCH_1):M_L_CPU1_SA_DQ(30)
  F9 M_L_CPU1_SA_DQ<2> MLA_DATA2 @T6G_MB_LIB.T6G(SCH_1):M_L_CPU1_SA_DQ(2)
AW10     NC MLA1_CS_L1     NC
CU10 M_L_CPU1_SB_DQS_DN<7> MLB_DQS_L7 @T6G_MB_LIB.T6G(SCH_1):M_L_CPU1_SB_DQS_DN(7)
 DB9 M_L_CPU1_SB_DQS_DP<3> MLB_DQS_H3 @T6G_MB_LIB.T6G(SCH_1):M_L_CPU1_SB_DQS_DP(3)
 CC9 M_L_CPU1_SB_DQ<2> MLB_DATA2 @T6G_MB_LIB.T6G(SCH_1):M_L_CPU1_SB_DQ(2)
AN10 M_L_CPU1_SA_DQS_DP<9> MLA_DQS_H9 @T6G_MB_LIB.T6G(SCH_1):M_L_CPU1_SA_DQS_DP(9)
AJ10 M_L_CPU1_SA_DQ<31> MLA_DATA31 @T6G_MB_LIB.T6G(SCH_1):M_L_CPU1_SA_DQ(31)
 AA9 M_L_CPU1_SA_DQ<20> MLA_DATA20 @T6G_MB_LIB.T6G(SCH_1):M_L_CPU1_SA_DQ(20)
 G10 M_L_CPU1_SA_DQ<3> MLA_DATA3 @T6G_MB_LIB.T6G(SCH_1):M_L_CPU1_SA_DQ(3)
 AJ9 M_L_CPU1_SA_CB<0> MLA_CHECK0 @T6G_MB_LIB.T6G(SCH_1):M_L_CPU1_SA_CB(0)
 AW9 M_L_CPU1_SA_CA<0> MLA_CA0 @T6G_MB_LIB.T6G(SCH_1):M_L_CPU1_SA_CA(0)
DC10 M_L_CPU1_SB_DQS_DN<8> MLB_DQS_L8 @T6G_MB_LIB.T6G(SCH_1):M_L_CPU1_SB_DQS_DN(8)
BY11 M_L_CPU1_SB_DQS_DP<4> MLB_DQS_H4 @T6G_MB_LIB.T6G(SCH_1):M_L_CPU1_SB_DQS_DP(4)
CD11 M_L_CPU1_SB_DQ<3> MLB_DATA3 @T6G_MB_LIB.T6G(SCH_1):M_L_CPU1_SB_DQ(3)
BG10 M_L_CPU1_SB_CA<0> MLB_CA0 @T6G_MB_LIB.T6G(SCH_1):M_L_CPU1_SB_CA(0)
AB11 M_L_CPU1_SA_DQ<21> MLA_DATA21 @T6G_MB_LIB.T6G(SCH_1):M_L_CPU1_SA_DQ(21)
  M9 M_L_CPU1_SA_DQ<10> MLA_DATA10 @T6G_MB_LIB.T6G(SCH_1):M_L_CPU1_SA_DQ(10)
  J9 M_L_CPU1_SA_DQ<4> MLA_DATA4 @T6G_MB_LIB.T6G(SCH_1):M_L_CPU1_SA_DQ(4)
AK11 M_L_CPU1_SA_CB<1> MLA_CHECK1 @T6G_MB_LIB.T6G(SCH_1):M_L_CPU1_SA_CB(1)
 AY9 M_L_CPU1_SA_CA<1> MLA_CA1 @T6G_MB_LIB.T6G(SCH_1):M_L_CPU1_SA_CA(1)
BF11 TP_M_L_CPU1_SA_TEST39L TEST39L @T6G_MB_LIB.T6G(SCH_1):TP_M_L_CPU1_SA_TEST39L

Q_RES_0402LF-15,1%,1/16W,CHIP,CS01502FB03  I313  R511
   1 M_L_CPU1_ALERT_N      A @T6G_MB_LIB.T6G(SCH_1):M_L_CPU1_ALERT_N
   2 M_L_CPU1_ALERT_R_N      B @T6G_MB_LIB.T6G(SCH_1):M_L_CPU1_ALERT_R_N


DRAWING: @T6G_MB_LIB.T6G(SCH_1):PAGE49 

GENOA_SP5-SOCKET6096_13568-001,SMLF,IO,DGA^6000030  I213  U26
 M40 GMI_CPU0_G2_CPU1_G0_TX_DN<15> G0_RXN0 @T6G_MB_LIB.T6G(SCH_1):GMI_CPU0_G2_CPU1_G0_TX_DN(15)
 K40 GMI_CPU0_G2_CPU1_G0_TX_DN<14> G0_RXN1 @T6G_MB_LIB.T6G(SCH_1):GMI_CPU0_G2_CPU1_G0_TX_DN(14)
 H40 GMI_CPU0_G2_CPU1_G0_TX_DN<13> G0_RXN2 @T6G_MB_LIB.T6G(SCH_1):GMI_CPU0_G2_CPU1_G0_TX_DN(13)
 L43 GMI_CPU0_G2_CPU1_G0_TX_DN<12> G0_RXN3 @T6G_MB_LIB.T6G(SCH_1):GMI_CPU0_G2_CPU1_G0_TX_DN(12)
 G43 GMI_CPU0_G2_CPU1_G0_TX_DN<11> G0_RXN4 @T6G_MB_LIB.T6G(SCH_1):GMI_CPU0_G2_CPU1_G0_TX_DN(11)
 J43 GMI_CPU0_G2_CPU1_G0_TX_DN<10> G0_RXN5 @T6G_MB_LIB.T6G(SCH_1):GMI_CPU0_G2_CPU1_G0_TX_DN(10)
 L46 GMI_CPU0_G2_CPU1_G0_TX_DN<9> G0_RXN6 @T6G_MB_LIB.T6G(SCH_1):GMI_CPU0_G2_CPU1_G0_TX_DN(9)
 G46 GMI_CPU0_G2_CPU1_G0_TX_DN<8> G0_RXN7 @T6G_MB_LIB.T6G(SCH_1):GMI_CPU0_G2_CPU1_G0_TX_DN(8)
 J46 GMI_CPU0_G2_CPU1_G0_TX_DN<7> G0_RXN8 @T6G_MB_LIB.T6G(SCH_1):GMI_CPU0_G2_CPU1_G0_TX_DN(7)
 L49 GMI_CPU0_G2_CPU1_G0_TX_DN<6> G0_RXN9 @T6G_MB_LIB.T6G(SCH_1):GMI_CPU0_G2_CPU1_G0_TX_DN(6)
 G49 GMI_CPU0_G2_CPU1_G0_TX_DN<5> G0_RXN10 @T6G_MB_LIB.T6G(SCH_1):GMI_CPU0_G2_CPU1_G0_TX_DN(5)
 J49 GMI_CPU0_G2_CPU1_G0_TX_DN<4> G0_RXN11 @T6G_MB_LIB.T6G(SCH_1):GMI_CPU0_G2_CPU1_G0_TX_DN(4)
 L52 GMI_CPU0_G2_CPU1_G0_TX_DN<3> G0_RXN12 @T6G_MB_LIB.T6G(SCH_1):GMI_CPU0_G2_CPU1_G0_TX_DN(3)
 G52 GMI_CPU0_G2_CPU1_G0_TX_DN<2> G0_RXN13 @T6G_MB_LIB.T6G(SCH_1):GMI_CPU0_G2_CPU1_G0_TX_DN(2)
 J52 GMI_CPU0_G2_CPU1_G0_TX_DN<1> G0_RXN14 @T6G_MB_LIB.T6G(SCH_1):GMI_CPU0_G2_CPU1_G0_TX_DN(1)
 N52 GMI_CPU0_G2_CPU1_G0_TX_DN<0> G0_RXN15 @T6G_MB_LIB.T6G(SCH_1):GMI_CPU0_G2_CPU1_G0_TX_DN(0)
 M41 GMI_CPU0_G2_CPU1_G0_TX_DP<15> G0_RXP0 @T6G_MB_LIB.T6G(SCH_1):GMI_CPU0_G2_CPU1_G0_TX_DP(15)
 K41 GMI_CPU0_G2_CPU1_G0_TX_DP<14> G0_RXP1 @T6G_MB_LIB.T6G(SCH_1):GMI_CPU0_G2_CPU1_G0_TX_DP(14)
 H41 GMI_CPU0_G2_CPU1_G0_TX_DP<13> G0_RXP2 @T6G_MB_LIB.T6G(SCH_1):GMI_CPU0_G2_CPU1_G0_TX_DP(13)
 L44 GMI_CPU0_G2_CPU1_G0_TX_DP<12> G0_RXP3 @T6G_MB_LIB.T6G(SCH_1):GMI_CPU0_G2_CPU1_G0_TX_DP(12)
 G44 GMI_CPU0_G2_CPU1_G0_TX_DP<11> G0_RXP4 @T6G_MB_LIB.T6G(SCH_1):GMI_CPU0_G2_CPU1_G0_TX_DP(11)
 J44 GMI_CPU0_G2_CPU1_G0_TX_DP<10> G0_RXP5 @T6G_MB_LIB.T6G(SCH_1):GMI_CPU0_G2_CPU1_G0_TX_DP(10)
 L47 GMI_CPU0_G2_CPU1_G0_TX_DP<9> G0_RXP6 @T6G_MB_LIB.T6G(SCH_1):GMI_CPU0_G2_CPU1_G0_TX_DP(9)
 G47 GMI_CPU0_G2_CPU1_G0_TX_DP<8> G0_RXP7 @T6G_MB_LIB.T6G(SCH_1):GMI_CPU0_G2_CPU1_G0_TX_DP(8)
 J47 GMI_CPU0_G2_CPU1_G0_TX_DP<7> G0_RXP8 @T6G_MB_LIB.T6G(SCH_1):GMI_CPU0_G2_CPU1_G0_TX_DP(7)
 L50 GMI_CPU0_G2_CPU1_G0_TX_DP<6> G0_RXP9 @T6G_MB_LIB.T6G(SCH_1):GMI_CPU0_G2_CPU1_G0_TX_DP(6)
 G50 GMI_CPU0_G2_CPU1_G0_TX_DP<5> G0_RXP10 @T6G_MB_LIB.T6G(SCH_1):GMI_CPU0_G2_CPU1_G0_TX_DP(5)
 J50 GMI_CPU0_G2_CPU1_G0_TX_DP<4> G0_RXP11 @T6G_MB_LIB.T6G(SCH_1):GMI_CPU0_G2_CPU1_G0_TX_DP(4)
 L53 GMI_CPU0_G2_CPU1_G0_TX_DP<3> G0_RXP12 @T6G_MB_LIB.T6G(SCH_1):GMI_CPU0_G2_CPU1_G0_TX_DP(3)
 G53 GMI_CPU0_G2_CPU1_G0_TX_DP<2> G0_RXP13 @T6G_MB_LIB.T6G(SCH_1):GMI_CPU0_G2_CPU1_G0_TX_DP(2)
 J53 GMI_CPU0_G2_CPU1_G0_TX_DP<1> G0_RXP14 @T6G_MB_LIB.T6G(SCH_1):GMI_CPU0_G2_CPU1_G0_TX_DP(1)
 N53 GMI_CPU0_G2_CPU1_G0_TX_DP<0> G0_RXP15 @T6G_MB_LIB.T6G(SCH_1):GMI_CPU0_G2_CPU1_G0_TX_DP(0)
AF41 GMI_CPU1_G0_CPU0_G2_TX_DN<15> G0_TXN0 @T6G_MB_LIB.T6G(SCH_1):GMI_CPU1_G0_CPU0_G2_TX_DN(15)
AD41 GMI_CPU1_G0_CPU0_G2_TX_DN<14> G0_TXN1 @T6G_MB_LIB.T6G(SCH_1):GMI_CPU1_G0_CPU0_G2_TX_DN(14)
AB41 GMI_CPU1_G0_CPU0_G2_TX_DN<13> G0_TXN2 @T6G_MB_LIB.T6G(SCH_1):GMI_CPU1_G0_CPU0_G2_TX_DN(13)
AG44 GMI_CPU1_G0_CPU0_G2_TX_DN<12> G0_TXN3 @T6G_MB_LIB.T6G(SCH_1):GMI_CPU1_G0_CPU0_G2_TX_DN(12)
AA44 GMI_CPU1_G0_CPU0_G2_TX_DN<11> G0_TXN4 @T6G_MB_LIB.T6G(SCH_1):GMI_CPU1_G0_CPU0_G2_TX_DN(11)
AC44 GMI_CPU1_G0_CPU0_G2_TX_DN<10> G0_TXN5 @T6G_MB_LIB.T6G(SCH_1):GMI_CPU1_G0_CPU0_G2_TX_DN(10)
AE44 GMI_CPU1_G0_CPU0_G2_TX_DN<9> G0_TXN6 @T6G_MB_LIB.T6G(SCH_1):GMI_CPU1_G0_CPU0_G2_TX_DN(9)
AG47 GMI_CPU1_G0_CPU0_G2_TX_DN<8> G0_TXN7 @T6G_MB_LIB.T6G(SCH_1):GMI_CPU1_G0_CPU0_G2_TX_DN(8)
AC47 GMI_CPU1_G0_CPU0_G2_TX_DN<7> G0_TXN8 @T6G_MB_LIB.T6G(SCH_1):GMI_CPU1_G0_CPU0_G2_TX_DN(7)
AE47 GMI_CPU1_G0_CPU0_G2_TX_DN<6> G0_TXN9 @T6G_MB_LIB.T6G(SCH_1):GMI_CPU1_G0_CPU0_G2_TX_DN(6)
AG50 GMI_CPU1_G0_CPU0_G2_TX_DN<5> G0_TXN10 @T6G_MB_LIB.T6G(SCH_1):GMI_CPU1_G0_CPU0_G2_TX_DN(5)
AC50 GMI_CPU1_G0_CPU0_G2_TX_DN<4> G0_TXN11 @T6G_MB_LIB.T6G(SCH_1):GMI_CPU1_G0_CPU0_G2_TX_DN(4)
AE50 GMI_CPU1_G0_CPU0_G2_TX_DN<3> G0_TXN12 @T6G_MB_LIB.T6G(SCH_1):GMI_CPU1_G0_CPU0_G2_TX_DN(3)
AG53 GMI_CPU1_G0_CPU0_G2_TX_DN<2> G0_TXN13 @T6G_MB_LIB.T6G(SCH_1):GMI_CPU1_G0_CPU0_G2_TX_DN(2)
AC53 GMI_CPU1_G0_CPU0_G2_TX_DN<1> G0_TXN14 @T6G_MB_LIB.T6G(SCH_1):GMI_CPU1_G0_CPU0_G2_TX_DN(1)
AE53 GMI_CPU1_G0_CPU0_G2_TX_DN<0> G0_TXN15 @T6G_MB_LIB.T6G(SCH_1):GMI_CPU1_G0_CPU0_G2_TX_DN(0)
AF40 GMI_CPU1_G0_CPU0_G2_TX_DP<15> G0_TXP0 @T6G_MB_LIB.T6G(SCH_1):GMI_CPU1_G0_CPU0_G2_TX_DP(15)
AD40 GMI_CPU1_G0_CPU0_G2_TX_DP<14> G0_TXP1 @T6G_MB_LIB.T6G(SCH_1):GMI_CPU1_G0_CPU0_G2_TX_DP(14)
AB40 GMI_CPU1_G0_CPU0_G2_TX_DP<13> G0_TXP2 @T6G_MB_LIB.T6G(SCH_1):GMI_CPU1_G0_CPU0_G2_TX_DP(13)
AG43 GMI_CPU1_G0_CPU0_G2_TX_DP<12> G0_TXP3 @T6G_MB_LIB.T6G(SCH_1):GMI_CPU1_G0_CPU0_G2_TX_DP(12)
AA43 GMI_CPU1_G0_CPU0_G2_TX_DP<11> G0_TXP4 @T6G_MB_LIB.T6G(SCH_1):GMI_CPU1_G0_CPU0_G2_TX_DP(11)
AC43 GMI_CPU1_G0_CPU0_G2_TX_DP<10> G0_TXP5 @T6G_MB_LIB.T6G(SCH_1):GMI_CPU1_G0_CPU0_G2_TX_DP(10)
AE43 GMI_CPU1_G0_CPU0_G2_TX_DP<9> G0_TXP6 @T6G_MB_LIB.T6G(SCH_1):GMI_CPU1_G0_CPU0_G2_TX_DP(9)
AG46 GMI_CPU1_G0_CPU0_G2_TX_DP<8> G0_TXP7 @T6G_MB_LIB.T6G(SCH_1):GMI_CPU1_G0_CPU0_G2_TX_DP(8)
AC46 GMI_CPU1_G0_CPU0_G2_TX_DP<7> G0_TXP8 @T6G_MB_LIB.T6G(SCH_1):GMI_CPU1_G0_CPU0_G2_TX_DP(7)
AE46 GMI_CPU1_G0_CPU0_G2_TX_DP<6> G0_TXP9 @T6G_MB_LIB.T6G(SCH_1):GMI_CPU1_G0_CPU0_G2_TX_DP(6)
AG49 GMI_CPU1_G0_CPU0_G2_TX_DP<5> G0_TXP10 @T6G_MB_LIB.T6G(SCH_1):GMI_CPU1_G0_CPU0_G2_TX_DP(5)
AC49 GMI_CPU1_G0_CPU0_G2_TX_DP<4> G0_TXP11 @T6G_MB_LIB.T6G(SCH_1):GMI_CPU1_G0_CPU0_G2_TX_DP(4)
AE49 GMI_CPU1_G0_CPU0_G2_TX_DP<3> G0_TXP12 @T6G_MB_LIB.T6G(SCH_1):GMI_CPU1_G0_CPU0_G2_TX_DP(3)
AG52 GMI_CPU1_G0_CPU0_G2_TX_DP<2> G0_TXP13 @T6G_MB_LIB.T6G(SCH_1):GMI_CPU1_G0_CPU0_G2_TX_DP(2)
AC52 GMI_CPU1_G0_CPU0_G2_TX_DP<1> G0_TXP14 @T6G_MB_LIB.T6G(SCH_1):GMI_CPU1_G0_CPU0_G2_TX_DP(1)
AE52 GMI_CPU1_G0_CPU0_G2_TX_DP<0> G0_TXP15 @T6G_MB_LIB.T6G(SCH_1):GMI_CPU1_G0_CPU0_G2_TX_DP(0)

GENOA_SP5-SOCKET6096_13568-001,SMLF,IO,DGA^6000030  I214  U26
AL52 P5E_CPU1_G1_TX_DP<15> G1_TXP15 @T6G_MB_LIB.T6G(SCH_1):P5E_CPU1_G1_TX_DP(15)
AJ52 P5E_CPU1_G1_TX_DP<14> G1_TXP14 @T6G_MB_LIB.T6G(SCH_1):P5E_CPU1_G1_TX_DP(14)
AN52 P5E_CPU1_G1_TX_DP<13> G1_TXP13 @T6G_MB_LIB.T6G(SCH_1):P5E_CPU1_G1_TX_DP(13)
AL49 P5E_CPU1_G1_TX_DP<12> G1_TXP12 @T6G_MB_LIB.T6G(SCH_1):P5E_CPU1_G1_TX_DP(12)
AJ49 P5E_CPU1_G1_TX_DP<11> G1_TXP11 @T6G_MB_LIB.T6G(SCH_1):P5E_CPU1_G1_TX_DP(11)
AN49 P5E_CPU1_G1_TX_DP<10> G1_TXP10 @T6G_MB_LIB.T6G(SCH_1):P5E_CPU1_G1_TX_DP(10)
AL46 P5E_CPU1_G1_TX_DP<9> G1_TXP9 @T6G_MB_LIB.T6G(SCH_1):P5E_CPU1_G1_TX_DP(9)
AJ46 P5E_CPU1_G1_TX_DP<8> G1_TXP8 @T6G_MB_LIB.T6G(SCH_1):P5E_CPU1_G1_TX_DP(8)
AL53 P5E_CPU1_G1_TX_DN<15> G1_TXN15 @T6G_MB_LIB.T6G(SCH_1):P5E_CPU1_G1_TX_DN(15)
AJ53 P5E_CPU1_G1_TX_DN<14> G1_TXN14 @T6G_MB_LIB.T6G(SCH_1):P5E_CPU1_G1_TX_DN(14)
AN53 P5E_CPU1_G1_TX_DN<13> G1_TXN13 @T6G_MB_LIB.T6G(SCH_1):P5E_CPU1_G1_TX_DN(13)
AL50 P5E_CPU1_G1_TX_DN<12> G1_TXN12 @T6G_MB_LIB.T6G(SCH_1):P5E_CPU1_G1_TX_DN(12)
AJ50 P5E_CPU1_G1_TX_DN<11> G1_TXN11 @T6G_MB_LIB.T6G(SCH_1):P5E_CPU1_G1_TX_DN(11)
AN50 P5E_CPU1_G1_TX_DN<10> G1_TXN10 @T6G_MB_LIB.T6G(SCH_1):P5E_CPU1_G1_TX_DN(10)
AL47 P5E_CPU1_G1_TX_DN<9> G1_TXN9 @T6G_MB_LIB.T6G(SCH_1):P5E_CPU1_G1_TX_DN(9)
AJ47 P5E_CPU1_G1_TX_DN<8> G1_TXN8 @T6G_MB_LIB.T6G(SCH_1):P5E_CPU1_G1_TX_DN(8)
 U53 P5E_CPU1_G1_RX_DP<15> G1_RXP15 @T6G_MB_LIB.T6G(SCH_1):P5E_CPU1_G1_RX_DP(15)
 R53 P5E_CPU1_G1_RX_DP<14> G1_RXP14 @T6G_MB_LIB.T6G(SCH_1):P5E_CPU1_G1_RX_DP(14)
 W53 P5E_CPU1_G1_RX_DP<13> G1_RXP13 @T6G_MB_LIB.T6G(SCH_1):P5E_CPU1_G1_RX_DP(13)
 U50 P5E_CPU1_G1_RX_DP<12> G1_RXP12 @T6G_MB_LIB.T6G(SCH_1):P5E_CPU1_G1_RX_DP(12)
 R50 P5E_CPU1_G1_RX_DP<11> G1_RXP11 @T6G_MB_LIB.T6G(SCH_1):P5E_CPU1_G1_RX_DP(11)
 N50 P5E_CPU1_G1_RX_DP<10> G1_RXP10 @T6G_MB_LIB.T6G(SCH_1):P5E_CPU1_G1_RX_DP(10)
 W50 P5E_CPU1_G1_RX_DP<9> G1_RXP9 @T6G_MB_LIB.T6G(SCH_1):P5E_CPU1_G1_RX_DP(9)
 R47 P5E_CPU1_G1_RX_DP<8> G1_RXP8 @T6G_MB_LIB.T6G(SCH_1):P5E_CPU1_G1_RX_DP(8)
 U52 P5E_CPU1_G1_RX_DN<15> G1_RXN15 @T6G_MB_LIB.T6G(SCH_1):P5E_CPU1_G1_RX_DN(15)
 R52 P5E_CPU1_G1_RX_DN<14> G1_RXN14 @T6G_MB_LIB.T6G(SCH_1):P5E_CPU1_G1_RX_DN(14)
 W52 P5E_CPU1_G1_RX_DN<13> G1_RXN13 @T6G_MB_LIB.T6G(SCH_1):P5E_CPU1_G1_RX_DN(13)
 U49 P5E_CPU1_G1_RX_DN<12> G1_RXN12 @T6G_MB_LIB.T6G(SCH_1):P5E_CPU1_G1_RX_DN(12)
 R49 P5E_CPU1_G1_RX_DN<11> G1_RXN11 @T6G_MB_LIB.T6G(SCH_1):P5E_CPU1_G1_RX_DN(11)
 N49 P5E_CPU1_G1_RX_DN<10> G1_RXN10 @T6G_MB_LIB.T6G(SCH_1):P5E_CPU1_G1_RX_DN(10)
 W49 P5E_CPU1_G1_RX_DN<9> G1_RXN9 @T6G_MB_LIB.T6G(SCH_1):P5E_CPU1_G1_RX_DN(9)
 R46 P5E_CPU1_G1_RX_DN<8> G1_RXN8 @T6G_MB_LIB.T6G(SCH_1):P5E_CPU1_G1_RX_DN(8)
AP40 P5E_CPU1_G1_TX_DP<0> G1_TXP0 @T6G_MB_LIB.T6G(SCH_1):P5E_CPU1_G1_TX_DP(0)
AM40 P5E_CPU1_G1_TX_DP<1> G1_TXP1 @T6G_MB_LIB.T6G(SCH_1):P5E_CPU1_G1_TX_DP(1)
AH40 P5E_CPU1_G1_TX_DP<2> G1_TXP2 @T6G_MB_LIB.T6G(SCH_1):P5E_CPU1_G1_TX_DP(2)
AP41 P5E_CPU1_G1_TX_DN<0> G1_TXN0 @T6G_MB_LIB.T6G(SCH_1):P5E_CPU1_G1_TX_DN(0)
 V41 P5E_CPU1_G1_RX_DP<0> G1_RXP0 @T6G_MB_LIB.T6G(SCH_1):P5E_CPU1_G1_RX_DP(0)
AK40 P5E_CPU1_G1_TX_DP<3> G1_TXP3 @T6G_MB_LIB.T6G(SCH_1):P5E_CPU1_G1_TX_DP(3)
AM41 P5E_CPU1_G1_TX_DN<1> G1_TXN1 @T6G_MB_LIB.T6G(SCH_1):P5E_CPU1_G1_TX_DN(1)
 T41 P5E_CPU1_G1_RX_DP<1> G1_RXP1 @T6G_MB_LIB.T6G(SCH_1):P5E_CPU1_G1_RX_DP(1)
AN43 P5E_CPU1_G1_TX_DP<4> G1_TXP4 @T6G_MB_LIB.T6G(SCH_1):P5E_CPU1_G1_TX_DP(4)
AH41 P5E_CPU1_G1_TX_DN<2> G1_TXN2 @T6G_MB_LIB.T6G(SCH_1):P5E_CPU1_G1_TX_DN(2)
 P41 P5E_CPU1_G1_RX_DP<2> G1_RXP2 @T6G_MB_LIB.T6G(SCH_1):P5E_CPU1_G1_RX_DP(2)
 V40 P5E_CPU1_G1_RX_DN<0> G1_RXN0 @T6G_MB_LIB.T6G(SCH_1):P5E_CPU1_G1_RX_DN(0)
AJ43 P5E_CPU1_G1_TX_DP<5> G1_TXP5 @T6G_MB_LIB.T6G(SCH_1):P5E_CPU1_G1_TX_DP(5)
AK41 P5E_CPU1_G1_TX_DN<3> G1_TXN3 @T6G_MB_LIB.T6G(SCH_1):P5E_CPU1_G1_TX_DN(3)
 U44 P5E_CPU1_G1_RX_DP<3> G1_RXP3 @T6G_MB_LIB.T6G(SCH_1):P5E_CPU1_G1_RX_DP(3)
 T40 P5E_CPU1_G1_RX_DN<1> G1_RXN1 @T6G_MB_LIB.T6G(SCH_1):P5E_CPU1_G1_RX_DN(1)
AL43 P5E_CPU1_G1_TX_DP<6> G1_TXP6 @T6G_MB_LIB.T6G(SCH_1):P5E_CPU1_G1_TX_DP(6)
AN44 P5E_CPU1_G1_TX_DN<4> G1_TXN4 @T6G_MB_LIB.T6G(SCH_1):P5E_CPU1_G1_TX_DN(4)
 N44 P5E_CPU1_G1_RX_DP<4> G1_RXP4 @T6G_MB_LIB.T6G(SCH_1):P5E_CPU1_G1_RX_DP(4)
 P40 P5E_CPU1_G1_RX_DN<2> G1_RXN2 @T6G_MB_LIB.T6G(SCH_1):P5E_CPU1_G1_RX_DN(2)
AN46 P5E_CPU1_G1_TX_DP<7> G1_TXP7 @T6G_MB_LIB.T6G(SCH_1):P5E_CPU1_G1_TX_DP(7)
AJ44 P5E_CPU1_G1_TX_DN<5> G1_TXN5 @T6G_MB_LIB.T6G(SCH_1):P5E_CPU1_G1_TX_DN(5)
 R44 P5E_CPU1_G1_RX_DP<5> G1_RXP5 @T6G_MB_LIB.T6G(SCH_1):P5E_CPU1_G1_RX_DP(5)
 U43 P5E_CPU1_G1_RX_DN<3> G1_RXN3 @T6G_MB_LIB.T6G(SCH_1):P5E_CPU1_G1_RX_DN(3)
AL44 P5E_CPU1_G1_TX_DN<6> G1_TXN6 @T6G_MB_LIB.T6G(SCH_1):P5E_CPU1_G1_TX_DN(6)
 U47 P5E_CPU1_G1_RX_DP<6> G1_RXP6 @T6G_MB_LIB.T6G(SCH_1):P5E_CPU1_G1_RX_DP(6)
 N43 P5E_CPU1_G1_RX_DN<4> G1_RXN4 @T6G_MB_LIB.T6G(SCH_1):P5E_CPU1_G1_RX_DN(4)
AN47 P5E_CPU1_G1_TX_DN<7> G1_TXN7 @T6G_MB_LIB.T6G(SCH_1):P5E_CPU1_G1_TX_DN(7)
 N47 P5E_CPU1_G1_RX_DP<7> G1_RXP7 @T6G_MB_LIB.T6G(SCH_1):P5E_CPU1_G1_RX_DP(7)
 R43 P5E_CPU1_G1_RX_DN<5> G1_RXN5 @T6G_MB_LIB.T6G(SCH_1):P5E_CPU1_G1_RX_DN(5)
 U46 P5E_CPU1_G1_RX_DN<6> G1_RXN6 @T6G_MB_LIB.T6G(SCH_1):P5E_CPU1_G1_RX_DN(6)
 N46 P5E_CPU1_G1_RX_DN<7> G1_RXN7 @T6G_MB_LIB.T6G(SCH_1):P5E_CPU1_G1_RX_DN(7)


DRAWING: @T6G_MB_LIB.T6G(SCH_1):PAGE50 

GENOA_SP5-SOCKET6096_13568-001,SMLF,IO,DGA^6000030  I143  U26
 G29 GMI_CPU1_G2_CPU0_G0_TX_DP<7> G2_TXP8 @T6G_MB_LIB.T6G(SCH_1):GMI_CPU1_G2_CPU0_G0_TX_DP(7)
 G30 GMI_CPU1_G2_CPU0_G0_TX_DN<7> G2_TXN8 @T6G_MB_LIB.T6G(SCH_1):GMI_CPU1_G2_CPU0_G0_TX_DN(7)
 J32 GMI_CPU1_G2_CPU0_G0_TX_DP<5> G2_TXP10 @T6G_MB_LIB.T6G(SCH_1):GMI_CPU1_G2_CPU0_G0_TX_DP(5)
 J33 GMI_CPU1_G2_CPU0_G0_TX_DN<5> G2_TXN10 @T6G_MB_LIB.T6G(SCH_1):GMI_CPU1_G2_CPU0_G0_TX_DN(5)
 L32 GMI_CPU1_G2_CPU0_G0_TX_DP<3> G2_TXP12 @T6G_MB_LIB.T6G(SCH_1):GMI_CPU1_G2_CPU0_G0_TX_DP(3)
 L33 GMI_CPU1_G2_CPU0_G0_TX_DN<3> G2_TXN12 @T6G_MB_LIB.T6G(SCH_1):GMI_CPU1_G2_CPU0_G0_TX_DN(3)
 K35 GMI_CPU1_G2_CPU0_G0_TX_DP<1> G2_TXP14 @T6G_MB_LIB.T6G(SCH_1):GMI_CPU1_G2_CPU0_G0_TX_DP(1)
 K36 GMI_CPU1_G2_CPU0_G0_TX_DN<1> G2_TXN14 @T6G_MB_LIB.T6G(SCH_1):GMI_CPU1_G2_CPU0_G0_TX_DN(1)
 L29 GMI_CPU1_G2_CPU0_G0_TX_DP<6> G2_TXP9 @T6G_MB_LIB.T6G(SCH_1):GMI_CPU1_G2_CPU0_G0_TX_DP(6)
 L30 GMI_CPU1_G2_CPU0_G0_TX_DN<6> G2_TXN9 @T6G_MB_LIB.T6G(SCH_1):GMI_CPU1_G2_CPU0_G0_TX_DN(6)
 G32 GMI_CPU1_G2_CPU0_G0_TX_DP<4> G2_TXP11 @T6G_MB_LIB.T6G(SCH_1):GMI_CPU1_G2_CPU0_G0_TX_DP(4)
 G33 GMI_CPU1_G2_CPU0_G0_TX_DN<4> G2_TXN11 @T6G_MB_LIB.T6G(SCH_1):GMI_CPU1_G2_CPU0_G0_TX_DN(4)
 H35 GMI_CPU1_G2_CPU0_G0_TX_DP<2> G2_TXP13 @T6G_MB_LIB.T6G(SCH_1):GMI_CPU1_G2_CPU0_G0_TX_DP(2)
 H36 GMI_CPU1_G2_CPU0_G0_TX_DN<2> G2_TXN13 @T6G_MB_LIB.T6G(SCH_1):GMI_CPU1_G2_CPU0_G0_TX_DN(2)
 M35 GMI_CPU1_G2_CPU0_G0_TX_DP<0> G2_TXP15 @T6G_MB_LIB.T6G(SCH_1):GMI_CPU1_G2_CPU0_G0_TX_DP(0)
 M36 GMI_CPU1_G2_CPU0_G0_TX_DN<0> G2_TXN15 @T6G_MB_LIB.T6G(SCH_1):GMI_CPU1_G2_CPU0_G0_TX_DN(0)
AG30 GMI_CPU0_G0_CPU1_G2_TX_DP<7> G2_RXP8 @T6G_MB_LIB.T6G(SCH_1):GMI_CPU0_G0_CPU1_G2_TX_DP(7)
AG29 GMI_CPU0_G0_CPU1_G2_TX_DN<7> G2_RXN8 @T6G_MB_LIB.T6G(SCH_1):GMI_CPU0_G0_CPU1_G2_TX_DN(7)
AC33 GMI_CPU0_G0_CPU1_G2_TX_DP<5> G2_RXP10 @T6G_MB_LIB.T6G(SCH_1):GMI_CPU0_G0_CPU1_G2_TX_DP(5)
AC32 GMI_CPU0_G0_CPU1_G2_TX_DN<5> G2_RXN10 @T6G_MB_LIB.T6G(SCH_1):GMI_CPU0_G0_CPU1_G2_TX_DN(5)
AG33 GMI_CPU0_G0_CPU1_G2_TX_DP<3> G2_RXP12 @T6G_MB_LIB.T6G(SCH_1):GMI_CPU0_G0_CPU1_G2_TX_DP(3)
AG32 GMI_CPU0_G0_CPU1_G2_TX_DN<3> G2_RXN12 @T6G_MB_LIB.T6G(SCH_1):GMI_CPU0_G0_CPU1_G2_TX_DN(3)
AD36 GMI_CPU0_G0_CPU1_G2_TX_DP<1> G2_RXP14 @T6G_MB_LIB.T6G(SCH_1):GMI_CPU0_G0_CPU1_G2_TX_DP(1)
AD35 GMI_CPU0_G0_CPU1_G2_TX_DN<1> G2_RXN14 @T6G_MB_LIB.T6G(SCH_1):GMI_CPU0_G0_CPU1_G2_TX_DN(1)
AE33 GMI_CPU0_G0_CPU1_G2_TX_DP<6> G2_RXP9 @T6G_MB_LIB.T6G(SCH_1):GMI_CPU0_G0_CPU1_G2_TX_DP(6)
AE32 GMI_CPU0_G0_CPU1_G2_TX_DN<6> G2_RXN9 @T6G_MB_LIB.T6G(SCH_1):GMI_CPU0_G0_CPU1_G2_TX_DN(6)
AA33 GMI_CPU0_G0_CPU1_G2_TX_DP<4> G2_RXP11 @T6G_MB_LIB.T6G(SCH_1):GMI_CPU0_G0_CPU1_G2_TX_DP(4)
AA32 GMI_CPU0_G0_CPU1_G2_TX_DN<4> G2_RXN11 @T6G_MB_LIB.T6G(SCH_1):GMI_CPU0_G0_CPU1_G2_TX_DN(4)
AB36 GMI_CPU0_G0_CPU1_G2_TX_DP<2> G2_RXP13 @T6G_MB_LIB.T6G(SCH_1):GMI_CPU0_G0_CPU1_G2_TX_DP(2)
AB35 GMI_CPU0_G0_CPU1_G2_TX_DN<2> G2_RXN13 @T6G_MB_LIB.T6G(SCH_1):GMI_CPU0_G0_CPU1_G2_TX_DN(2)
AF36 GMI_CPU0_G0_CPU1_G2_TX_DP<0> G2_RXP15 @T6G_MB_LIB.T6G(SCH_1):GMI_CPU0_G0_CPU1_G2_TX_DP(0)
AF35 GMI_CPU0_G0_CPU1_G2_TX_DN<0> G2_RXN15 @T6G_MB_LIB.T6G(SCH_1):GMI_CPU0_G0_CPU1_G2_TX_DN(0)
 J23 GMI_CPU1_G2_CPU0_G0_TX_DP<14> G2_TXP1 @T6G_MB_LIB.T6G(SCH_1):GMI_CPU1_G2_CPU0_G0_TX_DP(14)
 G23 GMI_CPU1_G2_CPU0_G0_TX_DP<13> G2_TXP2 @T6G_MB_LIB.T6G(SCH_1):GMI_CPU1_G2_CPU0_G0_TX_DP(13)
 N24 GMI_CPU1_G2_CPU0_G0_TX_DN<15> G2_TXN0 @T6G_MB_LIB.T6G(SCH_1):GMI_CPU1_G2_CPU0_G0_TX_DN(15)
AE24 GMI_CPU0_G0_CPU1_G2_TX_DP<15> G2_RXP0 @T6G_MB_LIB.T6G(SCH_1):GMI_CPU0_G0_CPU1_G2_TX_DP(15)
 L23 GMI_CPU1_G2_CPU0_G0_TX_DP<12> G2_TXP3 @T6G_MB_LIB.T6G(SCH_1):GMI_CPU1_G2_CPU0_G0_TX_DP(12)
 J24 GMI_CPU1_G2_CPU0_G0_TX_DN<14> G2_TXN1 @T6G_MB_LIB.T6G(SCH_1):GMI_CPU1_G2_CPU0_G0_TX_DN(14)
AC24 GMI_CPU0_G0_CPU1_G2_TX_DP<14> G2_RXP1 @T6G_MB_LIB.T6G(SCH_1):GMI_CPU0_G0_CPU1_G2_TX_DP(14)
 J26 GMI_CPU1_G2_CPU0_G0_TX_DP<11> G2_TXP4 @T6G_MB_LIB.T6G(SCH_1):GMI_CPU1_G2_CPU0_G0_TX_DP(11)
 G24 GMI_CPU1_G2_CPU0_G0_TX_DN<13> G2_TXN2 @T6G_MB_LIB.T6G(SCH_1):GMI_CPU1_G2_CPU0_G0_TX_DN(13)
AG24 GMI_CPU0_G0_CPU1_G2_TX_DP<13> G2_RXP2 @T6G_MB_LIB.T6G(SCH_1):GMI_CPU0_G0_CPU1_G2_TX_DP(13)
AE23 GMI_CPU0_G0_CPU1_G2_TX_DN<15> G2_RXN0 @T6G_MB_LIB.T6G(SCH_1):GMI_CPU0_G0_CPU1_G2_TX_DN(15)
 G26 GMI_CPU1_G2_CPU0_G0_TX_DP<10> G2_TXP5 @T6G_MB_LIB.T6G(SCH_1):GMI_CPU1_G2_CPU0_G0_TX_DP(10)
 L24 GMI_CPU1_G2_CPU0_G0_TX_DN<12> G2_TXN3 @T6G_MB_LIB.T6G(SCH_1):GMI_CPU1_G2_CPU0_G0_TX_DN(12)
AE27 GMI_CPU0_G0_CPU1_G2_TX_DP<12> G2_RXP3 @T6G_MB_LIB.T6G(SCH_1):GMI_CPU0_G0_CPU1_G2_TX_DP(12)
AC23 GMI_CPU0_G0_CPU1_G2_TX_DN<14> G2_RXN1 @T6G_MB_LIB.T6G(SCH_1):GMI_CPU0_G0_CPU1_G2_TX_DN(14)
 L26 GMI_CPU1_G2_CPU0_G0_TX_DP<9> G2_TXP6 @T6G_MB_LIB.T6G(SCH_1):GMI_CPU1_G2_CPU0_G0_TX_DP(9)
 J27 GMI_CPU1_G2_CPU0_G0_TX_DN<11> G2_TXN4 @T6G_MB_LIB.T6G(SCH_1):GMI_CPU1_G2_CPU0_G0_TX_DN(11)
AC27 GMI_CPU0_G0_CPU1_G2_TX_DP<11> G2_RXP4 @T6G_MB_LIB.T6G(SCH_1):GMI_CPU0_G0_CPU1_G2_TX_DP(11)
AG23 GMI_CPU0_G0_CPU1_G2_TX_DN<13> G2_RXN2 @T6G_MB_LIB.T6G(SCH_1):GMI_CPU0_G0_CPU1_G2_TX_DN(13)
 J29 GMI_CPU1_G2_CPU0_G0_TX_DP<8> G2_TXP7 @T6G_MB_LIB.T6G(SCH_1):GMI_CPU1_G2_CPU0_G0_TX_DP(8)
 G27 GMI_CPU1_G2_CPU0_G0_TX_DN<10> G2_TXN5 @T6G_MB_LIB.T6G(SCH_1):GMI_CPU1_G2_CPU0_G0_TX_DN(10)
AG27 GMI_CPU0_G0_CPU1_G2_TX_DP<10> G2_RXP5 @T6G_MB_LIB.T6G(SCH_1):GMI_CPU0_G0_CPU1_G2_TX_DP(10)
AE26 GMI_CPU0_G0_CPU1_G2_TX_DN<12> G2_RXN3 @T6G_MB_LIB.T6G(SCH_1):GMI_CPU0_G0_CPU1_G2_TX_DN(12)
 L27 GMI_CPU1_G2_CPU0_G0_TX_DN<9> G2_TXN6 @T6G_MB_LIB.T6G(SCH_1):GMI_CPU1_G2_CPU0_G0_TX_DN(9)
AE30 GMI_CPU0_G0_CPU1_G2_TX_DP<9> G2_RXP6 @T6G_MB_LIB.T6G(SCH_1):GMI_CPU0_G0_CPU1_G2_TX_DP(9)
AC26 GMI_CPU0_G0_CPU1_G2_TX_DN<11> G2_RXN4 @T6G_MB_LIB.T6G(SCH_1):GMI_CPU0_G0_CPU1_G2_TX_DN(11)
 J30 GMI_CPU1_G2_CPU0_G0_TX_DN<8> G2_TXN7 @T6G_MB_LIB.T6G(SCH_1):GMI_CPU1_G2_CPU0_G0_TX_DN(8)
AC30 GMI_CPU0_G0_CPU1_G2_TX_DP<8> G2_RXP7 @T6G_MB_LIB.T6G(SCH_1):GMI_CPU0_G0_CPU1_G2_TX_DP(8)
AG26 GMI_CPU0_G0_CPU1_G2_TX_DN<10> G2_RXN5 @T6G_MB_LIB.T6G(SCH_1):GMI_CPU0_G0_CPU1_G2_TX_DN(10)
AE29 GMI_CPU0_G0_CPU1_G2_TX_DN<9> G2_RXN6 @T6G_MB_LIB.T6G(SCH_1):GMI_CPU0_G0_CPU1_G2_TX_DN(9)
AC29 GMI_CPU0_G0_CPU1_G2_TX_DN<8> G2_RXN7 @T6G_MB_LIB.T6G(SCH_1):GMI_CPU0_G0_CPU1_G2_TX_DN(8)
 N23 GMI_CPU1_G2_CPU0_G0_TX_DP<15> G2_TXP0 @T6G_MB_LIB.T6G(SCH_1):GMI_CPU1_G2_CPU0_G0_TX_DP(15)

GENOA_SP5-SOCKET6096_13568-001,SMLF,IO,DGA^6000030  I144  U26
 P35 GMI_CPU1_G3_CPU0_G1_TX_DP<2> G3_TXP13||SATA35_TXP @T6G_MB_LIB.T6G(SCH_1):GMI_CPU1_G3_CPU0_G1_TX_DP(2)
 R32 GMI_CPU1_G3_CPU0_G1_TX_DP<5> G3_TXP10||SATA32_TXP @T6G_MB_LIB.T6G(SCH_1):GMI_CPU1_G3_CPU0_G1_TX_DP(5)
AN26 GMI_CPU0_G1_CPU1_G3_TX_DN<10> G3_RXN5||SATA25_RXN @T6G_MB_LIB.T6G(SCH_1):GMI_CPU0_G1_CPU1_G3_TX_DN(10)
 W24 GMI_CPU1_G3_CPU0_G1_TX_DN<13> G3_TXN2||SATA22_TXN @T6G_MB_LIB.T6G(SCH_1):GMI_CPU1_G3_CPU0_G1_TX_DN(13)
AK36 GMI_CPU0_G1_CPU1_G3_TX_DP<3> G3_RXP12||SATA34_RXP @T6G_MB_LIB.T6G(SCH_1):GMI_CPU0_G1_CPU1_G3_TX_DP(3)
AL24 GMI_CPU0_G1_CPU1_G3_TX_DP<15> G3_RXP0||SATA20_RXP @T6G_MB_LIB.T6G(SCH_1):GMI_CPU0_G1_CPU1_G3_TX_DP(15)
 T36 GMI_CPU1_G3_CPU0_G1_TX_DN<1> G3_TXN14||SATA36_TXN @T6G_MB_LIB.T6G(SCH_1):GMI_CPU1_G3_CPU0_G1_TX_DN(1)
 N33 GMI_CPU1_G3_CPU0_G1_TX_DN<4> G3_TXN11||SATA33_TXN @T6G_MB_LIB.T6G(SCH_1):GMI_CPU1_G3_CPU0_G1_TX_DN(4)
 N27 GMI_CPU1_G3_CPU0_G1_TX_DN<10> G3_TXN5||SATA25_TXN @T6G_MB_LIB.T6G(SCH_1):GMI_CPU1_G3_CPU0_G1_TX_DN(10)
AP36 GMI_CPU0_G1_CPU1_G3_TX_DP<0> G3_RXP15||SATA37_RXP @T6G_MB_LIB.T6G(SCH_1):GMI_CPU0_G1_CPU1_G3_TX_DP(0)
AL30 GMI_CPU0_G1_CPU1_G3_TX_DP<9> G3_RXP6||SATA26_RXP @T6G_MB_LIB.T6G(SCH_1):GMI_CPU0_G1_CPU1_G3_TX_DP(9)
AL27 GMI_CPU0_G1_CPU1_G3_TX_DP<12> G3_RXP3||SATA23_RXP @T6G_MB_LIB.T6G(SCH_1):GMI_CPU0_G1_CPU1_G3_TX_DP(12)
 U26 GMI_CPU1_G3_CPU0_G1_TX_DP<12> G3_TXP3||SATA23_TXP @T6G_MB_LIB.T6G(SCH_1):GMI_CPU1_G3_CPU0_G1_TX_DP(12)
 U23 GMI_CPU1_G3_CPU0_G1_TX_DP<15> G3_TXP0||SATA20_TXP @T6G_MB_LIB.T6G(SCH_1):GMI_CPU1_G3_CPU0_G1_TX_DP(15)
AJ32 GMI_CPU0_G1_CPU1_G3_TX_DN<5> G3_RXN10||SATA32_RXN @T6G_MB_LIB.T6G(SCH_1):GMI_CPU0_G1_CPU1_G3_TX_DN(5)
 W26 GMI_CPU1_G3_CPU0_G1_TX_DP<9> G3_TXP6||SATA26_TXP @T6G_MB_LIB.T6G(SCH_1):GMI_CPU1_G3_CPU0_G1_TX_DP(9)
AH35 GMI_CPU0_G1_CPU1_G3_TX_DN<2> G3_RXN13||SATA35_RXN @T6G_MB_LIB.T6G(SCH_1):GMI_CPU0_G1_CPU1_G3_TX_DN(2)
 N32 GMI_CPU1_G3_CPU0_G1_TX_DP<4> G3_TXP11||SATA33_TXP @T6G_MB_LIB.T6G(SCH_1):GMI_CPU1_G3_CPU0_G1_TX_DP(4)
AN30 GMI_CPU0_G1_CPU1_G3_TX_DP<7> G3_RXP8||SATA30_RXP @T6G_MB_LIB.T6G(SCH_1):GMI_CPU0_G1_CPU1_G3_TX_DP(7)
AL26 GMI_CPU0_G1_CPU1_G3_TX_DN<12> G3_RXN3||SATA23_RXN @T6G_MB_LIB.T6G(SCH_1):GMI_CPU0_G1_CPU1_G3_TX_DN(12)
AL23 GMI_CPU0_G1_CPU1_G3_TX_DN<15> G3_RXN0||SATA20_RXN @T6G_MB_LIB.T6G(SCH_1):GMI_CPU0_G1_CPU1_G3_TX_DN(15)
 T35 GMI_CPU1_G3_CPU0_G1_TX_DP<1> G3_TXP14||SATA36_TXP @T6G_MB_LIB.T6G(SCH_1):GMI_CPU1_G3_CPU0_G1_TX_DP(1)
 N29 GMI_CPU1_G3_CPU0_G1_TX_DP<7> G3_TXP8||SATA30_TXP @T6G_MB_LIB.T6G(SCH_1):GMI_CPU1_G3_CPU0_G1_TX_DP(7)
 U24 GMI_CPU1_G3_CPU0_G1_TX_DN<15> G3_TXN0||SATA20_TXN @T6G_MB_LIB.T6G(SCH_1):GMI_CPU1_G3_CPU0_G1_TX_DN(15)
AL29 GMI_CPU0_G1_CPU1_G3_TX_DN<9> G3_RXN6||SATA26_RXN @T6G_MB_LIB.T6G(SCH_1):GMI_CPU0_G1_CPU1_G3_TX_DN(9)
 W27 GMI_CPU1_G3_CPU0_G1_TX_DN<9> G3_TXN6||SATA26_TXN @T6G_MB_LIB.T6G(SCH_1):GMI_CPU1_G3_CPU0_G1_TX_DN(9)
 U27 GMI_CPU1_G3_CPU0_G1_TX_DN<12> G3_TXN3||SATA23_TXN @T6G_MB_LIB.T6G(SCH_1):GMI_CPU1_G3_CPU0_G1_TX_DN(12)
AH36 GMI_CPU0_G1_CPU1_G3_TX_DP<2> G3_RXP13||SATA35_RXP @T6G_MB_LIB.T6G(SCH_1):GMI_CPU0_G1_CPU1_G3_TX_DP(2)
AJ33 GMI_CPU0_G1_CPU1_G3_TX_DP<5> G3_RXP10||SATA32_RXP @T6G_MB_LIB.T6G(SCH_1):GMI_CPU0_G1_CPU1_G3_TX_DP(5)
AJ27 GMI_CPU0_G1_CPU1_G3_TX_DP<11> G3_RXP4||SATA24_RXP @T6G_MB_LIB.T6G(SCH_1):GMI_CPU0_G1_CPU1_G3_TX_DP(11)
AJ24 GMI_CPU0_G1_CPU1_G3_TX_DP<14> G3_RXP1||SATA21_RXP @T6G_MB_LIB.T6G(SCH_1):GMI_CPU0_G1_CPU1_G3_TX_DP(14)
 V36 GMI_CPU1_G3_CPU0_G1_TX_DN<0> G3_TXN15||SATA37_TXN @T6G_MB_LIB.T6G(SCH_1):GMI_CPU1_G3_CPU0_G1_TX_DN(0)
 U33 GMI_CPU1_G3_CPU0_G1_TX_DN<3> G3_TXN12||SATA34_TXN @T6G_MB_LIB.T6G(SCH_1):GMI_CPU1_G3_CPU0_G1_TX_DN(3)
AN29 GMI_CPU0_G1_CPU1_G3_TX_DN<7> G3_RXN8||SATA30_RXN @T6G_MB_LIB.T6G(SCH_1):GMI_CPU0_G1_CPU1_G3_TX_DN(7)
AJ30 GMI_CPU0_G1_CPU1_G3_TX_DP<8> G3_RXP7||SATA27_RXP @T6G_MB_LIB.T6G(SCH_1):GMI_CPU0_G1_CPU1_G3_TX_DP(8)
 R26 GMI_CPU1_G3_CPU0_G1_TX_DP<11> G3_TXP4||SATA24_TXP @T6G_MB_LIB.T6G(SCH_1):GMI_CPU1_G3_CPU0_G1_TX_DP(11)
 R23 GMI_CPU1_G3_CPU0_G1_TX_DP<14> G3_TXP1||SATA21_TXP @T6G_MB_LIB.T6G(SCH_1):GMI_CPU1_G3_CPU0_G1_TX_DP(14)
AM35 GMI_CPU0_G1_CPU1_G3_TX_DN<1> G3_RXN14||SATA36_RXN @T6G_MB_LIB.T6G(SCH_1):GMI_CPU0_G1_CPU1_G3_TX_DN(1)
AN32 GMI_CPU0_G1_CPU1_G3_TX_DN<4> G3_RXN11||SATA33_RXN @T6G_MB_LIB.T6G(SCH_1):GMI_CPU0_G1_CPU1_G3_TX_DN(4)
 N30 GMI_CPU1_G3_CPU0_G1_TX_DN<7> G3_TXN8||SATA30_TXN @T6G_MB_LIB.T6G(SCH_1):GMI_CPU1_G3_CPU0_G1_TX_DN(7)
 R29 GMI_CPU1_G3_CPU0_G1_TX_DP<8> G3_TXP7||SATA27_TXP @T6G_MB_LIB.T6G(SCH_1):GMI_CPU1_G3_CPU0_G1_TX_DP(8)
AL33 GMI_CPU0_G1_CPU1_G3_TX_DP<6> G3_RXP9||SATA31_RXP @T6G_MB_LIB.T6G(SCH_1):GMI_CPU0_G1_CPU1_G3_TX_DP(6)
 U32 GMI_CPU1_G3_CPU0_G1_TX_DP<3> G3_TXP12||SATA34_TXP @T6G_MB_LIB.T6G(SCH_1):GMI_CPU1_G3_CPU0_G1_TX_DP(3)
AJ29 GMI_CPU0_G1_CPU1_G3_TX_DN<8> G3_RXN7||SATA27_RXN @T6G_MB_LIB.T6G(SCH_1):GMI_CPU0_G1_CPU1_G3_TX_DN(8)
AJ26 GMI_CPU0_G1_CPU1_G3_TX_DN<11> G3_RXN4||SATA24_RXN @T6G_MB_LIB.T6G(SCH_1):GMI_CPU0_G1_CPU1_G3_TX_DN(11)
AJ23 GMI_CPU0_G1_CPU1_G3_TX_DN<14> G3_RXN1||SATA21_RXN @T6G_MB_LIB.T6G(SCH_1):GMI_CPU0_G1_CPU1_G3_TX_DN(14)
 V35 GMI_CPU1_G3_CPU0_G1_TX_DP<0> G3_TXP15||SATA37_TXP @T6G_MB_LIB.T6G(SCH_1):GMI_CPU1_G3_CPU0_G1_TX_DP(0)
 U29 GMI_CPU1_G3_CPU0_G1_TX_DP<6> G3_TXP9||SATA31_TXP @T6G_MB_LIB.T6G(SCH_1):GMI_CPU1_G3_CPU0_G1_TX_DP(6)
 R24 GMI_CPU1_G3_CPU0_G1_TX_DN<14> G3_TXN1||SATA21_TXN @T6G_MB_LIB.T6G(SCH_1):GMI_CPU1_G3_CPU0_G1_TX_DN(14)
AN33 GMI_CPU0_G1_CPU1_G3_TX_DP<4> G3_RXP11||SATA33_RXP @T6G_MB_LIB.T6G(SCH_1):GMI_CPU0_G1_CPU1_G3_TX_DP(4)
 P36 GMI_CPU1_G3_CPU0_G1_TX_DN<2> G3_TXN13||SATA35_TXN @T6G_MB_LIB.T6G(SCH_1):GMI_CPU1_G3_CPU0_G1_TX_DN(2)
 R33 GMI_CPU1_G3_CPU0_G1_TX_DN<5> G3_TXN10||SATA32_TXN @T6G_MB_LIB.T6G(SCH_1):GMI_CPU1_G3_CPU0_G1_TX_DN(5)
 R30 GMI_CPU1_G3_CPU0_G1_TX_DN<8> G3_TXN7||SATA27_TXN @T6G_MB_LIB.T6G(SCH_1):GMI_CPU1_G3_CPU0_G1_TX_DN(8)
 R27 GMI_CPU1_G3_CPU0_G1_TX_DN<11> G3_TXN4||SATA24_TXN @T6G_MB_LIB.T6G(SCH_1):GMI_CPU1_G3_CPU0_G1_TX_DN(11)
AM36 GMI_CPU0_G1_CPU1_G3_TX_DP<1> G3_RXP14||SATA36_RXP @T6G_MB_LIB.T6G(SCH_1):GMI_CPU0_G1_CPU1_G3_TX_DP(1)
AN27 GMI_CPU0_G1_CPU1_G3_TX_DP<10> G3_RXP5||SATA25_RXP @T6G_MB_LIB.T6G(SCH_1):GMI_CPU0_G1_CPU1_G3_TX_DP(10)
AN24 GMI_CPU0_G1_CPU1_G3_TX_DP<13> G3_RXP2||SATA22_RXP @T6G_MB_LIB.T6G(SCH_1):GMI_CPU0_G1_CPU1_G3_TX_DP(13)
 W23 GMI_CPU1_G3_CPU0_G1_TX_DP<13> G3_TXP2||SATA22_TXP @T6G_MB_LIB.T6G(SCH_1):GMI_CPU1_G3_CPU0_G1_TX_DP(13)
AL32 GMI_CPU0_G1_CPU1_G3_TX_DN<6> G3_RXN9||SATA31_RXN @T6G_MB_LIB.T6G(SCH_1):GMI_CPU0_G1_CPU1_G3_TX_DN(6)
 N26 GMI_CPU1_G3_CPU0_G1_TX_DP<10> G3_TXP5||SATA25_TXP @T6G_MB_LIB.T6G(SCH_1):GMI_CPU1_G3_CPU0_G1_TX_DP(10)
AP35 GMI_CPU0_G1_CPU1_G3_TX_DN<0> G3_RXN15||SATA37_RXN @T6G_MB_LIB.T6G(SCH_1):GMI_CPU0_G1_CPU1_G3_TX_DN(0)
AK35 GMI_CPU0_G1_CPU1_G3_TX_DN<3> G3_RXN12||SATA34_RXN @T6G_MB_LIB.T6G(SCH_1):GMI_CPU0_G1_CPU1_G3_TX_DN(3)
 U30 GMI_CPU1_G3_CPU0_G1_TX_DN<6> G3_TXN9||SATA31_TXN @T6G_MB_LIB.T6G(SCH_1):GMI_CPU1_G3_CPU0_G1_TX_DN(6)
AN23 GMI_CPU0_G1_CPU1_G3_TX_DN<13> G3_RXN2||SATA22_RXN @T6G_MB_LIB.T6G(SCH_1):GMI_CPU0_G1_CPU1_G3_TX_DN(13)


DRAWING: @T6G_MB_LIB.T6G(SCH_1):PAGE51 

GENOA_SP5-SOCKET6096_13568-001,SMLF,IO,DGA^6000030  I147  U26
BW53 P5E_CPU1_P0_RX_DN<0> P0_RXN0||SATA00_RXN @T6G_MB_LIB.T6G(SCH_1):P5E_CPU1_P0_RX_DN(0)
BW47 P5E_CPU1_P0_RX_DN<6> P0_RXN6||SATA06_RXN @T6G_MB_LIB.T6G(SCH_1):P5E_CPU1_P0_RX_DN(6)
BW50 P5E_CPU1_P0_RX_DN<3> P0_RXN3||SATA03_RXN @T6G_MB_LIB.T6G(SCH_1):P5E_CPU1_P0_RX_DN(3)
CN49 P5E_CPU1_P0_TX_DN<3> P0_TXN3||SATA03_TXN @T6G_MB_LIB.T6G(SCH_1):P5E_CPU1_P0_TX_DN(3)
CN52 P5E_CPU1_P0_TX_DN<0> P0_TXN0||SATA00_TXN @T6G_MB_LIB.T6G(SCH_1):P5E_CPU1_P0_TX_DN(0)
CA52 P5E_CPU1_P0_RX_DP<1> P0_RXP1||SATA01_RXP @T6G_MB_LIB.T6G(SCH_1):P5E_CPU1_P0_RX_DP(1)
CL49 P5E_CPU1_P0_TX_DN<6> P0_TXN6||SATA06_TXN @T6G_MB_LIB.T6G(SCH_1):P5E_CPU1_P0_TX_DN(6)
CA46 P5E_CPU1_P0_RX_DP<7> P0_RXP7||SATA07_RXP @T6G_MB_LIB.T6G(SCH_1):P5E_CPU1_P0_RX_DP(7)
CA49 P5E_CPU1_P0_RX_DP<4> P0_RXP4||SATA04_RXP @T6G_MB_LIB.T6G(SCH_1):P5E_CPU1_P0_RX_DP(4)
CR50 P5E_CPU1_P0_TX_DP<4> P0_TXP4||SATA04_TXP @T6G_MB_LIB.T6G(SCH_1):P5E_CPU1_P0_TX_DP(4)
CR53 P5E_CPU1_P0_TX_DP<1> P0_TXP1||SATA01_TXP @T6G_MB_LIB.T6G(SCH_1):P5E_CPU1_P0_TX_DP(1)
CR47 P5E_CPU1_P0_TX_DP<7> P0_TXP7||SATA07_TXP @T6G_MB_LIB.T6G(SCH_1):P5E_CPU1_P0_TX_DP(7)
CA50 P5E_CPU1_P0_RX_DN<4> P0_RXN4||SATA04_RXN @T6G_MB_LIB.T6G(SCH_1):P5E_CPU1_P0_RX_DN(4)
CA53 P5E_CPU1_P0_RX_DN<1> P0_RXN1||SATA01_RXN @T6G_MB_LIB.T6G(SCH_1):P5E_CPU1_P0_RX_DN(1)
CA47 P5E_CPU1_P0_RX_DN<7> P0_RXN7||SATA07_RXN @T6G_MB_LIB.T6G(SCH_1):P5E_CPU1_P0_RX_DN(7)
CR49 P5E_CPU1_P0_TX_DN<4> P0_TXN4||SATA04_TXN @T6G_MB_LIB.T6G(SCH_1):P5E_CPU1_P0_TX_DN(4)
CR46 P5E_CPU1_P0_TX_DN<7> P0_TXN7||SATA07_TXN @T6G_MB_LIB.T6G(SCH_1):P5E_CPU1_P0_TX_DN(7)
CR52 P5E_CPU1_P0_TX_DN<1> P0_TXN1||SATA01_TXN @T6G_MB_LIB.T6G(SCH_1):P5E_CPU1_P0_TX_DN(1)
BU52 P5E_CPU1_P0_RX_DP<2> P0_RXP2||SATA02_RXP @T6G_MB_LIB.T6G(SCH_1):P5E_CPU1_P0_RX_DP(2)
BU49 P5E_CPU1_P0_RX_DP<5> P0_RXP5||SATA05_RXP @T6G_MB_LIB.T6G(SCH_1):P5E_CPU1_P0_RX_DP(5)
CU50 P5E_CPU1_P0_TX_DP<5> P0_TXP5||SATA05_TXP @T6G_MB_LIB.T6G(SCH_1):P5E_CPU1_P0_TX_DP(5)
CL53 P5E_CPU1_P0_TX_DP<2> P0_TXP2||SATA02_TXP @T6G_MB_LIB.T6G(SCH_1):P5E_CPU1_P0_TX_DP(2)
BU50 P5E_CPU1_P0_RX_DN<5> P0_RXN5||SATA05_RXN @T6G_MB_LIB.T6G(SCH_1):P5E_CPU1_P0_RX_DN(5)
BU53 P5E_CPU1_P0_RX_DN<2> P0_RXN2||SATA02_RXN @T6G_MB_LIB.T6G(SCH_1):P5E_CPU1_P0_RX_DN(2)
CL52 P5E_CPU1_P0_TX_DN<2> P0_TXN2||SATA02_TXN @T6G_MB_LIB.T6G(SCH_1):P5E_CPU1_P0_TX_DN(2)
BW52 P5E_CPU1_P0_RX_DP<0> P0_RXP0||SATA00_RXP @T6G_MB_LIB.T6G(SCH_1):P5E_CPU1_P0_RX_DP(0)
CU49 P5E_CPU1_P0_TX_DN<5> P0_TXN5||SATA05_TXN @T6G_MB_LIB.T6G(SCH_1):P5E_CPU1_P0_TX_DN(5)
BW46 P5E_CPU1_P0_RX_DP<6> P0_RXP6||SATA06_RXP @T6G_MB_LIB.T6G(SCH_1):P5E_CPU1_P0_RX_DP(6)
BW49 P5E_CPU1_P0_RX_DP<3> P0_RXP3||SATA03_RXP @T6G_MB_LIB.T6G(SCH_1):P5E_CPU1_P0_RX_DP(3)
CN53 P5E_CPU1_P0_TX_DP<0> P0_TXP0||SATA00_TXP @T6G_MB_LIB.T6G(SCH_1):P5E_CPU1_P0_TX_DP(0)
CL50 P5E_CPU1_P0_TX_DP<6> P0_TXP6||SATA06_TXP @T6G_MB_LIB.T6G(SCH_1):P5E_CPU1_P0_TX_DP(6)
CN50 P5E_CPU1_P0_TX_DP<3> P0_TXP3||SATA03_TXP @T6G_MB_LIB.T6G(SCH_1):P5E_CPU1_P0_TX_DP(3)
CT40 P5E_CPU1_P0_TX_DN<13> P0_TXN13||SATA15_TXN @T6G_MB_LIB.T6G(SCH_1):P5E_CPU1_P0_TX_DN(13)
CR43 P5E_CPU1_P0_TX_DN<10> P0_TXN10||SATA12_TXN @T6G_MB_LIB.T6G(SCH_1):P5E_CPU1_P0_TX_DN(10)
BV40 P5E_CPU1_P0_RX_DP<14> P0_RXP14||SATA16_RXP @T6G_MB_LIB.T6G(SCH_1):P5E_CPU1_P0_RX_DP(14)
BU46 P5E_CPU1_P0_RX_DP<8> P0_RXP8||SATA10_RXP @T6G_MB_LIB.T6G(SCH_1):P5E_CPU1_P0_RX_DP(8)
BY41 P5E_CPU1_P0_RX_DN<12> P0_RXN12||SATA14_RXN @T6G_MB_LIB.T6G(SCH_1):P5E_CPU1_P0_RX_DN(12)
CU47 P5E_CPU1_P0_TX_DP<8> P0_TXP8||SATA10_TXP @T6G_MB_LIB.T6G(SCH_1):P5E_CPU1_P0_TX_DP(8)
BT41 P5E_CPU1_P0_RX_DN<15> P0_RXN15||SATA17_RXN @T6G_MB_LIB.T6G(SCH_1):P5E_CPU1_P0_RX_DN(15)
CR44 P5E_CPU1_P0_TX_DP<10> P0_TXP10||SATA12_TXP @T6G_MB_LIB.T6G(SCH_1):P5E_CPU1_P0_TX_DP(10)
CT41 P5E_CPU1_P0_TX_DP<13> P0_TXP13||SATA15_TXP @T6G_MB_LIB.T6G(SCH_1):P5E_CPU1_P0_TX_DP(13)
BU47 P5E_CPU1_P0_RX_DN<8> P0_RXN8||SATA10_RXN @T6G_MB_LIB.T6G(SCH_1):P5E_CPU1_P0_RX_DN(8)
CU43 P5E_CPU1_P0_TX_DN<11> P0_TXN11||SATA13_TXN @T6G_MB_LIB.T6G(SCH_1):P5E_CPU1_P0_TX_DN(11)
CU46 P5E_CPU1_P0_TX_DN<8> P0_TXN8||SATA10_TXN @T6G_MB_LIB.T6G(SCH_1):P5E_CPU1_P0_TX_DN(8)
BT40 P5E_CPU1_P0_RX_DP<15> P0_RXP15||SATA17_RXP @T6G_MB_LIB.T6G(SCH_1):P5E_CPU1_P0_RX_DP(15)
BY40 P5E_CPU1_P0_RX_DP<12> P0_RXP12||SATA14_RXP @T6G_MB_LIB.T6G(SCH_1):P5E_CPU1_P0_RX_DP(12)
CP40 P5E_CPU1_P0_TX_DN<14> P0_TXN14||SATA16_TXN @T6G_MB_LIB.T6G(SCH_1):P5E_CPU1_P0_TX_DN(14)
BW43 P5E_CPU1_P0_RX_DP<9> P0_RXP9||SATA11_RXP @T6G_MB_LIB.T6G(SCH_1):P5E_CPU1_P0_RX_DP(9)
CN47 P5E_CPU1_P0_TX_DP<9> P0_TXP9||SATA11_TXP @T6G_MB_LIB.T6G(SCH_1):P5E_CPU1_P0_TX_DP(9)
CB41 P5E_CPU1_P0_RX_DN<13> P0_RXN13||SATA15_RXN @T6G_MB_LIB.T6G(SCH_1):P5E_CPU1_P0_RX_DN(13)
CA44 P5E_CPU1_P0_RX_DN<10> P0_RXN10||SATA12_RXN @T6G_MB_LIB.T6G(SCH_1):P5E_CPU1_P0_RX_DN(10)
CP41 P5E_CPU1_P0_TX_DP<14> P0_TXP14||SATA16_TXP @T6G_MB_LIB.T6G(SCH_1):P5E_CPU1_P0_TX_DP(14)
CU44 P5E_CPU1_P0_TX_DP<11> P0_TXP11||SATA13_TXP @T6G_MB_LIB.T6G(SCH_1):P5E_CPU1_P0_TX_DP(11)
BW44 P5E_CPU1_P0_RX_DN<9> P0_RXN9||SATA11_RXN @T6G_MB_LIB.T6G(SCH_1):P5E_CPU1_P0_RX_DN(9)
CA43 P5E_CPU1_P0_RX_DP<10> P0_RXP10||SATA12_RXP @T6G_MB_LIB.T6G(SCH_1):P5E_CPU1_P0_RX_DP(10)
CN43 P5E_CPU1_P0_TX_DN<12> P0_TXN12||SATA14_TXN @T6G_MB_LIB.T6G(SCH_1):P5E_CPU1_P0_TX_DN(12)
CN46 P5E_CPU1_P0_TX_DN<9> P0_TXN9||SATA11_TXN @T6G_MB_LIB.T6G(SCH_1):P5E_CPU1_P0_TX_DN(9)
CB40 P5E_CPU1_P0_RX_DP<13> P0_RXP13||SATA15_RXP @T6G_MB_LIB.T6G(SCH_1):P5E_CPU1_P0_RX_DP(13)
CM40 P5E_CPU1_P0_TX_DN<15> P0_TXN15||SATA17_TXN @T6G_MB_LIB.T6G(SCH_1):P5E_CPU1_P0_TX_DN(15)
BV41 P5E_CPU1_P0_RX_DN<14> P0_RXN14||SATA16_RXN @T6G_MB_LIB.T6G(SCH_1):P5E_CPU1_P0_RX_DN(14)
BU44 P5E_CPU1_P0_RX_DN<11> P0_RXN11||SATA13_RXN @T6G_MB_LIB.T6G(SCH_1):P5E_CPU1_P0_RX_DN(11)
CM41 P5E_CPU1_P0_TX_DP<15> P0_TXP15||SATA17_TXP @T6G_MB_LIB.T6G(SCH_1):P5E_CPU1_P0_TX_DP(15)
CN44 P5E_CPU1_P0_TX_DP<12> P0_TXP12||SATA14_TXP @T6G_MB_LIB.T6G(SCH_1):P5E_CPU1_P0_TX_DP(12)
BU43 P5E_CPU1_P0_RX_DP<11> P0_RXP11||SATA13_RXP @T6G_MB_LIB.T6G(SCH_1):P5E_CPU1_P0_RX_DP(11)

GENOA_SP5-SOCKET6096_13568-001,SMLF,IO,DGA^6000030  I148  U26
CC46 P5E_CPU1_P1_RX_DP<8> P1_RXP8 @T6G_MB_LIB.T6G(SCH_1):P5E_CPU1_P1_RX_DP(8)
CC47 P5E_CPU1_P1_RX_DN<8> P1_RXN8 @T6G_MB_LIB.T6G(SCH_1):P5E_CPU1_P1_RX_DN(8)
CE43 P5E_CPU1_P1_RX_DP<9> P1_RXP9 @T6G_MB_LIB.T6G(SCH_1):P5E_CPU1_P1_RX_DP(9)
CE44 P5E_CPU1_P1_RX_DN<9> P1_RXN9 @T6G_MB_LIB.T6G(SCH_1):P5E_CPU1_P1_RX_DN(9)
CG43 P5E_CPU1_P1_RX_DP<10> P1_RXP10 @T6G_MB_LIB.T6G(SCH_1):P5E_CPU1_P1_RX_DP(10)
CG44 P5E_CPU1_P1_RX_DN<10> P1_RXN10 @T6G_MB_LIB.T6G(SCH_1):P5E_CPU1_P1_RX_DN(10)
CJ43 P5E_CPU1_P1_RX_DP<11> P1_RXP11 @T6G_MB_LIB.T6G(SCH_1):P5E_CPU1_P1_RX_DP(11)
CJ44 P5E_CPU1_P1_RX_DN<11> P1_RXN11 @T6G_MB_LIB.T6G(SCH_1):P5E_CPU1_P1_RX_DN(11)
CC43 P5E_CPU1_P1_RX_DP<12> P1_RXP12 @T6G_MB_LIB.T6G(SCH_1):P5E_CPU1_P1_RX_DP(12)
CC44 P5E_CPU1_P1_RX_DN<12> P1_RXN12 @T6G_MB_LIB.T6G(SCH_1):P5E_CPU1_P1_RX_DN(12)
CH40 P5E_CPU1_P1_RX_DP<13> P1_RXP13 @T6G_MB_LIB.T6G(SCH_1):P5E_CPU1_P1_RX_DP(13)
CH41 P5E_CPU1_P1_RX_DN<13> P1_RXN13 @T6G_MB_LIB.T6G(SCH_1):P5E_CPU1_P1_RX_DN(13)
CF40 P5E_CPU1_P1_RX_DP<14> P1_RXP14 @T6G_MB_LIB.T6G(SCH_1):P5E_CPU1_P1_RX_DP(14)
CF41 P5E_CPU1_P1_RX_DN<14> P1_RXN14 @T6G_MB_LIB.T6G(SCH_1):P5E_CPU1_P1_RX_DN(14)
CD40 P5E_CPU1_P1_RX_DP<15> P1_RXP15 @T6G_MB_LIB.T6G(SCH_1):P5E_CPU1_P1_RX_DP(15)
CD41 P5E_CPU1_P1_RX_DN<15> P1_RXN15 @T6G_MB_LIB.T6G(SCH_1):P5E_CPU1_P1_RX_DN(15)
DC47 P5E_CPU1_P1_TX_DP<8> P1_TXP8 @T6G_MB_LIB.T6G(SCH_1):P5E_CPU1_P1_TX_DP(8)
DC46 P5E_CPU1_P1_TX_DN<8> P1_TXN8 @T6G_MB_LIB.T6G(SCH_1):P5E_CPU1_P1_TX_DN(8)
CW47 P5E_CPU1_P1_TX_DP<9> P1_TXP9 @T6G_MB_LIB.T6G(SCH_1):P5E_CPU1_P1_TX_DP(9)
CW46 P5E_CPU1_P1_TX_DN<9> P1_TXN9 @T6G_MB_LIB.T6G(SCH_1):P5E_CPU1_P1_TX_DN(9)
DA44 P5E_CPU1_P1_TX_DP<10> P1_TXP10 @T6G_MB_LIB.T6G(SCH_1):P5E_CPU1_P1_TX_DP(10)
DA43 P5E_CPU1_P1_TX_DN<10> P1_TXN10 @T6G_MB_LIB.T6G(SCH_1):P5E_CPU1_P1_TX_DN(10)
DC44 P5E_CPU1_P1_TX_DP<11> P1_TXP11 @T6G_MB_LIB.T6G(SCH_1):P5E_CPU1_P1_TX_DP(11)
DC43 P5E_CPU1_P1_TX_DN<11> P1_TXN11 @T6G_MB_LIB.T6G(SCH_1):P5E_CPU1_P1_TX_DN(11)
CW44 P5E_CPU1_P1_TX_DP<12> P1_TXP12 @T6G_MB_LIB.T6G(SCH_1):P5E_CPU1_P1_TX_DP(12)
CW43 P5E_CPU1_P1_TX_DN<12> P1_TXN12 @T6G_MB_LIB.T6G(SCH_1):P5E_CPU1_P1_TX_DN(12)
DB41 P5E_CPU1_P1_TX_DP<13> P1_TXP13 @T6G_MB_LIB.T6G(SCH_1):P5E_CPU1_P1_TX_DP(13)
DB40 P5E_CPU1_P1_TX_DN<13> P1_TXN13 @T6G_MB_LIB.T6G(SCH_1):P5E_CPU1_P1_TX_DN(13)
CY41 P5E_CPU1_P1_TX_DP<14> P1_TXP14 @T6G_MB_LIB.T6G(SCH_1):P5E_CPU1_P1_TX_DP(14)
CY40 P5E_CPU1_P1_TX_DN<14> P1_TXN14 @T6G_MB_LIB.T6G(SCH_1):P5E_CPU1_P1_TX_DN(14)
CV41 P5E_CPU1_P1_TX_DP<15> P1_TXP15 @T6G_MB_LIB.T6G(SCH_1):P5E_CPU1_P1_TX_DP(15)
CV40 P5E_CPU1_P1_TX_DN<15> P1_TXN15 @T6G_MB_LIB.T6G(SCH_1):P5E_CPU1_P1_TX_DN(15)
CG47 P5E_CPU1_P1_RX_DN<7> P1_RXN7 @T6G_MB_LIB.T6G(SCH_1):P5E_CPU1_P1_RX_DN(7)
CU53 P5E_CPU1_P1_TX_DP<0> P1_TXP0 @T6G_MB_LIB.T6G(SCH_1):P5E_CPU1_P1_TX_DP(0)
DA53 P5E_CPU1_P1_TX_DP<1> P1_TXP1 @T6G_MB_LIB.T6G(SCH_1):P5E_CPU1_P1_TX_DP(1)
DC53 P5E_CPU1_P1_TX_DP<2> P1_TXP2 @T6G_MB_LIB.T6G(SCH_1):P5E_CPU1_P1_TX_DP(2)
CU52 P5E_CPU1_P1_TX_DN<0> P1_TXN0 @T6G_MB_LIB.T6G(SCH_1):P5E_CPU1_P1_TX_DN(0)
CE52 P5E_CPU1_P1_RX_DP<0> P1_RXP0 @T6G_MB_LIB.T6G(SCH_1):P5E_CPU1_P1_RX_DP(0)
CW53 P5E_CPU1_P1_TX_DP<3> P1_TXP3 @T6G_MB_LIB.T6G(SCH_1):P5E_CPU1_P1_TX_DP(3)
DA52 P5E_CPU1_P1_TX_DN<1> P1_TXN1 @T6G_MB_LIB.T6G(SCH_1):P5E_CPU1_P1_TX_DN(1)
CG52 P5E_CPU1_P1_RX_DP<1> P1_RXP1 @T6G_MB_LIB.T6G(SCH_1):P5E_CPU1_P1_RX_DP(1)
DA50 P5E_CPU1_P1_TX_DP<4> P1_TXP4 @T6G_MB_LIB.T6G(SCH_1):P5E_CPU1_P1_TX_DP(4)
DC52 P5E_CPU1_P1_TX_DN<2> P1_TXN2 @T6G_MB_LIB.T6G(SCH_1):P5E_CPU1_P1_TX_DN(2)
CC52 P5E_CPU1_P1_RX_DP<2> P1_RXP2 @T6G_MB_LIB.T6G(SCH_1):P5E_CPU1_P1_RX_DP(2)
CE53 P5E_CPU1_P1_RX_DN<0> P1_RXN0 @T6G_MB_LIB.T6G(SCH_1):P5E_CPU1_P1_RX_DN(0)
DC50 P5E_CPU1_P1_TX_DP<5> P1_TXP5 @T6G_MB_LIB.T6G(SCH_1):P5E_CPU1_P1_TX_DP(5)
CW52 P5E_CPU1_P1_TX_DN<3> P1_TXN3 @T6G_MB_LIB.T6G(SCH_1):P5E_CPU1_P1_TX_DN(3)
CE49 P5E_CPU1_P1_RX_DP<3> P1_RXP3 @T6G_MB_LIB.T6G(SCH_1):P5E_CPU1_P1_RX_DP(3)
CG53 P5E_CPU1_P1_RX_DN<1> P1_RXN1 @T6G_MB_LIB.T6G(SCH_1):P5E_CPU1_P1_RX_DN(1)
CW50 P5E_CPU1_P1_TX_DP<6> P1_TXP6 @T6G_MB_LIB.T6G(SCH_1):P5E_CPU1_P1_TX_DP(6)
DA49 P5E_CPU1_P1_TX_DN<4> P1_TXN4 @T6G_MB_LIB.T6G(SCH_1):P5E_CPU1_P1_TX_DN(4)
CG49 P5E_CPU1_P1_RX_DP<4> P1_RXP4 @T6G_MB_LIB.T6G(SCH_1):P5E_CPU1_P1_RX_DP(4)
CC53 P5E_CPU1_P1_RX_DN<2> P1_RXN2 @T6G_MB_LIB.T6G(SCH_1):P5E_CPU1_P1_RX_DN(2)
DA47 P5E_CPU1_P1_TX_DP<7> P1_TXP7 @T6G_MB_LIB.T6G(SCH_1):P5E_CPU1_P1_TX_DP(7)
DC49 P5E_CPU1_P1_TX_DN<5> P1_TXN5 @T6G_MB_LIB.T6G(SCH_1):P5E_CPU1_P1_TX_DN(5)
CC49 P5E_CPU1_P1_RX_DP<5> P1_RXP5 @T6G_MB_LIB.T6G(SCH_1):P5E_CPU1_P1_RX_DP(5)
CE50 P5E_CPU1_P1_RX_DN<3> P1_RXN3 @T6G_MB_LIB.T6G(SCH_1):P5E_CPU1_P1_RX_DN(3)
CW49 P5E_CPU1_P1_TX_DN<6> P1_TXN6 @T6G_MB_LIB.T6G(SCH_1):P5E_CPU1_P1_TX_DN(6)
CE46 P5E_CPU1_P1_RX_DP<6> P1_RXP6 @T6G_MB_LIB.T6G(SCH_1):P5E_CPU1_P1_RX_DP(6)
CG50 P5E_CPU1_P1_RX_DN<4> P1_RXN4 @T6G_MB_LIB.T6G(SCH_1):P5E_CPU1_P1_RX_DN(4)
DA46 P5E_CPU1_P1_TX_DN<7> P1_TXN7 @T6G_MB_LIB.T6G(SCH_1):P5E_CPU1_P1_TX_DN(7)
CG46 P5E_CPU1_P1_RX_DP<7> P1_RXP7 @T6G_MB_LIB.T6G(SCH_1):P5E_CPU1_P1_RX_DP(7)
CC50 P5E_CPU1_P1_RX_DN<5> P1_RXN5 @T6G_MB_LIB.T6G(SCH_1):P5E_CPU1_P1_RX_DN(5)
CE47 P5E_CPU1_P1_RX_DN<6> P1_RXN6 @T6G_MB_LIB.T6G(SCH_1):P5E_CPU1_P1_RX_DN(6)


DRAWING: @T6G_MB_LIB.T6G(SCH_1):PAGE52 

GENOA_SP5-SOCKET6096_13568-001,SMLF,IO,DGA^6000030  I147  U26
CV35 P5E_CPU1_P3_RX_DP<0> P3_RXP0 @T6G_MB_LIB.T6G(SCH_1):P5E_CPU1_P3_RX_DP(0)
CV36 P5E_CPU1_P3_RX_DN<0> P3_RXN0 @T6G_MB_LIB.T6G(SCH_1):P5E_CPU1_P3_RX_DN(0)
CY35 P5E_CPU1_P3_RX_DP<1> P3_RXP1 @T6G_MB_LIB.T6G(SCH_1):P5E_CPU1_P3_RX_DP(1)
CY36 P5E_CPU1_P3_RX_DN<1> P3_RXN1 @T6G_MB_LIB.T6G(SCH_1):P5E_CPU1_P3_RX_DN(1)
DB35 P5E_CPU1_P3_RX_DP<2> P3_RXP2 @T6G_MB_LIB.T6G(SCH_1):P5E_CPU1_P3_RX_DP(2)
DB36 P5E_CPU1_P3_RX_DN<2> P3_RXN2 @T6G_MB_LIB.T6G(SCH_1):P5E_CPU1_P3_RX_DN(2)
CW32 P5E_CPU1_P3_RX_DP<3> P3_RXP3 @T6G_MB_LIB.T6G(SCH_1):P5E_CPU1_P3_RX_DP(3)
CW33 P5E_CPU1_P3_RX_DN<3> P3_RXN3 @T6G_MB_LIB.T6G(SCH_1):P5E_CPU1_P3_RX_DN(3)
DC32 P5E_CPU1_P3_RX_DP<4> P3_RXP4 @T6G_MB_LIB.T6G(SCH_1):P5E_CPU1_P3_RX_DP(4)
DC33 P5E_CPU1_P3_RX_DN<4> P3_RXN4 @T6G_MB_LIB.T6G(SCH_1):P5E_CPU1_P3_RX_DN(4)
DA32 P5E_CPU1_P3_RX_DP<5> P3_RXP5 @T6G_MB_LIB.T6G(SCH_1):P5E_CPU1_P3_RX_DP(5)
DA33 P5E_CPU1_P3_RX_DN<5> P3_RXN5 @T6G_MB_LIB.T6G(SCH_1):P5E_CPU1_P3_RX_DN(5)
CW29 P5E_CPU1_P3_RX_DP<6> P3_RXP6 @T6G_MB_LIB.T6G(SCH_1):P5E_CPU1_P3_RX_DP(6)
CW30 P5E_CPU1_P3_RX_DN<6> P3_RXN6 @T6G_MB_LIB.T6G(SCH_1):P5E_CPU1_P3_RX_DN(6)
DC29 P5E_CPU1_P3_RX_DP<7> P3_RXP7 @T6G_MB_LIB.T6G(SCH_1):P5E_CPU1_P3_RX_DP(7)
DC30 P5E_CPU1_P3_RX_DN<7> P3_RXN7 @T6G_MB_LIB.T6G(SCH_1):P5E_CPU1_P3_RX_DN(7)
DA29 P5E_CPU1_P3_RX_DP<8> P3_RXP8 @T6G_MB_LIB.T6G(SCH_1):P5E_CPU1_P3_RX_DP(8)
DA30 P5E_CPU1_P3_RX_DN<8> P3_RXN8 @T6G_MB_LIB.T6G(SCH_1):P5E_CPU1_P3_RX_DN(8)
CW26 P5E_CPU1_P3_RX_DP<9> P3_RXP9 @T6G_MB_LIB.T6G(SCH_1):P5E_CPU1_P3_RX_DP(9)
CW27 P5E_CPU1_P3_RX_DN<9> P3_RXN9 @T6G_MB_LIB.T6G(SCH_1):P5E_CPU1_P3_RX_DN(9)
DC26 P5E_CPU1_P3_RX_DP<10> P3_RXP10 @T6G_MB_LIB.T6G(SCH_1):P5E_CPU1_P3_RX_DP(10)
DC27 P5E_CPU1_P3_RX_DN<10> P3_RXN10 @T6G_MB_LIB.T6G(SCH_1):P5E_CPU1_P3_RX_DN(10)
DA26 P5E_CPU1_P3_RX_DP<11> P3_RXP11 @T6G_MB_LIB.T6G(SCH_1):P5E_CPU1_P3_RX_DP(11)
DA27 P5E_CPU1_P3_RX_DN<11> P3_RXN11 @T6G_MB_LIB.T6G(SCH_1):P5E_CPU1_P3_RX_DN(11)
CW23 P5E_CPU1_P3_RX_DP<12> P3_RXP12 @T6G_MB_LIB.T6G(SCH_1):P5E_CPU1_P3_RX_DP(12)
CW24 P5E_CPU1_P3_RX_DN<12> P3_RXN12 @T6G_MB_LIB.T6G(SCH_1):P5E_CPU1_P3_RX_DN(12)
DC23 P5E_CPU1_P3_RX_DP<13> P3_RXP13 @T6G_MB_LIB.T6G(SCH_1):P5E_CPU1_P3_RX_DP(13)
DC24 P5E_CPU1_P3_RX_DN<13> P3_RXN13 @T6G_MB_LIB.T6G(SCH_1):P5E_CPU1_P3_RX_DN(13)
DA23 P5E_CPU1_P3_RX_DP<14> P3_RXP14 @T6G_MB_LIB.T6G(SCH_1):P5E_CPU1_P3_RX_DP(14)
DA24 P5E_CPU1_P3_RX_DN<14> P3_RXN14 @T6G_MB_LIB.T6G(SCH_1):P5E_CPU1_P3_RX_DN(14)
CU23 P5E_CPU1_P3_RX_DP<15> P3_RXP15 @T6G_MB_LIB.T6G(SCH_1):P5E_CPU1_P3_RX_DP(15)
CU24 P5E_CPU1_P3_RX_DN<15> P3_RXN15 @T6G_MB_LIB.T6G(SCH_1):P5E_CPU1_P3_RX_DN(15)
CD36 P5E_CPU1_P3_TX_DP<0> P3_TXP0 @T6G_MB_LIB.T6G(SCH_1):P5E_CPU1_P3_TX_DP(0)
CD35 P5E_CPU1_P3_TX_DN<0> P3_TXN0 @T6G_MB_LIB.T6G(SCH_1):P5E_CPU1_P3_TX_DN(0)
CF36 P5E_CPU1_P3_TX_DP<1> P3_TXP1 @T6G_MB_LIB.T6G(SCH_1):P5E_CPU1_P3_TX_DP(1)
CF35 P5E_CPU1_P3_TX_DN<1> P3_TXN1 @T6G_MB_LIB.T6G(SCH_1):P5E_CPU1_P3_TX_DN(1)
CH36 P5E_CPU1_P3_TX_DP<2> P3_TXP2 @T6G_MB_LIB.T6G(SCH_1):P5E_CPU1_P3_TX_DP(2)
CH35 P5E_CPU1_P3_TX_DN<2> P3_TXN2 @T6G_MB_LIB.T6G(SCH_1):P5E_CPU1_P3_TX_DN(2)
CC33 P5E_CPU1_P3_TX_DP<3> P3_TXP3 @T6G_MB_LIB.T6G(SCH_1):P5E_CPU1_P3_TX_DP(3)
CC32 P5E_CPU1_P3_TX_DN<3> P3_TXN3 @T6G_MB_LIB.T6G(SCH_1):P5E_CPU1_P3_TX_DN(3)
CJ33 P5E_CPU1_P3_TX_DP<4> P3_TXP4 @T6G_MB_LIB.T6G(SCH_1):P5E_CPU1_P3_TX_DP(4)
CJ32 P5E_CPU1_P3_TX_DN<4> P3_TXN4 @T6G_MB_LIB.T6G(SCH_1):P5E_CPU1_P3_TX_DN(4)
CG33 P5E_CPU1_P3_TX_DP<5> P3_TXP5 @T6G_MB_LIB.T6G(SCH_1):P5E_CPU1_P3_TX_DP(5)
CG32 P5E_CPU1_P3_TX_DN<5> P3_TXN5 @T6G_MB_LIB.T6G(SCH_1):P5E_CPU1_P3_TX_DN(5)
CE33 P5E_CPU1_P3_TX_DP<6> P3_TXP6 @T6G_MB_LIB.T6G(SCH_1):P5E_CPU1_P3_TX_DP(6)
CE32 P5E_CPU1_P3_TX_DN<6> P3_TXN6 @T6G_MB_LIB.T6G(SCH_1):P5E_CPU1_P3_TX_DN(6)
CC30 P5E_CPU1_P3_TX_DP<7> P3_TXP7 @T6G_MB_LIB.T6G(SCH_1):P5E_CPU1_P3_TX_DP(7)
CC29 P5E_CPU1_P3_TX_DN<7> P3_TXN7 @T6G_MB_LIB.T6G(SCH_1):P5E_CPU1_P3_TX_DN(7)
CG30 P5E_CPU1_P3_TX_DP<8> P3_TXP8 @T6G_MB_LIB.T6G(SCH_1):P5E_CPU1_P3_TX_DP(8)
CG29 P5E_CPU1_P3_TX_DN<8> P3_TXN8 @T6G_MB_LIB.T6G(SCH_1):P5E_CPU1_P3_TX_DN(8)
CE30 P5E_CPU1_P3_TX_DP<9> P3_TXP9 @T6G_MB_LIB.T6G(SCH_1):P5E_CPU1_P3_TX_DP(9)
CE29 P5E_CPU1_P3_TX_DN<9> P3_TXN9 @T6G_MB_LIB.T6G(SCH_1):P5E_CPU1_P3_TX_DN(9)
CC27 P5E_CPU1_P3_TX_DP<10> P3_TXP10 @T6G_MB_LIB.T6G(SCH_1):P5E_CPU1_P3_TX_DP(10)
CC26 P5E_CPU1_P3_TX_DN<10> P3_TXN10 @T6G_MB_LIB.T6G(SCH_1):P5E_CPU1_P3_TX_DN(10)
CG27 P5E_CPU1_P3_TX_DP<11> P3_TXP11 @T6G_MB_LIB.T6G(SCH_1):P5E_CPU1_P3_TX_DP(11)
CG26 P5E_CPU1_P3_TX_DN<11> P3_TXN11 @T6G_MB_LIB.T6G(SCH_1):P5E_CPU1_P3_TX_DN(11)
CE27 P5E_CPU1_P3_TX_DP<12> P3_TXP12 @T6G_MB_LIB.T6G(SCH_1):P5E_CPU1_P3_TX_DP(12)
CE26 P5E_CPU1_P3_TX_DN<12> P3_TXN12 @T6G_MB_LIB.T6G(SCH_1):P5E_CPU1_P3_TX_DN(12)
CC24 P5E_CPU1_P3_TX_DP<13> P3_TXP13 @T6G_MB_LIB.T6G(SCH_1):P5E_CPU1_P3_TX_DP(13)
CC23 P5E_CPU1_P3_TX_DN<13> P3_TXN13 @T6G_MB_LIB.T6G(SCH_1):P5E_CPU1_P3_TX_DN(13)
CG24 P5E_CPU1_P3_TX_DP<14> P3_TXP14 @T6G_MB_LIB.T6G(SCH_1):P5E_CPU1_P3_TX_DP(14)
CG23 P5E_CPU1_P3_TX_DN<14> P3_TXN14 @T6G_MB_LIB.T6G(SCH_1):P5E_CPU1_P3_TX_DN(14)
CE24 P5E_CPU1_P3_TX_DP<15> P3_TXP15 @T6G_MB_LIB.T6G(SCH_1):P5E_CPU1_P3_TX_DP(15)
CE23 P5E_CPU1_P3_TX_DN<15> P3_TXN15 @T6G_MB_LIB.T6G(SCH_1):P5E_CPU1_P3_TX_DN(15)

GENOA_SP5-SOCKET6096_13568-001,SMLF,IO,DGA^6000030  I148  U26
CR29 P5E_CPU1_P2_RX_DP<8> P2_RXP8 @T6G_MB_LIB.T6G(SCH_1):P5E_CPU1_P2_RX_DP(8)
CR30 P5E_CPU1_P2_RX_DN<8> P2_RXN8 @T6G_MB_LIB.T6G(SCH_1):P5E_CPU1_P2_RX_DN(8)
CL26 P5E_CPU1_P2_RX_DP<9> P2_RXP9 @T6G_MB_LIB.T6G(SCH_1):P5E_CPU1_P2_RX_DP(9)
CL27 P5E_CPU1_P2_RX_DN<9> P2_RXN9 @T6G_MB_LIB.T6G(SCH_1):P5E_CPU1_P2_RX_DN(9)
CU26 P5E_CPU1_P2_RX_DP<10> P2_RXP10 @T6G_MB_LIB.T6G(SCH_1):P5E_CPU1_P2_RX_DP(10)
CU27 P5E_CPU1_P2_RX_DN<10> P2_RXN10 @T6G_MB_LIB.T6G(SCH_1):P5E_CPU1_P2_RX_DN(10)
CR26 P5E_CPU1_P2_RX_DP<11> P2_RXP11 @T6G_MB_LIB.T6G(SCH_1):P5E_CPU1_P2_RX_DP(11)
CR27 P5E_CPU1_P2_RX_DN<11> P2_RXN11 @T6G_MB_LIB.T6G(SCH_1):P5E_CPU1_P2_RX_DN(11)
CN26 P5E_CPU1_P2_RX_DP<12> P2_RXP12 @T6G_MB_LIB.T6G(SCH_1):P5E_CPU1_P2_RX_DP(12)
CN27 P5E_CPU1_P2_RX_DN<12> P2_RXN12 @T6G_MB_LIB.T6G(SCH_1):P5E_CPU1_P2_RX_DN(12)
CL23 P5E_CPU1_P2_RX_DP<13> P2_RXP13 @T6G_MB_LIB.T6G(SCH_1):P5E_CPU1_P2_RX_DP(13)
CL24 P5E_CPU1_P2_RX_DN<13> P2_RXN13 @T6G_MB_LIB.T6G(SCH_1):P5E_CPU1_P2_RX_DN(13)
CR23 P5E_CPU1_P2_RX_DP<14> P2_RXP14 @T6G_MB_LIB.T6G(SCH_1):P5E_CPU1_P2_RX_DP(14)
CR24 P5E_CPU1_P2_RX_DN<14> P2_RXN14 @T6G_MB_LIB.T6G(SCH_1):P5E_CPU1_P2_RX_DN(14)
CN23 P5E_CPU1_P2_RX_DP<15> P2_RXP15 @T6G_MB_LIB.T6G(SCH_1):P5E_CPU1_P2_RX_DP(15)
CN24 P5E_CPU1_P2_RX_DN<15> P2_RXN15 @T6G_MB_LIB.T6G(SCH_1):P5E_CPU1_P2_RX_DN(15)
CA30 P5E_CPU1_P2_TX_DP<8> P2_TXP8 @T6G_MB_LIB.T6G(SCH_1):P5E_CPU1_P2_TX_DP(8)
CA29 P5E_CPU1_P2_TX_DN<8> P2_TXN8 @T6G_MB_LIB.T6G(SCH_1):P5E_CPU1_P2_TX_DN(8)
BW30 P5E_CPU1_P2_TX_DP<9> P2_TXP9 @T6G_MB_LIB.T6G(SCH_1):P5E_CPU1_P2_TX_DP(9)
BW29 P5E_CPU1_P2_TX_DN<9> P2_TXN9 @T6G_MB_LIB.T6G(SCH_1):P5E_CPU1_P2_TX_DN(9)
BU27 P5E_CPU1_P2_TX_DP<10> P2_TXP10 @T6G_MB_LIB.T6G(SCH_1):P5E_CPU1_P2_TX_DP(10)
BU26 P5E_CPU1_P2_TX_DN<10> P2_TXN10 @T6G_MB_LIB.T6G(SCH_1):P5E_CPU1_P2_TX_DN(10)
CA27 P5E_CPU1_P2_TX_DP<11> P2_TXP11 @T6G_MB_LIB.T6G(SCH_1):P5E_CPU1_P2_TX_DP(11)
CA26 P5E_CPU1_P2_TX_DN<11> P2_TXN11 @T6G_MB_LIB.T6G(SCH_1):P5E_CPU1_P2_TX_DN(11)
BW27 P5E_CPU1_P2_TX_DP<12> P2_TXP12 @T6G_MB_LIB.T6G(SCH_1):P5E_CPU1_P2_TX_DP(12)
BW26 P5E_CPU1_P2_TX_DN<12> P2_TXN12 @T6G_MB_LIB.T6G(SCH_1):P5E_CPU1_P2_TX_DN(12)
BU24 P5E_CPU1_P2_TX_DP<13> P2_TXP13 @T6G_MB_LIB.T6G(SCH_1):P5E_CPU1_P2_TX_DP(13)
BU23 P5E_CPU1_P2_TX_DN<13> P2_TXN13 @T6G_MB_LIB.T6G(SCH_1):P5E_CPU1_P2_TX_DN(13)
CA24 P5E_CPU1_P2_TX_DP<14> P2_TXP14 @T6G_MB_LIB.T6G(SCH_1):P5E_CPU1_P2_TX_DP(14)
CA23 P5E_CPU1_P2_TX_DN<14> P2_TXN14 @T6G_MB_LIB.T6G(SCH_1):P5E_CPU1_P2_TX_DN(14)
BW24 P5E_CPU1_P2_TX_DP<15> P2_TXP15 @T6G_MB_LIB.T6G(SCH_1):P5E_CPU1_P2_TX_DP(15)
BW23 P5E_CPU1_P2_TX_DN<15> P2_TXN15 @T6G_MB_LIB.T6G(SCH_1):P5E_CPU1_P2_TX_DN(15)
BT36 P5E_CPU1_P2_TX_DP<0> P2_TXP0 @T6G_MB_LIB.T6G(SCH_1):P5E_CPU1_P2_TX_DP(0)
BV36 P5E_CPU1_P2_TX_DP<1> P2_TXP1 @T6G_MB_LIB.T6G(SCH_1):P5E_CPU1_P2_TX_DP(1)
CB36 P5E_CPU1_P2_TX_DP<2> P2_TXP2 @T6G_MB_LIB.T6G(SCH_1):P5E_CPU1_P2_TX_DP(2)
BT35 P5E_CPU1_P2_TX_DN<0> P2_TXN0 @T6G_MB_LIB.T6G(SCH_1):P5E_CPU1_P2_TX_DN(0)
CM35 P5E_CPU1_P2_RX_DP<0> P2_RXP0 @T6G_MB_LIB.T6G(SCH_1):P5E_CPU1_P2_RX_DP(0)
BY36 P5E_CPU1_P2_TX_DP<3> P2_TXP3 @T6G_MB_LIB.T6G(SCH_1):P5E_CPU1_P2_TX_DP(3)
BV35 P5E_CPU1_P2_TX_DN<1> P2_TXN1 @T6G_MB_LIB.T6G(SCH_1):P5E_CPU1_P2_TX_DN(1)
CP35 P5E_CPU1_P2_RX_DP<1> P2_RXP1 @T6G_MB_LIB.T6G(SCH_1):P5E_CPU1_P2_RX_DP(1)
BU33 P5E_CPU1_P2_TX_DP<4> P2_TXP4 @T6G_MB_LIB.T6G(SCH_1):P5E_CPU1_P2_TX_DP(4)
CB35 P5E_CPU1_P2_TX_DN<2> P2_TXN2 @T6G_MB_LIB.T6G(SCH_1):P5E_CPU1_P2_TX_DN(2)
CT35 P5E_CPU1_P2_RX_DP<2> P2_RXP2 @T6G_MB_LIB.T6G(SCH_1):P5E_CPU1_P2_RX_DP(2)
CM36 P5E_CPU1_P2_RX_DN<0> P2_RXN0 @T6G_MB_LIB.T6G(SCH_1):P5E_CPU1_P2_RX_DN(0)
CA33 P5E_CPU1_P2_TX_DP<5> P2_TXP5 @T6G_MB_LIB.T6G(SCH_1):P5E_CPU1_P2_TX_DP(5)
BY35 P5E_CPU1_P2_TX_DN<3> P2_TXN3 @T6G_MB_LIB.T6G(SCH_1):P5E_CPU1_P2_TX_DN(3)
CN32 P5E_CPU1_P2_RX_DP<3> P2_RXP3 @T6G_MB_LIB.T6G(SCH_1):P5E_CPU1_P2_RX_DP(3)
CP36 P5E_CPU1_P2_RX_DN<1> P2_RXN1 @T6G_MB_LIB.T6G(SCH_1):P5E_CPU1_P2_RX_DN(1)
BW33 P5E_CPU1_P2_TX_DP<6> P2_TXP6 @T6G_MB_LIB.T6G(SCH_1):P5E_CPU1_P2_TX_DP(6)
BU32 P5E_CPU1_P2_TX_DN<4> P2_TXN4 @T6G_MB_LIB.T6G(SCH_1):P5E_CPU1_P2_TX_DN(4)
CU32 P5E_CPU1_P2_RX_DP<4> P2_RXP4 @T6G_MB_LIB.T6G(SCH_1):P5E_CPU1_P2_RX_DP(4)
CT36 P5E_CPU1_P2_RX_DN<2> P2_RXN2 @T6G_MB_LIB.T6G(SCH_1):P5E_CPU1_P2_RX_DN(2)
BU30 P5E_CPU1_P2_TX_DP<7> P2_TXP7 @T6G_MB_LIB.T6G(SCH_1):P5E_CPU1_P2_TX_DP(7)
CA32 P5E_CPU1_P2_TX_DN<5> P2_TXN5 @T6G_MB_LIB.T6G(SCH_1):P5E_CPU1_P2_TX_DN(5)
CR32 P5E_CPU1_P2_RX_DP<5> P2_RXP5 @T6G_MB_LIB.T6G(SCH_1):P5E_CPU1_P2_RX_DP(5)
CN33 P5E_CPU1_P2_RX_DN<3> P2_RXN3 @T6G_MB_LIB.T6G(SCH_1):P5E_CPU1_P2_RX_DN(3)
BW32 P5E_CPU1_P2_TX_DN<6> P2_TXN6 @T6G_MB_LIB.T6G(SCH_1):P5E_CPU1_P2_TX_DN(6)
CN29 P5E_CPU1_P2_RX_DP<6> P2_RXP6 @T6G_MB_LIB.T6G(SCH_1):P5E_CPU1_P2_RX_DP(6)
CU33 P5E_CPU1_P2_RX_DN<4> P2_RXN4 @T6G_MB_LIB.T6G(SCH_1):P5E_CPU1_P2_RX_DN(4)
BU29 P5E_CPU1_P2_TX_DN<7> P2_TXN7 @T6G_MB_LIB.T6G(SCH_1):P5E_CPU1_P2_TX_DN(7)
CU29 P5E_CPU1_P2_RX_DP<7> P2_RXP7 @T6G_MB_LIB.T6G(SCH_1):P5E_CPU1_P2_RX_DP(7)
CR33 P5E_CPU1_P2_RX_DN<5> P2_RXN5 @T6G_MB_LIB.T6G(SCH_1):P5E_CPU1_P2_RX_DN(5)
CN30 P5E_CPU1_P2_RX_DN<6> P2_RXN6 @T6G_MB_LIB.T6G(SCH_1):P5E_CPU1_P2_RX_DN(6)
CU30 P5E_CPU1_P2_RX_DN<7> P2_RXN7 @T6G_MB_LIB.T6G(SCH_1):P5E_CPU1_P2_RX_DN(7)


DRAWING: @T6G_MB_LIB.T6G(SCH_1):PAGE54 

GENOA_SP5-SOCKET6096_13568-001,SMLF,IO,DGA^6000030  I190  U26
 A68 APML_CPU1_ALERT_N ALERT_L @T6G_MB_LIB.T6G(SCH_1):APML_CPU1_ALERT_N
 B66 PRSNT_CPU1_N CPU_PRESENT_L @T6G_MB_LIB.T6G(SCH_1):PRSNT_CPU1_N
 C16 JTAG_CPU1_DBREQ_N DBREQ_L @T6G_MB_LIB.T6G(SCH_1):JTAG_CPU1_DBREQ_N
 A69 CPU1_PROCHOT_N PROCHOT_L @T6G_MB_LIB.T6G(SCH_1):CPU1_PROCHOT_N
DJ55 CPU1_SA0    SA0 @T6G_MB_LIB.T6G(SCH_1):CPU1_SA0
DJ71 SMB_APML_CPU1_SCL    SIC @T6G_MB_LIB.T6G(SCH_1):SMB_APML_CPU1_SCL
DH71 SMB_APML_CPU1_SDA    SID @T6G_MB_LIB.T6G(SCH_1):SMB_APML_CPU1_SDA
 C17 JTAG_CPU1_TDI    TDI @T6G_MB_LIB.T6G(SCH_1):JTAG_CPU1_TDI
 C18 JTAG_CPU1_R_TDO    TDO @T6G_MB_LIB.T6G(SCH_1):JTAG_CPU1_R_TDO
 DJ9 CPU1_THERMTRIP_N THERMTRIP_L @T6G_MB_LIB.T6G(SCH_1):CPU1_THERMTRIP_N
 A16 JTAG_CPU1_TMS    TMS @T6G_MB_LIB.T6G(SCH_1):JTAG_CPU1_TMS
 A17 JTAG_CPU1_TRST_N TRST_L @T6G_MB_LIB.T6G(SCH_1):JTAG_CPU1_TRST_N
 C66 CPU1_XTRIG_R2_L4 XTRIG_L4 @T6G_MB_LIB.T6G(SCH_1):CPU1_XTRIG_R2_L4
 C65 CPU1_XTRIG_R2_L5 XTRIG_L5 @T6G_MB_LIB.T6G(SCH_1):CPU1_XTRIG_R2_L5
 A66 CPU1_XTRIG_R2_L6 XTRIG_L6 @T6G_MB_LIB.T6G(SCH_1):CPU1_XTRIG_R2_L6
 A65 CPU1_XTRIG_R2_L7 XTRIG_L7 @T6G_MB_LIB.T6G(SCH_1):CPU1_XTRIG_R2_L7
DJ56 CPU1_SA1    SA1 @T6G_MB_LIB.T6G(SCH_1):CPU1_SA1
 C70 CPU1_CORETYPE0 CORETYPE0 @T6G_MB_LIB.T6G(SCH_1):CPU1_CORETYPE0
 B69 CPU1_CORETYPE1 CORETYPE1 @T6G_MB_LIB.T6G(SCH_1):CPU1_CORETYPE1
 C68 CPU1_SP5R2  SP5R2 @T6G_MB_LIB.T6G(SCH_1):CPU1_SP5R2
DH73 CPU1_SP5R3  SP5R3 @T6G_MB_LIB.T6G(SCH_1):CPU1_SP5R3
DH10 CPU1_SP5R4  SP5R4 @T6G_MB_LIB.T6G(SCH_1):CPU1_SP5R4
 C22 FM_P1_PCC0_N PCC0_L @T6G_MB_LIB.T6G(SCH_1):FM_P1_PCC0_N
DG72 FM_P1_PCC1_N PCC1_L @T6G_MB_LIB.T6G(SCH_1):FM_P1_PCC1_N
 C32 NC_CPU1_AZ_BITCLK AZ_BITCLK @T6G_MB_LIB.T6G(SCH_1):NC_CPU1_AZ_BITCLK
 D32 NC_CPU1_AZ_SYNC AZ_SYNC @T6G_MB_LIB.T6G(SCH_1):NC_CPU1_AZ_SYNC
 A22 SVID_PVDDCR_CPU0_P1_SVD   SVD0 @T6G_MB_LIB.T6G(SCH_1):SVID_PVDDCR_CPU0_P1_SVD
 B21 SVID_PVDDCR_CPU0_P1_SVTO   SVT0 @T6G_MB_LIB.T6G(SCH_1):SVID_PVDDCR_CPU0_P1_SVTO
DH72 SVID_PVDDCR_CPU1_P1_SVD   SVD1 @T6G_MB_LIB.T6G(SCH_1):SVID_PVDDCR_CPU1_P1_SVD
 A23 SVID_PVDDCR_CPU0_P1_SVC   SVC0 @T6G_MB_LIB.T6G(SCH_1):SVID_PVDDCR_CPU0_P1_SVC
DG73 SVID_PVDDCR_CPU1_P1_SVTO   SVT1 @T6G_MB_LIB.T6G(SCH_1):SVID_PVDDCR_CPU1_P1_SVTO
DJ72 SVID_PVDDCR_CPU1_P1_SVC   SVC1 @T6G_MB_LIB.T6G(SCH_1):SVID_PVDDCR_CPU1_P1_SVC
DG35 TP_CPU1_UART0_RX UART0_RXD||AGPIO136 @T6G_MB_LIB.T6G(SCH_1):TP_CPU1_UART0_RX
DF34 TP_CPU1_UART0_RTS_N UART0_RTS_L||UART2_RXD||AGPIO137 @T6G_MB_LIB.T6G(SCH_1):TP_CPU1_UART0_RTS_N
DG34 TP_CPU1_UART0_INTR UART0_INTR||AGPIO139 @T6G_MB_LIB.T6G(SCH_1):TP_CPU1_UART0_INTR
DJ34 TP_CPU1_UART0_TX UART0_TXD||AGPIO138 @T6G_MB_LIB.T6G(SCH_1):TP_CPU1_UART0_TX
DJ33 TP_CPU1_UART0_CTS_N UART0_CTS_L||UART2_TXD||AGPIO135 @T6G_MB_LIB.T6G(SCH_1):TP_CPU1_UART0_CTS_N
 A33 NC_CPU1_AZ_SDIN2 AZ_SDIN2||SW_MDATA0 @T6G_MB_LIB.T6G(SCH_1):NC_CPU1_AZ_SDIN2
 A32 NC_CPU1_AZ_SDOUT AZ_SDOUT||SW_MDATA2 @T6G_MB_LIB.T6G(SCH_1):NC_CPU1_AZ_SDOUT
 A34 NC_CPU1_AZ_RST_N AZ_RST_L||SW_MDATA1 @T6G_MB_LIB.T6G(SCH_1):NC_CPU1_AZ_RST_N
 C33 NC_CPU1_AZ_SDIN0 AZ_SDIN0||SW_MDATA3 @T6G_MB_LIB.T6G(SCH_1):NC_CPU1_AZ_SDIN0
 D33 NC_CPU1_AZ_SDIN1 AZ_SDIN1||SW_MCLK @T6G_MB_LIB.T6G(SCH_1):NC_CPU1_AZ_SDIN1
 C19 CPU1_SP5R1  SP5R1 @T6G_MB_LIB.T6G(SCH_1):CPU1_SP5R1
 B17 JTAG_CPU1_TCK    TCK @T6G_MB_LIB.T6G(SCH_1):JTAG_CPU1_TCK
 DH8    GND RTC_LDO_SELECT @T6G_MB_LIB.T6G(SCH_1):GND
DH33 TP_CPU1_UART1_RX UART1_RXD||AGPIO141 @T6G_MB_LIB.T6G(SCH_1):TP_CPU1_UART1_RX
DJ32     NC UART1_TXD||AGPIO142     NC
  C3 VSENSE_VSS_SENSE_A_P1 VSS_SENSE_A @T6G_MB_LIB.T6G(SCH_1):VSENSE_VSS_SENSE_A_P1
BR54 VSENSE_VSS_SENSE_B_P1 VSS_SENSE_B @T6G_MB_LIB.T6G(SCH_1):VSENSE_VSS_SENSE_B_P1
 DJ3 VSENSE_VSS_SENSE_C_P1 VSS_SENSE_C @T6G_MB_LIB.T6G(SCH_1):VSENSE_VSS_SENSE_C_P1
 B73 VSENSE_PVDD18_S5_P1_DN VSS_SENSE_D @T6G_MB_LIB.T6G(SCH_1):VSENSE_PVDD18_S5_P1_DN
BR53 VSENSE_PVDDIO_P1_DP VDDIO_SENSE @T6G_MB_LIB.T6G(SCH_1):VSENSE_PVDDIO_P1_DP
 DH3 VSENSE_PVDD11_S3_P1_DP VDD_11_S3_SENSE @T6G_MB_LIB.T6G(SCH_1):VSENSE_PVDD11_S3_P1_DP
 C74 VSENSE_PVDD18_S5_P1_DP VDD_18_S5_SENSE @T6G_MB_LIB.T6G(SCH_1):VSENSE_PVDD18_S5_P1_DP
BP53 TP_VSENSE_PVDD33_S5_P1 VDD_33_S5_SENSE @T6G_MB_LIB.T6G(SCH_1):TP_VSENSE_PVDD33_S5_P1
  B3 VSENSE_PVDDCR_SOC_P1_DP VDDCR_SOC_SENSE @T6G_MB_LIB.T6G(SCH_1):VSENSE_PVDDCR_SOC_P1_DP
 DG3 VSENSE_PVDDCR_CPU1_P1_DP VDDCR_CPU1_SENSE @T6G_MB_LIB.T6G(SCH_1):VSENSE_PVDDCR_CPU1_P1_DP
  C2 VSENSE_PVDDCR_CPU0_P1_DP VDDCR_CPU0_SENSE @T6G_MB_LIB.T6G(SCH_1):VSENSE_PVDDCR_CPU0_P1_DP
AA23 TP_CPU1_TEST6_X3D4 TEST6_X3D4 @T6G_MB_LIB.T6G(SCH_1):TP_CPU1_TEST6_X3D4
CJ30 TP_CPU1_TEST6_CCD1 TEST6_CCD1 @T6G_MB_LIB.T6G(SCH_1):TP_CPU1_TEST6_CCD1
AA51 TP_CPU1_TEST5_CCD0 TEST5_CCD0 @T6G_MB_LIB.T6G(SCH_1):TP_CPU1_TEST5_CCD0
CJ53 TP_CPU1_TEST6_X3D5 TEST6_X3D5 @T6G_MB_LIB.T6G(SCH_1):TP_CPU1_TEST6_X3D5
CJ46 TP_CPU1_TEST6_CCD2 TEST6_CCD2 @T6G_MB_LIB.T6G(SCH_1):TP_CPU1_TEST6_CCD2
CJ27 TP_CPU1_TEST5_CCD1 TEST5_CCD1 @T6G_MB_LIB.T6G(SCH_1):TP_CPU1_TEST5_CCD1
AA50 TP_CPU1_TEST4_CCD0 TEST4_CCD0 @T6G_MB_LIB.T6G(SCH_1):TP_CPU1_TEST4_CCD0
 Y46 TP_CPU1_TEST6_CCD3 TEST6_CCD3 @T6G_MB_LIB.T6G(SCH_1):TP_CPU1_TEST6_CCD3
CJ49 TP_CPU1_TEST5_CCD2 TEST5_CCD2 @T6G_MB_LIB.T6G(SCH_1):TP_CPU1_TEST5_CCD2
CJ28 TP_CPU1_TEST4_CCD1 TEST4_CCD1 @T6G_MB_LIB.T6G(SCH_1):TP_CPU1_TEST4_CCD1
 Y30 TP_CPU1_TEST5_CCD3 TEST5_CCD3 @T6G_MB_LIB.T6G(SCH_1):TP_CPU1_TEST5_CCD3
AA25 TP_CPU1_TEST4_IOD TEST4_IOD @T6G_MB_LIB.T6G(SCH_1):TP_CPU1_TEST4_IOD
CJ48 TP_CPU1_TEST4_CCD2 TEST4_CCD2 @T6G_MB_LIB.T6G(SCH_1):TP_CPU1_TEST4_CCD2
AA24 TP_CPU1_TEST5_IOD TEST5_IOD @T6G_MB_LIB.T6G(SCH_1):TP_CPU1_TEST5_IOD
AA53 TP_CPU1_TEST5_CCD4 TEST5_CCD4 @T6G_MB_LIB.T6G(SCH_1):TP_CPU1_TEST5_CCD4
AA30 TP_CPU1_TEST4_CCD3 TEST4_CCD3 @T6G_MB_LIB.T6G(SCH_1):TP_CPU1_TEST4_CCD3
AA49 TP_CPU1_TEST6_IOD TEST6_IOD @T6G_MB_LIB.T6G(SCH_1):TP_CPU1_TEST6_IOD
CJ25 TP_CPU1_TEST5_CCD5 TEST5_CCD5 @T6G_MB_LIB.T6G(SCH_1):TP_CPU1_TEST5_CCD5
AA52 TP_CPU1_TEST4_CCD4 TEST4_CCD4 @T6G_MB_LIB.T6G(SCH_1):TP_CPU1_TEST4_CCD4
CJ51 TP_CPU1_TEST5_CCD6 TEST5_CCD6 @T6G_MB_LIB.T6G(SCH_1):TP_CPU1_TEST5_CCD6
CJ26 TP_CPU1_TEST4_CCD5 TEST4_CCD5 @T6G_MB_LIB.T6G(SCH_1):TP_CPU1_TEST4_CCD5
AA26 TP_CPU1_TEST5_CCD7 TEST5_CCD7 @T6G_MB_LIB.T6G(SCH_1):TP_CPU1_TEST5_CCD7
CJ50 TP_CPU1_TEST4_CCD6 TEST4_CCD6 @T6G_MB_LIB.T6G(SCH_1):TP_CPU1_TEST4_CCD6
 B60 TP_CPU1_TEST47_CCD0 TEST47_CCD0 @T6G_MB_LIB.T6G(SCH_1):TP_CPU1_TEST47_CCD0
 Y47 TP_CPU1_TEST5_CCD8 TEST5_CCD8 @T6G_MB_LIB.T6G(SCH_1):TP_CPU1_TEST5_CCD8
 B61 TP_CPU1_TEST50_IOD TEST50_IOD @T6G_MB_LIB.T6G(SCH_1):TP_CPU1_TEST50_IOD
AA27 TP_CPU1_TEST4_CCD7 TEST4_CCD7 @T6G_MB_LIB.T6G(SCH_1):TP_CPU1_TEST4_CCD7
CJ24 TP_CPU1_TEST47_CCD1 TEST47_CCD1 @T6G_MB_LIB.T6G(SCH_1):TP_CPU1_TEST47_CCD1
CK29 TP_CPU1_TEST5_CCD9 TEST5_CCD9 @T6G_MB_LIB.T6G(SCH_1):TP_CPU1_TEST5_CCD9
AA48 TP_CPU1_TEST4_CCD8 TEST4_CCD8 @T6G_MB_LIB.T6G(SCH_1):TP_CPU1_TEST4_CCD8
CK46 TP_CPU1_TEST47_CCD2 TEST47_CCD2 @T6G_MB_LIB.T6G(SCH_1):TP_CPU1_TEST47_CCD2
CJ47 TP_CPU1_TEST4_CCD10 TEST4_CCD10 @T6G_MB_LIB.T6G(SCH_1):TP_CPU1_TEST4_CCD10
CK30 TP_CPU1_TEST4_CCD9 TEST4_CCD9 @T6G_MB_LIB.T6G(SCH_1):TP_CPU1_TEST4_CCD9
CK47 TP_CPU1_TEST5_CCD10 TEST5_CCD10 @T6G_MB_LIB.T6G(SCH_1):TP_CPU1_TEST5_CCD10
AA28 TP_CPU1_TEST4_CCD11 TEST4_CCD11 @T6G_MB_LIB.T6G(SCH_1):TP_CPU1_TEST4_CCD11
 Y29 TP_CPU1_TEST5_CCD11 TEST5_CCD11 @T6G_MB_LIB.T6G(SCH_1):TP_CPU1_TEST5_CCD11
AA47 TP_CPU1_TEST6_X3D0 TEST6_X3D0 @T6G_MB_LIB.T6G(SCH_1):TP_CPU1_TEST6_X3D0
 B58 TP_CPU1_TEST47_IOD0 TEST47_IOD0 @T6G_MB_LIB.T6G(SCH_1):TP_CPU1_TEST47_IOD0
CJ29 TP_CPU1_TEST6_X3D1 TEST6_X3D1 @T6G_MB_LIB.T6G(SCH_1):TP_CPU1_TEST6_X3D1
  D7 TP_CPU1_TEST47_IOD1 TEST47_IOD1 @T6G_MB_LIB.T6G(SCH_1):TP_CPU1_TEST47_IOD1
AA29 TP_CPU1_TEST6_X3D2 TEST6_X3D2 @T6G_MB_LIB.T6G(SCH_1):TP_CPU1_TEST6_X3D2
CJ52 TP_CPU1_TEST6_X3D3 TEST6_X3D3 @T6G_MB_LIB.T6G(SCH_1):TP_CPU1_TEST6_X3D3
AA46 TP_CPU1_TEST6_CCD0 TEST6_CCD0 @T6G_MB_LIB.T6G(SCH_1):TP_CPU1_TEST6_CCD0
 E32 TP_CPU1_TEST47_CCD3 TEST47_CCD3 @T6G_MB_LIB.T6G(SCH_1):TP_CPU1_TEST47_CCD3
 W31 TP_CPU1_TEST41_IOD TEST41_IOD @T6G_MB_LIB.T6G(SCH_1):TP_CPU1_TEST41_IOD
 C63 CPU1_BP0    BP0 @T6G_MB_LIB.T6G(SCH_1):CPU1_BP0
 C62 CPU1_BP1    BP1 @T6G_MB_LIB.T6G(SCH_1):CPU1_BP1
 A63 CPU1_BP2    BP2 @T6G_MB_LIB.T6G(SCH_1):CPU1_BP2
 A62 CPU1_BP3    BP3 @T6G_MB_LIB.T6G(SCH_1):CPU1_BP3
 D68 CPU1_CORETYPE2 CORETYPE2 @T6G_MB_LIB.T6G(SCH_1):CPU1_CORETYPE2

Q_RES_0402LF-0,5%,1/16W,CHIP,CS00002JB13  I203  R529
   1 JTAG_CPU1_R_TDO      A @T6G_MB_LIB.T6G(SCH_1):JTAG_CPU1_R_TDO
   2 JTAG_CPU1_TDO      B @T6G_MB_LIB.T6G(SCH_1):JTAG_CPU1_TDO

TP_TP-NA,TP30  I237  TP20
   1 VSENSE_PVDDCR_SOC_P1_DP     TP @T6G_MB_LIB.T6G(SCH_1):VSENSE_PVDDCR_SOC_P1_DP

TP_TP-NA,TP30  I238  TP19
   1 VSENSE_PVDD18_S5_P1_DP     TP @T6G_MB_LIB.T6G(SCH_1):VSENSE_PVDD18_S5_P1_DP

TP_TP-NA,TP30  I240  TP18
   1 VSENSE_PVDD11_S3_P1_DP     TP @T6G_MB_LIB.T6G(SCH_1):VSENSE_PVDD11_S3_P1_DP

TP_TP-NA,TP30  I241  TP17
   1 VSENSE_PVDDCR_CPU0_P1_DP     TP @T6G_MB_LIB.T6G(SCH_1):VSENSE_PVDDCR_CPU0_P1_DP

TP_TP-NA,TP30  I242  TP16
   1 VSENSE_PVDDCR_CPU1_P1_DP     TP @T6G_MB_LIB.T6G(SCH_1):VSENSE_PVDDCR_CPU1_P1_DP

TP_TP-NA,TP30  I243  TP15
   1 VSENSE_PVDDIO_P1_DP     TP @T6G_MB_LIB.T6G(SCH_1):VSENSE_PVDDIO_P1_DP

TP_TP-NA,TP30  I244  TP14
   1 VSENSE_PVDD18_S5_P1_DN     TP @T6G_MB_LIB.T6G(SCH_1):VSENSE_PVDD18_S5_P1_DN

TP_TP-NA,TP30  I245  TP13
   1 VSENSE_VSS_SENSE_C_P1     TP @T6G_MB_LIB.T6G(SCH_1):VSENSE_VSS_SENSE_C_P1

TP_TP-NA,TP30  I272  TP12
   1 VSENSE_VSS_SENSE_B_P1     TP @T6G_MB_LIB.T6G(SCH_1):VSENSE_VSS_SENSE_B_P1

TP_TP-NA,TP30  I273  TP11
   1 VSENSE_VSS_SENSE_A_P1     TP @T6G_MB_LIB.T6G(SCH_1):VSENSE_VSS_SENSE_A_P1

Q_RES_0402LF-1K,1%,1/16W,CHIP,CS21002FB06  I308  R528
   1 PVDD18_S5_P1      A @T6G_MB_LIB.T6G(SCH_1):PVDD18_S5_P1
   2 JTAG_CPU1_DBREQ_N      B @T6G_MB_LIB.T6G(SCH_1):JTAG_CPU1_DBREQ_N

Q_RES_0402LF-1K,1%,1/16W,CHIP,CS21002FB06  I309  R527
   1 PVDD18_S5_P1      A @T6G_MB_LIB.T6G(SCH_1):PVDD18_S5_P1
   2 JTAG_CPU1_TMS      B @T6G_MB_LIB.T6G(SCH_1):JTAG_CPU1_TMS

Q_CAP_C0402-0.001UF,50V,10%,EMPTY,CH30106KB19  I310  C235
   1 JTAG_CPU1_DBREQ_N      A @T6G_MB_LIB.T6G(SCH_1):JTAG_CPU1_DBREQ_N
   2    GND      B @T6G_MB_LIB.T6G(SCH_1):GND

Q_CAP_C0402-0.001UF,50V,10%,EMPTY,CH30106KB19  I311  C234
   1 JTAG_CPU1_TMS      A @T6G_MB_LIB.T6G(SCH_1):JTAG_CPU1_TMS
   2    GND      B @T6G_MB_LIB.T6G(SCH_1):GND

Q_RES_0402LF-1K,1%,1/16W,CHIP,CS21002FB06  I314  R526
   1 PVDD18_S5_P1      A @T6G_MB_LIB.T6G(SCH_1):PVDD18_S5_P1
   2 JTAG_CPU1_TCK      B @T6G_MB_LIB.T6G(SCH_1):JTAG_CPU1_TCK

Q_CAP_C0402-0.001UF,50V,10%,EMPTY,CH30106KB19  I315  C233
   1 JTAG_CPU1_TCK      A @T6G_MB_LIB.T6G(SCH_1):JTAG_CPU1_TCK
   2    GND      B @T6G_MB_LIB.T6G(SCH_1):GND

Q_RES_0402LF-1K,1%,1/16W,CHIP,CS21002FB06  I316  R525
   1 PVDD18_S5_P1      A @T6G_MB_LIB.T6G(SCH_1):PVDD18_S5_P1
   2 JTAG_CPU1_TRST_N      B @T6G_MB_LIB.T6G(SCH_1):JTAG_CPU1_TRST_N

Q_RES_0402LF-1K,1%,1/16W,CHIP,CS21002FB06  I317  R524
   1 PVDD18_S5_P1      A @T6G_MB_LIB.T6G(SCH_1):PVDD18_S5_P1
   2 JTAG_CPU1_TDI      B @T6G_MB_LIB.T6G(SCH_1):JTAG_CPU1_TDI

Q_CAP_C0402-0.001UF,50V,10%,EMPTY,CH30106KB19  I318  C232
   1 JTAG_CPU1_TRST_N      A @T6G_MB_LIB.T6G(SCH_1):JTAG_CPU1_TRST_N
   2    GND      B @T6G_MB_LIB.T6G(SCH_1):GND

Q_CAP_C0402-0.001UF,50V,10%,EMPTY,CH30106KB19  I319  C231
   1 JTAG_CPU1_TDI      A @T6G_MB_LIB.T6G(SCH_1):JTAG_CPU1_TDI
   2    GND      B @T6G_MB_LIB.T6G(SCH_1):GND

Q_RES_0402LF-1K,1%,1/16W,CHIP,CS21002FB06  I324  R523
   1 PVDD18_S5_P1      A @T6G_MB_LIB.T6G(SCH_1):PVDD18_S5_P1
   2 JTAG_CPU1_TDO      B @T6G_MB_LIB.T6G(SCH_1):JTAG_CPU1_TDO

Q_CAP_C0402-0.001UF,50V,10%,EMPTY,CH30106KB19  I325  C230
   1 JTAG_CPU1_TDO      A @T6G_MB_LIB.T6G(SCH_1):JTAG_CPU1_TDO
   2    GND      B @T6G_MB_LIB.T6G(SCH_1):GND

Q_RES_0402LF-0,5%,1/16W,CHIP,CS00002JB13  I333  PR170
   1 SVID_PVDDCR_CPU0_P1_SVD_R      A @T6G_MB_LIB.T6G(SCH_1):SVID_PVDDCR_CPU0_P1_SVD_R
   2 SVID_PVDDCR_CPU0_P1_SVD      B @T6G_MB_LIB.T6G(SCH_1):SVID_PVDDCR_CPU0_P1_SVD

Q_RES_0402LF-0,5%,1/16W,CHIP,CS00002JB13  I334  PR169
   1 SVID_PVDDCR_CPU0_P1_SVC_R      A @T6G_MB_LIB.T6G(SCH_1):SVID_PVDDCR_CPU0_P1_SVC_R
   2 SVID_PVDDCR_CPU0_P1_SVC      B @T6G_MB_LIB.T6G(SCH_1):SVID_PVDDCR_CPU0_P1_SVC

Q_RES_0402LF-0,5%,1/16W,CHIP,CS00002JB13  I337  PR237
   1 SVID_PVDDCR_CPU1_P1_SVD_R      A @T6G_MB_LIB.T6G(SCH_1):SVID_PVDDCR_CPU1_P1_SVD_R
   2 SVID_PVDDCR_CPU1_P1_SVD      B @T6G_MB_LIB.T6G(SCH_1):SVID_PVDDCR_CPU1_P1_SVD

Q_RES_0402LF-0,5%,1/16W,CHIP,CS00002JB13  I338  PR236
   1 SVID_PVDDCR_CPU1_P1_SVC_R      A @T6G_MB_LIB.T6G(SCH_1):SVID_PVDDCR_CPU1_P1_SVC_R
   2 SVID_PVDDCR_CPU1_P1_SVC      B @T6G_MB_LIB.T6G(SCH_1):SVID_PVDDCR_CPU1_P1_SVC

Q_RES_0402LF-0,5%,1/16W,CHIP,CS00002JB13  I361  R618
   1 CPU1_XTRIG_R2_L5      A @T6G_MB_LIB.T6G(SCH_1):CPU1_XTRIG_R2_L5
   2 CPU1_XTRIG_L5      B @T6G_MB_LIB.T6G(SCH_1):CPU1_XTRIG_L5

Q_RES_0402LF-0,5%,1/16W,CHIP,CS00002JB13  I362  R486
   1 CPU1_XTRIG_R2_L4      A @T6G_MB_LIB.T6G(SCH_1):CPU1_XTRIG_R2_L4
   2 CPU1_XTRIG_L4      B @T6G_MB_LIB.T6G(SCH_1):CPU1_XTRIG_L4

Q_RES_0402LF-0,5%,1/16W,CHIP,CS00002JB13  I363  R928
   1 CPU1_XTRIG_R2_L7      A @T6G_MB_LIB.T6G(SCH_1):CPU1_XTRIG_R2_L7
   2 CPU1_XTRIG_L7      B @T6G_MB_LIB.T6G(SCH_1):CPU1_XTRIG_L7

Q_RES_0402LF-0,5%,1/16W,CHIP,CS00002JB13  I364  R862
   1 CPU1_XTRIG_R2_L6      A @T6G_MB_LIB.T6G(SCH_1):CPU1_XTRIG_R2_L6
   2 CPU1_XTRIG_L6      B @T6G_MB_LIB.T6G(SCH_1):CPU1_XTRIG_L6

Q_RES_0402LF-0,5%,1/16W,CHIP,CS00002JB13  I371  R929
   1 CPU1_XTRIG_L4      A @T6G_MB_LIB.T6G(SCH_1):CPU1_XTRIG_L4
   2 CPU1_XTRIG_R1_L4      B @T6G_MB_LIB.T6G(SCH_1):CPU1_XTRIG_R1_L4

Q_RES_0402LF-0,5%,1/16W,CHIP,CS00002JB13  I372  R930
   1 CPU1_XTRIG_L5      A @T6G_MB_LIB.T6G(SCH_1):CPU1_XTRIG_L5
   2 CPU1_XTRIG_R1_L5      B @T6G_MB_LIB.T6G(SCH_1):CPU1_XTRIG_R1_L5

Q_RES_0402LF-0,5%,1/16W,CHIP,CS00002JB13  I373  R932
   1 CPU1_XTRIG_L7      A @T6G_MB_LIB.T6G(SCH_1):CPU1_XTRIG_L7
   2 CPU1_XTRIG_R1_L7      B @T6G_MB_LIB.T6G(SCH_1):CPU1_XTRIG_R1_L7

Q_RES_0402LF-0,5%,1/16W,CHIP,CS00002JB13  I374  R931
   1 CPU1_XTRIG_L6      A @T6G_MB_LIB.T6G(SCH_1):CPU1_XTRIG_L6
   2 CPU1_XTRIG_R1_L6      B @T6G_MB_LIB.T6G(SCH_1):CPU1_XTRIG_R1_L6

Q_RES_0402LF-2.2K,5%,1/16W,CHIP,CS22202JB07  I387  R517
   1 P3V3_AUX      A @T6G_MB_LIB.T6G(SCH_1):P3V3_AUX
   2 CPU1_SP5R2      B @T6G_MB_LIB.T6G(SCH_1):CPU1_SP5R2

Q_RES_0402LF-2.2K,5%,1/16W,CHIP,CS22202JB07  I388  R522
   1 P3V3_AUX      A @T6G_MB_LIB.T6G(SCH_1):P3V3_AUX
   2 CPU1_SP5R1      B @T6G_MB_LIB.T6G(SCH_1):CPU1_SP5R1

Q_RES_0402LF-2.2K,5%,1/16W,CHIP,CS22202JB07  I390  R513
   1 P3V3_AUX      A @T6G_MB_LIB.T6G(SCH_1):P3V3_AUX
   2 CPU1_SP5R4      B @T6G_MB_LIB.T6G(SCH_1):CPU1_SP5R4

Q_RES_0402LF-2.2K,5%,1/16W,CHIP,CS22202JB07  I391  R515
   1 P3V3_AUX      A @T6G_MB_LIB.T6G(SCH_1):P3V3_AUX
   2 CPU1_SP5R3      B @T6G_MB_LIB.T6G(SCH_1):CPU1_SP5R3

Q_RES_0402LF-2.2K,5%,1/16W,CHIP,CS22202JB07  I396  R520
   1 CPU1_PROCHOT_N      A @T6G_MB_LIB.T6G(SCH_1):CPU1_PROCHOT_N
   2 PVDD18_S5_P1      B @T6G_MB_LIB.T6G(SCH_1):PVDD18_S5_P1

Q_RES_0402LF-2.2K,5%,1/16W,CHIP,CS22202JB07  I398  R535
   1 APML_CPU1_ALERT_N      A @T6G_MB_LIB.T6G(SCH_1):APML_CPU1_ALERT_N
   2 PVDD18_S5_P1      B @T6G_MB_LIB.T6G(SCH_1):PVDD18_S5_P1

Q_RES_0402LF-2.2K,5%,1/16W,CHIP,CS22202JB07  I400  R512
   1 P3V3_AUX      A @T6G_MB_LIB.T6G(SCH_1):P3V3_AUX
   2 CPU1_CORETYPE2      B @T6G_MB_LIB.T6G(SCH_1):CPU1_CORETYPE2

Q_RES_0402LF-2.2K,5%,1/16W,CHIP,CS22202JB07  I401  R514
   1 P3V3_AUX      A @T6G_MB_LIB.T6G(SCH_1):P3V3_AUX
   2 CPU1_CORETYPE1      B @T6G_MB_LIB.T6G(SCH_1):CPU1_CORETYPE1

Q_RES_0402LF-2.2K,5%,1/16W,CHIP,CS22202JB07  I402  R516
   1 P3V3_AUX      A @T6G_MB_LIB.T6G(SCH_1):P3V3_AUX
   2 CPU1_CORETYPE0      B @T6G_MB_LIB.T6G(SCH_1):CPU1_CORETYPE0

Q_RES_0402LF-2.2K,5%,1/16W,CHIP,CS22202JB07  I403  R518
   1 PVDD18_S5_P1      A @T6G_MB_LIB.T6G(SCH_1):PVDD18_S5_P1
   2 CPU1_SA0      B @T6G_MB_LIB.T6G(SCH_1):CPU1_SA0

Q_RES_0402LF-2.2K,5%,1/16W,EMPTY,CS22202JB07  I404  R519
   1 CPU1_SA0      A @T6G_MB_LIB.T6G(SCH_1):CPU1_SA0
   2    GND      B @T6G_MB_LIB.T6G(SCH_1):GND

Q_RES_0402LF-2.2K,5%,1/16W,CHIP,CS22202JB07  I405  R521
   1 CPU1_SA1      A @T6G_MB_LIB.T6G(SCH_1):CPU1_SA1
   2    GND      B @T6G_MB_LIB.T6G(SCH_1):GND

Q_RES_0402LF-2.2K,5%,1/16W,CHIP,CS22202JB07  I406  R531
   1 CPU1_BP0      A @T6G_MB_LIB.T6G(SCH_1):CPU1_BP0
   2 PVDD18_S5_P1      B @T6G_MB_LIB.T6G(SCH_1):PVDD18_S5_P1

Q_RES_0402LF-2.2K,5%,1/16W,CHIP,CS22202JB07  I407  R532
   1 CPU1_BP1      A @T6G_MB_LIB.T6G(SCH_1):CPU1_BP1
   2 PVDD18_S5_P1      B @T6G_MB_LIB.T6G(SCH_1):PVDD18_S5_P1

Q_RES_0402LF-2.2K,5%,1/16W,CHIP,CS22202JB07  I408  R533
   1 CPU1_BP2      A @T6G_MB_LIB.T6G(SCH_1):CPU1_BP2
   2 PVDD18_S5_P1      B @T6G_MB_LIB.T6G(SCH_1):PVDD18_S5_P1

Q_RES_0402LF-2.2K,5%,1/16W,CHIP,CS22202JB07  I409  R534
   1 CPU1_BP3      A @T6G_MB_LIB.T6G(SCH_1):CPU1_BP3
   2 PVDD18_S5_P1      B @T6G_MB_LIB.T6G(SCH_1):PVDD18_S5_P1

Q_RES_0402LF-2.2K,5%,1/16W,CHIP,CS22202JB07  I410  R537
   1 CPU1_XTRIG_L4      A @T6G_MB_LIB.T6G(SCH_1):CPU1_XTRIG_L4
   2 PVDD18_S5_P1      B @T6G_MB_LIB.T6G(SCH_1):PVDD18_S5_P1

Q_RES_0402LF-2.2K,5%,1/16W,CHIP,CS22202JB07  I411  R538
   1 CPU1_XTRIG_L5      A @T6G_MB_LIB.T6G(SCH_1):CPU1_XTRIG_L5
   2 PVDD18_S5_P1      B @T6G_MB_LIB.T6G(SCH_1):PVDD18_S5_P1

Q_RES_0402LF-2.2K,5%,1/16W,CHIP,CS22202JB07  I412  R539
   1 CPU1_XTRIG_L6      A @T6G_MB_LIB.T6G(SCH_1):CPU1_XTRIG_L6
   2 PVDD18_S5_P1      B @T6G_MB_LIB.T6G(SCH_1):PVDD18_S5_P1

Q_RES_0402LF-2.2K,5%,1/16W,CHIP,CS22202JB07  I413  R540
   1 CPU1_XTRIG_L7      A @T6G_MB_LIB.T6G(SCH_1):CPU1_XTRIG_L7
   2 PVDD18_S5_P1      B @T6G_MB_LIB.T6G(SCH_1):PVDD18_S5_P1

Q_RES_0402LF-33,5%,1/16W,CHIP,CS03302JB10  I415  R488
   1 CPU1_THERMTRIP_N      A @T6G_MB_LIB.T6G(SCH_1):CPU1_THERMTRIP_N
   2 CPU1_THERMTRIP_R_N      B @T6G_MB_LIB.T6G(SCH_1):CPU1_THERMTRIP_R_N

Q_RES_0402LF-33,5%,1/16W,CHIP,CS03302JB10  I417  R497
   1 APML_CPU1_ALERT_N      A @T6G_MB_LIB.T6G(SCH_1):APML_CPU1_ALERT_N
   2 APML_CPU1_ALERT_R_N      B @T6G_MB_LIB.T6G(SCH_1):APML_CPU1_ALERT_R_N

SCONN8_G802M0083150RD3HR-SCONN8_G802M0083150RD3HR,A  I418  J7
   1 CPU1_XTRIG_R1_L4      1 @T6G_MB_LIB.T6G(SCH_1):CPU1_XTRIG_R1_L4
   2    GND      2 @T6G_MB_LIB.T6G(SCH_1):GND
   3 CPU1_XTRIG_R1_L5      3 @T6G_MB_LIB.T6G(SCH_1):CPU1_XTRIG_R1_L5
   4    GND      4 @T6G_MB_LIB.T6G(SCH_1):GND
   5 CPU1_XTRIG_R1_L6      5 @T6G_MB_LIB.T6G(SCH_1):CPU1_XTRIG_R1_L6
   6    GND      6 @T6G_MB_LIB.T6G(SCH_1):GND
   7 CPU1_XTRIG_R1_L7      7 @T6G_MB_LIB.T6G(SCH_1):CPU1_XTRIG_R1_L7
   8    GND      8 @T6G_MB_LIB.T6G(SCH_1):GND

SCONN8_G802M0083150RD3HR-SCONN8_G802M0083150RD3HR,A  I419  J49
   1 CPU1_BP0      1 @T6G_MB_LIB.T6G(SCH_1):CPU1_BP0
   2    GND      2 @T6G_MB_LIB.T6G(SCH_1):GND
   3 CPU1_BP1      3 @T6G_MB_LIB.T6G(SCH_1):CPU1_BP1
   4    GND      4 @T6G_MB_LIB.T6G(SCH_1):GND
   5 CPU1_BP2      5 @T6G_MB_LIB.T6G(SCH_1):CPU1_BP2
   6    GND      6 @T6G_MB_LIB.T6G(SCH_1):GND
   7 CPU1_BP3      7 @T6G_MB_LIB.T6G(SCH_1):CPU1_BP3
   8    GND      8 @T6G_MB_LIB.T6G(SCH_1):GND

Q_RES_0402LF-2.2K,5%,1/16W,EMPTY,CS22202JB07  I421  R536
   1 CPU1_THERMTRIP_N      A @T6G_MB_LIB.T6G(SCH_1):CPU1_THERMTRIP_N
   2 PVDD18_S5_P1      B @T6G_MB_LIB.T6G(SCH_1):PVDD18_S5_P1


DRAWING: @T6G_MB_LIB.T6G(SCH_1):PAGE55 

Q_CAP_C0402-2.7PF,50V,0.1PF,NPO,CH-276B0B00  I3  C236
   1 XTAL_CPU1_X48M_X1      A @T6G_MB_LIB.T6G(SCH_1):XTAL_CPU1_X48M_X1
   2    GND      B @T6G_MB_LIB.T6G(SCH_1):GND

Q_CAP_0402-10PF,50V,1%,NPO,TMP_QCH0106F0B00  I5  C238
   1 XTAL_CPU1_R_X32K_X1      A @T6G_MB_LIB.T6G(SCH_1):XTAL_CPU1_R_X32K_X1
   2    GND      B @T6G_MB_LIB.T6G(SCH_1):GND

Q_CRYSTAL_SMLF-32.768KHZ,EMPTY,BG632768012  I7  Y5
   1 XTAL_CPU1_R_X32K_X1      1 @T6G_MB_LIB.T6G(SCH_1):XTAL_CPU1_R_X32K_X1
   2 XTAL_CPU1_R_X32K_X2      2 @T6G_MB_LIB.T6G(SCH_1):XTAL_CPU1_R_X32K_X2

Q_CAP_0402-10PF,50V,1%,NPO,TMP_QCH0106F0B00  I9  C239
   1 XTAL_CPU1_R_X32K_X2      A @T6G_MB_LIB.T6G(SCH_1):XTAL_CPU1_R_X32K_X2
   2    GND      B @T6G_MB_LIB.T6G(SCH_1):GND

Q_RES_0402LF-10M,1%,1/16W,CHIP,CS61002FB02  I10  R571
   1 XTAL_CPU1_X48M_X1      A @T6G_MB_LIB.T6G(SCH_1):XTAL_CPU1_X48M_X1
   2 XTAL_CPU1_X48M_X2_R      B @T6G_MB_LIB.T6G(SCH_1):XTAL_CPU1_X48M_X2_R

Q_XTAL_4P_13BI_24GND-48MHZ,SMLF,MISC,BG648000076  I12  Y4
   1 XTAL_CPU1_X48M_X1     X1 @T6G_MB_LIB.T6G(SCH_1):XTAL_CPU1_X48M_X1
   2    GND     G1 @T6G_MB_LIB.T6G(SCH_1):GND
   4    GND     G2 @T6G_MB_LIB.T6G(SCH_1):GND
   3 XTAL_CPU1_X48M_X2_R     X2 @T6G_MB_LIB.T6G(SCH_1):XTAL_CPU1_X48M_X2_R

Q_CAP_C0402-2.7PF,50V,0.1PF,NPO,CH-276B0B00  I15  C237
   1 XTAL_CPU1_X48M_X2_R      A @T6G_MB_LIB.T6G(SCH_1):XTAL_CPU1_X48M_X2_R
   2    GND      B @T6G_MB_LIB.T6G(SCH_1):GND

Q_RES_0402LF-0,5%,1/16W,EMPTY,CS00002JB13  I24  R574
   1 XTAL_CPU1_R_X32K_X1      A @T6G_MB_LIB.T6G(SCH_1):XTAL_CPU1_R_X32K_X1
   2 XTAL_CPU1_X32K_X1      B @T6G_MB_LIB.T6G(SCH_1):XTAL_CPU1_X32K_X1

Q_RES_0402LF-0,5%,1/16W,CHIP,CS00002JB13  I26  R573
   1 CLK_CPU0_RTCCLK      A @T6G_MB_LIB.T6G(SCH_1):CLK_CPU0_RTCCLK
   2 XTAL_CPU1_X32K_X1      B @T6G_MB_LIB.T6G(SCH_1):XTAL_CPU1_X32K_X1

GENOA_SP5-SOCKET6096_13568-001,SMLF,IO,DGA^6000030  I182  U26
 DJ8 CPU1_PWR_GD_IN PWR_GOOD @T6G_MB_LIB.T6G(SCH_1):CPU1_PWR_GD_IN
DG10 RST_CPU1_RSMRST_N RSMRST_L @T6G_MB_LIB.T6G(SCH_1):RST_CPU1_RSMRST_N
 DJ5 CPU1_SLP_S3_N SLP_S3_L @T6G_MB_LIB.T6G(SCH_1):CPU1_SLP_S3_N
 DG4 CPU1_SLP_S5_N SLP_S5_L @T6G_MB_LIB.T6G(SCH_1):CPU1_SLP_S5_N
 DH6 RST_CPU1_SYS_N SYS_RESET_L||AGPIO1 @T6G_MB_LIB.T6G(SCH_1):RST_CPU1_SYS_N
DJ10 IRQ_WAKE_N WAKE_L||AGPIO2 @T6G_MB_LIB.T6G(SCH_1):IRQ_WAKE_N
DJ14 XTAL_CPU1_X32K_X1 X32K_X1 @T6G_MB_LIB.T6G(SCH_1):XTAL_CPU1_X32K_X1
DJ13 XTAL_CPU1_X32K_X2 X32K_X2 @T6G_MB_LIB.T6G(SCH_1):XTAL_CPU1_X32K_X2
DJ17 XTAL_CPU1_X48M_X1 X48M_X1 @T6G_MB_LIB.T6G(SCH_1):XTAL_CPU1_X48M_X1
DJ16 XTAL_CPU1_X48M_X2 X48M_X2 @T6G_MB_LIB.T6G(SCH_1):XTAL_CPU1_X48M_X2
 DH7 NC_CPU1_PWR_BTN_N PWR_BTN_L||AGPIO0 @T6G_MB_LIB.T6G(SCH_1):NC_CPU1_PWR_BTN_N
 B64 CPU1_NV_SAVE_N NV_SAVE_L @T6G_MB_LIB.T6G(SCH_1):CPU1_NV_SAVE_N
 B63 CPU1_FORCE_SELFREFRESH FORCE_SELFREFRESH @T6G_MB_LIB.T6G(SCH_1):CPU1_FORCE_SELFREFRESH
 DH9 CLK_CPU1_RTCCLK RTCCLK @T6G_MB_LIB.T6G(SCH_1):CLK_CPU1_RTCCLK
  C9 CLK_100M_CPU1_CLK05_R_DN GPP_CLK05N @T6G_MB_LIB.T6G(SCH_1):CLK_100M_CPU1_CLK05_R_DN
DJ50     NC GPP_CLK15N     NC
 C12 CLK_100M_CPU1_CLK04_R_DN GPP_CLK04N @T6G_MB_LIB.T6G(SCH_1):CLK_100M_CPU1_CLK04_R_DN
DJ47     NC GPP_CLK14N     NC
  B9 CLK_100M_CPU1_CLK05_R_DP GPP_CLK05P @T6G_MB_LIB.T6G(SCH_1):CLK_100M_CPU1_CLK05_R_DP
 A11 CLK_100M_CPU1_CLK03_R_DN GPP_CLK03N @T6G_MB_LIB.T6G(SCH_1):CLK_100M_CPU1_CLK03_R_DN
DJ51     NC GPP_CLK15P     NC
DJ54 CLK_100M_CPU1_CLK13_R_DN GPP_CLK13N @T6G_MB_LIB.T6G(SCH_1):CLK_100M_CPU1_CLK13_R_DN
 B12 CLK_100M_CPU1_CLK04_R_DP GPP_CLK04P @T6G_MB_LIB.T6G(SCH_1):CLK_100M_CPU1_CLK04_R_DP
  C6 CLK_100M_CPU1_CLK02_R_DN GPP_CLK02N @T6G_MB_LIB.T6G(SCH_1):CLK_100M_CPU1_CLK02_R_DN
DJ48     NC GPP_CLK14P     NC
DJ44 CLK_100M_CPU1_CLK12_R_DN GPP_CLK12N @T6G_MB_LIB.T6G(SCH_1):CLK_100M_CPU1_CLK12_R_DN
 A10 CLK_100M_CPU1_CLK03_R_DP GPP_CLK03P @T6G_MB_LIB.T6G(SCH_1):CLK_100M_CPU1_CLK03_R_DP
  A7 CLK_100M_CPU1_CLK01_R_DN GPP_CLK01N @T6G_MB_LIB.T6G(SCH_1):CLK_100M_CPU1_CLK01_R_DN
DJ53 CLK_100M_CPU1_CLK13_R_DP GPP_CLK13P @T6G_MB_LIB.T6G(SCH_1):CLK_100M_CPU1_CLK13_R_DP
DJ42 CLK_100M_CPU1_CLK11_R_DN GPP_CLK11N @T6G_MB_LIB.T6G(SCH_1):CLK_100M_CPU1_CLK11_R_DN
  B6 CLK_100M_CPU1_CLK02_R_DP GPP_CLK02P @T6G_MB_LIB.T6G(SCH_1):CLK_100M_CPU1_CLK02_R_DP
DJ45 CLK_100M_CPU1_CLK12_R_DP GPP_CLK12P @T6G_MB_LIB.T6G(SCH_1):CLK_100M_CPU1_CLK12_R_DP
  A8 CLK_100M_CPU1_CLK01_R_DP GPP_CLK01P @T6G_MB_LIB.T6G(SCH_1):CLK_100M_CPU1_CLK01_R_DP
DJ41 CLK_100M_CPU1_CLK11_R_DP GPP_CLK11P @T6G_MB_LIB.T6G(SCH_1):CLK_100M_CPU1_CLK11_R_DP
DF36     NC AGPIO4||SATA_ACT_L     NC
DE36 CPU1_SPD_HOST_CTRL_R_N AGPIO3||SPD_HOST_CTRL_L @T6G_MB_LIB.T6G(SCH_1):CPU1_SPD_HOST_CTRL_R_N
DG36 RST_CPU1_PERST1_N PCIE_RST1_L||AGPIO26 @T6G_MB_LIB.T6G(SCH_1):RST_CPU1_PERST1_N
 B15     NC SGPIO_LOAD||AGPIO261     NC
 B72     NC I3C2_SDA||I2C2_SDA||SPD2_SDA||AGPIO150     NC
 D15     NC SGPIO_DATAOUT||AGPIO260     NC
  B4     NC I3C3_SDA||I2C3_SDA||SPD3_SDA||AGPIO152     NC
 A13     NC AGPIO258||SGPIO2_CLK||CLK_REQ02_L     NC
 A14     NC AGPIO256||SGPIO0_CLK     NC
 D18 RST_CPU1_PERST0_N PCIE_RST0_L||AGPIO266 @T6G_MB_LIB.T6G(SCH_1):RST_CPU1_PERST0_N
DH16 FM_BMC_TPM_PRES_N AGPIO115||CLK_REQ11_L @T6G_MB_LIB.T6G(SCH_1):FM_BMC_TPM_PRES_N
 B71 I3C_0_SPD_DDRAF_CPU1_R_SDA I3C0_SDA||I2C0_SDA||SPD0_SDA||SMBUS0_SDA||AGPIO146 @T6G_MB_LIB.T6G(SCH_1):I3C_0_SPD_DDRAF_CPU1_R_SDA
  C7 I3C_1_SPD_DDRGL_CPU1_R_SCL I3C1_SCL||I2C1_SCL||SPD1_SCL||AGPIO147 @T6G_MB_LIB.T6G(SCH_1):I3C_1_SPD_DDRGL_CPU1_R_SCL
 C72     NC I3C2_SCL||I2C2_SCL||SPD2_SCL||AGPIO149     NC
 A71 I3C_0_SPD_DDRAF_CPU1_R_SCL I3C0_SCL||I2C0_SCL||SPD0_SCL||SMBUS0_SCL||AGPIO145 @T6G_MB_LIB.T6G(SCH_1):I3C_0_SPD_DDRAF_CPU1_R_SCL
 B16     NC AGPIO259||SGPIO3_CLK     NC
DH36 CPU1_PWRGD_OUT PWRGD_OUT||AGPIO12 @T6G_MB_LIB.T6G(SCH_1):CPU1_PWRGD_OUT
DH15 FM_CPU1_BMC_RST_N AGPIO116||CLK_REQ12_L @T6G_MB_LIB.T6G(SCH_1):FM_CPU1_BMC_RST_N
  A5 I3C_1_SPD_DDRGL_CPU1_R_SDA I3C1_SDA||I2C1_SDA||SPD1_SDA||AGPIO148 @T6G_MB_LIB.T6G(SCH_1):I3C_1_SPD_DDRGL_CPU1_R_SDA
  A4     NC I3C3_SCL||I2C3_SCL||SPD3_SCL||AGPIO151     NC
DG12     NC I2C4_SCL||HP_SCL||UBM_SCL||AGPIO13     NC
DH12     NC I2C4_SDA||HP_SDA||UBM_SDA||AGPIO14     NC
DJ21     NC I2C5_SCL||BMC_SCL||SMBUS1_SCL||AGPIO19     NC
DJ20     NC I2C5_SDA||BMC_SDA||SMBUS1_SDA||AGPIO20     NC
DJ11 CPU1_SMERR_N SMERR_L||AGPIO24 @T6G_MB_LIB.T6G(SCH_1):CPU1_SMERR_N
 A19 CLK_100M_REF_IN_DP REFCLK100SSC_P||GPP_CLK10P @T6G_MB_LIB.T6G(SCH_1):CLK_100M_REF_IN_DP
 A20 CLK_100M_REF_IN_DN REFCLK100SSC_N||GPP_CLK10N @T6G_MB_LIB.T6G(SCH_1):CLK_100M_REF_IN_DN
 B67 RST_CPU1_RESETL_N RESET_L @T6G_MB_LIB.T6G(SCH_1):RST_CPU1_RESETL_N
DH30     NC AGPIO104     NC
DE30     NC AGPIO105     NC
DF31     NC AGPIO106     NC
DG31     NC AGPIO107     NC
DG32     NC AGPIO109     NC
DG11     NC AGPIO87     NC
DF33 TP_SLOT2_BUF_SKU_ID0 AGPIO21 @T6G_MB_LIB.T6G(SCH_1):TP_SLOT2_BUF_SKU_ID0
DJ29     NC AGPIO88     NC
DE32 TP_SLOT2_BUF_SKU_ID1 AGPIO22 @T6G_MB_LIB.T6G(SCH_1):TP_SLOT2_BUF_SKU_ID1
DJ35 INT_CPU1_HP_UBM_N GENINT_L||PM_INTR_L||UBM_CPRSNT_CHANGE_DET_L||AGPIO89 @T6G_MB_LIB.T6G(SCH_1):INT_CPU1_HP_UBM_N
DF40 IRQ_CPU_BMC_NMI_N AGPIO5||DEVSLP0||SATA_ZP0_L @T6G_MB_LIB.T6G(SCH_1):IRQ_CPU_BMC_NMI_N
DE40 FM_BMC_READY_N AGPIO6||DEVSLP1||SATA_ZP1_L @T6G_MB_LIB.T6G(SCH_1):FM_BMC_READY_N
 D69 PWRGD_CPU1_PWROK PWROK||SVI_RST_L @T6G_MB_LIB.T6G(SCH_1):PWRGD_CPU1_PWROK
 C14     NC AGPIO257||SGPIO1_CLK||CLK_REQ01_L     NC
 D14 SMB_CPU1_SEC_SDA SEC_SDA||AGPIO263 @T6G_MB_LIB.T6G(SCH_1):SMB_CPU1_SEC_SDA
 B14 SMB_CPU1_SEC_SCL SEC_SCL||AGPIO262 @T6G_MB_LIB.T6G(SCH_1):SMB_CPU1_SEC_SCL
DJ31 CPU1_NMI_SYNC_FLOOD_N NMI_SYNC_FLOOD_L @T6G_MB_LIB.T6G(SCH_1):CPU1_NMI_SYNC_FLOOD_N
 DH4     NC AGPIO7     NC

Q_RES_0402LF-0,5%,1/16W,CHIP,CS00002JB13  I236  R570
   1 CPU1_SPD_HOST_CTRL_N      A @T6G_MB_LIB.T6G(SCH_1):CPU1_SPD_HOST_CTRL_N
   2 CPU1_SPD_HOST_CTRL_R_N      B @T6G_MB_LIB.T6G(SCH_1):CPU1_SPD_HOST_CTRL_R_N

Q_RES_0402LF-2.2K,5%,1/16W,CHIP,CS22202JB07  I292  R1424
   1 PVDD18_S5_P1      A @T6G_MB_LIB.T6G(SCH_1):PVDD18_S5_P1
   2 INT_CPU1_HP_UBM_N      B @T6G_MB_LIB.T6G(SCH_1):INT_CPU1_HP_UBM_N

Q_RES_0402LF-0,5%,1/16W,EMPTY,CS00002JB13  I296  R575
   1 XTAL_CPU1_R_X32K_X2      A @T6G_MB_LIB.T6G(SCH_1):XTAL_CPU1_R_X32K_X2
   2 XTAL_CPU1_X32K_X2      B @T6G_MB_LIB.T6G(SCH_1):XTAL_CPU1_X32K_X2

Q_RES_0402LF-0,5%,1/16W,EMPTY,CS00002JB13  I297  R191
   1 FM_CPU1_SLP_S5_N      A @T6G_MB_LIB.T6G(SCH_1):FM_CPU1_SLP_S5_N
   2 CPU1_SLP_S5_N      B @T6G_MB_LIB.T6G(SCH_1):CPU1_SLP_S5_N

Q_RES_0402LF-0,5%,1/16W,EMPTY,CS00002JB13  I298  R192
   1 FM_CPU1_SLP_S3_N      A @T6G_MB_LIB.T6G(SCH_1):FM_CPU1_SLP_S3_N
   2 CPU1_SLP_S3_N      B @T6G_MB_LIB.T6G(SCH_1):CPU1_SLP_S3_N

Q_RES_0402LF-0,5%,1/16W,CHIP,CS00002JB13  I302  R3352
   1 CLK_100M_CPU1_CLK11_R_DP      A @T6G_MB_LIB.T6G(SCH_1):CLK_100M_CPU1_CLK11_R_DP
   2 CLK_100M_CPU1_CLK11_DP      B @T6G_MB_LIB.T6G(SCH_1):CLK_100M_CPU1_CLK11_DP

Q_RES_0402LF-0,5%,1/16W,CHIP,CS00002JB13  I303  R3353
   1 CLK_100M_CPU1_CLK11_R_DN      A @T6G_MB_LIB.T6G(SCH_1):CLK_100M_CPU1_CLK11_R_DN
   2 CLK_100M_CPU1_CLK11_DN      B @T6G_MB_LIB.T6G(SCH_1):CLK_100M_CPU1_CLK11_DN

Q_RES_0402LF-0,5%,1/16W,CHIP,CS00002JB13  I306  R3355
   1 CLK_100M_CPU1_CLK01_R_DN      A @T6G_MB_LIB.T6G(SCH_1):CLK_100M_CPU1_CLK01_R_DN
   2 CLK_100M_CPU1_CLK01_DN      B @T6G_MB_LIB.T6G(SCH_1):CLK_100M_CPU1_CLK01_DN

Q_RES_0402LF-0,5%,1/16W,CHIP,CS00002JB13  I307  R3354
   1 CLK_100M_CPU1_CLK01_R_DP      A @T6G_MB_LIB.T6G(SCH_1):CLK_100M_CPU1_CLK01_R_DP
   2 CLK_100M_CPU1_CLK01_DP      B @T6G_MB_LIB.T6G(SCH_1):CLK_100M_CPU1_CLK01_DP

Q_RES_0402LF-0,5%,1/16W,CHIP,CS00002JB13  I308  R3194
   1 CLK_100M_CPU1_CLK02_R_DP      A @T6G_MB_LIB.T6G(SCH_1):CLK_100M_CPU1_CLK02_R_DP
   2 CLK_100M_CPU1_CLK02_DP      B @T6G_MB_LIB.T6G(SCH_1):CLK_100M_CPU1_CLK02_DP

Q_RES_0402LF-0,5%,1/16W,CHIP,CS00002JB13  I309  R3195
   1 CLK_100M_CPU1_CLK02_R_DN      A @T6G_MB_LIB.T6G(SCH_1):CLK_100M_CPU1_CLK02_R_DN
   2 CLK_100M_CPU1_CLK02_DN      B @T6G_MB_LIB.T6G(SCH_1):CLK_100M_CPU1_CLK02_DN

Q_RES_0402LF-0,5%,1/16W,CHIP,CS00002JB13  I312  R3196
   1 CLK_100M_CPU1_CLK03_R_DP      A @T6G_MB_LIB.T6G(SCH_1):CLK_100M_CPU1_CLK03_R_DP
   2 CLK_100M_CPU1_CLK03_DP      B @T6G_MB_LIB.T6G(SCH_1):CLK_100M_CPU1_CLK03_DP

Q_RES_0402LF-0,5%,1/16W,CHIP,CS00002JB13  I313  R3197
   1 CLK_100M_CPU1_CLK03_R_DN      A @T6G_MB_LIB.T6G(SCH_1):CLK_100M_CPU1_CLK03_R_DN
   2 CLK_100M_CPU1_CLK03_DN      B @T6G_MB_LIB.T6G(SCH_1):CLK_100M_CPU1_CLK03_DN

Q_RES_0402LF-0,5%,1/16W,CHIP,CS00002JB13  I316  R3198
   1 CLK_100M_CPU1_CLK04_R_DP      A @T6G_MB_LIB.T6G(SCH_1):CLK_100M_CPU1_CLK04_R_DP
   2 CLK_100M_CPU1_CLK04_DP      B @T6G_MB_LIB.T6G(SCH_1):CLK_100M_CPU1_CLK04_DP

Q_RES_0402LF-0,5%,1/16W,CHIP,CS00002JB13  I317  R3199
   1 CLK_100M_CPU1_CLK04_R_DN      A @T6G_MB_LIB.T6G(SCH_1):CLK_100M_CPU1_CLK04_R_DN
   2 CLK_100M_CPU1_CLK04_DN      B @T6G_MB_LIB.T6G(SCH_1):CLK_100M_CPU1_CLK04_DN

Q_RES_0402LF-0,5%,1/16W,CHIP,CS00002JB13  I320  R3200
   1 CLK_100M_CPU1_CLK05_R_DP      A @T6G_MB_LIB.T6G(SCH_1):CLK_100M_CPU1_CLK05_R_DP
   2 CLK_100M_CPU1_CLK05_DP      B @T6G_MB_LIB.T6G(SCH_1):CLK_100M_CPU1_CLK05_DP

Q_RES_0402LF-0,5%,1/16W,CHIP,CS00002JB13  I321  R3201
   1 CLK_100M_CPU1_CLK05_R_DN      A @T6G_MB_LIB.T6G(SCH_1):CLK_100M_CPU1_CLK05_R_DN
   2 CLK_100M_CPU1_CLK05_DN      B @T6G_MB_LIB.T6G(SCH_1):CLK_100M_CPU1_CLK05_DN

Q_RES_0402LF-0,5%,1/16W,CHIP,CS00002JB13  I326  R4306
   1 CLK_100M_CPU1_CLK12_R_DN      A @T6G_MB_LIB.T6G(SCH_1):CLK_100M_CPU1_CLK12_R_DN
   2 CLK_100M_CPU1_CLK12_DN      B @T6G_MB_LIB.T6G(SCH_1):CLK_100M_CPU1_CLK12_DN

Q_RES_0402LF-0,5%,1/16W,CHIP,CS00002JB13  I327  R4305
   1 CLK_100M_CPU1_CLK12_R_DP      A @T6G_MB_LIB.T6G(SCH_1):CLK_100M_CPU1_CLK12_R_DP
   2 CLK_100M_CPU1_CLK12_DP      B @T6G_MB_LIB.T6G(SCH_1):CLK_100M_CPU1_CLK12_DP

Q_RES_0402LF-4.7K,5%,1/16W,EMPTY,CS24702JB10  I330  R5032
   1    GND      A @T6G_MB_LIB.T6G(SCH_1):GND
   2 IRQ_CPU_BMC_NMI_N      B @T6G_MB_LIB.T6G(SCH_1):IRQ_CPU_BMC_NMI_N

Q_RES_0402LF-4.7K,5%,1/16W,EMPTY,CS24702JB10  I331  R5031
   1    GND      A @T6G_MB_LIB.T6G(SCH_1):GND
   2 FM_BMC_READY_N      B @T6G_MB_LIB.T6G(SCH_1):FM_BMC_READY_N

Q_RES_0402LF-4.7K,5%,1/16W,EMPTY,CS24702JB10  I334  R5030
   1    GND      A @T6G_MB_LIB.T6G(SCH_1):GND
   2 FM_BMC_TPM_PRES_N      B @T6G_MB_LIB.T6G(SCH_1):FM_BMC_TPM_PRES_N

Q_RES_0402LF-4.7K,5%,1/16W,EMPTY,CS24702JB10  I335  R491
   1    GND      A @T6G_MB_LIB.T6G(SCH_1):GND
   2 CPU1_PWRGD_OUT      B @T6G_MB_LIB.T6G(SCH_1):CPU1_PWRGD_OUT

Q_RES_0402LF-4.7K,5%,1/16W,CHIP,CS24702JB10  I336  R544
   1 IRQ_CPU_BMC_NMI_N      A @T6G_MB_LIB.T6G(SCH_1):IRQ_CPU_BMC_NMI_N
   2 PVDD18_S5_P1      B @T6G_MB_LIB.T6G(SCH_1):PVDD18_S5_P1

Q_RES_0402LF-4.7K,5%,1/16W,CHIP,CS24702JB10  I337  R545
   1 FM_BMC_READY_N      A @T6G_MB_LIB.T6G(SCH_1):FM_BMC_READY_N
   2 PVDD18_S5_P1      B @T6G_MB_LIB.T6G(SCH_1):PVDD18_S5_P1

Q_RES_0402LF-4.7K,5%,1/16W,CHIP,CS24702JB10  I338  R546
   1 FM_BMC_TPM_PRES_N      A @T6G_MB_LIB.T6G(SCH_1):FM_BMC_TPM_PRES_N
   2 PVDD18_S5_P1      B @T6G_MB_LIB.T6G(SCH_1):PVDD18_S5_P1

Q_RES_0402LF-4.7K,5%,1/16W,EMPTY,CS24702JB10  I339  R456
   1 CPU1_PWRGD_OUT      A @T6G_MB_LIB.T6G(SCH_1):CPU1_PWRGD_OUT
   2 PVDD18_S5_P1      B @T6G_MB_LIB.T6G(SCH_1):PVDD18_S5_P1

Q_RES_0402LF-4.7K,5%,1/16W,EMPTY,CS24702JB10  I341  R584
   1    GND      A @T6G_MB_LIB.T6G(SCH_1):GND
   2 RST_CPU1_RSMRST_N      B @T6G_MB_LIB.T6G(SCH_1):RST_CPU1_RSMRST_N

Q_RES_0402LF-4.7K,5%,1/16W,EMPTY,CS24702JB10  I342  R583
   1 RST_CPU1_RSMRST_N      A @T6G_MB_LIB.T6G(SCH_1):RST_CPU1_RSMRST_N
   2 PVDD18_S5_P1      B @T6G_MB_LIB.T6G(SCH_1):PVDD18_S5_P1

Q_RES_0402LF-4.7K,5%,1/16W,EMPTY,CS24702JB10  I352  R548
   1 CPU1_SLP_S5_N      A @T6G_MB_LIB.T6G(SCH_1):CPU1_SLP_S5_N
   2 PVDD18_S5_P1      B @T6G_MB_LIB.T6G(SCH_1):PVDD18_S5_P1

Q_RES_0402LF-4.7K,5%,1/16W,EMPTY,CS24702JB10  I353  R549
   1 CPU1_SLP_S3_N      A @T6G_MB_LIB.T6G(SCH_1):CPU1_SLP_S3_N
   2 PVDD18_S5_P1      B @T6G_MB_LIB.T6G(SCH_1):PVDD18_S5_P1

Q_RES_0402LF-2.2K,5%,1/16W,CHIP,CS22202JB07  I355  R562
   1 PVDD18_S5_P1      A @T6G_MB_LIB.T6G(SCH_1):PVDD18_S5_P1
   2 CPU1_NMI_SYNC_FLOOD_N      B @T6G_MB_LIB.T6G(SCH_1):CPU1_NMI_SYNC_FLOOD_N

Q_RES_0402LF-2.2K,5%,1/16W,CHIP,CS22202JB07  I356  R559
   1 PVDD18_S5_P1      A @T6G_MB_LIB.T6G(SCH_1):PVDD18_S5_P1
   2 RST_CPU1_SYS_N      B @T6G_MB_LIB.T6G(SCH_1):RST_CPU1_SYS_N

Q_RES_0402LF-1K,1%,1/16W,EMPTY,CS21002FB06  I357  R556
   1 PVDD18_S5_P1      A @T6G_MB_LIB.T6G(SCH_1):PVDD18_S5_P1
   2 RST_CPU1_RESETL_N      B @T6G_MB_LIB.T6G(SCH_1):RST_CPU1_RESETL_N

Q_RES_0402LF-4.7K,5%,1/16W,CHIP,CS24702JB10  I359  R553
   1 CPU1_NV_SAVE_N      A @T6G_MB_LIB.T6G(SCH_1):CPU1_NV_SAVE_N
   2 PVDD18_S5_P1      B @T6G_MB_LIB.T6G(SCH_1):PVDD18_S5_P1

Q_RES_0402LF-4.7K,5%,1/16W,CHIP,CS24702JB10  I360  R551
   1 CPU1_SPD_HOST_CTRL_N      A @T6G_MB_LIB.T6G(SCH_1):CPU1_SPD_HOST_CTRL_N
   2 PVDD18_S5_P1      B @T6G_MB_LIB.T6G(SCH_1):PVDD18_S5_P1

Q_RES_0402LF-4.7K,5%,1/16W,CHIP,CS24702JB10  I362  R547
   1 FM_CPU1_BMC_RST_N      A @T6G_MB_LIB.T6G(SCH_1):FM_CPU1_BMC_RST_N
   2 PVDD18_S5_P1      B @T6G_MB_LIB.T6G(SCH_1):PVDD18_S5_P1

Q_RES_0402LF-4.7K,5%,1/16W,CHIP,CS24702JB10  I363  R550
   1 CPU1_SMERR_N      A @T6G_MB_LIB.T6G(SCH_1):CPU1_SMERR_N
   2 PVDD18_S5_P1      B @T6G_MB_LIB.T6G(SCH_1):PVDD18_S5_P1

Q_RES_0402LF-1K,1%,1/16W,EMPTY,CS21002FB06  I364  R557
   1 PVDD18_S5_P1      A @T6G_MB_LIB.T6G(SCH_1):PVDD18_S5_P1
   2 PWRGD_CPU1_PWROK      B @T6G_MB_LIB.T6G(SCH_1):PWRGD_CPU1_PWROK

Q_RES_0402LF-1K,1%,1/16W,EMPTY,CS21002FB06  I365  R541
   1 PVDD11_S3_P1      A @T6G_MB_LIB.T6G(SCH_1):PVDD11_S3_P1
   2 I3C_1_SPD_DDRGL_CPU1_R_SDA      B @T6G_MB_LIB.T6G(SCH_1):I3C_1_SPD_DDRGL_CPU1_R_SDA

Q_RES_0402LF-1K,1%,1/16W,EMPTY,CS21002FB06  I366  R542
   1 PVDD11_S3_P1      A @T6G_MB_LIB.T6G(SCH_1):PVDD11_S3_P1
   2 I3C_1_SPD_DDRGL_CPU1_R_SCL      B @T6G_MB_LIB.T6G(SCH_1):I3C_1_SPD_DDRGL_CPU1_R_SCL

Q_RES_0402LF-1K,1%,1/16W,EMPTY,CS21002FB06  I367  R543
   1 PVDD11_S3_P1      A @T6G_MB_LIB.T6G(SCH_1):PVDD11_S3_P1
   2 I3C_0_SPD_DDRAF_CPU1_R_SDA      B @T6G_MB_LIB.T6G(SCH_1):I3C_0_SPD_DDRAF_CPU1_R_SDA

Q_RES_0402LF-1K,1%,1/16W,EMPTY,CS21002FB06  I368  R563
   1 PVDD11_S3_P1      A @T6G_MB_LIB.T6G(SCH_1):PVDD11_S3_P1
   2 I3C_0_SPD_DDRAF_CPU1_R_SCL      B @T6G_MB_LIB.T6G(SCH_1):I3C_0_SPD_DDRAF_CPU1_R_SCL

Q_RES_0402LF-49.9,1%,1/16W,CHIP,CS04992FB07  I386  R5103
   1 XTAL_CPU1_X48M_X2      A @T6G_MB_LIB.T6G(SCH_1):XTAL_CPU1_X48M_X2
   2 XTAL_CPU1_X48M_X2_R      B @T6G_MB_LIB.T6G(SCH_1):XTAL_CPU1_X48M_X2_R

Q_CAP_0402-1000PF,50V,5%,X7R,TMP_QCH21006JB10  I388  C5024
   1 RST_CPU1_RSMRST_N      A @T6G_MB_LIB.T6G(SCH_1):RST_CPU1_RSMRST_N
   2    GND      B @T6G_MB_LIB.T6G(SCH_1):GND

Q_RES_0402LF-20M,1%,1/16W,CHIP,CS62002FB01  I389  R572
   1 XTAL_CPU1_R_X32K_X1      A @T6G_MB_LIB.T6G(SCH_1):XTAL_CPU1_R_X32K_X1
   2 XTAL_CPU1_R_X32K_X2      B @T6G_MB_LIB.T6G(SCH_1):XTAL_CPU1_R_X32K_X2

Q_RES_0402LF-4.7K,5%,1/16W,EMPTY,CS24702JB10  I390  R558
   1 CPU1_FORCE_SELFREFRESH      A @T6G_MB_LIB.T6G(SCH_1):CPU1_FORCE_SELFREFRESH
   2 PVDD18_S5_P1      B @T6G_MB_LIB.T6G(SCH_1):PVDD18_S5_P1

Q_RES_0402LF-2.2K,5%,1/16W,CHIP,CS22202JB07  I392  R6503
   1 CPU1_FORCE_SELFREFRESH      A @T6G_MB_LIB.T6G(SCH_1):CPU1_FORCE_SELFREFRESH
   2    GND      B @T6G_MB_LIB.T6G(SCH_1):GND

Q_RES_0402LF-0,5%,1/16W,CHIP,CS00002JB13  I394  R8351
   1 CLK_100M_CPU1_CLK13_R_DN      A @T6G_MB_LIB.T6G(SCH_1):CLK_100M_CPU1_CLK13_R_DN
   2 CLK_100M_CPU1_CLK13_DN      B @T6G_MB_LIB.T6G(SCH_1):CLK_100M_CPU1_CLK13_DN

Q_RES_0402LF-0,5%,1/16W,CHIP,CS00002JB13  I397  R8350
   1 CLK_100M_CPU1_CLK13_R_DP      A @T6G_MB_LIB.T6G(SCH_1):CLK_100M_CPU1_CLK13_R_DP
   2 CLK_100M_CPU1_CLK13_DP      B @T6G_MB_LIB.T6G(SCH_1):CLK_100M_CPU1_CLK13_DP


DRAWING: @T6G_MB_LIB.T6G(SCH_1):PAGE56 

GENOA_SP5-SOCKET6096_13568-001,SMLF,IO,DGA^6000030  I8  U26
 A25 NC_CPU1_USB2_USB00_DN USB00_DN @T6G_MB_LIB.T6G(SCH_1):NC_CPU1_USB2_USB00_DN
 A26 NC_CPU1_USB2_USB00_DP USB00_DP @T6G_MB_LIB.T6G(SCH_1):NC_CPU1_USB2_USB00_DP
 E26 NC_CPU1_USB3_USB00_RXN USB00_RXN @T6G_MB_LIB.T6G(SCH_1):NC_CPU1_USB3_USB00_RXN
 E27 NC_CPU1_USB3_USB00_RXP USB00_RXP @T6G_MB_LIB.T6G(SCH_1):NC_CPU1_USB3_USB00_RXP
 C26 NC_CPU1_USB3_USB00_TXP USB00_TXN @T6G_MB_LIB.T6G(SCH_1):NC_CPU1_USB3_USB00_TXP
 C25 NC_CPU1_USB3_USB00_TXN USB00_TXP @T6G_MB_LIB.T6G(SCH_1):NC_CPU1_USB3_USB00_TXN
 A29 NC_CPU1_USB2_USB01_DN USB01_DN @T6G_MB_LIB.T6G(SCH_1):NC_CPU1_USB2_USB01_DN
 A28 NC_CPU1_USB2_USB01_DP USB01_DP @T6G_MB_LIB.T6G(SCH_1):NC_CPU1_USB2_USB01_DP
 C28 NC_CPU1_USB3_USB01_RXN USB01_RXN @T6G_MB_LIB.T6G(SCH_1):NC_CPU1_USB3_USB01_RXN
 C29 NC_CPU1_USB3_USB01_RXP USB01_RXP @T6G_MB_LIB.T6G(SCH_1):NC_CPU1_USB3_USB01_RXP
 E29 NC_CPU1_USB3_USB01_TXN USB01_TXN @T6G_MB_LIB.T6G(SCH_1):NC_CPU1_USB3_USB01_TXN
 E30 NC_CPU1_USB3_USB01_TXP USB01_TXP @T6G_MB_LIB.T6G(SCH_1):NC_CPU1_USB3_USB01_TXP
DH67 NC_CPU1_USB2_USB10_DN USB10_DN @T6G_MB_LIB.T6G(SCH_1):NC_CPU1_USB2_USB10_DN
DJ67 NC_CPU1_USB2_USB10_DP USB10_DP @T6G_MB_LIB.T6G(SCH_1):NC_CPU1_USB2_USB10_DP
DH65 NC_CPU1_USB3_USB10_RXN USB10_RXN @T6G_MB_LIB.T6G(SCH_1):NC_CPU1_USB3_USB10_RXN
DJ65 NC_CPU1_USB3_USB10_RXP USB10_RXP @T6G_MB_LIB.T6G(SCH_1):NC_CPU1_USB3_USB10_RXP
DJ69 NC_CPU1_USB3_USB10_TXN USB10_TXN @T6G_MB_LIB.T6G(SCH_1):NC_CPU1_USB3_USB10_TXN
DH69 NC_CPU1_USB3_USB10_TXP USB10_TXP @T6G_MB_LIB.T6G(SCH_1):NC_CPU1_USB3_USB10_TXP
DJ60 NC_CPU1_USB2_USB11_DN USB11_DN @T6G_MB_LIB.T6G(SCH_1):NC_CPU1_USB2_USB11_DN
DH60 NC_CPU1_USB2_USB11_DP USB11_DP @T6G_MB_LIB.T6G(SCH_1):NC_CPU1_USB2_USB11_DP
DH62 NC_CPU1_USB3_USB11_RXN USB11_RXN @T6G_MB_LIB.T6G(SCH_1):NC_CPU1_USB3_USB11_RXN
DJ62 NC_CPU1_USB3_USB11_RXP USB11_RXP @T6G_MB_LIB.T6G(SCH_1):NC_CPU1_USB3_USB11_RXP
DH58 NC_CPU1_USB3_USB11_TXN USB11_TXN @T6G_MB_LIB.T6G(SCH_1):NC_CPU1_USB3_USB11_TXN
DG58 NC_CPU1_USB3_USB11_TXP USB11_TXP @T6G_MB_LIB.T6G(SCH_1):NC_CPU1_USB3_USB11_TXP
DG40 NC_CPU1_USB10_OC_N USB10_OC_L||AGPIO16 @T6G_MB_LIB.T6G(SCH_1):NC_CPU1_USB10_OC_N
DH40 NC_CPU1_USB11_OC_N USB11_OC_L||AGPIO17 @T6G_MB_LIB.T6G(SCH_1):NC_CPU1_USB11_OC_N
DG28     NC ESPI_CS0_L||AGPIO124     NC
 E23 NC_CPU1_USB00_OC_N USB00_OC_L||AGPIO264 @T6G_MB_LIB.T6G(SCH_1):NC_CPU1_USB00_OC_N
DF30     NC SPI_CS0_L||AGPIO118     NC
DE24     NC ESPI1_DAT1||SPI1_DAT1||AGPIO132     NC
DH24     NC ESPI1_DAT0||SPI1_DAT0||AGPIO131     NC
DJ23     NC ESPI_CS1_L||AGPIO125     NC
DG25     NC ESPI1_DAT3||SPI1_DAT3||AGPIO134     NC
DF25     NC ESPI1_DAT2||SPI1_DAT2||AGPIO133     NC
DG29     NC ESPI0_DAT3||SPI0_DAT3||AGPIO123     NC
DJ28     NC ESPI0_DAT2||SPI0_DAT2||AGPIO122     NC
DG22     NC ESPI0_DAT1||SPI0_DAT1||AGPIO121     NC
DF28     NC ESPI0_DAT0||SPI0_DAT0||AGPIO120     NC
DH27     NC SPI_CS2_L||AGPIO126     NC
DG26     NC SPI_CS1_L||AGPIO119     NC
 E24 NC_CPU1_USB01_OC_N USB01_OC_L||AGPIO265 @T6G_MB_LIB.T6G(SCH_1):NC_CPU1_USB01_OC_N
DJ26     NC ESPI_RSTIN_L||KBRST_L||AGPIO129     NC
DF24     NC ESPI1_ALERT_L||AGPIO110     NC
DJ27 SPI_CPU1_R_CLK ESPI_CLK0||SPI_CLK0||AGPIO117 @T6G_MB_LIB.T6G(SCH_1):SPI_CPU1_R_CLK
DJ25     NC AGPIO76||SPI_TPM_CS_L     NC
DJ22     NC ESPI0_ALERT_L||AGPIO108     NC
DF27 PD_ESPI_CPU1_CLK2 ESPI_CLK2||AGPIO74 @T6G_MB_LIB.T6G(SCH_1):PD_ESPI_CPU1_CLK2
DG23     NC ESPI_CLK1||SPI_CLK1||AGPIO75     NC
DE27     NC ESPI_RSTOUT_L||AGPIO23     NC

Q_RES_0402LF-33,5%,1/16W,CHIP,CS03302JB10  I11  R738
   1 SPI_CPU1_CLK      A @T6G_MB_LIB.T6G(SCH_1):SPI_CPU1_CLK
   2 SPI_CPU1_R_CLK      B @T6G_MB_LIB.T6G(SCH_1):SPI_CPU1_R_CLK


DRAWING: @T6G_MB_LIB.T6G(SCH_1):PAGE57 

GENOA_SP5-SOCKET6096_13568-001,SMLF,IO,DGA^6000030  I29  U26
 W47 PVDDCR_CPU0_P1 VDDCR_CPU0_W47 @T6G_MB_LIB.T6G(SCH_1):PVDDCR_CPU0_P1
 W46 PVDDCR_CPU0_P1 VDDCR_CPU0_W46 @T6G_MB_LIB.T6G(SCH_1):PVDDCR_CPU0_P1
 W44 PVDDCR_CPU0_P1 VDDCR_CPU0_W44 @T6G_MB_LIB.T6G(SCH_1):PVDDCR_CPU0_P1
 W43 PVDDCR_CPU0_P1 VDDCR_CPU0_W43 @T6G_MB_LIB.T6G(SCH_1):PVDDCR_CPU0_P1
 W33 PVDDCR_CPU0_P1 VDDCR_CPU0_W33 @T6G_MB_LIB.T6G(SCH_1):PVDDCR_CPU0_P1
 W32 PVDDCR_CPU0_P1 VDDCR_CPU0_W32 @T6G_MB_LIB.T6G(SCH_1):PVDDCR_CPU0_P1
 W30 PVDDCR_CPU0_P1 VDDCR_CPU0_W30 @T6G_MB_LIB.T6G(SCH_1):PVDDCR_CPU0_P1
 W29 PVDDCR_CPU0_P1 VDDCR_CPU0_W29 @T6G_MB_LIB.T6G(SCH_1):PVDDCR_CPU0_P1
 U41 PVDDCR_CPU0_P1 VDDCR_CPU0_U41 @T6G_MB_LIB.T6G(SCH_1):PVDDCR_CPU0_P1
 U40 PVDDCR_CPU0_P1 VDDCR_CPU0_U40 @T6G_MB_LIB.T6G(SCH_1):PVDDCR_CPU0_P1
 U36 PVDDCR_CPU0_P1 VDDCR_CPU0_U36 @T6G_MB_LIB.T6G(SCH_1):PVDDCR_CPU0_P1
 U35 PVDDCR_CPU0_P1 VDDCR_CPU0_U35 @T6G_MB_LIB.T6G(SCH_1):PVDDCR_CPU0_P1
 T53 PVDDCR_CPU0_P1 VDDCR_CPU0_T53 @T6G_MB_LIB.T6G(SCH_1):PVDDCR_CPU0_P1
 T52 PVDDCR_CPU0_P1 VDDCR_CPU0_T52 @T6G_MB_LIB.T6G(SCH_1):PVDDCR_CPU0_P1
 T50 PVDDCR_CPU0_P1 VDDCR_CPU0_T50 @T6G_MB_LIB.T6G(SCH_1):PVDDCR_CPU0_P1
 T49 PVDDCR_CPU0_P1 VDDCR_CPU0_T49 @T6G_MB_LIB.T6G(SCH_1):PVDDCR_CPU0_P1
 T47 PVDDCR_CPU0_P1 VDDCR_CPU0_T47 @T6G_MB_LIB.T6G(SCH_1):PVDDCR_CPU0_P1
 T46 PVDDCR_CPU0_P1 VDDCR_CPU0_T46 @T6G_MB_LIB.T6G(SCH_1):PVDDCR_CPU0_P1
 T44 PVDDCR_CPU0_P1 VDDCR_CPU0_T44 @T6G_MB_LIB.T6G(SCH_1):PVDDCR_CPU0_P1
 T43 PVDDCR_CPU0_P1 VDDCR_CPU0_T43 @T6G_MB_LIB.T6G(SCH_1):PVDDCR_CPU0_P1
 T33 PVDDCR_CPU0_P1 VDDCR_CPU0_T33 @T6G_MB_LIB.T6G(SCH_1):PVDDCR_CPU0_P1
 T32 PVDDCR_CPU0_P1 VDDCR_CPU0_T32 @T6G_MB_LIB.T6G(SCH_1):PVDDCR_CPU0_P1
 T30 PVDDCR_CPU0_P1 VDDCR_CPU0_T30 @T6G_MB_LIB.T6G(SCH_1):PVDDCR_CPU0_P1
 T29 PVDDCR_CPU0_P1 VDDCR_CPU0_T29 @T6G_MB_LIB.T6G(SCH_1):PVDDCR_CPU0_P1
 T27 PVDDCR_CPU0_P1 VDDCR_CPU0_T27 @T6G_MB_LIB.T6G(SCH_1):PVDDCR_CPU0_P1
 T26 PVDDCR_CPU0_P1 VDDCR_CPU0_T26 @T6G_MB_LIB.T6G(SCH_1):PVDDCR_CPU0_P1
 T24 PVDDCR_CPU0_P1 VDDCR_CPU0_T24 @T6G_MB_LIB.T6G(SCH_1):PVDDCR_CPU0_P1
 T23 PVDDCR_CPU0_P1 VDDCR_CPU0_T23 @T6G_MB_LIB.T6G(SCH_1):PVDDCR_CPU0_P1
 N41 PVDDCR_CPU0_P1 VDDCR_CPU0_N41 @T6G_MB_LIB.T6G(SCH_1):PVDDCR_CPU0_P1
 N40 PVDDCR_CPU0_P1 VDDCR_CPU0_N40 @T6G_MB_LIB.T6G(SCH_1):PVDDCR_CPU0_P1
 N36 PVDDCR_CPU0_P1 VDDCR_CPU0_N36 @T6G_MB_LIB.T6G(SCH_1):PVDDCR_CPU0_P1
 N35 PVDDCR_CPU0_P1 VDDCR_CPU0_N35 @T6G_MB_LIB.T6G(SCH_1):PVDDCR_CPU0_P1
 M53 PVDDCR_CPU0_P1 VDDCR_CPU0_M53 @T6G_MB_LIB.T6G(SCH_1):PVDDCR_CPU0_P1
 M52 PVDDCR_CPU0_P1 VDDCR_CPU0_M52 @T6G_MB_LIB.T6G(SCH_1):PVDDCR_CPU0_P1
 M50 PVDDCR_CPU0_P1 VDDCR_CPU0_M50 @T6G_MB_LIB.T6G(SCH_1):PVDDCR_CPU0_P1
 M49 PVDDCR_CPU0_P1 VDDCR_CPU0_M49 @T6G_MB_LIB.T6G(SCH_1):PVDDCR_CPU0_P1
 M47 PVDDCR_CPU0_P1 VDDCR_CPU0_M47 @T6G_MB_LIB.T6G(SCH_1):PVDDCR_CPU0_P1
 M46 PVDDCR_CPU0_P1 VDDCR_CPU0_M46 @T6G_MB_LIB.T6G(SCH_1):PVDDCR_CPU0_P1
 M44 PVDDCR_CPU0_P1 VDDCR_CPU0_M44 @T6G_MB_LIB.T6G(SCH_1):PVDDCR_CPU0_P1
 M43 PVDDCR_CPU0_P1 VDDCR_CPU0_M43 @T6G_MB_LIB.T6G(SCH_1):PVDDCR_CPU0_P1
 M33 PVDDCR_CPU0_P1 VDDCR_CPU0_M33 @T6G_MB_LIB.T6G(SCH_1):PVDDCR_CPU0_P1
 M32 PVDDCR_CPU0_P1 VDDCR_CPU0_M32 @T6G_MB_LIB.T6G(SCH_1):PVDDCR_CPU0_P1
 M30 PVDDCR_CPU0_P1 VDDCR_CPU0_M30 @T6G_MB_LIB.T6G(SCH_1):PVDDCR_CPU0_P1
 M29 PVDDCR_CPU0_P1 VDDCR_CPU0_M29 @T6G_MB_LIB.T6G(SCH_1):PVDDCR_CPU0_P1
 M27 PVDDCR_CPU0_P1 VDDCR_CPU0_M27 @T6G_MB_LIB.T6G(SCH_1):PVDDCR_CPU0_P1
 M26 PVDDCR_CPU0_P1 VDDCR_CPU0_M26 @T6G_MB_LIB.T6G(SCH_1):PVDDCR_CPU0_P1
 M24 PVDDCR_CPU0_P1 VDDCR_CPU0_M24 @T6G_MB_LIB.T6G(SCH_1):PVDDCR_CPU0_P1
 M23 PVDDCR_CPU0_P1 VDDCR_CPU0_M23 @T6G_MB_LIB.T6G(SCH_1):PVDDCR_CPU0_P1
 J41 PVDDCR_CPU0_P1 VDDCR_CPU0_J41 @T6G_MB_LIB.T6G(SCH_1):PVDDCR_CPU0_P1
 J40 PVDDCR_CPU0_P1 VDDCR_CPU0_J40 @T6G_MB_LIB.T6G(SCH_1):PVDDCR_CPU0_P1
 J36 PVDDCR_CPU0_P1 VDDCR_CPU0_J36 @T6G_MB_LIB.T6G(SCH_1):PVDDCR_CPU0_P1
 J35 PVDDCR_CPU0_P1 VDDCR_CPU0_J35 @T6G_MB_LIB.T6G(SCH_1):PVDDCR_CPU0_P1
 H53 PVDDCR_CPU0_P1 VDDCR_CPU0_H53 @T6G_MB_LIB.T6G(SCH_1):PVDDCR_CPU0_P1
 H52 PVDDCR_CPU0_P1 VDDCR_CPU0_H52 @T6G_MB_LIB.T6G(SCH_1):PVDDCR_CPU0_P1
 H50 PVDDCR_CPU0_P1 VDDCR_CPU0_H50 @T6G_MB_LIB.T6G(SCH_1):PVDDCR_CPU0_P1
 H49 PVDDCR_CPU0_P1 VDDCR_CPU0_H49 @T6G_MB_LIB.T6G(SCH_1):PVDDCR_CPU0_P1
 H47 PVDDCR_CPU0_P1 VDDCR_CPU0_H47 @T6G_MB_LIB.T6G(SCH_1):PVDDCR_CPU0_P1
 H46 PVDDCR_CPU0_P1 VDDCR_CPU0_H46 @T6G_MB_LIB.T6G(SCH_1):PVDDCR_CPU0_P1
 H44 PVDDCR_CPU0_P1 VDDCR_CPU0_H44 @T6G_MB_LIB.T6G(SCH_1):PVDDCR_CPU0_P1
 H43 PVDDCR_CPU0_P1 VDDCR_CPU0_H43 @T6G_MB_LIB.T6G(SCH_1):PVDDCR_CPU0_P1
 H33 PVDDCR_CPU0_P1 VDDCR_CPU0_H33 @T6G_MB_LIB.T6G(SCH_1):PVDDCR_CPU0_P1
 H32 PVDDCR_CPU0_P1 VDDCR_CPU0_H32 @T6G_MB_LIB.T6G(SCH_1):PVDDCR_CPU0_P1
 H30 PVDDCR_CPU0_P1 VDDCR_CPU0_H30 @T6G_MB_LIB.T6G(SCH_1):PVDDCR_CPU0_P1
 H29 PVDDCR_CPU0_P1 VDDCR_CPU0_H29 @T6G_MB_LIB.T6G(SCH_1):PVDDCR_CPU0_P1
 H27 PVDDCR_CPU0_P1 VDDCR_CPU0_H27 @T6G_MB_LIB.T6G(SCH_1):PVDDCR_CPU0_P1
 H26 PVDDCR_CPU0_P1 VDDCR_CPU0_H26 @T6G_MB_LIB.T6G(SCH_1):PVDDCR_CPU0_P1
 H24 PVDDCR_CPU0_P1 VDDCR_CPU0_H24 @T6G_MB_LIB.T6G(SCH_1):PVDDCR_CPU0_P1
 H23 PVDDCR_CPU0_P1 VDDCR_CPU0_H23 @T6G_MB_LIB.T6G(SCH_1):PVDDCR_CPU0_P1
 G41 PVDDCR_CPU0_P1 VDDCR_CPU0_G41 @T6G_MB_LIB.T6G(SCH_1):PVDDCR_CPU0_P1
 G40 PVDDCR_CPU0_P1 VDDCR_CPU0_G40 @T6G_MB_LIB.T6G(SCH_1):PVDDCR_CPU0_P1
 G36 PVDDCR_CPU0_P1 VDDCR_CPU0_G36 @T6G_MB_LIB.T6G(SCH_1):PVDDCR_CPU0_P1
 G35 PVDDCR_CPU0_P1 VDDCR_CPU0_G35 @T6G_MB_LIB.T6G(SCH_1):PVDDCR_CPU0_P1
 F54 PVDDCR_CPU0_P1 VDDCR_CPU0_F54 @T6G_MB_LIB.T6G(SCH_1):PVDDCR_CPU0_P1
 F51 PVDDCR_CPU0_P1 VDDCR_CPU0_F51 @T6G_MB_LIB.T6G(SCH_1):PVDDCR_CPU0_P1
 F48 PVDDCR_CPU0_P1 VDDCR_CPU0_F48 @T6G_MB_LIB.T6G(SCH_1):PVDDCR_CPU0_P1
 F45 PVDDCR_CPU0_P1 VDDCR_CPU0_F45 @T6G_MB_LIB.T6G(SCH_1):PVDDCR_CPU0_P1
 F42 PVDDCR_CPU0_P1 VDDCR_CPU0_F42 @T6G_MB_LIB.T6G(SCH_1):PVDDCR_CPU0_P1
 F34 PVDDCR_CPU0_P1 VDDCR_CPU0_F34 @T6G_MB_LIB.T6G(SCH_1):PVDDCR_CPU0_P1
 F31 PVDDCR_CPU0_P1 VDDCR_CPU0_F31 @T6G_MB_LIB.T6G(SCH_1):PVDDCR_CPU0_P1
 F28 PVDDCR_CPU0_P1 VDDCR_CPU0_F28 @T6G_MB_LIB.T6G(SCH_1):PVDDCR_CPU0_P1
 F25 PVDDCR_CPU0_P1 VDDCR_CPU0_F25 @T6G_MB_LIB.T6G(SCH_1):PVDDCR_CPU0_P1
 F22 PVDDCR_CPU0_P1 VDDCR_CPU0_F22 @T6G_MB_LIB.T6G(SCH_1):PVDDCR_CPU0_P1
 E54 PVDDCR_CPU0_P1 VDDCR_CPU0_E54 @T6G_MB_LIB.T6G(SCH_1):PVDDCR_CPU0_P1
 E51 PVDDCR_CPU0_P1 VDDCR_CPU0_E51 @T6G_MB_LIB.T6G(SCH_1):PVDDCR_CPU0_P1
 E48 PVDDCR_CPU0_P1 VDDCR_CPU0_E48 @T6G_MB_LIB.T6G(SCH_1):PVDDCR_CPU0_P1
 E45 PVDDCR_CPU0_P1 VDDCR_CPU0_E45 @T6G_MB_LIB.T6G(SCH_1):PVDDCR_CPU0_P1
 E42 PVDDCR_CPU0_P1 VDDCR_CPU0_E42 @T6G_MB_LIB.T6G(SCH_1):PVDDCR_CPU0_P1
 E35 PVDDCR_CPU0_P1 VDDCR_CPU0_E35 @T6G_MB_LIB.T6G(SCH_1):PVDDCR_CPU0_P1
 E34 PVDDCR_CPU0_P1 VDDCR_CPU0_E34 @T6G_MB_LIB.T6G(SCH_1):PVDDCR_CPU0_P1
 E31 PVDDCR_CPU0_P1 VDDCR_CPU0_E31 @T6G_MB_LIB.T6G(SCH_1):PVDDCR_CPU0_P1
 E28 PVDDCR_CPU0_P1 VDDCR_CPU0_E28 @T6G_MB_LIB.T6G(SCH_1):PVDDCR_CPU0_P1
 E25 PVDDCR_CPU0_P1 VDDCR_CPU0_E25 @T6G_MB_LIB.T6G(SCH_1):PVDDCR_CPU0_P1
 E22 PVDDCR_CPU0_P1 VDDCR_CPU0_E22 @T6G_MB_LIB.T6G(SCH_1):PVDDCR_CPU0_P1
 D56 PVDDCR_CPU0_P1 VDDCR_CPU0_D56 @T6G_MB_LIB.T6G(SCH_1):PVDDCR_CPU0_P1
 D55 PVDDCR_CPU0_P1 VDDCR_CPU0_D55 @T6G_MB_LIB.T6G(SCH_1):PVDDCR_CPU0_P1
 C20 PVDDCR_CPU0_P1 VDDCR_CPU0_C20 @T6G_MB_LIB.T6G(SCH_1):PVDDCR_CPU0_P1
 B57 PVDDCR_CPU0_P1 VDDCR_CPU0_B57 @T6G_MB_LIB.T6G(SCH_1):PVDDCR_CPU0_P1
 B56 PVDDCR_CPU0_P1 VDDCR_CPU0_B56 @T6G_MB_LIB.T6G(SCH_1):PVDDCR_CPU0_P1
 B54 PVDDCR_CPU0_P1 VDDCR_CPU0_B54 @T6G_MB_LIB.T6G(SCH_1):PVDDCR_CPU0_P1
 B53 PVDDCR_CPU0_P1 VDDCR_CPU0_B53 @T6G_MB_LIB.T6G(SCH_1):PVDDCR_CPU0_P1
 B51 PVDDCR_CPU0_P1 VDDCR_CPU0_B51 @T6G_MB_LIB.T6G(SCH_1):PVDDCR_CPU0_P1
 B50 PVDDCR_CPU0_P1 VDDCR_CPU0_B50 @T6G_MB_LIB.T6G(SCH_1):PVDDCR_CPU0_P1
 B48 PVDDCR_CPU0_P1 VDDCR_CPU0_B48 @T6G_MB_LIB.T6G(SCH_1):PVDDCR_CPU0_P1
 B47 PVDDCR_CPU0_P1 VDDCR_CPU0_B47 @T6G_MB_LIB.T6G(SCH_1):PVDDCR_CPU0_P1
 B45 PVDDCR_CPU0_P1 VDDCR_CPU0_B45 @T6G_MB_LIB.T6G(SCH_1):PVDDCR_CPU0_P1
 B44 PVDDCR_CPU0_P1 VDDCR_CPU0_B44 @T6G_MB_LIB.T6G(SCH_1):PVDDCR_CPU0_P1
 B42 PVDDCR_CPU0_P1 VDDCR_CPU0_B42 @T6G_MB_LIB.T6G(SCH_1):PVDDCR_CPU0_P1
 B41 PVDDCR_CPU0_P1 VDDCR_CPU0_B41 @T6G_MB_LIB.T6G(SCH_1):PVDDCR_CPU0_P1
 B35 PVDDCR_CPU0_P1 VDDCR_CPU0_B35 @T6G_MB_LIB.T6G(SCH_1):PVDDCR_CPU0_P1
 B34 PVDDCR_CPU0_P1 VDDCR_CPU0_B34 @T6G_MB_LIB.T6G(SCH_1):PVDDCR_CPU0_P1
 B32 PVDDCR_CPU0_P1 VDDCR_CPU0_B32 @T6G_MB_LIB.T6G(SCH_1):PVDDCR_CPU0_P1
 B31 PVDDCR_CPU0_P1 VDDCR_CPU0_B31 @T6G_MB_LIB.T6G(SCH_1):PVDDCR_CPU0_P1
 B29 PVDDCR_CPU0_P1 VDDCR_CPU0_B29 @T6G_MB_LIB.T6G(SCH_1):PVDDCR_CPU0_P1
 B28 PVDDCR_CPU0_P1 VDDCR_CPU0_B28 @T6G_MB_LIB.T6G(SCH_1):PVDDCR_CPU0_P1
 B26 PVDDCR_CPU0_P1 VDDCR_CPU0_B26 @T6G_MB_LIB.T6G(SCH_1):PVDDCR_CPU0_P1
 B25 PVDDCR_CPU0_P1 VDDCR_CPU0_B25 @T6G_MB_LIB.T6G(SCH_1):PVDDCR_CPU0_P1
 B23 PVDDCR_CPU0_P1 VDDCR_CPU0_B23 @T6G_MB_LIB.T6G(SCH_1):PVDDCR_CPU0_P1
 B22 PVDDCR_CPU0_P1 VDDCR_CPU0_B22 @T6G_MB_LIB.T6G(SCH_1):PVDDCR_CPU0_P1
 B20 PVDDCR_CPU0_P1 VDDCR_CPU0_B20 @T6G_MB_LIB.T6G(SCH_1):PVDDCR_CPU0_P1
 B19 PVDDCR_CPU0_P1 VDDCR_CPU0_B19 @T6G_MB_LIB.T6G(SCH_1):PVDDCR_CPU0_P1
AT47 PVDDCR_CPU0_P1 VDDCR_CPU0_AT47 @T6G_MB_LIB.T6G(SCH_1):PVDDCR_CPU0_P1
AT45 PVDDCR_CPU0_P1 VDDCR_CPU0_AT45 @T6G_MB_LIB.T6G(SCH_1):PVDDCR_CPU0_P1
AT43 PVDDCR_CPU0_P1 VDDCR_CPU0_AT43 @T6G_MB_LIB.T6G(SCH_1):PVDDCR_CPU0_P1
AT41 PVDDCR_CPU0_P1 VDDCR_CPU0_AT41 @T6G_MB_LIB.T6G(SCH_1):PVDDCR_CPU0_P1
AT39 PVDDCR_CPU0_P1 VDDCR_CPU0_AT39 @T6G_MB_LIB.T6G(SCH_1):PVDDCR_CPU0_P1
AT36 PVDDCR_CPU0_P1 VDDCR_CPU0_AT36 @T6G_MB_LIB.T6G(SCH_1):PVDDCR_CPU0_P1
AT34 PVDDCR_CPU0_P1 VDDCR_CPU0_AT34 @T6G_MB_LIB.T6G(SCH_1):PVDDCR_CPU0_P1
AT32 PVDDCR_CPU0_P1 VDDCR_CPU0_AT32 @T6G_MB_LIB.T6G(SCH_1):PVDDCR_CPU0_P1
AT30 PVDDCR_CPU0_P1 VDDCR_CPU0_AT30 @T6G_MB_LIB.T6G(SCH_1):PVDDCR_CPU0_P1
AT28 PVDDCR_CPU0_P1 VDDCR_CPU0_AT28 @T6G_MB_LIB.T6G(SCH_1):PVDDCR_CPU0_P1
AT26 PVDDCR_CPU0_P1 VDDCR_CPU0_AT26 @T6G_MB_LIB.T6G(SCH_1):PVDDCR_CPU0_P1
AT24 PVDDCR_CPU0_P1 VDDCR_CPU0_AT24 @T6G_MB_LIB.T6G(SCH_1):PVDDCR_CPU0_P1
AR50 PVDDCR_CPU0_P1 VDDCR_CPU0_AR50 @T6G_MB_LIB.T6G(SCH_1):PVDDCR_CPU0_P1
AR48 PVDDCR_CPU0_P1 VDDCR_CPU0_AR48 @T6G_MB_LIB.T6G(SCH_1):PVDDCR_CPU0_P1
AR46 PVDDCR_CPU0_P1 VDDCR_CPU0_AR46 @T6G_MB_LIB.T6G(SCH_1):PVDDCR_CPU0_P1
AR44 PVDDCR_CPU0_P1 VDDCR_CPU0_AR44 @T6G_MB_LIB.T6G(SCH_1):PVDDCR_CPU0_P1
AR42 PVDDCR_CPU0_P1 VDDCR_CPU0_AR42 @T6G_MB_LIB.T6G(SCH_1):PVDDCR_CPU0_P1
AR40 PVDDCR_CPU0_P1 VDDCR_CPU0_AR40 @T6G_MB_LIB.T6G(SCH_1):PVDDCR_CPU0_P1
AR35 PVDDCR_CPU0_P1 VDDCR_CPU0_AR35 @T6G_MB_LIB.T6G(SCH_1):PVDDCR_CPU0_P1
AR33 PVDDCR_CPU0_P1 VDDCR_CPU0_AR33 @T6G_MB_LIB.T6G(SCH_1):PVDDCR_CPU0_P1
AR31 PVDDCR_CPU0_P1 VDDCR_CPU0_AR31 @T6G_MB_LIB.T6G(SCH_1):PVDDCR_CPU0_P1
AR29 PVDDCR_CPU0_P1 VDDCR_CPU0_AR29 @T6G_MB_LIB.T6G(SCH_1):PVDDCR_CPU0_P1
AR27 PVDDCR_CPU0_P1 VDDCR_CPU0_AR27 @T6G_MB_LIB.T6G(SCH_1):PVDDCR_CPU0_P1
AR25 PVDDCR_CPU0_P1 VDDCR_CPU0_AR25 @T6G_MB_LIB.T6G(SCH_1):PVDDCR_CPU0_P1
AR23 PVDDCR_CPU0_P1 VDDCR_CPU0_AR23 @T6G_MB_LIB.T6G(SCH_1):PVDDCR_CPU0_P1
AP53 PVDDCR_CPU0_P1 VDDCR_CPU0_AP53 @T6G_MB_LIB.T6G(SCH_1):PVDDCR_CPU0_P1
AP52 PVDDCR_CPU0_P1 VDDCR_CPU0_AP52 @T6G_MB_LIB.T6G(SCH_1):PVDDCR_CPU0_P1
AP50 PVDDCR_CPU0_P1 VDDCR_CPU0_AP50 @T6G_MB_LIB.T6G(SCH_1):PVDDCR_CPU0_P1
AP49 PVDDCR_CPU0_P1 VDDCR_CPU0_AP49 @T6G_MB_LIB.T6G(SCH_1):PVDDCR_CPU0_P1
AP47 PVDDCR_CPU0_P1 VDDCR_CPU0_AP47 @T6G_MB_LIB.T6G(SCH_1):PVDDCR_CPU0_P1
AP46 PVDDCR_CPU0_P1 VDDCR_CPU0_AP46 @T6G_MB_LIB.T6G(SCH_1):PVDDCR_CPU0_P1
AP44 PVDDCR_CPU0_P1 VDDCR_CPU0_AP44 @T6G_MB_LIB.T6G(SCH_1):PVDDCR_CPU0_P1
AP43 PVDDCR_CPU0_P1 VDDCR_CPU0_AP43 @T6G_MB_LIB.T6G(SCH_1):PVDDCR_CPU0_P1
AP33 PVDDCR_CPU0_P1 VDDCR_CPU0_AP33 @T6G_MB_LIB.T6G(SCH_1):PVDDCR_CPU0_P1
AP32 PVDDCR_CPU0_P1 VDDCR_CPU0_AP32 @T6G_MB_LIB.T6G(SCH_1):PVDDCR_CPU0_P1
AP30 PVDDCR_CPU0_P1 VDDCR_CPU0_AP30 @T6G_MB_LIB.T6G(SCH_1):PVDDCR_CPU0_P1
AP29 PVDDCR_CPU0_P1 VDDCR_CPU0_AP29 @T6G_MB_LIB.T6G(SCH_1):PVDDCR_CPU0_P1
AP27 PVDDCR_CPU0_P1 VDDCR_CPU0_AP27 @T6G_MB_LIB.T6G(SCH_1):PVDDCR_CPU0_P1
AP26 PVDDCR_CPU0_P1 VDDCR_CPU0_AP26 @T6G_MB_LIB.T6G(SCH_1):PVDDCR_CPU0_P1
AP24 PVDDCR_CPU0_P1 VDDCR_CPU0_AP24 @T6G_MB_LIB.T6G(SCH_1):PVDDCR_CPU0_P1
AP23 PVDDCR_CPU0_P1 VDDCR_CPU0_AP23 @T6G_MB_LIB.T6G(SCH_1):PVDDCR_CPU0_P1
AL41 PVDDCR_CPU0_P1 VDDCR_CPU0_AL41 @T6G_MB_LIB.T6G(SCH_1):PVDDCR_CPU0_P1
AL40 PVDDCR_CPU0_P1 VDDCR_CPU0_AL40 @T6G_MB_LIB.T6G(SCH_1):PVDDCR_CPU0_P1
AL36 PVDDCR_CPU0_P1 VDDCR_CPU0_AL36 @T6G_MB_LIB.T6G(SCH_1):PVDDCR_CPU0_P1
AL35 PVDDCR_CPU0_P1 VDDCR_CPU0_AL35 @T6G_MB_LIB.T6G(SCH_1):PVDDCR_CPU0_P1
AK53 PVDDCR_CPU0_P1 VDDCR_CPU0_AK53 @T6G_MB_LIB.T6G(SCH_1):PVDDCR_CPU0_P1
AK52 PVDDCR_CPU0_P1 VDDCR_CPU0_AK52 @T6G_MB_LIB.T6G(SCH_1):PVDDCR_CPU0_P1
AK50 PVDDCR_CPU0_P1 VDDCR_CPU0_AK50 @T6G_MB_LIB.T6G(SCH_1):PVDDCR_CPU0_P1
AK49 PVDDCR_CPU0_P1 VDDCR_CPU0_AK49 @T6G_MB_LIB.T6G(SCH_1):PVDDCR_CPU0_P1
AK47 PVDDCR_CPU0_P1 VDDCR_CPU0_AK47 @T6G_MB_LIB.T6G(SCH_1):PVDDCR_CPU0_P1
AK46 PVDDCR_CPU0_P1 VDDCR_CPU0_AK46 @T6G_MB_LIB.T6G(SCH_1):PVDDCR_CPU0_P1
AK44 PVDDCR_CPU0_P1 VDDCR_CPU0_AK44 @T6G_MB_LIB.T6G(SCH_1):PVDDCR_CPU0_P1
AK43 PVDDCR_CPU0_P1 VDDCR_CPU0_AK43 @T6G_MB_LIB.T6G(SCH_1):PVDDCR_CPU0_P1
AK33 PVDDCR_CPU0_P1 VDDCR_CPU0_AK33 @T6G_MB_LIB.T6G(SCH_1):PVDDCR_CPU0_P1
AK32 PVDDCR_CPU0_P1 VDDCR_CPU0_AK32 @T6G_MB_LIB.T6G(SCH_1):PVDDCR_CPU0_P1
AK30 PVDDCR_CPU0_P1 VDDCR_CPU0_AK30 @T6G_MB_LIB.T6G(SCH_1):PVDDCR_CPU0_P1
AK29 PVDDCR_CPU0_P1 VDDCR_CPU0_AK29 @T6G_MB_LIB.T6G(SCH_1):PVDDCR_CPU0_P1
AK27 PVDDCR_CPU0_P1 VDDCR_CPU0_AK27 @T6G_MB_LIB.T6G(SCH_1):PVDDCR_CPU0_P1
AK26 PVDDCR_CPU0_P1 VDDCR_CPU0_AK26 @T6G_MB_LIB.T6G(SCH_1):PVDDCR_CPU0_P1
AK24 PVDDCR_CPU0_P1 VDDCR_CPU0_AK24 @T6G_MB_LIB.T6G(SCH_1):PVDDCR_CPU0_P1
AK23 PVDDCR_CPU0_P1 VDDCR_CPU0_AK23 @T6G_MB_LIB.T6G(SCH_1):PVDDCR_CPU0_P1
AG41 PVDDCR_CPU0_P1 VDDCR_CPU0_AG41 @T6G_MB_LIB.T6G(SCH_1):PVDDCR_CPU0_P1
AG40 PVDDCR_CPU0_P1 VDDCR_CPU0_AG40 @T6G_MB_LIB.T6G(SCH_1):PVDDCR_CPU0_P1
AG36 PVDDCR_CPU0_P1 VDDCR_CPU0_AG36 @T6G_MB_LIB.T6G(SCH_1):PVDDCR_CPU0_P1
AG35 PVDDCR_CPU0_P1 VDDCR_CPU0_AG35 @T6G_MB_LIB.T6G(SCH_1):PVDDCR_CPU0_P1
AF53 PVDDCR_CPU0_P1 VDDCR_CPU0_AF53 @T6G_MB_LIB.T6G(SCH_1):PVDDCR_CPU0_P1
AF52 PVDDCR_CPU0_P1 VDDCR_CPU0_AF52 @T6G_MB_LIB.T6G(SCH_1):PVDDCR_CPU0_P1
AF50 PVDDCR_CPU0_P1 VDDCR_CPU0_AF50 @T6G_MB_LIB.T6G(SCH_1):PVDDCR_CPU0_P1
AF49 PVDDCR_CPU0_P1 VDDCR_CPU0_AF49 @T6G_MB_LIB.T6G(SCH_1):PVDDCR_CPU0_P1
AF47 PVDDCR_CPU0_P1 VDDCR_CPU0_AF47 @T6G_MB_LIB.T6G(SCH_1):PVDDCR_CPU0_P1
AF46 PVDDCR_CPU0_P1 VDDCR_CPU0_AF46 @T6G_MB_LIB.T6G(SCH_1):PVDDCR_CPU0_P1
AF44 PVDDCR_CPU0_P1 VDDCR_CPU0_AF44 @T6G_MB_LIB.T6G(SCH_1):PVDDCR_CPU0_P1
AF43 PVDDCR_CPU0_P1 VDDCR_CPU0_AF43 @T6G_MB_LIB.T6G(SCH_1):PVDDCR_CPU0_P1
AF33 PVDDCR_CPU0_P1 VDDCR_CPU0_AF33 @T6G_MB_LIB.T6G(SCH_1):PVDDCR_CPU0_P1
AF32 PVDDCR_CPU0_P1 VDDCR_CPU0_AF32 @T6G_MB_LIB.T6G(SCH_1):PVDDCR_CPU0_P1
AF30 PVDDCR_CPU0_P1 VDDCR_CPU0_AF30 @T6G_MB_LIB.T6G(SCH_1):PVDDCR_CPU0_P1
AF29 PVDDCR_CPU0_P1 VDDCR_CPU0_AF29 @T6G_MB_LIB.T6G(SCH_1):PVDDCR_CPU0_P1
AF27 PVDDCR_CPU0_P1 VDDCR_CPU0_AF27 @T6G_MB_LIB.T6G(SCH_1):PVDDCR_CPU0_P1
AF26 PVDDCR_CPU0_P1 VDDCR_CPU0_AF26 @T6G_MB_LIB.T6G(SCH_1):PVDDCR_CPU0_P1
AF24 PVDDCR_CPU0_P1 VDDCR_CPU0_AF24 @T6G_MB_LIB.T6G(SCH_1):PVDDCR_CPU0_P1
AF23 PVDDCR_CPU0_P1 VDDCR_CPU0_AF23 @T6G_MB_LIB.T6G(SCH_1):PVDDCR_CPU0_P1
AC41 PVDDCR_CPU0_P1 VDDCR_CPU0_AC41 @T6G_MB_LIB.T6G(SCH_1):PVDDCR_CPU0_P1
AC40 PVDDCR_CPU0_P1 VDDCR_CPU0_AC40 @T6G_MB_LIB.T6G(SCH_1):PVDDCR_CPU0_P1
AC36 PVDDCR_CPU0_P1 VDDCR_CPU0_AC36 @T6G_MB_LIB.T6G(SCH_1):PVDDCR_CPU0_P1
AC35 PVDDCR_CPU0_P1 VDDCR_CPU0_AC35 @T6G_MB_LIB.T6G(SCH_1):PVDDCR_CPU0_P1
AB53 PVDDCR_CPU0_P1 VDDCR_CPU0_AB53 @T6G_MB_LIB.T6G(SCH_1):PVDDCR_CPU0_P1
AB52 PVDDCR_CPU0_P1 VDDCR_CPU0_AB52 @T6G_MB_LIB.T6G(SCH_1):PVDDCR_CPU0_P1
AB50 PVDDCR_CPU0_P1 VDDCR_CPU0_AB50 @T6G_MB_LIB.T6G(SCH_1):PVDDCR_CPU0_P1
AB49 PVDDCR_CPU0_P1 VDDCR_CPU0_AB49 @T6G_MB_LIB.T6G(SCH_1):PVDDCR_CPU0_P1
AB47 PVDDCR_CPU0_P1 VDDCR_CPU0_AB47 @T6G_MB_LIB.T6G(SCH_1):PVDDCR_CPU0_P1
AB46 PVDDCR_CPU0_P1 VDDCR_CPU0_AB46 @T6G_MB_LIB.T6G(SCH_1):PVDDCR_CPU0_P1
AB44 PVDDCR_CPU0_P1 VDDCR_CPU0_AB44 @T6G_MB_LIB.T6G(SCH_1):PVDDCR_CPU0_P1
AB43 PVDDCR_CPU0_P1 VDDCR_CPU0_AB43 @T6G_MB_LIB.T6G(SCH_1):PVDDCR_CPU0_P1
AB33 PVDDCR_CPU0_P1 VDDCR_CPU0_AB33 @T6G_MB_LIB.T6G(SCH_1):PVDDCR_CPU0_P1
AB32 PVDDCR_CPU0_P1 VDDCR_CPU0_AB32 @T6G_MB_LIB.T6G(SCH_1):PVDDCR_CPU0_P1
AB30 PVDDCR_CPU0_P1 VDDCR_CPU0_AB30 @T6G_MB_LIB.T6G(SCH_1):PVDDCR_CPU0_P1
AB29 PVDDCR_CPU0_P1 VDDCR_CPU0_AB29 @T6G_MB_LIB.T6G(SCH_1):PVDDCR_CPU0_P1
AB27 PVDDCR_CPU0_P1 VDDCR_CPU0_AB27 @T6G_MB_LIB.T6G(SCH_1):PVDDCR_CPU0_P1
AB26 PVDDCR_CPU0_P1 VDDCR_CPU0_AB26 @T6G_MB_LIB.T6G(SCH_1):PVDDCR_CPU0_P1
AB24 PVDDCR_CPU0_P1 VDDCR_CPU0_AB24 @T6G_MB_LIB.T6G(SCH_1):PVDDCR_CPU0_P1
AB23 PVDDCR_CPU0_P1 VDDCR_CPU0_AB23 @T6G_MB_LIB.T6G(SCH_1):PVDDCR_CPU0_P1
 Y41 PVDDCR_CPU0_P1 VDDCR_CPU0_Y41 @T6G_MB_LIB.T6G(SCH_1):PVDDCR_CPU0_P1
 Y40 PVDDCR_CPU0_P1 VDDCR_CPU0_Y40 @T6G_MB_LIB.T6G(SCH_1):PVDDCR_CPU0_P1
 Y36 PVDDCR_CPU0_P1 VDDCR_CPU0_Y36 @T6G_MB_LIB.T6G(SCH_1):PVDDCR_CPU0_P1
 Y35 PVDDCR_CPU0_P1 VDDCR_CPU0_Y35 @T6G_MB_LIB.T6G(SCH_1):PVDDCR_CPU0_P1
AU42 PVDDCR_CPU0_P1 VDDCR_CPU0_AU42 @T6G_MB_LIB.T6G(SCH_1):PVDDCR_CPU0_P1
AU46 PVDDCR_CPU0_P1 VDDCR_CPU0_AU46 @T6G_MB_LIB.T6G(SCH_1):PVDDCR_CPU0_P1
AT49 PVDDCR_CPU0_P1 VDDCR_CPU0_AT49 @T6G_MB_LIB.T6G(SCH_1):PVDDCR_CPU0_P1
AU29 PVDDCR_CPU0_P1 VDDCR_CPU0_AU29 @T6G_MB_LIB.T6G(SCH_1):PVDDCR_CPU0_P1
AU44 PVDDCR_CPU0_P1 VDDCR_CPU0_AU44 @T6G_MB_LIB.T6G(SCH_1):PVDDCR_CPU0_P1
AU48 PVDDCR_CPU0_P1 VDDCR_CPU0_AU48 @T6G_MB_LIB.T6G(SCH_1):PVDDCR_CPU0_P1
AU25 PVDDCR_CPU0_P1 VDDCR_CPU0_AU25 @T6G_MB_LIB.T6G(SCH_1):PVDDCR_CPU0_P1
AU33 PVDDCR_CPU0_P1 VDDCR_CPU0_AU33 @T6G_MB_LIB.T6G(SCH_1):PVDDCR_CPU0_P1

GENOA_SP5-SOCKET6096_13568-001,SMLF,IO,DGA^6000030  I32  U26
BN31 PVDDCR_CPU1_P1 VDDCR_CPU1_BN31 @T6G_MB_LIB.T6G(SCH_1):PVDDCR_CPU1_P1
BN42 PVDDCR_CPU1_P1 VDDCR_CPU1_BN42 @T6G_MB_LIB.T6G(SCH_1):PVDDCR_CPU1_P1
BN50 PVDDCR_CPU1_P1 VDDCR_CPU1_BN50 @T6G_MB_LIB.T6G(SCH_1):PVDDCR_CPU1_P1
BP26 PVDDCR_CPU1_P1 VDDCR_CPU1_BP26 @T6G_MB_LIB.T6G(SCH_1):PVDDCR_CPU1_P1
BP30 PVDDCR_CPU1_P1 VDDCR_CPU1_BP30 @T6G_MB_LIB.T6G(SCH_1):PVDDCR_CPU1_P1
BP34 PVDDCR_CPU1_P1 VDDCR_CPU1_BP34 @T6G_MB_LIB.T6G(SCH_1):PVDDCR_CPU1_P1
BP36 PVDDCR_CPU1_P1 VDDCR_CPU1_BP36 @T6G_MB_LIB.T6G(SCH_1):PVDDCR_CPU1_P1
BP39 PVDDCR_CPU1_P1 VDDCR_CPU1_BP39 @T6G_MB_LIB.T6G(SCH_1):PVDDCR_CPU1_P1
BP41 PVDDCR_CPU1_P1 VDDCR_CPU1_BP41 @T6G_MB_LIB.T6G(SCH_1):PVDDCR_CPU1_P1
BP43 PVDDCR_CPU1_P1 VDDCR_CPU1_BP43 @T6G_MB_LIB.T6G(SCH_1):PVDDCR_CPU1_P1
BP45 PVDDCR_CPU1_P1 VDDCR_CPU1_BP45 @T6G_MB_LIB.T6G(SCH_1):PVDDCR_CPU1_P1
BP47 PVDDCR_CPU1_P1 VDDCR_CPU1_BP47 @T6G_MB_LIB.T6G(SCH_1):PVDDCR_CPU1_P1
BP49 PVDDCR_CPU1_P1 VDDCR_CPU1_BP49 @T6G_MB_LIB.T6G(SCH_1):PVDDCR_CPU1_P1
BR23 PVDDCR_CPU1_P1 VDDCR_CPU1_BR23 @T6G_MB_LIB.T6G(SCH_1):PVDDCR_CPU1_P1
BR25 PVDDCR_CPU1_P1 VDDCR_CPU1_BR25 @T6G_MB_LIB.T6G(SCH_1):PVDDCR_CPU1_P1
BR27 PVDDCR_CPU1_P1 VDDCR_CPU1_BR27 @T6G_MB_LIB.T6G(SCH_1):PVDDCR_CPU1_P1
BR29 PVDDCR_CPU1_P1 VDDCR_CPU1_BR29 @T6G_MB_LIB.T6G(SCH_1):PVDDCR_CPU1_P1
BR31 PVDDCR_CPU1_P1 VDDCR_CPU1_BR31 @T6G_MB_LIB.T6G(SCH_1):PVDDCR_CPU1_P1
BR33 PVDDCR_CPU1_P1 VDDCR_CPU1_BR33 @T6G_MB_LIB.T6G(SCH_1):PVDDCR_CPU1_P1
BR35 PVDDCR_CPU1_P1 VDDCR_CPU1_BR35 @T6G_MB_LIB.T6G(SCH_1):PVDDCR_CPU1_P1
BR40 PVDDCR_CPU1_P1 VDDCR_CPU1_BR40 @T6G_MB_LIB.T6G(SCH_1):PVDDCR_CPU1_P1
BR42 PVDDCR_CPU1_P1 VDDCR_CPU1_BR42 @T6G_MB_LIB.T6G(SCH_1):PVDDCR_CPU1_P1
BR44 PVDDCR_CPU1_P1 VDDCR_CPU1_BR44 @T6G_MB_LIB.T6G(SCH_1):PVDDCR_CPU1_P1
BR46 PVDDCR_CPU1_P1 VDDCR_CPU1_BR46 @T6G_MB_LIB.T6G(SCH_1):PVDDCR_CPU1_P1
BR48 PVDDCR_CPU1_P1 VDDCR_CPU1_BR48 @T6G_MB_LIB.T6G(SCH_1):PVDDCR_CPU1_P1
BR50 PVDDCR_CPU1_P1 VDDCR_CPU1_BR50 @T6G_MB_LIB.T6G(SCH_1):PVDDCR_CPU1_P1
BR52 PVDDCR_CPU1_P1 VDDCR_CPU1_BR52 @T6G_MB_LIB.T6G(SCH_1):PVDDCR_CPU1_P1
BT23 PVDDCR_CPU1_P1 VDDCR_CPU1_BT23 @T6G_MB_LIB.T6G(SCH_1):PVDDCR_CPU1_P1
BT24 PVDDCR_CPU1_P1 VDDCR_CPU1_BT24 @T6G_MB_LIB.T6G(SCH_1):PVDDCR_CPU1_P1
BT26 PVDDCR_CPU1_P1 VDDCR_CPU1_BT26 @T6G_MB_LIB.T6G(SCH_1):PVDDCR_CPU1_P1
BT27 PVDDCR_CPU1_P1 VDDCR_CPU1_BT27 @T6G_MB_LIB.T6G(SCH_1):PVDDCR_CPU1_P1
BT29 PVDDCR_CPU1_P1 VDDCR_CPU1_BT29 @T6G_MB_LIB.T6G(SCH_1):PVDDCR_CPU1_P1
BT30 PVDDCR_CPU1_P1 VDDCR_CPU1_BT30 @T6G_MB_LIB.T6G(SCH_1):PVDDCR_CPU1_P1
BT32 PVDDCR_CPU1_P1 VDDCR_CPU1_BT32 @T6G_MB_LIB.T6G(SCH_1):PVDDCR_CPU1_P1
BT33 PVDDCR_CPU1_P1 VDDCR_CPU1_BT33 @T6G_MB_LIB.T6G(SCH_1):PVDDCR_CPU1_P1
BT43 PVDDCR_CPU1_P1 VDDCR_CPU1_BT43 @T6G_MB_LIB.T6G(SCH_1):PVDDCR_CPU1_P1
BT44 PVDDCR_CPU1_P1 VDDCR_CPU1_BT44 @T6G_MB_LIB.T6G(SCH_1):PVDDCR_CPU1_P1
BT46 PVDDCR_CPU1_P1 VDDCR_CPU1_BT46 @T6G_MB_LIB.T6G(SCH_1):PVDDCR_CPU1_P1
BT47 PVDDCR_CPU1_P1 VDDCR_CPU1_BT47 @T6G_MB_LIB.T6G(SCH_1):PVDDCR_CPU1_P1
BT49 PVDDCR_CPU1_P1 VDDCR_CPU1_BT49 @T6G_MB_LIB.T6G(SCH_1):PVDDCR_CPU1_P1
BT50 PVDDCR_CPU1_P1 VDDCR_CPU1_BT50 @T6G_MB_LIB.T6G(SCH_1):PVDDCR_CPU1_P1
BT52 PVDDCR_CPU1_P1 VDDCR_CPU1_BT52 @T6G_MB_LIB.T6G(SCH_1):PVDDCR_CPU1_P1
BT53 PVDDCR_CPU1_P1 VDDCR_CPU1_BT53 @T6G_MB_LIB.T6G(SCH_1):PVDDCR_CPU1_P1
BW35 PVDDCR_CPU1_P1 VDDCR_CPU1_BW35 @T6G_MB_LIB.T6G(SCH_1):PVDDCR_CPU1_P1
BW36 PVDDCR_CPU1_P1 VDDCR_CPU1_BW36 @T6G_MB_LIB.T6G(SCH_1):PVDDCR_CPU1_P1
BW40 PVDDCR_CPU1_P1 VDDCR_CPU1_BW40 @T6G_MB_LIB.T6G(SCH_1):PVDDCR_CPU1_P1
BW41 PVDDCR_CPU1_P1 VDDCR_CPU1_BW41 @T6G_MB_LIB.T6G(SCH_1):PVDDCR_CPU1_P1
BY23 PVDDCR_CPU1_P1 VDDCR_CPU1_BY23 @T6G_MB_LIB.T6G(SCH_1):PVDDCR_CPU1_P1
BY24 PVDDCR_CPU1_P1 VDDCR_CPU1_BY24 @T6G_MB_LIB.T6G(SCH_1):PVDDCR_CPU1_P1
BY26 PVDDCR_CPU1_P1 VDDCR_CPU1_BY26 @T6G_MB_LIB.T6G(SCH_1):PVDDCR_CPU1_P1
BY27 PVDDCR_CPU1_P1 VDDCR_CPU1_BY27 @T6G_MB_LIB.T6G(SCH_1):PVDDCR_CPU1_P1
BY29 PVDDCR_CPU1_P1 VDDCR_CPU1_BY29 @T6G_MB_LIB.T6G(SCH_1):PVDDCR_CPU1_P1
BY30 PVDDCR_CPU1_P1 VDDCR_CPU1_BY30 @T6G_MB_LIB.T6G(SCH_1):PVDDCR_CPU1_P1
BY32 PVDDCR_CPU1_P1 VDDCR_CPU1_BY32 @T6G_MB_LIB.T6G(SCH_1):PVDDCR_CPU1_P1
BY33 PVDDCR_CPU1_P1 VDDCR_CPU1_BY33 @T6G_MB_LIB.T6G(SCH_1):PVDDCR_CPU1_P1
BY43 PVDDCR_CPU1_P1 VDDCR_CPU1_BY43 @T6G_MB_LIB.T6G(SCH_1):PVDDCR_CPU1_P1
BY44 PVDDCR_CPU1_P1 VDDCR_CPU1_BY44 @T6G_MB_LIB.T6G(SCH_1):PVDDCR_CPU1_P1
BY46 PVDDCR_CPU1_P1 VDDCR_CPU1_BY46 @T6G_MB_LIB.T6G(SCH_1):PVDDCR_CPU1_P1
BY47 PVDDCR_CPU1_P1 VDDCR_CPU1_BY47 @T6G_MB_LIB.T6G(SCH_1):PVDDCR_CPU1_P1
BY49 PVDDCR_CPU1_P1 VDDCR_CPU1_BY49 @T6G_MB_LIB.T6G(SCH_1):PVDDCR_CPU1_P1
BY50 PVDDCR_CPU1_P1 VDDCR_CPU1_BY50 @T6G_MB_LIB.T6G(SCH_1):PVDDCR_CPU1_P1
BY52 PVDDCR_CPU1_P1 VDDCR_CPU1_BY52 @T6G_MB_LIB.T6G(SCH_1):PVDDCR_CPU1_P1
BY53 PVDDCR_CPU1_P1 VDDCR_CPU1_BY53 @T6G_MB_LIB.T6G(SCH_1):PVDDCR_CPU1_P1
CC35 PVDDCR_CPU1_P1 VDDCR_CPU1_CC35 @T6G_MB_LIB.T6G(SCH_1):PVDDCR_CPU1_P1
CC36 PVDDCR_CPU1_P1 VDDCR_CPU1_CC36 @T6G_MB_LIB.T6G(SCH_1):PVDDCR_CPU1_P1
CC40 PVDDCR_CPU1_P1 VDDCR_CPU1_CC40 @T6G_MB_LIB.T6G(SCH_1):PVDDCR_CPU1_P1
CC41 PVDDCR_CPU1_P1 VDDCR_CPU1_CC41 @T6G_MB_LIB.T6G(SCH_1):PVDDCR_CPU1_P1
CD23 PVDDCR_CPU1_P1 VDDCR_CPU1_CD23 @T6G_MB_LIB.T6G(SCH_1):PVDDCR_CPU1_P1
CD24 PVDDCR_CPU1_P1 VDDCR_CPU1_CD24 @T6G_MB_LIB.T6G(SCH_1):PVDDCR_CPU1_P1
CD26 PVDDCR_CPU1_P1 VDDCR_CPU1_CD26 @T6G_MB_LIB.T6G(SCH_1):PVDDCR_CPU1_P1
CD27 PVDDCR_CPU1_P1 VDDCR_CPU1_CD27 @T6G_MB_LIB.T6G(SCH_1):PVDDCR_CPU1_P1
CD29 PVDDCR_CPU1_P1 VDDCR_CPU1_CD29 @T6G_MB_LIB.T6G(SCH_1):PVDDCR_CPU1_P1
CD30 PVDDCR_CPU1_P1 VDDCR_CPU1_CD30 @T6G_MB_LIB.T6G(SCH_1):PVDDCR_CPU1_P1
CD32 PVDDCR_CPU1_P1 VDDCR_CPU1_CD32 @T6G_MB_LIB.T6G(SCH_1):PVDDCR_CPU1_P1
CD33 PVDDCR_CPU1_P1 VDDCR_CPU1_CD33 @T6G_MB_LIB.T6G(SCH_1):PVDDCR_CPU1_P1
CD43 PVDDCR_CPU1_P1 VDDCR_CPU1_CD43 @T6G_MB_LIB.T6G(SCH_1):PVDDCR_CPU1_P1
CD44 PVDDCR_CPU1_P1 VDDCR_CPU1_CD44 @T6G_MB_LIB.T6G(SCH_1):PVDDCR_CPU1_P1
CD46 PVDDCR_CPU1_P1 VDDCR_CPU1_CD46 @T6G_MB_LIB.T6G(SCH_1):PVDDCR_CPU1_P1
CD47 PVDDCR_CPU1_P1 VDDCR_CPU1_CD47 @T6G_MB_LIB.T6G(SCH_1):PVDDCR_CPU1_P1
CD49 PVDDCR_CPU1_P1 VDDCR_CPU1_CD49 @T6G_MB_LIB.T6G(SCH_1):PVDDCR_CPU1_P1
CD50 PVDDCR_CPU1_P1 VDDCR_CPU1_CD50 @T6G_MB_LIB.T6G(SCH_1):PVDDCR_CPU1_P1
CD52 PVDDCR_CPU1_P1 VDDCR_CPU1_CD52 @T6G_MB_LIB.T6G(SCH_1):PVDDCR_CPU1_P1
CD53 PVDDCR_CPU1_P1 VDDCR_CPU1_CD53 @T6G_MB_LIB.T6G(SCH_1):PVDDCR_CPU1_P1
CG35 PVDDCR_CPU1_P1 VDDCR_CPU1_CG35 @T6G_MB_LIB.T6G(SCH_1):PVDDCR_CPU1_P1
CG36 PVDDCR_CPU1_P1 VDDCR_CPU1_CG36 @T6G_MB_LIB.T6G(SCH_1):PVDDCR_CPU1_P1
CG40 PVDDCR_CPU1_P1 VDDCR_CPU1_CG40 @T6G_MB_LIB.T6G(SCH_1):PVDDCR_CPU1_P1
CG41 PVDDCR_CPU1_P1 VDDCR_CPU1_CG41 @T6G_MB_LIB.T6G(SCH_1):PVDDCR_CPU1_P1
CH23 PVDDCR_CPU1_P1 VDDCR_CPU1_CH23 @T6G_MB_LIB.T6G(SCH_1):PVDDCR_CPU1_P1
CH24 PVDDCR_CPU1_P1 VDDCR_CPU1_CH24 @T6G_MB_LIB.T6G(SCH_1):PVDDCR_CPU1_P1
CH26 PVDDCR_CPU1_P1 VDDCR_CPU1_CH26 @T6G_MB_LIB.T6G(SCH_1):PVDDCR_CPU1_P1
CH27 PVDDCR_CPU1_P1 VDDCR_CPU1_CH27 @T6G_MB_LIB.T6G(SCH_1):PVDDCR_CPU1_P1
CH29 PVDDCR_CPU1_P1 VDDCR_CPU1_CH29 @T6G_MB_LIB.T6G(SCH_1):PVDDCR_CPU1_P1
CH30 PVDDCR_CPU1_P1 VDDCR_CPU1_CH30 @T6G_MB_LIB.T6G(SCH_1):PVDDCR_CPU1_P1
CH32 PVDDCR_CPU1_P1 VDDCR_CPU1_CH32 @T6G_MB_LIB.T6G(SCH_1):PVDDCR_CPU1_P1
CH33 PVDDCR_CPU1_P1 VDDCR_CPU1_CH33 @T6G_MB_LIB.T6G(SCH_1):PVDDCR_CPU1_P1
CH43 PVDDCR_CPU1_P1 VDDCR_CPU1_CH43 @T6G_MB_LIB.T6G(SCH_1):PVDDCR_CPU1_P1
CH44 PVDDCR_CPU1_P1 VDDCR_CPU1_CH44 @T6G_MB_LIB.T6G(SCH_1):PVDDCR_CPU1_P1
CH46 PVDDCR_CPU1_P1 VDDCR_CPU1_CH46 @T6G_MB_LIB.T6G(SCH_1):PVDDCR_CPU1_P1
CH47 PVDDCR_CPU1_P1 VDDCR_CPU1_CH47 @T6G_MB_LIB.T6G(SCH_1):PVDDCR_CPU1_P1
CH49 PVDDCR_CPU1_P1 VDDCR_CPU1_CH49 @T6G_MB_LIB.T6G(SCH_1):PVDDCR_CPU1_P1
CH50 PVDDCR_CPU1_P1 VDDCR_CPU1_CH50 @T6G_MB_LIB.T6G(SCH_1):PVDDCR_CPU1_P1
CH52 PVDDCR_CPU1_P1 VDDCR_CPU1_CH52 @T6G_MB_LIB.T6G(SCH_1):PVDDCR_CPU1_P1
CH53 PVDDCR_CPU1_P1 VDDCR_CPU1_CH53 @T6G_MB_LIB.T6G(SCH_1):PVDDCR_CPU1_P1
CK35 PVDDCR_CPU1_P1 VDDCR_CPU1_CK35 @T6G_MB_LIB.T6G(SCH_1):PVDDCR_CPU1_P1
CK36 PVDDCR_CPU1_P1 VDDCR_CPU1_CK36 @T6G_MB_LIB.T6G(SCH_1):PVDDCR_CPU1_P1
CK40 PVDDCR_CPU1_P1 VDDCR_CPU1_CK40 @T6G_MB_LIB.T6G(SCH_1):PVDDCR_CPU1_P1
CK41 PVDDCR_CPU1_P1 VDDCR_CPU1_CK41 @T6G_MB_LIB.T6G(SCH_1):PVDDCR_CPU1_P1
CL29 PVDDCR_CPU1_P1 VDDCR_CPU1_CL29 @T6G_MB_LIB.T6G(SCH_1):PVDDCR_CPU1_P1
CL30 PVDDCR_CPU1_P1 VDDCR_CPU1_CL30 @T6G_MB_LIB.T6G(SCH_1):PVDDCR_CPU1_P1
CL32 PVDDCR_CPU1_P1 VDDCR_CPU1_CL32 @T6G_MB_LIB.T6G(SCH_1):PVDDCR_CPU1_P1
CL33 PVDDCR_CPU1_P1 VDDCR_CPU1_CL33 @T6G_MB_LIB.T6G(SCH_1):PVDDCR_CPU1_P1
CL43 PVDDCR_CPU1_P1 VDDCR_CPU1_CL43 @T6G_MB_LIB.T6G(SCH_1):PVDDCR_CPU1_P1
CL44 PVDDCR_CPU1_P1 VDDCR_CPU1_CL44 @T6G_MB_LIB.T6G(SCH_1):PVDDCR_CPU1_P1
CL46 PVDDCR_CPU1_P1 VDDCR_CPU1_CL46 @T6G_MB_LIB.T6G(SCH_1):PVDDCR_CPU1_P1
CL47 PVDDCR_CPU1_P1 VDDCR_CPU1_CL47 @T6G_MB_LIB.T6G(SCH_1):PVDDCR_CPU1_P1
CN35 PVDDCR_CPU1_P1 VDDCR_CPU1_CN35 @T6G_MB_LIB.T6G(SCH_1):PVDDCR_CPU1_P1
CN36 PVDDCR_CPU1_P1 VDDCR_CPU1_CN36 @T6G_MB_LIB.T6G(SCH_1):PVDDCR_CPU1_P1
CN40 PVDDCR_CPU1_P1 VDDCR_CPU1_CN40 @T6G_MB_LIB.T6G(SCH_1):PVDDCR_CPU1_P1
CN41 PVDDCR_CPU1_P1 VDDCR_CPU1_CN41 @T6G_MB_LIB.T6G(SCH_1):PVDDCR_CPU1_P1
CP23 PVDDCR_CPU1_P1 VDDCR_CPU1_CP23 @T6G_MB_LIB.T6G(SCH_1):PVDDCR_CPU1_P1
CP24 PVDDCR_CPU1_P1 VDDCR_CPU1_CP24 @T6G_MB_LIB.T6G(SCH_1):PVDDCR_CPU1_P1
CP26 PVDDCR_CPU1_P1 VDDCR_CPU1_CP26 @T6G_MB_LIB.T6G(SCH_1):PVDDCR_CPU1_P1
CP27 PVDDCR_CPU1_P1 VDDCR_CPU1_CP27 @T6G_MB_LIB.T6G(SCH_1):PVDDCR_CPU1_P1
CP29 PVDDCR_CPU1_P1 VDDCR_CPU1_CP29 @T6G_MB_LIB.T6G(SCH_1):PVDDCR_CPU1_P1
CP30 PVDDCR_CPU1_P1 VDDCR_CPU1_CP30 @T6G_MB_LIB.T6G(SCH_1):PVDDCR_CPU1_P1
CP32 PVDDCR_CPU1_P1 VDDCR_CPU1_CP32 @T6G_MB_LIB.T6G(SCH_1):PVDDCR_CPU1_P1
CP33 PVDDCR_CPU1_P1 VDDCR_CPU1_CP33 @T6G_MB_LIB.T6G(SCH_1):PVDDCR_CPU1_P1
CP43 PVDDCR_CPU1_P1 VDDCR_CPU1_CP43 @T6G_MB_LIB.T6G(SCH_1):PVDDCR_CPU1_P1
CP44 PVDDCR_CPU1_P1 VDDCR_CPU1_CP44 @T6G_MB_LIB.T6G(SCH_1):PVDDCR_CPU1_P1
CP46 PVDDCR_CPU1_P1 VDDCR_CPU1_CP46 @T6G_MB_LIB.T6G(SCH_1):PVDDCR_CPU1_P1
CP47 PVDDCR_CPU1_P1 VDDCR_CPU1_CP47 @T6G_MB_LIB.T6G(SCH_1):PVDDCR_CPU1_P1
CP49 PVDDCR_CPU1_P1 VDDCR_CPU1_CP49 @T6G_MB_LIB.T6G(SCH_1):PVDDCR_CPU1_P1
CP50 PVDDCR_CPU1_P1 VDDCR_CPU1_CP50 @T6G_MB_LIB.T6G(SCH_1):PVDDCR_CPU1_P1
CP52 PVDDCR_CPU1_P1 VDDCR_CPU1_CP52 @T6G_MB_LIB.T6G(SCH_1):PVDDCR_CPU1_P1
CP53 PVDDCR_CPU1_P1 VDDCR_CPU1_CP53 @T6G_MB_LIB.T6G(SCH_1):PVDDCR_CPU1_P1
CU35 PVDDCR_CPU1_P1 VDDCR_CPU1_CU35 @T6G_MB_LIB.T6G(SCH_1):PVDDCR_CPU1_P1
CU36 PVDDCR_CPU1_P1 VDDCR_CPU1_CU36 @T6G_MB_LIB.T6G(SCH_1):PVDDCR_CPU1_P1
CU40 PVDDCR_CPU1_P1 VDDCR_CPU1_CU40 @T6G_MB_LIB.T6G(SCH_1):PVDDCR_CPU1_P1
CU41 PVDDCR_CPU1_P1 VDDCR_CPU1_CU41 @T6G_MB_LIB.T6G(SCH_1):PVDDCR_CPU1_P1
CV23 PVDDCR_CPU1_P1 VDDCR_CPU1_CV23 @T6G_MB_LIB.T6G(SCH_1):PVDDCR_CPU1_P1
CV24 PVDDCR_CPU1_P1 VDDCR_CPU1_CV24 @T6G_MB_LIB.T6G(SCH_1):PVDDCR_CPU1_P1
CV26 PVDDCR_CPU1_P1 VDDCR_CPU1_CV26 @T6G_MB_LIB.T6G(SCH_1):PVDDCR_CPU1_P1
CV27 PVDDCR_CPU1_P1 VDDCR_CPU1_CV27 @T6G_MB_LIB.T6G(SCH_1):PVDDCR_CPU1_P1
CV29 PVDDCR_CPU1_P1 VDDCR_CPU1_CV29 @T6G_MB_LIB.T6G(SCH_1):PVDDCR_CPU1_P1
CV30 PVDDCR_CPU1_P1 VDDCR_CPU1_CV30 @T6G_MB_LIB.T6G(SCH_1):PVDDCR_CPU1_P1
CV32 PVDDCR_CPU1_P1 VDDCR_CPU1_CV32 @T6G_MB_LIB.T6G(SCH_1):PVDDCR_CPU1_P1
CV33 PVDDCR_CPU1_P1 VDDCR_CPU1_CV33 @T6G_MB_LIB.T6G(SCH_1):PVDDCR_CPU1_P1
CV43 PVDDCR_CPU1_P1 VDDCR_CPU1_CV43 @T6G_MB_LIB.T6G(SCH_1):PVDDCR_CPU1_P1
CV44 PVDDCR_CPU1_P1 VDDCR_CPU1_CV44 @T6G_MB_LIB.T6G(SCH_1):PVDDCR_CPU1_P1
CV46 PVDDCR_CPU1_P1 VDDCR_CPU1_CV46 @T6G_MB_LIB.T6G(SCH_1):PVDDCR_CPU1_P1
CV47 PVDDCR_CPU1_P1 VDDCR_CPU1_CV47 @T6G_MB_LIB.T6G(SCH_1):PVDDCR_CPU1_P1
CV49 PVDDCR_CPU1_P1 VDDCR_CPU1_CV49 @T6G_MB_LIB.T6G(SCH_1):PVDDCR_CPU1_P1
CV50 PVDDCR_CPU1_P1 VDDCR_CPU1_CV50 @T6G_MB_LIB.T6G(SCH_1):PVDDCR_CPU1_P1
CV52 PVDDCR_CPU1_P1 VDDCR_CPU1_CV52 @T6G_MB_LIB.T6G(SCH_1):PVDDCR_CPU1_P1
CV53 PVDDCR_CPU1_P1 VDDCR_CPU1_CV53 @T6G_MB_LIB.T6G(SCH_1):PVDDCR_CPU1_P1
DA35 PVDDCR_CPU1_P1 VDDCR_CPU1_DA35 @T6G_MB_LIB.T6G(SCH_1):PVDDCR_CPU1_P1
DA36 PVDDCR_CPU1_P1 VDDCR_CPU1_DA36 @T6G_MB_LIB.T6G(SCH_1):PVDDCR_CPU1_P1
DA40 PVDDCR_CPU1_P1 VDDCR_CPU1_DA40 @T6G_MB_LIB.T6G(SCH_1):PVDDCR_CPU1_P1
DA41 PVDDCR_CPU1_P1 VDDCR_CPU1_DA41 @T6G_MB_LIB.T6G(SCH_1):PVDDCR_CPU1_P1
DB23 PVDDCR_CPU1_P1 VDDCR_CPU1_DB23 @T6G_MB_LIB.T6G(SCH_1):PVDDCR_CPU1_P1
DB24 PVDDCR_CPU1_P1 VDDCR_CPU1_DB24 @T6G_MB_LIB.T6G(SCH_1):PVDDCR_CPU1_P1
DB26 PVDDCR_CPU1_P1 VDDCR_CPU1_DB26 @T6G_MB_LIB.T6G(SCH_1):PVDDCR_CPU1_P1
DB27 PVDDCR_CPU1_P1 VDDCR_CPU1_DB27 @T6G_MB_LIB.T6G(SCH_1):PVDDCR_CPU1_P1
DB29 PVDDCR_CPU1_P1 VDDCR_CPU1_DB29 @T6G_MB_LIB.T6G(SCH_1):PVDDCR_CPU1_P1
DB30 PVDDCR_CPU1_P1 VDDCR_CPU1_DB30 @T6G_MB_LIB.T6G(SCH_1):PVDDCR_CPU1_P1
DB32 PVDDCR_CPU1_P1 VDDCR_CPU1_DB32 @T6G_MB_LIB.T6G(SCH_1):PVDDCR_CPU1_P1
DB33 PVDDCR_CPU1_P1 VDDCR_CPU1_DB33 @T6G_MB_LIB.T6G(SCH_1):PVDDCR_CPU1_P1
DB43 PVDDCR_CPU1_P1 VDDCR_CPU1_DB43 @T6G_MB_LIB.T6G(SCH_1):PVDDCR_CPU1_P1
DB44 PVDDCR_CPU1_P1 VDDCR_CPU1_DB44 @T6G_MB_LIB.T6G(SCH_1):PVDDCR_CPU1_P1
DB46 PVDDCR_CPU1_P1 VDDCR_CPU1_DB46 @T6G_MB_LIB.T6G(SCH_1):PVDDCR_CPU1_P1
DB47 PVDDCR_CPU1_P1 VDDCR_CPU1_DB47 @T6G_MB_LIB.T6G(SCH_1):PVDDCR_CPU1_P1
DB49 PVDDCR_CPU1_P1 VDDCR_CPU1_DB49 @T6G_MB_LIB.T6G(SCH_1):PVDDCR_CPU1_P1
DB50 PVDDCR_CPU1_P1 VDDCR_CPU1_DB50 @T6G_MB_LIB.T6G(SCH_1):PVDDCR_CPU1_P1
DB52 PVDDCR_CPU1_P1 VDDCR_CPU1_DB52 @T6G_MB_LIB.T6G(SCH_1):PVDDCR_CPU1_P1
DB53 PVDDCR_CPU1_P1 VDDCR_CPU1_DB53 @T6G_MB_LIB.T6G(SCH_1):PVDDCR_CPU1_P1
DC35 PVDDCR_CPU1_P1 VDDCR_CPU1_DC35 @T6G_MB_LIB.T6G(SCH_1):PVDDCR_CPU1_P1
DC36 PVDDCR_CPU1_P1 VDDCR_CPU1_DC36 @T6G_MB_LIB.T6G(SCH_1):PVDDCR_CPU1_P1
DC40 PVDDCR_CPU1_P1 VDDCR_CPU1_DC40 @T6G_MB_LIB.T6G(SCH_1):PVDDCR_CPU1_P1
DC41 PVDDCR_CPU1_P1 VDDCR_CPU1_DC41 @T6G_MB_LIB.T6G(SCH_1):PVDDCR_CPU1_P1
DD22 PVDDCR_CPU1_P1 VDDCR_CPU1_DD22 @T6G_MB_LIB.T6G(SCH_1):PVDDCR_CPU1_P1
DD25 PVDDCR_CPU1_P1 VDDCR_CPU1_DD25 @T6G_MB_LIB.T6G(SCH_1):PVDDCR_CPU1_P1
DD28 PVDDCR_CPU1_P1 VDDCR_CPU1_DD28 @T6G_MB_LIB.T6G(SCH_1):PVDDCR_CPU1_P1
DD31 PVDDCR_CPU1_P1 VDDCR_CPU1_DD31 @T6G_MB_LIB.T6G(SCH_1):PVDDCR_CPU1_P1
DD34 PVDDCR_CPU1_P1 VDDCR_CPU1_DD34 @T6G_MB_LIB.T6G(SCH_1):PVDDCR_CPU1_P1
DD42 PVDDCR_CPU1_P1 VDDCR_CPU1_DD42 @T6G_MB_LIB.T6G(SCH_1):PVDDCR_CPU1_P1
DD45 PVDDCR_CPU1_P1 VDDCR_CPU1_DD45 @T6G_MB_LIB.T6G(SCH_1):PVDDCR_CPU1_P1
DD48 PVDDCR_CPU1_P1 VDDCR_CPU1_DD48 @T6G_MB_LIB.T6G(SCH_1):PVDDCR_CPU1_P1
DD51 PVDDCR_CPU1_P1 VDDCR_CPU1_DD51 @T6G_MB_LIB.T6G(SCH_1):PVDDCR_CPU1_P1
DD54 PVDDCR_CPU1_P1 VDDCR_CPU1_DD54 @T6G_MB_LIB.T6G(SCH_1):PVDDCR_CPU1_P1
DE22 PVDDCR_CPU1_P1 VDDCR_CPU1_DE22 @T6G_MB_LIB.T6G(SCH_1):PVDDCR_CPU1_P1
DE25 PVDDCR_CPU1_P1 VDDCR_CPU1_DE25 @T6G_MB_LIB.T6G(SCH_1):PVDDCR_CPU1_P1
DE28 PVDDCR_CPU1_P1 VDDCR_CPU1_DE28 @T6G_MB_LIB.T6G(SCH_1):PVDDCR_CPU1_P1
DE31 PVDDCR_CPU1_P1 VDDCR_CPU1_DE31 @T6G_MB_LIB.T6G(SCH_1):PVDDCR_CPU1_P1
DE34 PVDDCR_CPU1_P1 VDDCR_CPU1_DE34 @T6G_MB_LIB.T6G(SCH_1):PVDDCR_CPU1_P1
DE35 PVDDCR_CPU1_P1 VDDCR_CPU1_DE35 @T6G_MB_LIB.T6G(SCH_1):PVDDCR_CPU1_P1
DE41 PVDDCR_CPU1_P1 VDDCR_CPU1_DE41 @T6G_MB_LIB.T6G(SCH_1):PVDDCR_CPU1_P1
DE42 PVDDCR_CPU1_P1 VDDCR_CPU1_DE42 @T6G_MB_LIB.T6G(SCH_1):PVDDCR_CPU1_P1
DE45 PVDDCR_CPU1_P1 VDDCR_CPU1_DE45 @T6G_MB_LIB.T6G(SCH_1):PVDDCR_CPU1_P1
DE48 PVDDCR_CPU1_P1 VDDCR_CPU1_DE48 @T6G_MB_LIB.T6G(SCH_1):PVDDCR_CPU1_P1
DE51 PVDDCR_CPU1_P1 VDDCR_CPU1_DE51 @T6G_MB_LIB.T6G(SCH_1):PVDDCR_CPU1_P1
DE54 PVDDCR_CPU1_P1 VDDCR_CPU1_DE54 @T6G_MB_LIB.T6G(SCH_1):PVDDCR_CPU1_P1
DG19 PVDDCR_CPU1_P1 VDDCR_CPU1_DG19 @T6G_MB_LIB.T6G(SCH_1):PVDDCR_CPU1_P1
DG57 PVDDCR_CPU1_P1 VDDCR_CPU1_DG57 @T6G_MB_LIB.T6G(SCH_1):PVDDCR_CPU1_P1
DH19 PVDDCR_CPU1_P1 VDDCR_CPU1_DH19 @T6G_MB_LIB.T6G(SCH_1):PVDDCR_CPU1_P1
DH20 PVDDCR_CPU1_P1 VDDCR_CPU1_DH20 @T6G_MB_LIB.T6G(SCH_1):PVDDCR_CPU1_P1
DH22 PVDDCR_CPU1_P1 VDDCR_CPU1_DH22 @T6G_MB_LIB.T6G(SCH_1):PVDDCR_CPU1_P1
DH23 PVDDCR_CPU1_P1 VDDCR_CPU1_DH23 @T6G_MB_LIB.T6G(SCH_1):PVDDCR_CPU1_P1
DH25 PVDDCR_CPU1_P1 VDDCR_CPU1_DH25 @T6G_MB_LIB.T6G(SCH_1):PVDDCR_CPU1_P1
DH26 PVDDCR_CPU1_P1 VDDCR_CPU1_DH26 @T6G_MB_LIB.T6G(SCH_1):PVDDCR_CPU1_P1
DH28 PVDDCR_CPU1_P1 VDDCR_CPU1_DH28 @T6G_MB_LIB.T6G(SCH_1):PVDDCR_CPU1_P1
DH29 PVDDCR_CPU1_P1 VDDCR_CPU1_DH29 @T6G_MB_LIB.T6G(SCH_1):PVDDCR_CPU1_P1
DH31 PVDDCR_CPU1_P1 VDDCR_CPU1_DH31 @T6G_MB_LIB.T6G(SCH_1):PVDDCR_CPU1_P1
DH32 PVDDCR_CPU1_P1 VDDCR_CPU1_DH32 @T6G_MB_LIB.T6G(SCH_1):PVDDCR_CPU1_P1
DH34 PVDDCR_CPU1_P1 VDDCR_CPU1_DH34 @T6G_MB_LIB.T6G(SCH_1):PVDDCR_CPU1_P1
DH35 PVDDCR_CPU1_P1 VDDCR_CPU1_DH35 @T6G_MB_LIB.T6G(SCH_1):PVDDCR_CPU1_P1
DH41 PVDDCR_CPU1_P1 VDDCR_CPU1_DH41 @T6G_MB_LIB.T6G(SCH_1):PVDDCR_CPU1_P1
DH42 PVDDCR_CPU1_P1 VDDCR_CPU1_DH42 @T6G_MB_LIB.T6G(SCH_1):PVDDCR_CPU1_P1
DH44 PVDDCR_CPU1_P1 VDDCR_CPU1_DH44 @T6G_MB_LIB.T6G(SCH_1):PVDDCR_CPU1_P1
DH53 PVDDCR_CPU1_P1 VDDCR_CPU1_DH53 @T6G_MB_LIB.T6G(SCH_1):PVDDCR_CPU1_P1
DH54 PVDDCR_CPU1_P1 VDDCR_CPU1_DH54 @T6G_MB_LIB.T6G(SCH_1):PVDDCR_CPU1_P1
DH56 PVDDCR_CPU1_P1 VDDCR_CPU1_DH56 @T6G_MB_LIB.T6G(SCH_1):PVDDCR_CPU1_P1
DH57 PVDDCR_CPU1_P1 VDDCR_CPU1_DH57 @T6G_MB_LIB.T6G(SCH_1):PVDDCR_CPU1_P1
DH45 PVDDCR_CPU1_P1 VDDCR_CPU1_DH45 @T6G_MB_LIB.T6G(SCH_1):PVDDCR_CPU1_P1
DH47 PVDDCR_CPU1_P1 VDDCR_CPU1_DH47 @T6G_MB_LIB.T6G(SCH_1):PVDDCR_CPU1_P1
DH48 PVDDCR_CPU1_P1 VDDCR_CPU1_DH48 @T6G_MB_LIB.T6G(SCH_1):PVDDCR_CPU1_P1
DH50 PVDDCR_CPU1_P1 VDDCR_CPU1_DH50 @T6G_MB_LIB.T6G(SCH_1):PVDDCR_CPU1_P1
DH51 PVDDCR_CPU1_P1 VDDCR_CPU1_DH51 @T6G_MB_LIB.T6G(SCH_1):PVDDCR_CPU1_P1
BP24 PVDDCR_CPU1_P1 VDDCR_CPU1_BP24 @T6G_MB_LIB.T6G(SCH_1):PVDDCR_CPU1_P1
BP28 PVDDCR_CPU1_P1 VDDCR_CPU1_BP28 @T6G_MB_LIB.T6G(SCH_1):PVDDCR_CPU1_P1
BP32 PVDDCR_CPU1_P1 VDDCR_CPU1_BP32 @T6G_MB_LIB.T6G(SCH_1):PVDDCR_CPU1_P1
BN27 PVDDCR_CPU1_P1 VDDCR_CPU1_BN27 @T6G_MB_LIB.T6G(SCH_1):PVDDCR_CPU1_P1
BN35 PVDDCR_CPU1_P1 VDDCR_CPU1_BN35 @T6G_MB_LIB.T6G(SCH_1):PVDDCR_CPU1_P1
BN46 PVDDCR_CPU1_P1 VDDCR_CPU1_BN46 @T6G_MB_LIB.T6G(SCH_1):PVDDCR_CPU1_P1

GENOA_SP5-SOCKET6096_13568-001,SMLF,IO,DGA^6000030  I45  U26
 H57 PVDDIO_P1 VDDIO_H57 @T6G_MB_LIB.T6G(SCH_1):PVDDIO_P1
 H64 PVDDIO_P1 VDDIO_H64 @T6G_MB_LIB.T6G(SCH_1):PVDDIO_P1
 H71 PVDDIO_P1 VDDIO_H71 @T6G_MB_LIB.T6G(SCH_1):PVDDIO_P1
 K54 PVDDIO_P1 VDDIO_K54 @T6G_MB_LIB.T6G(SCH_1):PVDDIO_P1
 L58 PVDDIO_P1 VDDIO_L58 @T6G_MB_LIB.T6G(SCH_1):PVDDIO_P1
 L65 PVDDIO_P1 VDDIO_L65 @T6G_MB_LIB.T6G(SCH_1):PVDDIO_P1
 L72 PVDDIO_P1 VDDIO_L72 @T6G_MB_LIB.T6G(SCH_1):PVDDIO_P1
 P54 PVDDIO_P1 VDDIO_P54 @T6G_MB_LIB.T6G(SCH_1):PVDDIO_P1
 P57 PVDDIO_P1 VDDIO_P57 @T6G_MB_LIB.T6G(SCH_1):PVDDIO_P1
 P64 PVDDIO_P1 VDDIO_P64 @T6G_MB_LIB.T6G(SCH_1):PVDDIO_P1
 P71 PVDDIO_P1 VDDIO_P71 @T6G_MB_LIB.T6G(SCH_1):PVDDIO_P1
 U58 PVDDIO_P1 VDDIO_U58 @T6G_MB_LIB.T6G(SCH_1):PVDDIO_P1
 U65 PVDDIO_P1 VDDIO_U65 @T6G_MB_LIB.T6G(SCH_1):PVDDIO_P1
 U72 PVDDIO_P1 VDDIO_U72 @T6G_MB_LIB.T6G(SCH_1):PVDDIO_P1
 V54 PVDDIO_P1 VDDIO_V54 @T6G_MB_LIB.T6G(SCH_1):PVDDIO_P1
 Y57 PVDDIO_P1 VDDIO_Y57 @T6G_MB_LIB.T6G(SCH_1):PVDDIO_P1
 Y64 PVDDIO_P1 VDDIO_Y64 @T6G_MB_LIB.T6G(SCH_1):PVDDIO_P1
 Y71 PVDDIO_P1 VDDIO_Y71 @T6G_MB_LIB.T6G(SCH_1):PVDDIO_P1
AA54 PVDDIO_P1 VDDIO_AA54 @T6G_MB_LIB.T6G(SCH_1):PVDDIO_P1
AC58 PVDDIO_P1 VDDIO_AC58 @T6G_MB_LIB.T6G(SCH_1):PVDDIO_P1
AC65 PVDDIO_P1 VDDIO_AC65 @T6G_MB_LIB.T6G(SCH_1):PVDDIO_P1
AC72 PVDDIO_P1 VDDIO_AC72 @T6G_MB_LIB.T6G(SCH_1):PVDDIO_P1
AD54 PVDDIO_P1 VDDIO_AD54 @T6G_MB_LIB.T6G(SCH_1):PVDDIO_P1
AF57 PVDDIO_P1 VDDIO_AF57 @T6G_MB_LIB.T6G(SCH_1):PVDDIO_P1
AF64 PVDDIO_P1 VDDIO_AF64 @T6G_MB_LIB.T6G(SCH_1):PVDDIO_P1
AF71 PVDDIO_P1 VDDIO_AF71 @T6G_MB_LIB.T6G(SCH_1):PVDDIO_P1
AH54 PVDDIO_P1 VDDIO_AH54 @T6G_MB_LIB.T6G(SCH_1):PVDDIO_P1
AJ58 PVDDIO_P1 VDDIO_AJ58 @T6G_MB_LIB.T6G(SCH_1):PVDDIO_P1
AJ65 PVDDIO_P1 VDDIO_AJ65 @T6G_MB_LIB.T6G(SCH_1):PVDDIO_P1
AJ72 PVDDIO_P1 VDDIO_AJ72 @T6G_MB_LIB.T6G(SCH_1):PVDDIO_P1
AM54 PVDDIO_P1 VDDIO_AM54 @T6G_MB_LIB.T6G(SCH_1):PVDDIO_P1
AM57 PVDDIO_P1 VDDIO_AM57 @T6G_MB_LIB.T6G(SCH_1):PVDDIO_P1
AM64 PVDDIO_P1 VDDIO_AM64 @T6G_MB_LIB.T6G(SCH_1):PVDDIO_P1
AM71 PVDDIO_P1 VDDIO_AM71 @T6G_MB_LIB.T6G(SCH_1):PVDDIO_P1
AR58 PVDDIO_P1 VDDIO_AR58 @T6G_MB_LIB.T6G(SCH_1):PVDDIO_P1
AR65 PVDDIO_P1 VDDIO_AR65 @T6G_MB_LIB.T6G(SCH_1):PVDDIO_P1
AR72 PVDDIO_P1 VDDIO_AR72 @T6G_MB_LIB.T6G(SCH_1):PVDDIO_P1
AV57 PVDDIO_P1 VDDIO_AV57 @T6G_MB_LIB.T6G(SCH_1):PVDDIO_P1
AV64 PVDDIO_P1 VDDIO_AV64 @T6G_MB_LIB.T6G(SCH_1):PVDDIO_P1
AV71 PVDDIO_P1 VDDIO_AV71 @T6G_MB_LIB.T6G(SCH_1):PVDDIO_P1
BA58 PVDDIO_P1 VDDIO_BA58 @T6G_MB_LIB.T6G(SCH_1):PVDDIO_P1
BA65 PVDDIO_P1 VDDIO_BA65 @T6G_MB_LIB.T6G(SCH_1):PVDDIO_P1
BA72 PVDDIO_P1 VDDIO_BA72 @T6G_MB_LIB.T6G(SCH_1):PVDDIO_P1
BD50 PVDDIO_P1 VDDIO_BD50 @T6G_MB_LIB.T6G(SCH_1):PVDDIO_P1
BD52 PVDDIO_P1 VDDIO_BD52 @T6G_MB_LIB.T6G(SCH_1):PVDDIO_P1
BD54 PVDDIO_P1 VDDIO_BD54 @T6G_MB_LIB.T6G(SCH_1):PVDDIO_P1
BF51 PVDDIO_P1 VDDIO_BF51 @T6G_MB_LIB.T6G(SCH_1):PVDDIO_P1
BF53 PVDDIO_P1 VDDIO_BF53 @T6G_MB_LIB.T6G(SCH_1):PVDDIO_P1
BF57 PVDDIO_P1 VDDIO_BF57 @T6G_MB_LIB.T6G(SCH_1):PVDDIO_P1
BF64 PVDDIO_P1 VDDIO_BF64 @T6G_MB_LIB.T6G(SCH_1):PVDDIO_P1
BF71 PVDDIO_P1 VDDIO_BF71 @T6G_MB_LIB.T6G(SCH_1):PVDDIO_P1
BG50 PVDDIO_P1 VDDIO_BG50 @T6G_MB_LIB.T6G(SCH_1):PVDDIO_P1
BG52 PVDDIO_P1 VDDIO_BG52 @T6G_MB_LIB.T6G(SCH_1):PVDDIO_P1
BG54 PVDDIO_P1 VDDIO_BG54 @T6G_MB_LIB.T6G(SCH_1):PVDDIO_P1
BH51 PVDDIO_P1 VDDIO_BH51 @T6G_MB_LIB.T6G(SCH_1):PVDDIO_P1
BH53 PVDDIO_P1 VDDIO_BH53 @T6G_MB_LIB.T6G(SCH_1):PVDDIO_P1
BJ50 PVDDIO_P1 VDDIO_BJ50 @T6G_MB_LIB.T6G(SCH_1):PVDDIO_P1
BJ52 PVDDIO_P1 VDDIO_BJ52 @T6G_MB_LIB.T6G(SCH_1):PVDDIO_P1
BJ54 PVDDIO_P1 VDDIO_BJ54 @T6G_MB_LIB.T6G(SCH_1):PVDDIO_P1
BJ58 PVDDIO_P1 VDDIO_BJ58 @T6G_MB_LIB.T6G(SCH_1):PVDDIO_P1
BJ65 PVDDIO_P1 VDDIO_BJ65 @T6G_MB_LIB.T6G(SCH_1):PVDDIO_P1
BJ72 PVDDIO_P1 VDDIO_BJ72 @T6G_MB_LIB.T6G(SCH_1):PVDDIO_P1
BK51 PVDDIO_P1 VDDIO_BK51 @T6G_MB_LIB.T6G(SCH_1):PVDDIO_P1
BK53 PVDDIO_P1 VDDIO_BK53 @T6G_MB_LIB.T6G(SCH_1):PVDDIO_P1
BL50 PVDDIO_P1 VDDIO_BL50 @T6G_MB_LIB.T6G(SCH_1):PVDDIO_P1
BL52 PVDDIO_P1 VDDIO_BL52 @T6G_MB_LIB.T6G(SCH_1):PVDDIO_P1
BL54 PVDDIO_P1 VDDIO_BL54 @T6G_MB_LIB.T6G(SCH_1):PVDDIO_P1
BM51 PVDDIO_P1 VDDIO_BM51 @T6G_MB_LIB.T6G(SCH_1):PVDDIO_P1
BM53 PVDDIO_P1 VDDIO_BM53 @T6G_MB_LIB.T6G(SCH_1):PVDDIO_P1
BM57 PVDDIO_P1 VDDIO_BM57 @T6G_MB_LIB.T6G(SCH_1):PVDDIO_P1
BM64 PVDDIO_P1 VDDIO_BM64 @T6G_MB_LIB.T6G(SCH_1):PVDDIO_P1
BM71 PVDDIO_P1 VDDIO_BM71 @T6G_MB_LIB.T6G(SCH_1):PVDDIO_P1
BN54 PVDDIO_P1 VDDIO_BN54 @T6G_MB_LIB.T6G(SCH_1):PVDDIO_P1
BR58 PVDDIO_P1 VDDIO_BR58 @T6G_MB_LIB.T6G(SCH_1):PVDDIO_P1
BR65 PVDDIO_P1 VDDIO_BR65 @T6G_MB_LIB.T6G(SCH_1):PVDDIO_P1
BR72 PVDDIO_P1 VDDIO_BR72 @T6G_MB_LIB.T6G(SCH_1):PVDDIO_P1
BV54 PVDDIO_P1 VDDIO_BV54 @T6G_MB_LIB.T6G(SCH_1):PVDDIO_P1
BV57 PVDDIO_P1 VDDIO_BV57 @T6G_MB_LIB.T6G(SCH_1):PVDDIO_P1
BV64 PVDDIO_P1 VDDIO_BV64 @T6G_MB_LIB.T6G(SCH_1):PVDDIO_P1
BV71 PVDDIO_P1 VDDIO_BV71 @T6G_MB_LIB.T6G(SCH_1):PVDDIO_P1
CA58 PVDDIO_P1 VDDIO_CA58 @T6G_MB_LIB.T6G(SCH_1):PVDDIO_P1
CA65 PVDDIO_P1 VDDIO_CA65 @T6G_MB_LIB.T6G(SCH_1):PVDDIO_P1
CA72 PVDDIO_P1 VDDIO_CA72 @T6G_MB_LIB.T6G(SCH_1):PVDDIO_P1
CB54 PVDDIO_P1 VDDIO_CB54 @T6G_MB_LIB.T6G(SCH_1):PVDDIO_P1
CD57 PVDDIO_P1 VDDIO_CD57 @T6G_MB_LIB.T6G(SCH_1):PVDDIO_P1
CD64 PVDDIO_P1 VDDIO_CD64 @T6G_MB_LIB.T6G(SCH_1):PVDDIO_P1
CD71 PVDDIO_P1 VDDIO_CD71 @T6G_MB_LIB.T6G(SCH_1):PVDDIO_P1
CF54 PVDDIO_P1 VDDIO_CF54 @T6G_MB_LIB.T6G(SCH_1):PVDDIO_P1
CG58 PVDDIO_P1 VDDIO_CG58 @T6G_MB_LIB.T6G(SCH_1):PVDDIO_P1
CG65 PVDDIO_P1 VDDIO_CG65 @T6G_MB_LIB.T6G(SCH_1):PVDDIO_P1
CG72 PVDDIO_P1 VDDIO_CG72 @T6G_MB_LIB.T6G(SCH_1):PVDDIO_P1
CJ54 PVDDIO_P1 VDDIO_CJ54 @T6G_MB_LIB.T6G(SCH_1):PVDDIO_P1
CK57 PVDDIO_P1 VDDIO_CK57 @T6G_MB_LIB.T6G(SCH_1):PVDDIO_P1
CK64 PVDDIO_P1 VDDIO_CK64 @T6G_MB_LIB.T6G(SCH_1):PVDDIO_P1
CK71 PVDDIO_P1 VDDIO_CK71 @T6G_MB_LIB.T6G(SCH_1):PVDDIO_P1
CM54 PVDDIO_P1 VDDIO_CM54 @T6G_MB_LIB.T6G(SCH_1):PVDDIO_P1
CN58 PVDDIO_P1 VDDIO_CN58 @T6G_MB_LIB.T6G(SCH_1):PVDDIO_P1
CN65 PVDDIO_P1 VDDIO_CN65 @T6G_MB_LIB.T6G(SCH_1):PVDDIO_P1
CN72 PVDDIO_P1 VDDIO_CN72 @T6G_MB_LIB.T6G(SCH_1):PVDDIO_P1
CT54 PVDDIO_P1 VDDIO_CT54 @T6G_MB_LIB.T6G(SCH_1):PVDDIO_P1
CT57 PVDDIO_P1 VDDIO_CT57 @T6G_MB_LIB.T6G(SCH_1):PVDDIO_P1
BJ18 PVDD11_S3_P1 VDD_11_S3_BJ18 @T6G_MB_LIB.T6G(SCH_1):PVDD11_S3_P1
BJ23 PVDD11_S3_P1 VDD_11_S3_BJ23 @T6G_MB_LIB.T6G(SCH_1):PVDD11_S3_P1
BJ25 PVDD11_S3_P1 VDD_11_S3_BJ25 @T6G_MB_LIB.T6G(SCH_1):PVDD11_S3_P1
BJ27 PVDD11_S3_P1 VDD_11_S3_BJ27 @T6G_MB_LIB.T6G(SCH_1):PVDD11_S3_P1
BK22 PVDD11_S3_P1 VDD_11_S3_BK22 @T6G_MB_LIB.T6G(SCH_1):PVDD11_S3_P1
BK24 PVDD11_S3_P1 VDD_11_S3_BK24 @T6G_MB_LIB.T6G(SCH_1):PVDD11_S3_P1
BK26 PVDD11_S3_P1 VDD_11_S3_BK26 @T6G_MB_LIB.T6G(SCH_1):PVDD11_S3_P1
BK28 PVDD11_S3_P1 VDD_11_S3_BK28 @T6G_MB_LIB.T6G(SCH_1):PVDD11_S3_P1
BK49 PVDD11_S3_P1 VDD_11_S3_BK49 @T6G_MB_LIB.T6G(SCH_1):PVDD11_S3_P1
BL23 PVDD11_S3_P1 VDD_11_S3_BL23 @T6G_MB_LIB.T6G(SCH_1):PVDD11_S3_P1
BL25 PVDD11_S3_P1 VDD_11_S3_BL25 @T6G_MB_LIB.T6G(SCH_1):PVDD11_S3_P1
BL27 PVDD11_S3_P1 VDD_11_S3_BL27 @T6G_MB_LIB.T6G(SCH_1):PVDD11_S3_P1
BL48 PVDD11_S3_P1 VDD_11_S3_BL48 @T6G_MB_LIB.T6G(SCH_1):PVDD11_S3_P1
BM12 PVDD11_S3_P1 VDD_11_S3_BM12 @T6G_MB_LIB.T6G(SCH_1):PVDD11_S3_P1
BM19 PVDD11_S3_P1 VDD_11_S3_BM19 @T6G_MB_LIB.T6G(SCH_1):PVDD11_S3_P1
BM22 PVDD11_S3_P1 VDD_11_S3_BM22 @T6G_MB_LIB.T6G(SCH_1):PVDD11_S3_P1
BM24 PVDD11_S3_P1 VDD_11_S3_BM24 @T6G_MB_LIB.T6G(SCH_1):PVDD11_S3_P1
BM26 PVDD11_S3_P1 VDD_11_S3_BM26 @T6G_MB_LIB.T6G(SCH_1):PVDD11_S3_P1
BM28 PVDD11_S3_P1 VDD_11_S3_BM28 @T6G_MB_LIB.T6G(SCH_1):PVDD11_S3_P1
BM30 PVDD11_S3_P1 VDD_11_S3_BM30 @T6G_MB_LIB.T6G(SCH_1):PVDD11_S3_P1
BM32 PVDD11_S3_P1 VDD_11_S3_BM32 @T6G_MB_LIB.T6G(SCH_1):PVDD11_S3_P1
BM34 PVDD11_S3_P1 VDD_11_S3_BM34 @T6G_MB_LIB.T6G(SCH_1):PVDD11_S3_P1
BM36 PVDD11_S3_P1 VDD_11_S3_BM36 @T6G_MB_LIB.T6G(SCH_1):PVDD11_S3_P1
BM39 PVDD11_S3_P1 VDD_11_S3_BM39 @T6G_MB_LIB.T6G(SCH_1):PVDD11_S3_P1
BM41 PVDD11_S3_P1 VDD_11_S3_BM41 @T6G_MB_LIB.T6G(SCH_1):PVDD11_S3_P1
BM43 PVDD11_S3_P1 VDD_11_S3_BM43 @T6G_MB_LIB.T6G(SCH_1):PVDD11_S3_P1
BM45 PVDD11_S3_P1 VDD_11_S3_BM45 @T6G_MB_LIB.T6G(SCH_1):PVDD11_S3_P1
BM47 PVDD11_S3_P1 VDD_11_S3_BM47 @T6G_MB_LIB.T6G(SCH_1):PVDD11_S3_P1
BM49 PVDD11_S3_P1 VDD_11_S3_BM49 @T6G_MB_LIB.T6G(SCH_1):PVDD11_S3_P1
BN25 PVDD11_S3_P1 VDD_11_S3_BN25 @T6G_MB_LIB.T6G(SCH_1):PVDD11_S3_P1
BN29 PVDD11_S3_P1 VDD_11_S3_BN29 @T6G_MB_LIB.T6G(SCH_1):PVDD11_S3_P1
BN33 PVDD11_S3_P1 VDD_11_S3_BN33 @T6G_MB_LIB.T6G(SCH_1):PVDD11_S3_P1
BN40 PVDD11_S3_P1 VDD_11_S3_BN40 @T6G_MB_LIB.T6G(SCH_1):PVDD11_S3_P1
BN44 PVDD11_S3_P1 VDD_11_S3_BN44 @T6G_MB_LIB.T6G(SCH_1):PVDD11_S3_P1
BN48 PVDD11_S3_P1 VDD_11_S3_BN48 @T6G_MB_LIB.T6G(SCH_1):PVDD11_S3_P1
BP22 PVDD11_S3_P1 VDD_11_S3_BP22 @T6G_MB_LIB.T6G(SCH_1):PVDD11_S3_P1
 BR4 PVDD11_S3_P1 VDD_11_S3_BR4 @T6G_MB_LIB.T6G(SCH_1):PVDD11_S3_P1
BR11 PVDD11_S3_P1 VDD_11_S3_BR11 @T6G_MB_LIB.T6G(SCH_1):PVDD11_S3_P1
BR18 PVDD11_S3_P1 VDD_11_S3_BR18 @T6G_MB_LIB.T6G(SCH_1):PVDD11_S3_P1
 BV5 PVDD11_S3_P1 VDD_11_S3_BV5 @T6G_MB_LIB.T6G(SCH_1):PVDD11_S3_P1
BV12 PVDD11_S3_P1 VDD_11_S3_BV12 @T6G_MB_LIB.T6G(SCH_1):PVDD11_S3_P1
BV19 PVDD11_S3_P1 VDD_11_S3_BV19 @T6G_MB_LIB.T6G(SCH_1):PVDD11_S3_P1
BV22 PVDD11_S3_P1 VDD_11_S3_BV22 @T6G_MB_LIB.T6G(SCH_1):PVDD11_S3_P1
 CA4 PVDD11_S3_P1 VDD_11_S3_CA4 @T6G_MB_LIB.T6G(SCH_1):PVDD11_S3_P1
CA11 PVDD11_S3_P1 VDD_11_S3_CA11 @T6G_MB_LIB.T6G(SCH_1):PVDD11_S3_P1
CA18 PVDD11_S3_P1 VDD_11_S3_CA18 @T6G_MB_LIB.T6G(SCH_1):PVDD11_S3_P1
CB22 PVDD11_S3_P1 VDD_11_S3_CB22 @T6G_MB_LIB.T6G(SCH_1):PVDD11_S3_P1
 CD5 PVDD11_S3_P1 VDD_11_S3_CD5 @T6G_MB_LIB.T6G(SCH_1):PVDD11_S3_P1
CD12 PVDD11_S3_P1 VDD_11_S3_CD12 @T6G_MB_LIB.T6G(SCH_1):PVDD11_S3_P1
CD19 PVDD11_S3_P1 VDD_11_S3_CD19 @T6G_MB_LIB.T6G(SCH_1):PVDD11_S3_P1
CF22 PVDD11_S3_P1 VDD_11_S3_CF22 @T6G_MB_LIB.T6G(SCH_1):PVDD11_S3_P1
 CG4 PVDD11_S3_P1 VDD_11_S3_CG4 @T6G_MB_LIB.T6G(SCH_1):PVDD11_S3_P1
CG11 PVDD11_S3_P1 VDD_11_S3_CG11 @T6G_MB_LIB.T6G(SCH_1):PVDD11_S3_P1
CG18 PVDD11_S3_P1 VDD_11_S3_CG18 @T6G_MB_LIB.T6G(SCH_1):PVDD11_S3_P1
CJ22 PVDD11_S3_P1 VDD_11_S3_CJ22 @T6G_MB_LIB.T6G(SCH_1):PVDD11_S3_P1
 CK5 PVDD11_S3_P1 VDD_11_S3_CK5 @T6G_MB_LIB.T6G(SCH_1):PVDD11_S3_P1
CK12 PVDD11_S3_P1 VDD_11_S3_CK12 @T6G_MB_LIB.T6G(SCH_1):PVDD11_S3_P1
CK19 PVDD11_S3_P1 VDD_11_S3_CK19 @T6G_MB_LIB.T6G(SCH_1):PVDD11_S3_P1
CM22 PVDD11_S3_P1 VDD_11_S3_CM22 @T6G_MB_LIB.T6G(SCH_1):PVDD11_S3_P1
 CN4 PVDD11_S3_P1 VDD_11_S3_CN4 @T6G_MB_LIB.T6G(SCH_1):PVDD11_S3_P1
CN11 PVDD11_S3_P1 VDD_11_S3_CN11 @T6G_MB_LIB.T6G(SCH_1):PVDD11_S3_P1
CN18 PVDD11_S3_P1 VDD_11_S3_CN18 @T6G_MB_LIB.T6G(SCH_1):PVDD11_S3_P1
 CT5 PVDD11_S3_P1 VDD_11_S3_CT5 @T6G_MB_LIB.T6G(SCH_1):PVDD11_S3_P1
AU54 PVDD18_S5_P1 VDD_18_S5_AU54 @T6G_MB_LIB.T6G(SCH_1):PVDD18_S5_P1
AR52 PVDD18_S5_P1 VDD_18_S5_AR52 @T6G_MB_LIB.T6G(SCH_1):PVDD18_S5_P1
AR54 PVDD18_S5_P1 VDD_18_S5_AR54 @T6G_MB_LIB.T6G(SCH_1):PVDD18_S5_P1
AT51 PVDD18_S5_P1 VDD_18_S5_AT51 @T6G_MB_LIB.T6G(SCH_1):PVDD18_S5_P1
AT53 PVDD18_S5_P1 VDD_18_S5_AT53 @T6G_MB_LIB.T6G(SCH_1):PVDD18_S5_P1
AU50 PVDD18_S5_P1 VDD_18_S5_AU50 @T6G_MB_LIB.T6G(SCH_1):PVDD18_S5_P1
AU52 PVDD18_S5_P1 VDD_18_S5_AU52 @T6G_MB_LIB.T6G(SCH_1):PVDD18_S5_P1
AV49 PVDD18_S5_P1 VDD_18_S5_AV49 @T6G_MB_LIB.T6G(SCH_1):PVDD18_S5_P1
AV51 PVDD18_S5_P1 VDD_18_S5_AV51 @T6G_MB_LIB.T6G(SCH_1):PVDD18_S5_P1
AV53 PVDD18_S5_P1 VDD_18_S5_AV53 @T6G_MB_LIB.T6G(SCH_1):PVDD18_S5_P1
AW50 PVDD18_S5_P1 VDD_18_S5_AW50 @T6G_MB_LIB.T6G(SCH_1):PVDD18_S5_P1
BC52 PVDD18_S5_P1 VDD_18_S5_BC52 @T6G_MB_LIB.T6G(SCH_1):PVDD18_S5_P1
BC54 PVDD18_S5_P1 VDD_18_S5_BC54 @T6G_MB_LIB.T6G(SCH_1):PVDD18_S5_P1
AW52 PVDD18_S5_P1 VDD_18_S5_AW52 @T6G_MB_LIB.T6G(SCH_1):PVDD18_S5_P1
AW54 PVDD18_S5_P1 VDD_18_S5_AW54 @T6G_MB_LIB.T6G(SCH_1):PVDD18_S5_P1
AY51 PVDD18_S5_P1 VDD_18_S5_AY51 @T6G_MB_LIB.T6G(SCH_1):PVDD18_S5_P1
AY53 PVDD18_S5_P1 VDD_18_S5_AY53 @T6G_MB_LIB.T6G(SCH_1):PVDD18_S5_P1
BA50 PVDD18_S5_P1 VDD_18_S5_BA50 @T6G_MB_LIB.T6G(SCH_1):PVDD18_S5_P1
BA52 PVDD18_S5_P1 VDD_18_S5_BA52 @T6G_MB_LIB.T6G(SCH_1):PVDD18_S5_P1
BA54 PVDD18_S5_P1 VDD_18_S5_BA54 @T6G_MB_LIB.T6G(SCH_1):PVDD18_S5_P1
BB51 PVDD18_S5_P1 VDD_18_S5_BB51 @T6G_MB_LIB.T6G(SCH_1):PVDD18_S5_P1
BB53 PVDD18_S5_P1 VDD_18_S5_BB53 @T6G_MB_LIB.T6G(SCH_1):PVDD18_S5_P1
CT12 PVDD11_S3_P1 VDD_11_S3_CT12 @T6G_MB_LIB.T6G(SCH_1):PVDD11_S3_P1
BN52 PVDD_33_S5 VDD_33_S5_BN52 @T6G_MB_LIB.T6G(SCH_1):PVDD_33_S5
BP51 PVDD_33_S5 VDD_33_S5_BP51 @T6G_MB_LIB.T6G(SCH_1):PVDD_33_S5
BH27 PVDD18_S5_P1 VDDIO_AUDIO @T6G_MB_LIB.T6G(SCH_1):PVDD18_S5_P1
BN23 CPU1_VDDBT_RTC_G VDDBT_RTC_G @T6G_MB_LIB.T6G(SCH_1):CPU1_VDDBT_RTC_G
DG71 PVDDIO_P1 VDDIO_DG71 @T6G_MB_LIB.T6G(SCH_1):PVDDIO_P1
DG64 PVDDIO_P1 VDDIO_DG64 @T6G_MB_LIB.T6G(SCH_1):PVDDIO_P1
DE72 PVDDIO_P1 VDDIO_DE72 @T6G_MB_LIB.T6G(SCH_1):PVDDIO_P1
DE65 PVDDIO_P1 VDDIO_DE65 @T6G_MB_LIB.T6G(SCH_1):PVDDIO_P1
DE58 PVDDIO_P1 VDDIO_DE58 @T6G_MB_LIB.T6G(SCH_1):PVDDIO_P1
DB71 PVDDIO_P1 VDDIO_DB71 @T6G_MB_LIB.T6G(SCH_1):PVDDIO_P1
DB64 PVDDIO_P1 VDDIO_DB64 @T6G_MB_LIB.T6G(SCH_1):PVDDIO_P1
DB57 PVDDIO_P1 VDDIO_DB57 @T6G_MB_LIB.T6G(SCH_1):PVDDIO_P1
CY54 PVDDIO_P1 VDDIO_CY54 @T6G_MB_LIB.T6G(SCH_1):PVDDIO_P1
CW72 PVDDIO_P1 VDDIO_CW72 @T6G_MB_LIB.T6G(SCH_1):PVDDIO_P1
CW65 PVDDIO_P1 VDDIO_CW65 @T6G_MB_LIB.T6G(SCH_1):PVDDIO_P1
CW58 PVDDIO_P1 VDDIO_CW58 @T6G_MB_LIB.T6G(SCH_1):PVDDIO_P1
CT71 PVDDIO_P1 VDDIO_CT71 @T6G_MB_LIB.T6G(SCH_1):PVDDIO_P1
CT64 PVDDIO_P1 VDDIO_CT64 @T6G_MB_LIB.T6G(SCH_1):PVDDIO_P1
 DG5 PVDD11_S3_P1 VDD_11_S3_DG5 @T6G_MB_LIB.T6G(SCH_1):PVDD11_S3_P1
DE18 PVDD11_S3_P1 VDD_11_S3_DE18 @T6G_MB_LIB.T6G(SCH_1):PVDD11_S3_P1
DE11 PVDD11_S3_P1 VDD_11_S3_DE11 @T6G_MB_LIB.T6G(SCH_1):PVDD11_S3_P1
 DE4 PVDD11_S3_P1 VDD_11_S3_DE4 @T6G_MB_LIB.T6G(SCH_1):PVDD11_S3_P1
DB19 PVDD11_S3_P1 VDD_11_S3_DB19 @T6G_MB_LIB.T6G(SCH_1):PVDD11_S3_P1
DB12 PVDD11_S3_P1 VDD_11_S3_DB12 @T6G_MB_LIB.T6G(SCH_1):PVDD11_S3_P1
 DB5 PVDD11_S3_P1 VDD_11_S3_DB5 @T6G_MB_LIB.T6G(SCH_1):PVDD11_S3_P1
CY22 PVDD11_S3_P1 VDD_11_S3_CY22 @T6G_MB_LIB.T6G(SCH_1):PVDD11_S3_P1
CW18 PVDD11_S3_P1 VDD_11_S3_CW18 @T6G_MB_LIB.T6G(SCH_1):PVDD11_S3_P1
CW11 PVDD11_S3_P1 VDD_11_S3_CW11 @T6G_MB_LIB.T6G(SCH_1):PVDD11_S3_P1
 CW4 PVDD11_S3_P1 VDD_11_S3_CW4 @T6G_MB_LIB.T6G(SCH_1):PVDD11_S3_P1
CT22 PVDD11_S3_P1 VDD_11_S3_CT22 @T6G_MB_LIB.T6G(SCH_1):PVDD11_S3_P1
CT19 PVDD11_S3_P1 VDD_11_S3_CT19 @T6G_MB_LIB.T6G(SCH_1):PVDD11_S3_P1

GENOA_SP5-SOCKET6096_13568-001,SMLF,IO,DGA^6000030  I46  U26
BD62     NC RSVD_BD62     NC
 D72     NC RSVD_D72     NC
 C54     NC RSVD_C54     NC
BD65     NC RSVD_BD65     NC
 E33     NC RSVD_E33     NC
  D4     NC RSVD_D4     NC
 A55     NC RSVD_A55     NC
BD69     NC RSVD_BD69     NC
 E36     NC RSVD_E36     NC
  D8     NC RSVD_D8     NC
 A56     NC RSVD_A56     NC
BD72     NC RSVD_BD72     NC
 BD4     NC RSVD_BD4     NC
 D11     NC RSVD_D11     NC
 A57     NC RSVD_A57     NC
DG17     NC RSVD_DG17     NC
 D22     NC RSVD_D22     NC
 A59     NC RSVD_A59     NC
DH17     NC RSVD_DH17     NC
BD11     NC RSVD_BD11     NC
 D34     NC RSVD_D34     NC
 A31     NC RSVD_A31     NC
DH21     NC RSVD_DH21     NC
BD14     NC RSVD_BD14     NC
 B40     NC RSVD_B40     NC
 A35     NC RSVD_A35     NC
 DJ4     NC RSVD_DJ4     NC
BD18     NC RSVD_BD18     NC
 D58     NC RSVD_D58     NC
 C31     NC RSVD_C31     NC
 A41     NC RSVD_A41     NC
BD21     NC RSVD_BD21     NC
 D62     NC RSVD_D62     NC
 C34     NC RSVD_C34     NC
 A42     NC RSVD_A42     NC
 D65     NC RSVD_D65     NC
 C35     NC RSVD_C35     NC
 A45     NC RSVD_A45     NC
 C53     NC RSVD_C53     NC
 A48     NC RSVD_A48     NC
 A50     NC RSVD_A50     NC
 A51     NC RSVD_A51     NC
 A54     NC RSVD_A54     NC
BD55     NC RSVD_BD55     NC
BD58     NC RSVD_BD58     NC
 D36     NC RSVD_D36     NC
 BD7     NC RSVD_BD7     NC
 A60     NC RSVD_A60     NC
DJ57     NC TEST6_X3D7     NC
DH14     NC TEST5_CCD13     NC
DH13     NC TEST4_CCD13     NC
DG42     NC TEST5_CCD14     NC
DF41     NC TEST4_CCD14     NC
 D23     NC TEST5_CCD15     NC
 C59     NC TEST5_CCD12     NC
 C58     NC TEST4_CCD12     NC
 C23     NC TEST4_CCD15     NC
 B36     NC TEST6_X3D6     NC

GENOA_SP5-SOCKET6096_13568-001,SMLF,IO,DGA^6000030  I49  U26
  B5 PVDDCR_SOC_P1 VDDCR_SOC_B5 @T6G_MB_LIB.T6G(SCH_1):PVDDCR_SOC_P1
  C4 PVDDCR_SOC_P1 VDDCR_SOC_C4 @T6G_MB_LIB.T6G(SCH_1):PVDDCR_SOC_P1
  E4 PVDDCR_SOC_P1 VDDCR_SOC_E4 @T6G_MB_LIB.T6G(SCH_1):PVDDCR_SOC_P1
 E11 PVDDCR_SOC_P1 VDDCR_SOC_E11 @T6G_MB_LIB.T6G(SCH_1):PVDDCR_SOC_P1
  H5 PVDDCR_SOC_P1 VDDCR_SOC_H5 @T6G_MB_LIB.T6G(SCH_1):PVDDCR_SOC_P1
 H12 PVDDCR_SOC_P1 VDDCR_SOC_H12 @T6G_MB_LIB.T6G(SCH_1):PVDDCR_SOC_P1
 H19 PVDDCR_SOC_P1 VDDCR_SOC_H19 @T6G_MB_LIB.T6G(SCH_1):PVDDCR_SOC_P1
 K22 PVDDCR_SOC_P1 VDDCR_SOC_K22 @T6G_MB_LIB.T6G(SCH_1):PVDDCR_SOC_P1
  L4 PVDDCR_SOC_P1 VDDCR_SOC_L4 @T6G_MB_LIB.T6G(SCH_1):PVDDCR_SOC_P1
 L11 PVDDCR_SOC_P1 VDDCR_SOC_L11 @T6G_MB_LIB.T6G(SCH_1):PVDDCR_SOC_P1
 L18 PVDDCR_SOC_P1 VDDCR_SOC_L18 @T6G_MB_LIB.T6G(SCH_1):PVDDCR_SOC_P1
  P5 PVDDCR_SOC_P1 VDDCR_SOC_P5 @T6G_MB_LIB.T6G(SCH_1):PVDDCR_SOC_P1
 P12 PVDDCR_SOC_P1 VDDCR_SOC_P12 @T6G_MB_LIB.T6G(SCH_1):PVDDCR_SOC_P1
 P19 PVDDCR_SOC_P1 VDDCR_SOC_P19 @T6G_MB_LIB.T6G(SCH_1):PVDDCR_SOC_P1
 P22 PVDDCR_SOC_P1 VDDCR_SOC_P22 @T6G_MB_LIB.T6G(SCH_1):PVDDCR_SOC_P1
  U4 PVDDCR_SOC_P1 VDDCR_SOC_U4 @T6G_MB_LIB.T6G(SCH_1):PVDDCR_SOC_P1
 U11 PVDDCR_SOC_P1 VDDCR_SOC_U11 @T6G_MB_LIB.T6G(SCH_1):PVDDCR_SOC_P1
 U18 PVDDCR_SOC_P1 VDDCR_SOC_U18 @T6G_MB_LIB.T6G(SCH_1):PVDDCR_SOC_P1
 V22 PVDDCR_SOC_P1 VDDCR_SOC_V22 @T6G_MB_LIB.T6G(SCH_1):PVDDCR_SOC_P1
  Y5 PVDDCR_SOC_P1 VDDCR_SOC_Y5 @T6G_MB_LIB.T6G(SCH_1):PVDDCR_SOC_P1
 Y12 PVDDCR_SOC_P1 VDDCR_SOC_Y12 @T6G_MB_LIB.T6G(SCH_1):PVDDCR_SOC_P1
 Y19 PVDDCR_SOC_P1 VDDCR_SOC_Y19 @T6G_MB_LIB.T6G(SCH_1):PVDDCR_SOC_P1
AA22 PVDDCR_SOC_P1 VDDCR_SOC_AA22 @T6G_MB_LIB.T6G(SCH_1):PVDDCR_SOC_P1
 AC4 PVDDCR_SOC_P1 VDDCR_SOC_AC4 @T6G_MB_LIB.T6G(SCH_1):PVDDCR_SOC_P1
AC11 PVDDCR_SOC_P1 VDDCR_SOC_AC11 @T6G_MB_LIB.T6G(SCH_1):PVDDCR_SOC_P1
AC18 PVDDCR_SOC_P1 VDDCR_SOC_AC18 @T6G_MB_LIB.T6G(SCH_1):PVDDCR_SOC_P1
AD22 PVDDCR_SOC_P1 VDDCR_SOC_AD22 @T6G_MB_LIB.T6G(SCH_1):PVDDCR_SOC_P1
 AF5 PVDDCR_SOC_P1 VDDCR_SOC_AF5 @T6G_MB_LIB.T6G(SCH_1):PVDDCR_SOC_P1
AF12 PVDDCR_SOC_P1 VDDCR_SOC_AF12 @T6G_MB_LIB.T6G(SCH_1):PVDDCR_SOC_P1
AF19 PVDDCR_SOC_P1 VDDCR_SOC_AF19 @T6G_MB_LIB.T6G(SCH_1):PVDDCR_SOC_P1
AH22 PVDDCR_SOC_P1 VDDCR_SOC_AH22 @T6G_MB_LIB.T6G(SCH_1):PVDDCR_SOC_P1
 AJ4 PVDDCR_SOC_P1 VDDCR_SOC_AJ4 @T6G_MB_LIB.T6G(SCH_1):PVDDCR_SOC_P1
AJ11 PVDDCR_SOC_P1 VDDCR_SOC_AJ11 @T6G_MB_LIB.T6G(SCH_1):PVDDCR_SOC_P1
AJ18 PVDDCR_SOC_P1 VDDCR_SOC_AJ18 @T6G_MB_LIB.T6G(SCH_1):PVDDCR_SOC_P1
 AM5 PVDDCR_SOC_P1 VDDCR_SOC_AM5 @T6G_MB_LIB.T6G(SCH_1):PVDDCR_SOC_P1
AM12 PVDDCR_SOC_P1 VDDCR_SOC_AM12 @T6G_MB_LIB.T6G(SCH_1):PVDDCR_SOC_P1
AM19 PVDDCR_SOC_P1 VDDCR_SOC_AM19 @T6G_MB_LIB.T6G(SCH_1):PVDDCR_SOC_P1
AM22 PVDDCR_SOC_P1 VDDCR_SOC_AM22 @T6G_MB_LIB.T6G(SCH_1):PVDDCR_SOC_P1
 AR4 PVDDCR_SOC_P1 VDDCR_SOC_AR4 @T6G_MB_LIB.T6G(SCH_1):PVDDCR_SOC_P1
AR11 PVDDCR_SOC_P1 VDDCR_SOC_AR11 @T6G_MB_LIB.T6G(SCH_1):PVDDCR_SOC_P1
AR18 PVDDCR_SOC_P1 VDDCR_SOC_AR18 @T6G_MB_LIB.T6G(SCH_1):PVDDCR_SOC_P1
AT22 PVDDCR_SOC_P1 VDDCR_SOC_AT22 @T6G_MB_LIB.T6G(SCH_1):PVDDCR_SOC_P1
AU23 PVDDCR_SOC_P1 VDDCR_SOC_AU23 @T6G_MB_LIB.T6G(SCH_1):PVDDCR_SOC_P1
AU27 PVDDCR_SOC_P1 VDDCR_SOC_AU27 @T6G_MB_LIB.T6G(SCH_1):PVDDCR_SOC_P1
AU31 PVDDCR_SOC_P1 VDDCR_SOC_AU31 @T6G_MB_LIB.T6G(SCH_1):PVDDCR_SOC_P1
AU35 PVDDCR_SOC_P1 VDDCR_SOC_AU35 @T6G_MB_LIB.T6G(SCH_1):PVDDCR_SOC_P1
AU40 PVDDCR_SOC_P1 VDDCR_SOC_AU40 @T6G_MB_LIB.T6G(SCH_1):PVDDCR_SOC_P1
 AV5 PVDDCR_SOC_P1 VDDCR_SOC_AV5 @T6G_MB_LIB.T6G(SCH_1):PVDDCR_SOC_P1
AV12 PVDDCR_SOC_P1 VDDCR_SOC_AV12 @T6G_MB_LIB.T6G(SCH_1):PVDDCR_SOC_P1
AV19 PVDDCR_SOC_P1 VDDCR_SOC_AV19 @T6G_MB_LIB.T6G(SCH_1):PVDDCR_SOC_P1
AV22 PVDDCR_SOC_P1 VDDCR_SOC_AV22 @T6G_MB_LIB.T6G(SCH_1):PVDDCR_SOC_P1
AV24 PVDDCR_SOC_P1 VDDCR_SOC_AV24 @T6G_MB_LIB.T6G(SCH_1):PVDDCR_SOC_P1
AV26 PVDDCR_SOC_P1 VDDCR_SOC_AV26 @T6G_MB_LIB.T6G(SCH_1):PVDDCR_SOC_P1
AV28 PVDDCR_SOC_P1 VDDCR_SOC_AV28 @T6G_MB_LIB.T6G(SCH_1):PVDDCR_SOC_P1
AV30 PVDDCR_SOC_P1 VDDCR_SOC_AV30 @T6G_MB_LIB.T6G(SCH_1):PVDDCR_SOC_P1
AV32 PVDDCR_SOC_P1 VDDCR_SOC_AV32 @T6G_MB_LIB.T6G(SCH_1):PVDDCR_SOC_P1
AV34 PVDDCR_SOC_P1 VDDCR_SOC_AV34 @T6G_MB_LIB.T6G(SCH_1):PVDDCR_SOC_P1
AV36 PVDDCR_SOC_P1 VDDCR_SOC_AV36 @T6G_MB_LIB.T6G(SCH_1):PVDDCR_SOC_P1
AV39 PVDDCR_SOC_P1 VDDCR_SOC_AV39 @T6G_MB_LIB.T6G(SCH_1):PVDDCR_SOC_P1
AV41 PVDDCR_SOC_P1 VDDCR_SOC_AV41 @T6G_MB_LIB.T6G(SCH_1):PVDDCR_SOC_P1
AV43 PVDDCR_SOC_P1 VDDCR_SOC_AV43 @T6G_MB_LIB.T6G(SCH_1):PVDDCR_SOC_P1
AV45 PVDDCR_SOC_P1 VDDCR_SOC_AV45 @T6G_MB_LIB.T6G(SCH_1):PVDDCR_SOC_P1
AV47 PVDDCR_SOC_P1 VDDCR_SOC_AV47 @T6G_MB_LIB.T6G(SCH_1):PVDDCR_SOC_P1
AW23 PVDDCR_SOC_P1 VDDCR_SOC_AW23 @T6G_MB_LIB.T6G(SCH_1):PVDDCR_SOC_P1
AW25 PVDDCR_SOC_P1 VDDCR_SOC_AW25 @T6G_MB_LIB.T6G(SCH_1):PVDDCR_SOC_P1
AW27 PVDDCR_SOC_P1 VDDCR_SOC_AW27 @T6G_MB_LIB.T6G(SCH_1):PVDDCR_SOC_P1
AW48 PVDDCR_SOC_P1 VDDCR_SOC_AW48 @T6G_MB_LIB.T6G(SCH_1):PVDDCR_SOC_P1
AY22 PVDDCR_SOC_P1 VDDCR_SOC_AY22 @T6G_MB_LIB.T6G(SCH_1):PVDDCR_SOC_P1
AY24 PVDDCR_SOC_P1 VDDCR_SOC_AY24 @T6G_MB_LIB.T6G(SCH_1):PVDDCR_SOC_P1
AY26 PVDDCR_SOC_P1 VDDCR_SOC_AY26 @T6G_MB_LIB.T6G(SCH_1):PVDDCR_SOC_P1
AY28 PVDDCR_SOC_P1 VDDCR_SOC_AY28 @T6G_MB_LIB.T6G(SCH_1):PVDDCR_SOC_P1
AY49 PVDDCR_SOC_P1 VDDCR_SOC_AY49 @T6G_MB_LIB.T6G(SCH_1):PVDDCR_SOC_P1
 BA4 PVDDCR_SOC_P1 VDDCR_SOC_BA4 @T6G_MB_LIB.T6G(SCH_1):PVDDCR_SOC_P1
BA11 PVDDCR_SOC_P1 VDDCR_SOC_BA11 @T6G_MB_LIB.T6G(SCH_1):PVDDCR_SOC_P1
BA18 PVDDCR_SOC_P1 VDDCR_SOC_BA18 @T6G_MB_LIB.T6G(SCH_1):PVDDCR_SOC_P1
BA23 PVDDCR_SOC_P1 VDDCR_SOC_BA23 @T6G_MB_LIB.T6G(SCH_1):PVDDCR_SOC_P1
BA25 PVDDCR_SOC_P1 VDDCR_SOC_BA25 @T6G_MB_LIB.T6G(SCH_1):PVDDCR_SOC_P1
BA27 PVDDCR_SOC_P1 VDDCR_SOC_BA27 @T6G_MB_LIB.T6G(SCH_1):PVDDCR_SOC_P1
BA48 PVDDCR_SOC_P1 VDDCR_SOC_BA48 @T6G_MB_LIB.T6G(SCH_1):PVDDCR_SOC_P1
BB22 PVDDCR_SOC_P1 VDDCR_SOC_BB22 @T6G_MB_LIB.T6G(SCH_1):PVDDCR_SOC_P1
BB24 PVDDCR_SOC_P1 VDDCR_SOC_BB24 @T6G_MB_LIB.T6G(SCH_1):PVDDCR_SOC_P1
BB26 PVDDCR_SOC_P1 VDDCR_SOC_BB26 @T6G_MB_LIB.T6G(SCH_1):PVDDCR_SOC_P1
BB28 PVDDCR_SOC_P1 VDDCR_SOC_BB28 @T6G_MB_LIB.T6G(SCH_1):PVDDCR_SOC_P1
BB49 PVDDCR_SOC_P1 VDDCR_SOC_BB49 @T6G_MB_LIB.T6G(SCH_1):PVDDCR_SOC_P1
BC23 PVDDCR_SOC_P1 VDDCR_SOC_BC23 @T6G_MB_LIB.T6G(SCH_1):PVDDCR_SOC_P1
BC25 PVDDCR_SOC_P1 VDDCR_SOC_BC25 @T6G_MB_LIB.T6G(SCH_1):PVDDCR_SOC_P1
BC27 PVDDCR_SOC_P1 VDDCR_SOC_BC27 @T6G_MB_LIB.T6G(SCH_1):PVDDCR_SOC_P1
BC48 PVDDCR_SOC_P1 VDDCR_SOC_BC48 @T6G_MB_LIB.T6G(SCH_1):PVDDCR_SOC_P1
 BD5 PVDDCR_SOC_P1 VDDCR_SOC_BD5 @T6G_MB_LIB.T6G(SCH_1):PVDDCR_SOC_P1
BD12 PVDDCR_SOC_P1 VDDCR_SOC_BD12 @T6G_MB_LIB.T6G(SCH_1):PVDDCR_SOC_P1
BD19 PVDDCR_SOC_P1 VDDCR_SOC_BD19 @T6G_MB_LIB.T6G(SCH_1):PVDDCR_SOC_P1
BD22 PVDDCR_SOC_P1 VDDCR_SOC_BD22 @T6G_MB_LIB.T6G(SCH_1):PVDDCR_SOC_P1
BD24 PVDDCR_SOC_P1 VDDCR_SOC_BD24 @T6G_MB_LIB.T6G(SCH_1):PVDDCR_SOC_P1
BD26 PVDDCR_SOC_P1 VDDCR_SOC_BD26 @T6G_MB_LIB.T6G(SCH_1):PVDDCR_SOC_P1
BD28 PVDDCR_SOC_P1 VDDCR_SOC_BD28 @T6G_MB_LIB.T6G(SCH_1):PVDDCR_SOC_P1
BD48 PVDDCR_SOC_P1 VDDCR_SOC_BD48 @T6G_MB_LIB.T6G(SCH_1):PVDDCR_SOC_P1
BF23 PVDDCR_SOC_P1 VDDCR_SOC_BF23 @T6G_MB_LIB.T6G(SCH_1):PVDDCR_SOC_P1
BF25 PVDDCR_SOC_P1 VDDCR_SOC_BF25 @T6G_MB_LIB.T6G(SCH_1):PVDDCR_SOC_P1
BF27 PVDDCR_SOC_P1 VDDCR_SOC_BF27 @T6G_MB_LIB.T6G(SCH_1):PVDDCR_SOC_P1
BF48 PVDDCR_SOC_P1 VDDCR_SOC_BF48 @T6G_MB_LIB.T6G(SCH_1):PVDDCR_SOC_P1
 BM5 PVDDCR_SOC_P1 VDDCR_SOC_BM5 @T6G_MB_LIB.T6G(SCH_1):PVDDCR_SOC_P1
BJ48 PVDDCR_SOC_P1 VDDCR_SOC_BJ48 @T6G_MB_LIB.T6G(SCH_1):PVDDCR_SOC_P1
BJ11 PVDDCR_SOC_P1 VDDCR_SOC_BJ11 @T6G_MB_LIB.T6G(SCH_1):PVDDCR_SOC_P1
 BJ4 PVDDCR_SOC_P1 VDDCR_SOC_BJ4 @T6G_MB_LIB.T6G(SCH_1):PVDDCR_SOC_P1
BH48 PVDDCR_SOC_P1 VDDCR_SOC_BH48 @T6G_MB_LIB.T6G(SCH_1):PVDDCR_SOC_P1
BH25 PVDDCR_SOC_P1 VDDCR_SOC_BH25 @T6G_MB_LIB.T6G(SCH_1):PVDDCR_SOC_P1
BH23 PVDDCR_SOC_P1 VDDCR_SOC_BH23 @T6G_MB_LIB.T6G(SCH_1):PVDDCR_SOC_P1
BG48 PVDDCR_SOC_P1 VDDCR_SOC_BG48 @T6G_MB_LIB.T6G(SCH_1):PVDDCR_SOC_P1
BG28 PVDDCR_SOC_P1 VDDCR_SOC_BG28 @T6G_MB_LIB.T6G(SCH_1):PVDDCR_SOC_P1
BG26 PVDDCR_SOC_P1 VDDCR_SOC_BG26 @T6G_MB_LIB.T6G(SCH_1):PVDDCR_SOC_P1
BG24 PVDDCR_SOC_P1 VDDCR_SOC_BG24 @T6G_MB_LIB.T6G(SCH_1):PVDDCR_SOC_P1
BG22 PVDDCR_SOC_P1 VDDCR_SOC_BG22 @T6G_MB_LIB.T6G(SCH_1):PVDDCR_SOC_P1

Q_RES_0402LF-0,5%,1/16W,CHIP,CS00002JB13  I51  R374
   1 PVDD18_S5_P1      A @T6G_MB_LIB.T6G(SCH_1):PVDD18_S5_P1
   2 CPU1_VDDBT_RTC_G      B @T6G_MB_LIB.T6G(SCH_1):CPU1_VDDBT_RTC_G

Q_RES_0402LF-0,5%,1/16W,EMPTY,CS00002JB13  I52  R373
   1 P1V5_BAT      A @T6G_MB_LIB.T6G(SCH_1):P1V5_BAT
   2 CPU1_VDDBT_RTC_G      B @T6G_MB_LIB.T6G(SCH_1):CPU1_VDDBT_RTC_G


DRAWING: @T6G_MB_LIB.T6G(SCH_1):PAGE58 

GENOA_SP5-SOCKET6096_13568-001,SMLF,IO,DGA^6000030  I1  U26
 H37    GND VSS_H37 @T6G_MB_LIB.T6G(SCH_1):GND
 H39    GND VSS_H39 @T6G_MB_LIB.T6G(SCH_1):GND
 H42    GND VSS_H42 @T6G_MB_LIB.T6G(SCH_1):GND
 H45    GND VSS_H45 @T6G_MB_LIB.T6G(SCH_1):GND
 H48    GND VSS_H48 @T6G_MB_LIB.T6G(SCH_1):GND
 H51    GND VSS_H51 @T6G_MB_LIB.T6G(SCH_1):GND
 H54    GND VSS_H54 @T6G_MB_LIB.T6G(SCH_1):GND
 H59    GND VSS_H59 @T6G_MB_LIB.T6G(SCH_1):GND
 H61    GND VSS_H61 @T6G_MB_LIB.T6G(SCH_1):GND
 H66    GND VSS_H66 @T6G_MB_LIB.T6G(SCH_1):GND
 H68    GND VSS_H68 @T6G_MB_LIB.T6G(SCH_1):GND
 H73    GND VSS_H73 @T6G_MB_LIB.T6G(SCH_1):GND
  J1    GND VSS_J1 @T6G_MB_LIB.T6G(SCH_1):GND
  J4    GND VSS_J4 @T6G_MB_LIB.T6G(SCH_1):GND
  J6    GND VSS_J6 @T6G_MB_LIB.T6G(SCH_1):GND
  J8    GND VSS_J8 @T6G_MB_LIB.T6G(SCH_1):GND
 J11    GND VSS_J11 @T6G_MB_LIB.T6G(SCH_1):GND
 J13    GND VSS_J13 @T6G_MB_LIB.T6G(SCH_1):GND
  A3    GND VSS_A3 @T6G_MB_LIB.T6G(SCH_1):GND
  A9    GND VSS_A9 @T6G_MB_LIB.T6G(SCH_1):GND
 A15    GND VSS_A15 @T6G_MB_LIB.T6G(SCH_1):GND
 A21    GND VSS_A21 @T6G_MB_LIB.T6G(SCH_1):GND
 A27    GND VSS_A27 @T6G_MB_LIB.T6G(SCH_1):GND
 A43    GND VSS_A43 @T6G_MB_LIB.T6G(SCH_1):GND
 A44    GND VSS_A44 @T6G_MB_LIB.T6G(SCH_1):GND
 A47    GND VSS_A47 @T6G_MB_LIB.T6G(SCH_1):GND
 A49    GND VSS_A49 @T6G_MB_LIB.T6G(SCH_1):GND
 A53    GND VSS_A53 @T6G_MB_LIB.T6G(SCH_1):GND
 A61    GND VSS_A61 @T6G_MB_LIB.T6G(SCH_1):GND
 A67    GND VSS_A67 @T6G_MB_LIB.T6G(SCH_1):GND
 A72    GND VSS_A72 @T6G_MB_LIB.T6G(SCH_1):GND
 A73    GND VSS_A73 @T6G_MB_LIB.T6G(SCH_1):GND
  B7    GND VSS_B7 @T6G_MB_LIB.T6G(SCH_1):GND
  B8    GND VSS_B8 @T6G_MB_LIB.T6G(SCH_1):GND
 B10    GND VSS_B10 @T6G_MB_LIB.T6G(SCH_1):GND
 B11    GND VSS_B11 @T6G_MB_LIB.T6G(SCH_1):GND
 B13    GND VSS_B13 @T6G_MB_LIB.T6G(SCH_1):GND
 B18    GND VSS_B18 @T6G_MB_LIB.T6G(SCH_1):GND
 B24    GND VSS_B24 @T6G_MB_LIB.T6G(SCH_1):GND
 B27    GND VSS_B27 @T6G_MB_LIB.T6G(SCH_1):GND
 B30    GND VSS_B30 @T6G_MB_LIB.T6G(SCH_1):GND
 B33    GND VSS_B33 @T6G_MB_LIB.T6G(SCH_1):GND
 B37    GND VSS_B37 @T6G_MB_LIB.T6G(SCH_1):GND
 B39    GND VSS_B39 @T6G_MB_LIB.T6G(SCH_1):GND
 B43    GND VSS_B43 @T6G_MB_LIB.T6G(SCH_1):GND
 B46    GND VSS_B46 @T6G_MB_LIB.T6G(SCH_1):GND
 B49    GND VSS_B49 @T6G_MB_LIB.T6G(SCH_1):GND
 B52    GND VSS_B52 @T6G_MB_LIB.T6G(SCH_1):GND
 B55    GND VSS_B55 @T6G_MB_LIB.T6G(SCH_1):GND
 B59    GND VSS_B59 @T6G_MB_LIB.T6G(SCH_1):GND
 B62    GND VSS_B62 @T6G_MB_LIB.T6G(SCH_1):GND
 B65    GND VSS_B65 @T6G_MB_LIB.T6G(SCH_1):GND
 B68    GND VSS_B68 @T6G_MB_LIB.T6G(SCH_1):GND
 B70    GND VSS_B70 @T6G_MB_LIB.T6G(SCH_1):GND
  C1    GND VSS_C1 @T6G_MB_LIB.T6G(SCH_1):GND
  C5    GND VSS_C5 @T6G_MB_LIB.T6G(SCH_1):GND
  C8    GND VSS_C8 @T6G_MB_LIB.T6G(SCH_1):GND
 C10    GND VSS_C10 @T6G_MB_LIB.T6G(SCH_1):GND
 C11    GND VSS_C11 @T6G_MB_LIB.T6G(SCH_1):GND
 C13    GND VSS_C13 @T6G_MB_LIB.T6G(SCH_1):GND
 C15    GND VSS_C15 @T6G_MB_LIB.T6G(SCH_1):GND
 C21    GND VSS_C21 @T6G_MB_LIB.T6G(SCH_1):GND
 C24    GND VSS_C24 @T6G_MB_LIB.T6G(SCH_1):GND
 C27    GND VSS_C27 @T6G_MB_LIB.T6G(SCH_1):GND
 C30    GND VSS_C30 @T6G_MB_LIB.T6G(SCH_1):GND
 C36    GND VSS_C36 @T6G_MB_LIB.T6G(SCH_1):GND
 C40    GND VSS_C40 @T6G_MB_LIB.T6G(SCH_1):GND
 C43    GND VSS_C43 @T6G_MB_LIB.T6G(SCH_1):GND
 C46    GND VSS_C46 @T6G_MB_LIB.T6G(SCH_1):GND
 C49    GND VSS_C49 @T6G_MB_LIB.T6G(SCH_1):GND
 C52    GND VSS_C52 @T6G_MB_LIB.T6G(SCH_1):GND
 C55    GND VSS_C55 @T6G_MB_LIB.T6G(SCH_1):GND
 C56    GND VSS_C56 @T6G_MB_LIB.T6G(SCH_1):GND
 C57    GND VSS_C57 @T6G_MB_LIB.T6G(SCH_1):GND
 C61    GND VSS_C61 @T6G_MB_LIB.T6G(SCH_1):GND
 C64    GND VSS_C64 @T6G_MB_LIB.T6G(SCH_1):GND
 C67    GND VSS_C67 @T6G_MB_LIB.T6G(SCH_1):GND
 C69    GND VSS_C69 @T6G_MB_LIB.T6G(SCH_1):GND
 C71    GND VSS_C71 @T6G_MB_LIB.T6G(SCH_1):GND
 C73    GND VSS_C73 @T6G_MB_LIB.T6G(SCH_1):GND
 C75    GND VSS_C75 @T6G_MB_LIB.T6G(SCH_1):GND
  D2    GND VSS_D2 @T6G_MB_LIB.T6G(SCH_1):GND
  D3    GND VSS_D3 @T6G_MB_LIB.T6G(SCH_1):GND
  D5    GND VSS_D5 @T6G_MB_LIB.T6G(SCH_1):GND
  D6    GND VSS_D6 @T6G_MB_LIB.T6G(SCH_1):GND
  D9    GND VSS_D9 @T6G_MB_LIB.T6G(SCH_1):GND
 D10    GND VSS_D10 @T6G_MB_LIB.T6G(SCH_1):GND
 D12    GND VSS_D12 @T6G_MB_LIB.T6G(SCH_1):GND
 D13    GND VSS_D13 @T6G_MB_LIB.T6G(SCH_1):GND
 D16    GND VSS_D16 @T6G_MB_LIB.T6G(SCH_1):GND
 D17    GND VSS_D17 @T6G_MB_LIB.T6G(SCH_1):GND
 D19    GND VSS_D19 @T6G_MB_LIB.T6G(SCH_1):GND
 D20    GND VSS_D20 @T6G_MB_LIB.T6G(SCH_1):GND
 D21    GND VSS_D21 @T6G_MB_LIB.T6G(SCH_1):GND
 D24    GND VSS_D24 @T6G_MB_LIB.T6G(SCH_1):GND
 D25    GND VSS_D25 @T6G_MB_LIB.T6G(SCH_1):GND
 D26    GND VSS_D26 @T6G_MB_LIB.T6G(SCH_1):GND
 D27    GND VSS_D27 @T6G_MB_LIB.T6G(SCH_1):GND
 D28    GND VSS_D28 @T6G_MB_LIB.T6G(SCH_1):GND
 D29    GND VSS_D29 @T6G_MB_LIB.T6G(SCH_1):GND
 D30    GND VSS_D30 @T6G_MB_LIB.T6G(SCH_1):GND
 D31    GND VSS_D31 @T6G_MB_LIB.T6G(SCH_1):GND
 D35    GND VSS_D35 @T6G_MB_LIB.T6G(SCH_1):GND
 D37    GND VSS_D37 @T6G_MB_LIB.T6G(SCH_1):GND
 D39    GND VSS_D39 @T6G_MB_LIB.T6G(SCH_1):GND
 D40    GND VSS_D40 @T6G_MB_LIB.T6G(SCH_1):GND
 D41    GND VSS_D41 @T6G_MB_LIB.T6G(SCH_1):GND
 D42    GND VSS_D42 @T6G_MB_LIB.T6G(SCH_1):GND
 D43    GND VSS_D43 @T6G_MB_LIB.T6G(SCH_1):GND
 D44    GND VSS_D44 @T6G_MB_LIB.T6G(SCH_1):GND
 D45    GND VSS_D45 @T6G_MB_LIB.T6G(SCH_1):GND
 D46    GND VSS_D46 @T6G_MB_LIB.T6G(SCH_1):GND
 D47    GND VSS_D47 @T6G_MB_LIB.T6G(SCH_1):GND
 D48    GND VSS_D48 @T6G_MB_LIB.T6G(SCH_1):GND
 D49    GND VSS_D49 @T6G_MB_LIB.T6G(SCH_1):GND
 D50    GND VSS_D50 @T6G_MB_LIB.T6G(SCH_1):GND
 D51    GND VSS_D51 @T6G_MB_LIB.T6G(SCH_1):GND
 D52    GND VSS_D52 @T6G_MB_LIB.T6G(SCH_1):GND
 D53    GND VSS_D53 @T6G_MB_LIB.T6G(SCH_1):GND
 D54    GND VSS_D54 @T6G_MB_LIB.T6G(SCH_1):GND
 D57    GND VSS_D57 @T6G_MB_LIB.T6G(SCH_1):GND
 D59    GND VSS_D59 @T6G_MB_LIB.T6G(SCH_1):GND
 D60    GND VSS_D60 @T6G_MB_LIB.T6G(SCH_1):GND
 D61    GND VSS_D61 @T6G_MB_LIB.T6G(SCH_1):GND
 D63    GND VSS_D63 @T6G_MB_LIB.T6G(SCH_1):GND
 D64    GND VSS_D64 @T6G_MB_LIB.T6G(SCH_1):GND
 D66    GND VSS_D66 @T6G_MB_LIB.T6G(SCH_1):GND
 D67    GND VSS_D67 @T6G_MB_LIB.T6G(SCH_1):GND
 D70    GND VSS_D70 @T6G_MB_LIB.T6G(SCH_1):GND
 D71    GND VSS_D71 @T6G_MB_LIB.T6G(SCH_1):GND
 D73    GND VSS_D73 @T6G_MB_LIB.T6G(SCH_1):GND
 D74    GND VSS_D74 @T6G_MB_LIB.T6G(SCH_1):GND
  E1    GND VSS_E1 @T6G_MB_LIB.T6G(SCH_1):GND
  E3    GND VSS_E3 @T6G_MB_LIB.T6G(SCH_1):GND
  E6    GND VSS_E6 @T6G_MB_LIB.T6G(SCH_1):GND
  E7    GND VSS_E7 @T6G_MB_LIB.T6G(SCH_1):GND
  E8    GND VSS_E8 @T6G_MB_LIB.T6G(SCH_1):GND
 E10    GND VSS_E10 @T6G_MB_LIB.T6G(SCH_1):GND
 E13    GND VSS_E13 @T6G_MB_LIB.T6G(SCH_1):GND
 E14    GND VSS_E14 @T6G_MB_LIB.T6G(SCH_1):GND
 E15    GND VSS_E15 @T6G_MB_LIB.T6G(SCH_1):GND
 E17    GND VSS_E17 @T6G_MB_LIB.T6G(SCH_1):GND
 E18    GND VSS_E18 @T6G_MB_LIB.T6G(SCH_1):GND
 E20    GND VSS_E20 @T6G_MB_LIB.T6G(SCH_1):GND
 E21    GND VSS_E21 @T6G_MB_LIB.T6G(SCH_1):GND
 E52    GND VSS_E52 @T6G_MB_LIB.T6G(SCH_1):GND
 E53    GND VSS_E53 @T6G_MB_LIB.T6G(SCH_1):GND
 E55    GND VSS_E55 @T6G_MB_LIB.T6G(SCH_1):GND
 E56    GND VSS_E56 @T6G_MB_LIB.T6G(SCH_1):GND
 E58    GND VSS_E58 @T6G_MB_LIB.T6G(SCH_1):GND
 E59    GND VSS_E59 @T6G_MB_LIB.T6G(SCH_1):GND
 E61    GND VSS_E61 @T6G_MB_LIB.T6G(SCH_1):GND
 E62    GND VSS_E62 @T6G_MB_LIB.T6G(SCH_1):GND
 E63    GND VSS_E63 @T6G_MB_LIB.T6G(SCH_1):GND
 E65    GND VSS_E65 @T6G_MB_LIB.T6G(SCH_1):GND
 E66    GND VSS_E66 @T6G_MB_LIB.T6G(SCH_1):GND
 E68    GND VSS_E68 @T6G_MB_LIB.T6G(SCH_1):GND
 E69    GND VSS_E69 @T6G_MB_LIB.T6G(SCH_1):GND
 E70    GND VSS_E70 @T6G_MB_LIB.T6G(SCH_1):GND
 E72    GND VSS_E72 @T6G_MB_LIB.T6G(SCH_1):GND
 E73    GND VSS_E73 @T6G_MB_LIB.T6G(SCH_1):GND
 E75    GND VSS_E75 @T6G_MB_LIB.T6G(SCH_1):GND
  F3    GND VSS_F3 @T6G_MB_LIB.T6G(SCH_1):GND
  F5    GND VSS_F5 @T6G_MB_LIB.T6G(SCH_1):GND
  F8    GND VSS_F8 @T6G_MB_LIB.T6G(SCH_1):GND
 F10    GND VSS_F10 @T6G_MB_LIB.T6G(SCH_1):GND
 F12    GND VSS_F12 @T6G_MB_LIB.T6G(SCH_1):GND
 F15    GND VSS_F15 @T6G_MB_LIB.T6G(SCH_1):GND
 F17    GND VSS_F17 @T6G_MB_LIB.T6G(SCH_1):GND
 F19    GND VSS_F19 @T6G_MB_LIB.T6G(SCH_1):GND
 F23    GND VSS_F23 @T6G_MB_LIB.T6G(SCH_1):GND
 F24    GND VSS_F24 @T6G_MB_LIB.T6G(SCH_1):GND
 F26    GND VSS_F26 @T6G_MB_LIB.T6G(SCH_1):GND
 F27    GND VSS_F27 @T6G_MB_LIB.T6G(SCH_1):GND
 F29    GND VSS_F29 @T6G_MB_LIB.T6G(SCH_1):GND
 F30    GND VSS_F30 @T6G_MB_LIB.T6G(SCH_1):GND
 F32    GND VSS_F32 @T6G_MB_LIB.T6G(SCH_1):GND
 F33    GND VSS_F33 @T6G_MB_LIB.T6G(SCH_1):GND
 F35    GND VSS_F35 @T6G_MB_LIB.T6G(SCH_1):GND
 F36    GND VSS_F36 @T6G_MB_LIB.T6G(SCH_1):GND
 F37    GND VSS_F37 @T6G_MB_LIB.T6G(SCH_1):GND
 F39    GND VSS_F39 @T6G_MB_LIB.T6G(SCH_1):GND
 F40    GND VSS_F40 @T6G_MB_LIB.T6G(SCH_1):GND
 F41    GND VSS_F41 @T6G_MB_LIB.T6G(SCH_1):GND
 F43    GND VSS_F43 @T6G_MB_LIB.T6G(SCH_1):GND
 F44    GND VSS_F44 @T6G_MB_LIB.T6G(SCH_1):GND
 F46    GND VSS_F46 @T6G_MB_LIB.T6G(SCH_1):GND
 F47    GND VSS_F47 @T6G_MB_LIB.T6G(SCH_1):GND
 F49    GND VSS_F49 @T6G_MB_LIB.T6G(SCH_1):GND
 F50    GND VSS_F50 @T6G_MB_LIB.T6G(SCH_1):GND
 F52    GND VSS_F52 @T6G_MB_LIB.T6G(SCH_1):GND
 F53    GND VSS_F53 @T6G_MB_LIB.T6G(SCH_1):GND
 F57    GND VSS_F57 @T6G_MB_LIB.T6G(SCH_1):GND
 F59    GND VSS_F59 @T6G_MB_LIB.T6G(SCH_1):GND
 F61    GND VSS_F61 @T6G_MB_LIB.T6G(SCH_1):GND
 F64    GND VSS_F64 @T6G_MB_LIB.T6G(SCH_1):GND
 F66    GND VSS_F66 @T6G_MB_LIB.T6G(SCH_1):GND
 F68    GND VSS_F68 @T6G_MB_LIB.T6G(SCH_1):GND
 F71    GND VSS_F71 @T6G_MB_LIB.T6G(SCH_1):GND
 F73    GND VSS_F73 @T6G_MB_LIB.T6G(SCH_1):GND
  G1    GND VSS_G1 @T6G_MB_LIB.T6G(SCH_1):GND
  G4    GND VSS_G4 @T6G_MB_LIB.T6G(SCH_1):GND
  G6    GND VSS_G6 @T6G_MB_LIB.T6G(SCH_1):GND
  G8    GND VSS_G8 @T6G_MB_LIB.T6G(SCH_1):GND
 G11    GND VSS_G11 @T6G_MB_LIB.T6G(SCH_1):GND
 G13    GND VSS_G13 @T6G_MB_LIB.T6G(SCH_1):GND
 G15    GND VSS_G15 @T6G_MB_LIB.T6G(SCH_1):GND
 G18    GND VSS_G18 @T6G_MB_LIB.T6G(SCH_1):GND
 G20    GND VSS_G20 @T6G_MB_LIB.T6G(SCH_1):GND
 G22    GND VSS_G22 @T6G_MB_LIB.T6G(SCH_1):GND
 G25    GND VSS_G25 @T6G_MB_LIB.T6G(SCH_1):GND
 G28    GND VSS_G28 @T6G_MB_LIB.T6G(SCH_1):GND
 G31    GND VSS_G31 @T6G_MB_LIB.T6G(SCH_1):GND
 G34    GND VSS_G34 @T6G_MB_LIB.T6G(SCH_1):GND
 G42    GND VSS_G42 @T6G_MB_LIB.T6G(SCH_1):GND
 G45    GND VSS_G45 @T6G_MB_LIB.T6G(SCH_1):GND
 G48    GND VSS_G48 @T6G_MB_LIB.T6G(SCH_1):GND
 G51    GND VSS_G51 @T6G_MB_LIB.T6G(SCH_1):GND
 G54    GND VSS_G54 @T6G_MB_LIB.T6G(SCH_1):GND
 G56    GND VSS_G56 @T6G_MB_LIB.T6G(SCH_1):GND
 G58    GND VSS_G58 @T6G_MB_LIB.T6G(SCH_1):GND
 G61    GND VSS_G61 @T6G_MB_LIB.T6G(SCH_1):GND
 G63    GND VSS_G63 @T6G_MB_LIB.T6G(SCH_1):GND
 G65    GND VSS_G65 @T6G_MB_LIB.T6G(SCH_1):GND
 G68    GND VSS_G68 @T6G_MB_LIB.T6G(SCH_1):GND
 G70    GND VSS_G70 @T6G_MB_LIB.T6G(SCH_1):GND
 G72    GND VSS_G72 @T6G_MB_LIB.T6G(SCH_1):GND
 G75    GND VSS_G75 @T6G_MB_LIB.T6G(SCH_1):GND
  H3    GND VSS_H3 @T6G_MB_LIB.T6G(SCH_1):GND
  H8    GND VSS_H8 @T6G_MB_LIB.T6G(SCH_1):GND
 H10    GND VSS_H10 @T6G_MB_LIB.T6G(SCH_1):GND
 H15    GND VSS_H15 @T6G_MB_LIB.T6G(SCH_1):GND
 H17    GND VSS_H17 @T6G_MB_LIB.T6G(SCH_1):GND
 H22    GND VSS_H22 @T6G_MB_LIB.T6G(SCH_1):GND
 H25    GND VSS_H25 @T6G_MB_LIB.T6G(SCH_1):GND
 H28    GND VSS_H28 @T6G_MB_LIB.T6G(SCH_1):GND
 H31    GND VSS_H31 @T6G_MB_LIB.T6G(SCH_1):GND
 H34    GND VSS_H34 @T6G_MB_LIB.T6G(SCH_1):GND

GENOA_SP5-SOCKET6096_13568-001,SMLF,IO,DGA^6000030  I3  U26
AW63    GND VSS_AW63 @T6G_MB_LIB.T6G(SCH_1):GND
AW65    GND VSS_AW65 @T6G_MB_LIB.T6G(SCH_1):GND
AW68    GND VSS_AW68 @T6G_MB_LIB.T6G(SCH_1):GND
AW70    GND VSS_AW70 @T6G_MB_LIB.T6G(SCH_1):GND
AW72    GND VSS_AW72 @T6G_MB_LIB.T6G(SCH_1):GND
AW75    GND VSS_AW75 @T6G_MB_LIB.T6G(SCH_1):GND
 AY3    GND VSS_AY3 @T6G_MB_LIB.T6G(SCH_1):GND
 AY5    GND VSS_AY5 @T6G_MB_LIB.T6G(SCH_1):GND
 AY8    GND VSS_AY8 @T6G_MB_LIB.T6G(SCH_1):GND
AY10    GND VSS_AY10 @T6G_MB_LIB.T6G(SCH_1):GND
AY12    GND VSS_AY12 @T6G_MB_LIB.T6G(SCH_1):GND
AY15    GND VSS_AY15 @T6G_MB_LIB.T6G(SCH_1):GND
AY17    GND VSS_AY17 @T6G_MB_LIB.T6G(SCH_1):GND
AY19    GND VSS_AY19 @T6G_MB_LIB.T6G(SCH_1):GND
AY23    GND VSS_AY23 @T6G_MB_LIB.T6G(SCH_1):GND
AY25    GND VSS_AY25 @T6G_MB_LIB.T6G(SCH_1):GND
AY27    GND VSS_AY27 @T6G_MB_LIB.T6G(SCH_1):GND
AY48    GND VSS_AY48 @T6G_MB_LIB.T6G(SCH_1):GND
AY50    GND VSS_AY50 @T6G_MB_LIB.T6G(SCH_1):GND
AY52    GND VSS_AY52 @T6G_MB_LIB.T6G(SCH_1):GND
AY54    GND VSS_AY54 @T6G_MB_LIB.T6G(SCH_1):GND
AY57    GND VSS_AY57 @T6G_MB_LIB.T6G(SCH_1):GND
AY59    GND VSS_AY59 @T6G_MB_LIB.T6G(SCH_1):GND
AY61    GND VSS_AY61 @T6G_MB_LIB.T6G(SCH_1):GND
AY64    GND VSS_AY64 @T6G_MB_LIB.T6G(SCH_1):GND
AY66    GND VSS_AY66 @T6G_MB_LIB.T6G(SCH_1):GND
AY68    GND VSS_AY68 @T6G_MB_LIB.T6G(SCH_1):GND
AY71    GND VSS_AY71 @T6G_MB_LIB.T6G(SCH_1):GND
AY73    GND VSS_AY73 @T6G_MB_LIB.T6G(SCH_1):GND
 BA1    GND VSS_BA1 @T6G_MB_LIB.T6G(SCH_1):GND
 BA6    GND VSS_BA6 @T6G_MB_LIB.T6G(SCH_1):GND
 BA8    GND VSS_BA8 @T6G_MB_LIB.T6G(SCH_1):GND
BA13    GND VSS_BA13 @T6G_MB_LIB.T6G(SCH_1):GND
BA15    GND VSS_BA15 @T6G_MB_LIB.T6G(SCH_1):GND
BA20    GND VSS_BA20 @T6G_MB_LIB.T6G(SCH_1):GND
BA22    GND VSS_BA22 @T6G_MB_LIB.T6G(SCH_1):GND
BA24    GND VSS_BA24 @T6G_MB_LIB.T6G(SCH_1):GND
BA26    GND VSS_BA26 @T6G_MB_LIB.T6G(SCH_1):GND
BA28    GND VSS_BA28 @T6G_MB_LIB.T6G(SCH_1):GND
BA49    GND VSS_BA49 @T6G_MB_LIB.T6G(SCH_1):GND
BA51    GND VSS_BA51 @T6G_MB_LIB.T6G(SCH_1):GND
BA53    GND VSS_BA53 @T6G_MB_LIB.T6G(SCH_1):GND
BA56    GND VSS_BA56 @T6G_MB_LIB.T6G(SCH_1):GND
BA61    GND VSS_BA61 @T6G_MB_LIB.T6G(SCH_1):GND
BA63    GND VSS_BA63 @T6G_MB_LIB.T6G(SCH_1):GND
BA68    GND VSS_BA68 @T6G_MB_LIB.T6G(SCH_1):GND
BA70    GND VSS_BA70 @T6G_MB_LIB.T6G(SCH_1):GND
BA75    GND VSS_BA75 @T6G_MB_LIB.T6G(SCH_1):GND
 BB3    GND VSS_BB3 @T6G_MB_LIB.T6G(SCH_1):GND
 BB5    GND VSS_BB5 @T6G_MB_LIB.T6G(SCH_1):GND
 BB8    GND VSS_BB8 @T6G_MB_LIB.T6G(SCH_1):GND
BB10    GND VSS_BB10 @T6G_MB_LIB.T6G(SCH_1):GND
BB12    GND VSS_BB12 @T6G_MB_LIB.T6G(SCH_1):GND
BB15    GND VSS_BB15 @T6G_MB_LIB.T6G(SCH_1):GND
BB17    GND VSS_BB17 @T6G_MB_LIB.T6G(SCH_1):GND
BB19    GND VSS_BB19 @T6G_MB_LIB.T6G(SCH_1):GND
BB23    GND VSS_BB23 @T6G_MB_LIB.T6G(SCH_1):GND
BB25    GND VSS_BB25 @T6G_MB_LIB.T6G(SCH_1):GND
BB27    GND VSS_BB27 @T6G_MB_LIB.T6G(SCH_1):GND
BB48    GND VSS_BB48 @T6G_MB_LIB.T6G(SCH_1):GND
BB50    GND VSS_BB50 @T6G_MB_LIB.T6G(SCH_1):GND
BB52    GND VSS_BB52 @T6G_MB_LIB.T6G(SCH_1):GND
BB54    GND VSS_BB54 @T6G_MB_LIB.T6G(SCH_1):GND
BB57    GND VSS_BB57 @T6G_MB_LIB.T6G(SCH_1):GND
BB59    GND VSS_BB59 @T6G_MB_LIB.T6G(SCH_1):GND
BB61    GND VSS_BB61 @T6G_MB_LIB.T6G(SCH_1):GND
BB64    GND VSS_BB64 @T6G_MB_LIB.T6G(SCH_1):GND
BB66    GND VSS_BB66 @T6G_MB_LIB.T6G(SCH_1):GND
BB68    GND VSS_BB68 @T6G_MB_LIB.T6G(SCH_1):GND
BB71    GND VSS_BB71 @T6G_MB_LIB.T6G(SCH_1):GND
BB73    GND VSS_BB73 @T6G_MB_LIB.T6G(SCH_1):GND
 BC1    GND VSS_BC1 @T6G_MB_LIB.T6G(SCH_1):GND
 BC4    GND VSS_BC4 @T6G_MB_LIB.T6G(SCH_1):GND
 BC6    GND VSS_BC6 @T6G_MB_LIB.T6G(SCH_1):GND
 BC8    GND VSS_BC8 @T6G_MB_LIB.T6G(SCH_1):GND
BC11    GND VSS_BC11 @T6G_MB_LIB.T6G(SCH_1):GND
BC13    GND VSS_BC13 @T6G_MB_LIB.T6G(SCH_1):GND
BC15    GND VSS_BC15 @T6G_MB_LIB.T6G(SCH_1):GND
BC18    GND VSS_BC18 @T6G_MB_LIB.T6G(SCH_1):GND
BC20    GND VSS_BC20 @T6G_MB_LIB.T6G(SCH_1):GND
BC22    GND VSS_BC22 @T6G_MB_LIB.T6G(SCH_1):GND
BC24    GND VSS_BC24 @T6G_MB_LIB.T6G(SCH_1):GND
BC26    GND VSS_BC26 @T6G_MB_LIB.T6G(SCH_1):GND
BC28    GND VSS_BC28 @T6G_MB_LIB.T6G(SCH_1):GND
BC49    GND VSS_BC49 @T6G_MB_LIB.T6G(SCH_1):GND
BC50    GND VSS_BC50 @T6G_MB_LIB.T6G(SCH_1):GND
BC51    GND VSS_BC51 @T6G_MB_LIB.T6G(SCH_1):GND
BC53    GND VSS_BC53 @T6G_MB_LIB.T6G(SCH_1):GND
BC56    GND VSS_BC56 @T6G_MB_LIB.T6G(SCH_1):GND
BC58    GND VSS_BC58 @T6G_MB_LIB.T6G(SCH_1):GND
BC61    GND VSS_BC61 @T6G_MB_LIB.T6G(SCH_1):GND
BC63    GND VSS_BC63 @T6G_MB_LIB.T6G(SCH_1):GND
BC65    GND VSS_BC65 @T6G_MB_LIB.T6G(SCH_1):GND
BC68    GND VSS_BC68 @T6G_MB_LIB.T6G(SCH_1):GND
BC70    GND VSS_BC70 @T6G_MB_LIB.T6G(SCH_1):GND
BC72    GND VSS_BC72 @T6G_MB_LIB.T6G(SCH_1):GND
BC75    GND VSS_BC75 @T6G_MB_LIB.T6G(SCH_1):GND
 BD3    GND VSS_BD3 @T6G_MB_LIB.T6G(SCH_1):GND
 BD8    GND VSS_BD8 @T6G_MB_LIB.T6G(SCH_1):GND
BD10    GND VSS_BD10 @T6G_MB_LIB.T6G(SCH_1):GND
BD15    GND VSS_BD15 @T6G_MB_LIB.T6G(SCH_1):GND
BD17    GND VSS_BD17 @T6G_MB_LIB.T6G(SCH_1):GND
BD23    GND VSS_BD23 @T6G_MB_LIB.T6G(SCH_1):GND
BD25    GND VSS_BD25 @T6G_MB_LIB.T6G(SCH_1):GND
BD27    GND VSS_BD27 @T6G_MB_LIB.T6G(SCH_1):GND
BD49    GND VSS_BD49 @T6G_MB_LIB.T6G(SCH_1):GND
BD51    GND VSS_BD51 @T6G_MB_LIB.T6G(SCH_1):GND
BD53    GND VSS_BD53 @T6G_MB_LIB.T6G(SCH_1):GND
BD57    GND VSS_BD57 @T6G_MB_LIB.T6G(SCH_1):GND
BD59    GND VSS_BD59 @T6G_MB_LIB.T6G(SCH_1):GND
BD61    GND VSS_BD61 @T6G_MB_LIB.T6G(SCH_1):GND
BD64    GND VSS_BD64 @T6G_MB_LIB.T6G(SCH_1):GND
BD66    GND VSS_BD66 @T6G_MB_LIB.T6G(SCH_1):GND
BD68    GND VSS_BD68 @T6G_MB_LIB.T6G(SCH_1):GND
BD71    GND VSS_BD71 @T6G_MB_LIB.T6G(SCH_1):GND
BD73    GND VSS_BD73 @T6G_MB_LIB.T6G(SCH_1):GND
 BF3    GND VSS_BF3 @T6G_MB_LIB.T6G(SCH_1):GND
 BF5    GND VSS_BF5 @T6G_MB_LIB.T6G(SCH_1):GND
 BF8    GND VSS_BF8 @T6G_MB_LIB.T6G(SCH_1):GND
BF10    GND VSS_BF10 @T6G_MB_LIB.T6G(SCH_1):GND
BF12    GND VSS_BF12 @T6G_MB_LIB.T6G(SCH_1):GND
BF15    GND VSS_BF15 @T6G_MB_LIB.T6G(SCH_1):GND
BF17    GND VSS_BF17 @T6G_MB_LIB.T6G(SCH_1):GND
BF19    GND VSS_BF19 @T6G_MB_LIB.T6G(SCH_1):GND
BF22    GND VSS_BF22 @T6G_MB_LIB.T6G(SCH_1):GND
BF24    GND VSS_BF24 @T6G_MB_LIB.T6G(SCH_1):GND
BF26    GND VSS_BF26 @T6G_MB_LIB.T6G(SCH_1):GND
BF28    GND VSS_BF28 @T6G_MB_LIB.T6G(SCH_1):GND
BF49    GND VSS_BF49 @T6G_MB_LIB.T6G(SCH_1):GND
BF50    GND VSS_BF50 @T6G_MB_LIB.T6G(SCH_1):GND
BF52    GND VSS_BF52 @T6G_MB_LIB.T6G(SCH_1):GND
BF54    GND VSS_BF54 @T6G_MB_LIB.T6G(SCH_1):GND
BF59    GND VSS_BF59 @T6G_MB_LIB.T6G(SCH_1):GND
BF61    GND VSS_BF61 @T6G_MB_LIB.T6G(SCH_1):GND
BF66    GND VSS_BF66 @T6G_MB_LIB.T6G(SCH_1):GND
BF68    GND VSS_BF68 @T6G_MB_LIB.T6G(SCH_1):GND
BF73    GND VSS_BF73 @T6G_MB_LIB.T6G(SCH_1):GND
 BG1    GND VSS_BG1 @T6G_MB_LIB.T6G(SCH_1):GND
 BG4    GND VSS_BG4 @T6G_MB_LIB.T6G(SCH_1):GND
 BG6    GND VSS_BG6 @T6G_MB_LIB.T6G(SCH_1):GND
 BG8    GND VSS_BG8 @T6G_MB_LIB.T6G(SCH_1):GND
BG11    GND VSS_BG11 @T6G_MB_LIB.T6G(SCH_1):GND
BG13    GND VSS_BG13 @T6G_MB_LIB.T6G(SCH_1):GND
BG15    GND VSS_BG15 @T6G_MB_LIB.T6G(SCH_1):GND
BG18    GND VSS_BG18 @T6G_MB_LIB.T6G(SCH_1):GND
BG20    GND VSS_BG20 @T6G_MB_LIB.T6G(SCH_1):GND
BG23    GND VSS_BG23 @T6G_MB_LIB.T6G(SCH_1):GND
BG25    GND VSS_BG25 @T6G_MB_LIB.T6G(SCH_1):GND
BG27    GND VSS_BG27 @T6G_MB_LIB.T6G(SCH_1):GND
BG49    GND VSS_BG49 @T6G_MB_LIB.T6G(SCH_1):GND
BG51    GND VSS_BG51 @T6G_MB_LIB.T6G(SCH_1):GND
BG53    GND VSS_BG53 @T6G_MB_LIB.T6G(SCH_1):GND
BG56    GND VSS_BG56 @T6G_MB_LIB.T6G(SCH_1):GND
BG58    GND VSS_BG58 @T6G_MB_LIB.T6G(SCH_1):GND
BG61    GND VSS_BG61 @T6G_MB_LIB.T6G(SCH_1):GND
BG63    GND VSS_BG63 @T6G_MB_LIB.T6G(SCH_1):GND
BG65    GND VSS_BG65 @T6G_MB_LIB.T6G(SCH_1):GND
BG68    GND VSS_BG68 @T6G_MB_LIB.T6G(SCH_1):GND
BG70    GND VSS_BG70 @T6G_MB_LIB.T6G(SCH_1):GND
BG72    GND VSS_BG72 @T6G_MB_LIB.T6G(SCH_1):GND
BG75    GND VSS_BG75 @T6G_MB_LIB.T6G(SCH_1):GND
 BH3    GND VSS_BH3 @T6G_MB_LIB.T6G(SCH_1):GND
 BH5    GND VSS_BH5 @T6G_MB_LIB.T6G(SCH_1):GND
 BH8    GND VSS_BH8 @T6G_MB_LIB.T6G(SCH_1):GND
BH10    GND VSS_BH10 @T6G_MB_LIB.T6G(SCH_1):GND
BH12    GND VSS_BH12 @T6G_MB_LIB.T6G(SCH_1):GND
BH15    GND VSS_BH15 @T6G_MB_LIB.T6G(SCH_1):GND
BH17    GND VSS_BH17 @T6G_MB_LIB.T6G(SCH_1):GND
BH19    GND VSS_BH19 @T6G_MB_LIB.T6G(SCH_1):GND
BH22    GND VSS_BH22 @T6G_MB_LIB.T6G(SCH_1):GND
BH24    GND VSS_BH24 @T6G_MB_LIB.T6G(SCH_1):GND
BH26    GND VSS_BH26 @T6G_MB_LIB.T6G(SCH_1):GND
BH28    GND VSS_BH28 @T6G_MB_LIB.T6G(SCH_1):GND
BH49    GND VSS_BH49 @T6G_MB_LIB.T6G(SCH_1):GND
BH50    GND VSS_BH50 @T6G_MB_LIB.T6G(SCH_1):GND
BH52    GND VSS_BH52 @T6G_MB_LIB.T6G(SCH_1):GND
BH54    GND VSS_BH54 @T6G_MB_LIB.T6G(SCH_1):GND
BH57    GND VSS_BH57 @T6G_MB_LIB.T6G(SCH_1):GND
BH59    GND VSS_BH59 @T6G_MB_LIB.T6G(SCH_1):GND
BH61    GND VSS_BH61 @T6G_MB_LIB.T6G(SCH_1):GND
BH64    GND VSS_BH64 @T6G_MB_LIB.T6G(SCH_1):GND
BH66    GND VSS_BH66 @T6G_MB_LIB.T6G(SCH_1):GND
BH68    GND VSS_BH68 @T6G_MB_LIB.T6G(SCH_1):GND
BH71    GND VSS_BH71 @T6G_MB_LIB.T6G(SCH_1):GND
BH73    GND VSS_BH73 @T6G_MB_LIB.T6G(SCH_1):GND
 BJ1    GND VSS_BJ1 @T6G_MB_LIB.T6G(SCH_1):GND
 BJ6    GND VSS_BJ6 @T6G_MB_LIB.T6G(SCH_1):GND
 BJ8    GND VSS_BJ8 @T6G_MB_LIB.T6G(SCH_1):GND
BJ13    GND VSS_BJ13 @T6G_MB_LIB.T6G(SCH_1):GND
BJ15    GND VSS_BJ15 @T6G_MB_LIB.T6G(SCH_1):GND
BJ20    GND VSS_BJ20 @T6G_MB_LIB.T6G(SCH_1):GND
BJ22    GND VSS_BJ22 @T6G_MB_LIB.T6G(SCH_1):GND
BJ24    GND VSS_BJ24 @T6G_MB_LIB.T6G(SCH_1):GND
BJ26    GND VSS_BJ26 @T6G_MB_LIB.T6G(SCH_1):GND
BJ28    GND VSS_BJ28 @T6G_MB_LIB.T6G(SCH_1):GND
BJ49    GND VSS_BJ49 @T6G_MB_LIB.T6G(SCH_1):GND
BJ51    GND VSS_BJ51 @T6G_MB_LIB.T6G(SCH_1):GND
BJ53    GND VSS_BJ53 @T6G_MB_LIB.T6G(SCH_1):GND
BJ56    GND VSS_BJ56 @T6G_MB_LIB.T6G(SCH_1):GND
BJ61    GND VSS_BJ61 @T6G_MB_LIB.T6G(SCH_1):GND
BJ63    GND VSS_BJ63 @T6G_MB_LIB.T6G(SCH_1):GND
BJ68    GND VSS_BJ68 @T6G_MB_LIB.T6G(SCH_1):GND
BJ70    GND VSS_BJ70 @T6G_MB_LIB.T6G(SCH_1):GND
BJ75    GND VSS_BJ75 @T6G_MB_LIB.T6G(SCH_1):GND
 BK3    GND VSS_BK3 @T6G_MB_LIB.T6G(SCH_1):GND
 BK5    GND VSS_BK5 @T6G_MB_LIB.T6G(SCH_1):GND
 BK8    GND VSS_BK8 @T6G_MB_LIB.T6G(SCH_1):GND
BK10    GND VSS_BK10 @T6G_MB_LIB.T6G(SCH_1):GND
BK12    GND VSS_BK12 @T6G_MB_LIB.T6G(SCH_1):GND
BK15    GND VSS_BK15 @T6G_MB_LIB.T6G(SCH_1):GND
BK17    GND VSS_BK17 @T6G_MB_LIB.T6G(SCH_1):GND
BK19    GND VSS_BK19 @T6G_MB_LIB.T6G(SCH_1):GND
BK23    GND VSS_BK23 @T6G_MB_LIB.T6G(SCH_1):GND
BK25    GND VSS_BK25 @T6G_MB_LIB.T6G(SCH_1):GND
BK27    GND VSS_BK27 @T6G_MB_LIB.T6G(SCH_1):GND
BK48    GND VSS_BK48 @T6G_MB_LIB.T6G(SCH_1):GND
BK50    GND VSS_BK50 @T6G_MB_LIB.T6G(SCH_1):GND
BK52    GND VSS_BK52 @T6G_MB_LIB.T6G(SCH_1):GND
BK54    GND VSS_BK54 @T6G_MB_LIB.T6G(SCH_1):GND
BK57    GND VSS_BK57 @T6G_MB_LIB.T6G(SCH_1):GND
BK59    GND VSS_BK59 @T6G_MB_LIB.T6G(SCH_1):GND
BK61    GND VSS_BK61 @T6G_MB_LIB.T6G(SCH_1):GND
BK64    GND VSS_BK64 @T6G_MB_LIB.T6G(SCH_1):GND
BK66    GND VSS_BK66 @T6G_MB_LIB.T6G(SCH_1):GND
BK68    GND VSS_BK68 @T6G_MB_LIB.T6G(SCH_1):GND
BK71    GND VSS_BK71 @T6G_MB_LIB.T6G(SCH_1):GND
BK73    GND VSS_BK73 @T6G_MB_LIB.T6G(SCH_1):GND
 BL1    GND VSS_BL1 @T6G_MB_LIB.T6G(SCH_1):GND
 BL4    GND VSS_BL4 @T6G_MB_LIB.T6G(SCH_1):GND
 BL6    GND VSS_BL6 @T6G_MB_LIB.T6G(SCH_1):GND
 BL8    GND VSS_BL8 @T6G_MB_LIB.T6G(SCH_1):GND
BL11    GND VSS_BL11 @T6G_MB_LIB.T6G(SCH_1):GND
BL13    GND VSS_BL13 @T6G_MB_LIB.T6G(SCH_1):GND
BL15    GND VSS_BL15 @T6G_MB_LIB.T6G(SCH_1):GND
BL18    GND VSS_BL18 @T6G_MB_LIB.T6G(SCH_1):GND
BL20    GND VSS_BL20 @T6G_MB_LIB.T6G(SCH_1):GND
BL22    GND VSS_BL22 @T6G_MB_LIB.T6G(SCH_1):GND
BL24    GND VSS_BL24 @T6G_MB_LIB.T6G(SCH_1):GND

GENOA_SP5-SOCKET6096_13568-001,SMLF,IO,DGA^6000030  I6  U26
AM42    GND VSS_AM42 @T6G_MB_LIB.T6G(SCH_1):GND
AM43    GND VSS_AM43 @T6G_MB_LIB.T6G(SCH_1):GND
AM44    GND VSS_AM44 @T6G_MB_LIB.T6G(SCH_1):GND
AM45    GND VSS_AM45 @T6G_MB_LIB.T6G(SCH_1):GND
AM46    GND VSS_AM46 @T6G_MB_LIB.T6G(SCH_1):GND
AM47    GND VSS_AM47 @T6G_MB_LIB.T6G(SCH_1):GND
AM48    GND VSS_AM48 @T6G_MB_LIB.T6G(SCH_1):GND
AM49    GND VSS_AM49 @T6G_MB_LIB.T6G(SCH_1):GND
AM50    GND VSS_AM50 @T6G_MB_LIB.T6G(SCH_1):GND
AM51    GND VSS_AM51 @T6G_MB_LIB.T6G(SCH_1):GND
AM52    GND VSS_AM52 @T6G_MB_LIB.T6G(SCH_1):GND
AM53    GND VSS_AM53 @T6G_MB_LIB.T6G(SCH_1):GND
AM59    GND VSS_AM59 @T6G_MB_LIB.T6G(SCH_1):GND
AM61    GND VSS_AM61 @T6G_MB_LIB.T6G(SCH_1):GND
AM66    GND VSS_AM66 @T6G_MB_LIB.T6G(SCH_1):GND
AM68    GND VSS_AM68 @T6G_MB_LIB.T6G(SCH_1):GND
AM73    GND VSS_AM73 @T6G_MB_LIB.T6G(SCH_1):GND
 AN1    GND VSS_AN1 @T6G_MB_LIB.T6G(SCH_1):GND
 AN4    GND VSS_AN4 @T6G_MB_LIB.T6G(SCH_1):GND
 AN6    GND VSS_AN6 @T6G_MB_LIB.T6G(SCH_1):GND
 AN8    GND VSS_AN8 @T6G_MB_LIB.T6G(SCH_1):GND
AN11    GND VSS_AN11 @T6G_MB_LIB.T6G(SCH_1):GND
AN13    GND VSS_AN13 @T6G_MB_LIB.T6G(SCH_1):GND
AN15    GND VSS_AN15 @T6G_MB_LIB.T6G(SCH_1):GND
AN18    GND VSS_AN18 @T6G_MB_LIB.T6G(SCH_1):GND
AN22    GND VSS_AN22 @T6G_MB_LIB.T6G(SCH_1):GND
AN25    GND VSS_AN25 @T6G_MB_LIB.T6G(SCH_1):GND
AN28    GND VSS_AN28 @T6G_MB_LIB.T6G(SCH_1):GND
AN31    GND VSS_AN31 @T6G_MB_LIB.T6G(SCH_1):GND
AN34    GND VSS_AN34 @T6G_MB_LIB.T6G(SCH_1):GND
AN35    GND VSS_AN35 @T6G_MB_LIB.T6G(SCH_1):GND
AN36    GND VSS_AN36 @T6G_MB_LIB.T6G(SCH_1):GND
AN40    GND VSS_AN40 @T6G_MB_LIB.T6G(SCH_1):GND
AN41    GND VSS_AN41 @T6G_MB_LIB.T6G(SCH_1):GND
AN42    GND VSS_AN42 @T6G_MB_LIB.T6G(SCH_1):GND
AN45    GND VSS_AN45 @T6G_MB_LIB.T6G(SCH_1):GND
AN48    GND VSS_AN48 @T6G_MB_LIB.T6G(SCH_1):GND
AN51    GND VSS_AN51 @T6G_MB_LIB.T6G(SCH_1):GND
AN54    GND VSS_AN54 @T6G_MB_LIB.T6G(SCH_1):GND
AN56    GND VSS_AN56 @T6G_MB_LIB.T6G(SCH_1):GND
AN58    GND VSS_AN58 @T6G_MB_LIB.T6G(SCH_1):GND
AN61    GND VSS_AN61 @T6G_MB_LIB.T6G(SCH_1):GND
AN63    GND VSS_AN63 @T6G_MB_LIB.T6G(SCH_1):GND
AN65    GND VSS_AN65 @T6G_MB_LIB.T6G(SCH_1):GND
AN68    GND VSS_AN68 @T6G_MB_LIB.T6G(SCH_1):GND
AN70    GND VSS_AN70 @T6G_MB_LIB.T6G(SCH_1):GND
AN72    GND VSS_AN72 @T6G_MB_LIB.T6G(SCH_1):GND
AN75    GND VSS_AN75 @T6G_MB_LIB.T6G(SCH_1):GND
 AP3    GND VSS_AP3 @T6G_MB_LIB.T6G(SCH_1):GND
 AP5    GND VSS_AP5 @T6G_MB_LIB.T6G(SCH_1):GND
 AP8    GND VSS_AP8 @T6G_MB_LIB.T6G(SCH_1):GND
AP10    GND VSS_AP10 @T6G_MB_LIB.T6G(SCH_1):GND
AP12    GND VSS_AP12 @T6G_MB_LIB.T6G(SCH_1):GND
AP15    GND VSS_AP15 @T6G_MB_LIB.T6G(SCH_1):GND
AP17    GND VSS_AP17 @T6G_MB_LIB.T6G(SCH_1):GND
AP19    GND VSS_AP19 @T6G_MB_LIB.T6G(SCH_1):GND
AP22    GND VSS_AP22 @T6G_MB_LIB.T6G(SCH_1):GND
AP25    GND VSS_AP25 @T6G_MB_LIB.T6G(SCH_1):GND
AP28    GND VSS_AP28 @T6G_MB_LIB.T6G(SCH_1):GND
AP31    GND VSS_AP31 @T6G_MB_LIB.T6G(SCH_1):GND
AP34    GND VSS_AP34 @T6G_MB_LIB.T6G(SCH_1):GND
AP37    GND VSS_AP37 @T6G_MB_LIB.T6G(SCH_1):GND
AP39    GND VSS_AP39 @T6G_MB_LIB.T6G(SCH_1):GND
AP42    GND VSS_AP42 @T6G_MB_LIB.T6G(SCH_1):GND
AP45    GND VSS_AP45 @T6G_MB_LIB.T6G(SCH_1):GND
AP48    GND VSS_AP48 @T6G_MB_LIB.T6G(SCH_1):GND
AP51    GND VSS_AP51 @T6G_MB_LIB.T6G(SCH_1):GND
AP54    GND VSS_AP54 @T6G_MB_LIB.T6G(SCH_1):GND
AP57    GND VSS_AP57 @T6G_MB_LIB.T6G(SCH_1):GND
AP59    GND VSS_AP59 @T6G_MB_LIB.T6G(SCH_1):GND
AP61    GND VSS_AP61 @T6G_MB_LIB.T6G(SCH_1):GND
AP64    GND VSS_AP64 @T6G_MB_LIB.T6G(SCH_1):GND
AP66    GND VSS_AP66 @T6G_MB_LIB.T6G(SCH_1):GND
AP68    GND VSS_AP68 @T6G_MB_LIB.T6G(SCH_1):GND
AP71    GND VSS_AP71 @T6G_MB_LIB.T6G(SCH_1):GND
AP73    GND VSS_AP73 @T6G_MB_LIB.T6G(SCH_1):GND
 AR1    GND VSS_AR1 @T6G_MB_LIB.T6G(SCH_1):GND
 AR5    GND VSS_AR5 @T6G_MB_LIB.T6G(SCH_1):GND
 AR6    GND VSS_AR6 @T6G_MB_LIB.T6G(SCH_1):GND
 AR8    GND VSS_AR8 @T6G_MB_LIB.T6G(SCH_1):GND
 AR9    GND VSS_AR9 @T6G_MB_LIB.T6G(SCH_1):GND
AR12    GND VSS_AR12 @T6G_MB_LIB.T6G(SCH_1):GND
AR13    GND VSS_AR13 @T6G_MB_LIB.T6G(SCH_1):GND
AR15    GND VSS_AR15 @T6G_MB_LIB.T6G(SCH_1):GND
AR16    GND VSS_AR16 @T6G_MB_LIB.T6G(SCH_1):GND
AR19    GND VSS_AR19 @T6G_MB_LIB.T6G(SCH_1):GND
AR20    GND VSS_AR20 @T6G_MB_LIB.T6G(SCH_1):GND
AR22    GND VSS_AR22 @T6G_MB_LIB.T6G(SCH_1):GND
AR24    GND VSS_AR24 @T6G_MB_LIB.T6G(SCH_1):GND
AR26    GND VSS_AR26 @T6G_MB_LIB.T6G(SCH_1):GND
AR28    GND VSS_AR28 @T6G_MB_LIB.T6G(SCH_1):GND
AR30    GND VSS_AR30 @T6G_MB_LIB.T6G(SCH_1):GND
AR32    GND VSS_AR32 @T6G_MB_LIB.T6G(SCH_1):GND
AR34    GND VSS_AR34 @T6G_MB_LIB.T6G(SCH_1):GND
AR36    GND VSS_AR36 @T6G_MB_LIB.T6G(SCH_1):GND
AR41    GND VSS_AR41 @T6G_MB_LIB.T6G(SCH_1):GND
AR43    GND VSS_AR43 @T6G_MB_LIB.T6G(SCH_1):GND
AR45    GND VSS_AR45 @T6G_MB_LIB.T6G(SCH_1):GND
AR47    GND VSS_AR47 @T6G_MB_LIB.T6G(SCH_1):GND
AR49    GND VSS_AR49 @T6G_MB_LIB.T6G(SCH_1):GND
AR51    GND VSS_AR51 @T6G_MB_LIB.T6G(SCH_1):GND
AR53    GND VSS_AR53 @T6G_MB_LIB.T6G(SCH_1):GND
AR56    GND VSS_AR56 @T6G_MB_LIB.T6G(SCH_1):GND
AR57    GND VSS_AR57 @T6G_MB_LIB.T6G(SCH_1):GND
AR60    GND VSS_AR60 @T6G_MB_LIB.T6G(SCH_1):GND
AR61    GND VSS_AR61 @T6G_MB_LIB.T6G(SCH_1):GND
AR63    GND VSS_AR63 @T6G_MB_LIB.T6G(SCH_1):GND
AR64    GND VSS_AR64 @T6G_MB_LIB.T6G(SCH_1):GND
AR67    GND VSS_AR67 @T6G_MB_LIB.T6G(SCH_1):GND
AR68    GND VSS_AR68 @T6G_MB_LIB.T6G(SCH_1):GND
AR70    GND VSS_AR70 @T6G_MB_LIB.T6G(SCH_1):GND
AR71    GND VSS_AR71 @T6G_MB_LIB.T6G(SCH_1):GND
AR75    GND VSS_AR75 @T6G_MB_LIB.T6G(SCH_1):GND
 AT3    GND VSS_AT3 @T6G_MB_LIB.T6G(SCH_1):GND
 AT4    GND VSS_AT4 @T6G_MB_LIB.T6G(SCH_1):GND
 AT5    GND VSS_AT5 @T6G_MB_LIB.T6G(SCH_1):GND
 AT6    GND VSS_AT6 @T6G_MB_LIB.T6G(SCH_1):GND
 AT8    GND VSS_AT8 @T6G_MB_LIB.T6G(SCH_1):GND
 AT9    GND VSS_AT9 @T6G_MB_LIB.T6G(SCH_1):GND
AT10    GND VSS_AT10 @T6G_MB_LIB.T6G(SCH_1):GND
AT12    GND VSS_AT12 @T6G_MB_LIB.T6G(SCH_1):GND
AT13    GND VSS_AT13 @T6G_MB_LIB.T6G(SCH_1):GND
AT15    GND VSS_AT15 @T6G_MB_LIB.T6G(SCH_1):GND
AT16    GND VSS_AT16 @T6G_MB_LIB.T6G(SCH_1):GND
AT17    GND VSS_AT17 @T6G_MB_LIB.T6G(SCH_1):GND
AT19    GND VSS_AT19 @T6G_MB_LIB.T6G(SCH_1):GND
AT20    GND VSS_AT20 @T6G_MB_LIB.T6G(SCH_1):GND
AT23    GND VSS_AT23 @T6G_MB_LIB.T6G(SCH_1):GND
AT25    GND VSS_AT25 @T6G_MB_LIB.T6G(SCH_1):GND
AT27    GND VSS_AT27 @T6G_MB_LIB.T6G(SCH_1):GND
AT29    GND VSS_AT29 @T6G_MB_LIB.T6G(SCH_1):GND
AT31    GND VSS_AT31 @T6G_MB_LIB.T6G(SCH_1):GND
AT33    GND VSS_AT33 @T6G_MB_LIB.T6G(SCH_1):GND
AT35    GND VSS_AT35 @T6G_MB_LIB.T6G(SCH_1):GND
AT37    GND VSS_AT37 @T6G_MB_LIB.T6G(SCH_1):GND
AT40    GND VSS_AT40 @T6G_MB_LIB.T6G(SCH_1):GND
AT42    GND VSS_AT42 @T6G_MB_LIB.T6G(SCH_1):GND
AT44    GND VSS_AT44 @T6G_MB_LIB.T6G(SCH_1):GND
AT46    GND VSS_AT46 @T6G_MB_LIB.T6G(SCH_1):GND
AT48    GND VSS_AT48 @T6G_MB_LIB.T6G(SCH_1):GND
AT50    GND VSS_AT50 @T6G_MB_LIB.T6G(SCH_1):GND
AT52    GND VSS_AT52 @T6G_MB_LIB.T6G(SCH_1):GND
AT54    GND VSS_AT54 @T6G_MB_LIB.T6G(SCH_1):GND
AT56    GND VSS_AT56 @T6G_MB_LIB.T6G(SCH_1):GND
AT57    GND VSS_AT57 @T6G_MB_LIB.T6G(SCH_1):GND
AT59    GND VSS_AT59 @T6G_MB_LIB.T6G(SCH_1):GND
AT60    GND VSS_AT60 @T6G_MB_LIB.T6G(SCH_1):GND
AT61    GND VSS_AT61 @T6G_MB_LIB.T6G(SCH_1):GND
AT63    GND VSS_AT63 @T6G_MB_LIB.T6G(SCH_1):GND
AT64    GND VSS_AT64 @T6G_MB_LIB.T6G(SCH_1):GND
AT66    GND VSS_AT66 @T6G_MB_LIB.T6G(SCH_1):GND
AT67    GND VSS_AT67 @T6G_MB_LIB.T6G(SCH_1):GND
AT68    GND VSS_AT68 @T6G_MB_LIB.T6G(SCH_1):GND
AT70    GND VSS_AT70 @T6G_MB_LIB.T6G(SCH_1):GND
AT71    GND VSS_AT71 @T6G_MB_LIB.T6G(SCH_1):GND
AT72    GND VSS_AT72 @T6G_MB_LIB.T6G(SCH_1):GND
AT73    GND VSS_AT73 @T6G_MB_LIB.T6G(SCH_1):GND
 AU1    GND VSS_AU1 @T6G_MB_LIB.T6G(SCH_1):GND
 AU3    GND VSS_AU3 @T6G_MB_LIB.T6G(SCH_1):GND
 AU4    GND VSS_AU4 @T6G_MB_LIB.T6G(SCH_1):GND
 AU6    GND VSS_AU6 @T6G_MB_LIB.T6G(SCH_1):GND
 AU8    GND VSS_AU8 @T6G_MB_LIB.T6G(SCH_1):GND
AU11    GND VSS_AU11 @T6G_MB_LIB.T6G(SCH_1):GND
AU13    GND VSS_AU13 @T6G_MB_LIB.T6G(SCH_1):GND
AU15    GND VSS_AU15 @T6G_MB_LIB.T6G(SCH_1):GND
AU18    GND VSS_AU18 @T6G_MB_LIB.T6G(SCH_1):GND
AU20    GND VSS_AU20 @T6G_MB_LIB.T6G(SCH_1):GND
AU22    GND VSS_AU22 @T6G_MB_LIB.T6G(SCH_1):GND
AU24    GND VSS_AU24 @T6G_MB_LIB.T6G(SCH_1):GND
AU26    GND VSS_AU26 @T6G_MB_LIB.T6G(SCH_1):GND
AU28    GND VSS_AU28 @T6G_MB_LIB.T6G(SCH_1):GND
AU30    GND VSS_AU30 @T6G_MB_LIB.T6G(SCH_1):GND
AU32    GND VSS_AU32 @T6G_MB_LIB.T6G(SCH_1):GND
AU34    GND VSS_AU34 @T6G_MB_LIB.T6G(SCH_1):GND
AU36    GND VSS_AU36 @T6G_MB_LIB.T6G(SCH_1):GND
AU41    GND VSS_AU41 @T6G_MB_LIB.T6G(SCH_1):GND
AU43    GND VSS_AU43 @T6G_MB_LIB.T6G(SCH_1):GND
AU45    GND VSS_AU45 @T6G_MB_LIB.T6G(SCH_1):GND
AU47    GND VSS_AU47 @T6G_MB_LIB.T6G(SCH_1):GND
AU49    GND VSS_AU49 @T6G_MB_LIB.T6G(SCH_1):GND
AU51    GND VSS_AU51 @T6G_MB_LIB.T6G(SCH_1):GND
AU53    GND VSS_AU53 @T6G_MB_LIB.T6G(SCH_1):GND
AU56    GND VSS_AU56 @T6G_MB_LIB.T6G(SCH_1):GND
AU58    GND VSS_AU58 @T6G_MB_LIB.T6G(SCH_1):GND
AU61    GND VSS_AU61 @T6G_MB_LIB.T6G(SCH_1):GND
AU63    GND VSS_AU63 @T6G_MB_LIB.T6G(SCH_1):GND
AU65    GND VSS_AU65 @T6G_MB_LIB.T6G(SCH_1):GND
AU68    GND VSS_AU68 @T6G_MB_LIB.T6G(SCH_1):GND
AU70    GND VSS_AU70 @T6G_MB_LIB.T6G(SCH_1):GND
AU72    GND VSS_AU72 @T6G_MB_LIB.T6G(SCH_1):GND
AU73    GND VSS_AU73 @T6G_MB_LIB.T6G(SCH_1):GND
AU75    GND VSS_AU75 @T6G_MB_LIB.T6G(SCH_1):GND
 AV3    GND VSS_AV3 @T6G_MB_LIB.T6G(SCH_1):GND
 AV8    GND VSS_AV8 @T6G_MB_LIB.T6G(SCH_1):GND
AV10    GND VSS_AV10 @T6G_MB_LIB.T6G(SCH_1):GND
AV15    GND VSS_AV15 @T6G_MB_LIB.T6G(SCH_1):GND
AV17    GND VSS_AV17 @T6G_MB_LIB.T6G(SCH_1):GND
AV23    GND VSS_AV23 @T6G_MB_LIB.T6G(SCH_1):GND
AV25    GND VSS_AV25 @T6G_MB_LIB.T6G(SCH_1):GND
AV27    GND VSS_AV27 @T6G_MB_LIB.T6G(SCH_1):GND
AV29    GND VSS_AV29 @T6G_MB_LIB.T6G(SCH_1):GND
AV31    GND VSS_AV31 @T6G_MB_LIB.T6G(SCH_1):GND
AV33    GND VSS_AV33 @T6G_MB_LIB.T6G(SCH_1):GND
AV35    GND VSS_AV35 @T6G_MB_LIB.T6G(SCH_1):GND
AV37    GND VSS_AV37 @T6G_MB_LIB.T6G(SCH_1):GND
AV40    GND VSS_AV40 @T6G_MB_LIB.T6G(SCH_1):GND
AV42    GND VSS_AV42 @T6G_MB_LIB.T6G(SCH_1):GND
AV44    GND VSS_AV44 @T6G_MB_LIB.T6G(SCH_1):GND
AV46    GND VSS_AV46 @T6G_MB_LIB.T6G(SCH_1):GND
AV48    GND VSS_AV48 @T6G_MB_LIB.T6G(SCH_1):GND
AV50    GND VSS_AV50 @T6G_MB_LIB.T6G(SCH_1):GND
AV52    GND VSS_AV52 @T6G_MB_LIB.T6G(SCH_1):GND
AV54    GND VSS_AV54 @T6G_MB_LIB.T6G(SCH_1):GND
AV59    GND VSS_AV59 @T6G_MB_LIB.T6G(SCH_1):GND
AV61    GND VSS_AV61 @T6G_MB_LIB.T6G(SCH_1):GND
AV66    GND VSS_AV66 @T6G_MB_LIB.T6G(SCH_1):GND
AV68    GND VSS_AV68 @T6G_MB_LIB.T6G(SCH_1):GND
AV73    GND VSS_AV73 @T6G_MB_LIB.T6G(SCH_1):GND
 AW1    GND VSS_AW1 @T6G_MB_LIB.T6G(SCH_1):GND
 AW4    GND VSS_AW4 @T6G_MB_LIB.T6G(SCH_1):GND
 AW6    GND VSS_AW6 @T6G_MB_LIB.T6G(SCH_1):GND
 AW8    GND VSS_AW8 @T6G_MB_LIB.T6G(SCH_1):GND
AW11    GND VSS_AW11 @T6G_MB_LIB.T6G(SCH_1):GND
AW13    GND VSS_AW13 @T6G_MB_LIB.T6G(SCH_1):GND
AW15    GND VSS_AW15 @T6G_MB_LIB.T6G(SCH_1):GND
AW18    GND VSS_AW18 @T6G_MB_LIB.T6G(SCH_1):GND
AW20    GND VSS_AW20 @T6G_MB_LIB.T6G(SCH_1):GND
AW22    GND VSS_AW22 @T6G_MB_LIB.T6G(SCH_1):GND
AW24    GND VSS_AW24 @T6G_MB_LIB.T6G(SCH_1):GND
AW26    GND VSS_AW26 @T6G_MB_LIB.T6G(SCH_1):GND
AW28    GND VSS_AW28 @T6G_MB_LIB.T6G(SCH_1):GND
AW49    GND VSS_AW49 @T6G_MB_LIB.T6G(SCH_1):GND
AW51    GND VSS_AW51 @T6G_MB_LIB.T6G(SCH_1):GND
AW53    GND VSS_AW53 @T6G_MB_LIB.T6G(SCH_1):GND
AW56    GND VSS_AW56 @T6G_MB_LIB.T6G(SCH_1):GND
AW58    GND VSS_AW58 @T6G_MB_LIB.T6G(SCH_1):GND
AW61    GND VSS_AW61 @T6G_MB_LIB.T6G(SCH_1):GND

GENOA_SP5-SOCKET6096_13568-001,SMLF,IO,DGA^6000030  I9  U26
AK10    GND VSS_AK10 @T6G_MB_LIB.T6G(SCH_1):GND
AK12    GND VSS_AK12 @T6G_MB_LIB.T6G(SCH_1):GND
AK15    GND VSS_AK15 @T6G_MB_LIB.T6G(SCH_1):GND
AK17    GND VSS_AK17 @T6G_MB_LIB.T6G(SCH_1):GND
AK19    GND VSS_AK19 @T6G_MB_LIB.T6G(SCH_1):GND
AK22    GND VSS_AK22 @T6G_MB_LIB.T6G(SCH_1):GND
AK25    GND VSS_AK25 @T6G_MB_LIB.T6G(SCH_1):GND
AK28    GND VSS_AK28 @T6G_MB_LIB.T6G(SCH_1):GND
AK31    GND VSS_AK31 @T6G_MB_LIB.T6G(SCH_1):GND
AK34    GND VSS_AK34 @T6G_MB_LIB.T6G(SCH_1):GND
AK37    GND VSS_AK37 @T6G_MB_LIB.T6G(SCH_1):GND
AK39    GND VSS_AK39 @T6G_MB_LIB.T6G(SCH_1):GND
AK42    GND VSS_AK42 @T6G_MB_LIB.T6G(SCH_1):GND
AK45    GND VSS_AK45 @T6G_MB_LIB.T6G(SCH_1):GND
AK48    GND VSS_AK48 @T6G_MB_LIB.T6G(SCH_1):GND
AK51    GND VSS_AK51 @T6G_MB_LIB.T6G(SCH_1):GND
AK54    GND VSS_AK54 @T6G_MB_LIB.T6G(SCH_1):GND
AK57    GND VSS_AK57 @T6G_MB_LIB.T6G(SCH_1):GND
AK59    GND VSS_AK59 @T6G_MB_LIB.T6G(SCH_1):GND
AK61    GND VSS_AK61 @T6G_MB_LIB.T6G(SCH_1):GND
AK64    GND VSS_AK64 @T6G_MB_LIB.T6G(SCH_1):GND
AK66    GND VSS_AK66 @T6G_MB_LIB.T6G(SCH_1):GND
AK68    GND VSS_AK68 @T6G_MB_LIB.T6G(SCH_1):GND
AK71    GND VSS_AK71 @T6G_MB_LIB.T6G(SCH_1):GND
AK73    GND VSS_AK73 @T6G_MB_LIB.T6G(SCH_1):GND
 AL1    GND VSS_AL1 @T6G_MB_LIB.T6G(SCH_1):GND
 AL4    GND VSS_AL4 @T6G_MB_LIB.T6G(SCH_1):GND
 AL6    GND VSS_AL6 @T6G_MB_LIB.T6G(SCH_1):GND
 AL8    GND VSS_AL8 @T6G_MB_LIB.T6G(SCH_1):GND
AL11    GND VSS_AL11 @T6G_MB_LIB.T6G(SCH_1):GND
AL13    GND VSS_AL13 @T6G_MB_LIB.T6G(SCH_1):GND
AL15    GND VSS_AL15 @T6G_MB_LIB.T6G(SCH_1):GND
AL18    GND VSS_AL18 @T6G_MB_LIB.T6G(SCH_1):GND
AL20    GND VSS_AL20 @T6G_MB_LIB.T6G(SCH_1):GND
AL22    GND VSS_AL22 @T6G_MB_LIB.T6G(SCH_1):GND
AL25    GND VSS_AL25 @T6G_MB_LIB.T6G(SCH_1):GND
AL28    GND VSS_AL28 @T6G_MB_LIB.T6G(SCH_1):GND
AL31    GND VSS_AL31 @T6G_MB_LIB.T6G(SCH_1):GND
AL34    GND VSS_AL34 @T6G_MB_LIB.T6G(SCH_1):GND
AL42    GND VSS_AL42 @T6G_MB_LIB.T6G(SCH_1):GND
AL45    GND VSS_AL45 @T6G_MB_LIB.T6G(SCH_1):GND
AL48    GND VSS_AL48 @T6G_MB_LIB.T6G(SCH_1):GND
AL51    GND VSS_AL51 @T6G_MB_LIB.T6G(SCH_1):GND
AL54    GND VSS_AL54 @T6G_MB_LIB.T6G(SCH_1):GND
AL56    GND VSS_AL56 @T6G_MB_LIB.T6G(SCH_1):GND
AL58    GND VSS_AL58 @T6G_MB_LIB.T6G(SCH_1):GND
AL61    GND VSS_AL61 @T6G_MB_LIB.T6G(SCH_1):GND
AL63    GND VSS_AL63 @T6G_MB_LIB.T6G(SCH_1):GND
AL65    GND VSS_AL65 @T6G_MB_LIB.T6G(SCH_1):GND
AL68    GND VSS_AL68 @T6G_MB_LIB.T6G(SCH_1):GND
AL70    GND VSS_AL70 @T6G_MB_LIB.T6G(SCH_1):GND
AL72    GND VSS_AL72 @T6G_MB_LIB.T6G(SCH_1):GND
AL75    GND VSS_AL75 @T6G_MB_LIB.T6G(SCH_1):GND
 AM3    GND VSS_AM3 @T6G_MB_LIB.T6G(SCH_1):GND
 AM8    GND VSS_AM8 @T6G_MB_LIB.T6G(SCH_1):GND
AM10    GND VSS_AM10 @T6G_MB_LIB.T6G(SCH_1):GND
AM15    GND VSS_AM15 @T6G_MB_LIB.T6G(SCH_1):GND
AM17    GND VSS_AM17 @T6G_MB_LIB.T6G(SCH_1):GND
AM23    GND VSS_AM23 @T6G_MB_LIB.T6G(SCH_1):GND
AM24    GND VSS_AM24 @T6G_MB_LIB.T6G(SCH_1):GND
AM25    GND VSS_AM25 @T6G_MB_LIB.T6G(SCH_1):GND
AM26    GND VSS_AM26 @T6G_MB_LIB.T6G(SCH_1):GND
AM27    GND VSS_AM27 @T6G_MB_LIB.T6G(SCH_1):GND
AM28    GND VSS_AM28 @T6G_MB_LIB.T6G(SCH_1):GND
AM29    GND VSS_AM29 @T6G_MB_LIB.T6G(SCH_1):GND
AM30    GND VSS_AM30 @T6G_MB_LIB.T6G(SCH_1):GND
AM31    GND VSS_AM31 @T6G_MB_LIB.T6G(SCH_1):GND
AM32    GND VSS_AM32 @T6G_MB_LIB.T6G(SCH_1):GND
AM33    GND VSS_AM33 @T6G_MB_LIB.T6G(SCH_1):GND
AM34    GND VSS_AM34 @T6G_MB_LIB.T6G(SCH_1):GND
AM39    GND VSS_AM39 @T6G_MB_LIB.T6G(SCH_1):GND
AD49    GND VSS_AD49 @T6G_MB_LIB.T6G(SCH_1):GND
AD50    GND VSS_AD50 @T6G_MB_LIB.T6G(SCH_1):GND
AD51    GND VSS_AD51 @T6G_MB_LIB.T6G(SCH_1):GND
AD52    GND VSS_AD52 @T6G_MB_LIB.T6G(SCH_1):GND
AD53    GND VSS_AD53 @T6G_MB_LIB.T6G(SCH_1):GND
AD57    GND VSS_AD57 @T6G_MB_LIB.T6G(SCH_1):GND
AD59    GND VSS_AD59 @T6G_MB_LIB.T6G(SCH_1):GND
AD61    GND VSS_AD61 @T6G_MB_LIB.T6G(SCH_1):GND
AD64    GND VSS_AD64 @T6G_MB_LIB.T6G(SCH_1):GND
AD66    GND VSS_AD66 @T6G_MB_LIB.T6G(SCH_1):GND
AD68    GND VSS_AD68 @T6G_MB_LIB.T6G(SCH_1):GND
AD71    GND VSS_AD71 @T6G_MB_LIB.T6G(SCH_1):GND
AD73    GND VSS_AD73 @T6G_MB_LIB.T6G(SCH_1):GND
 AE1    GND VSS_AE1 @T6G_MB_LIB.T6G(SCH_1):GND
 AE6    GND VSS_AE6 @T6G_MB_LIB.T6G(SCH_1):GND
 AE8    GND VSS_AE8 @T6G_MB_LIB.T6G(SCH_1):GND
AE11    GND VSS_AE11 @T6G_MB_LIB.T6G(SCH_1):GND
AE13    GND VSS_AE13 @T6G_MB_LIB.T6G(SCH_1):GND
AE15    GND VSS_AE15 @T6G_MB_LIB.T6G(SCH_1):GND
AE18    GND VSS_AE18 @T6G_MB_LIB.T6G(SCH_1):GND
AE20    GND VSS_AE20 @T6G_MB_LIB.T6G(SCH_1):GND
AE22    GND VSS_AE22 @T6G_MB_LIB.T6G(SCH_1):GND
AE25    GND VSS_AE25 @T6G_MB_LIB.T6G(SCH_1):GND
AE28    GND VSS_AE28 @T6G_MB_LIB.T6G(SCH_1):GND
AE31    GND VSS_AE31 @T6G_MB_LIB.T6G(SCH_1):GND
AE34    GND VSS_AE34 @T6G_MB_LIB.T6G(SCH_1):GND
AE35    GND VSS_AE35 @T6G_MB_LIB.T6G(SCH_1):GND
AE36    GND VSS_AE36 @T6G_MB_LIB.T6G(SCH_1):GND
AE40    GND VSS_AE40 @T6G_MB_LIB.T6G(SCH_1):GND
AE41    GND VSS_AE41 @T6G_MB_LIB.T6G(SCH_1):GND
AE42    GND VSS_AE42 @T6G_MB_LIB.T6G(SCH_1):GND
AE45    GND VSS_AE45 @T6G_MB_LIB.T6G(SCH_1):GND
AE48    GND VSS_AE48 @T6G_MB_LIB.T6G(SCH_1):GND
AE51    GND VSS_AE51 @T6G_MB_LIB.T6G(SCH_1):GND
AE54    GND VSS_AE54 @T6G_MB_LIB.T6G(SCH_1):GND
AE56    GND VSS_AE56 @T6G_MB_LIB.T6G(SCH_1):GND
AE58    GND VSS_AE58 @T6G_MB_LIB.T6G(SCH_1):GND
AE61    GND VSS_AE61 @T6G_MB_LIB.T6G(SCH_1):GND
AE63    GND VSS_AE63 @T6G_MB_LIB.T6G(SCH_1):GND
AE65    GND VSS_AE65 @T6G_MB_LIB.T6G(SCH_1):GND
AE68    GND VSS_AE68 @T6G_MB_LIB.T6G(SCH_1):GND
AE70    GND VSS_AE70 @T6G_MB_LIB.T6G(SCH_1):GND
AE72    GND VSS_AE72 @T6G_MB_LIB.T6G(SCH_1):GND
AE75    GND VSS_AE75 @T6G_MB_LIB.T6G(SCH_1):GND
 AF3    GND VSS_AF3 @T6G_MB_LIB.T6G(SCH_1):GND
 AF8    GND VSS_AF8 @T6G_MB_LIB.T6G(SCH_1):GND
AF10    GND VSS_AF10 @T6G_MB_LIB.T6G(SCH_1):GND
AF15    GND VSS_AF15 @T6G_MB_LIB.T6G(SCH_1):GND
AF17    GND VSS_AF17 @T6G_MB_LIB.T6G(SCH_1):GND
AF22    GND VSS_AF22 @T6G_MB_LIB.T6G(SCH_1):GND
AF25    GND VSS_AF25 @T6G_MB_LIB.T6G(SCH_1):GND
AF28    GND VSS_AF28 @T6G_MB_LIB.T6G(SCH_1):GND
AF31    GND VSS_AF31 @T6G_MB_LIB.T6G(SCH_1):GND
AF34    GND VSS_AF34 @T6G_MB_LIB.T6G(SCH_1):GND
AF37    GND VSS_AF37 @T6G_MB_LIB.T6G(SCH_1):GND
AF39    GND VSS_AF39 @T6G_MB_LIB.T6G(SCH_1):GND
AF42    GND VSS_AF42 @T6G_MB_LIB.T6G(SCH_1):GND
AF45    GND VSS_AF45 @T6G_MB_LIB.T6G(SCH_1):GND
AF48    GND VSS_AF48 @T6G_MB_LIB.T6G(SCH_1):GND
AF51    GND VSS_AF51 @T6G_MB_LIB.T6G(SCH_1):GND
AF54    GND VSS_AF54 @T6G_MB_LIB.T6G(SCH_1):GND
AF59    GND VSS_AF59 @T6G_MB_LIB.T6G(SCH_1):GND
AF61    GND VSS_AF61 @T6G_MB_LIB.T6G(SCH_1):GND
AF66    GND VSS_AF66 @T6G_MB_LIB.T6G(SCH_1):GND
AF68    GND VSS_AF68 @T6G_MB_LIB.T6G(SCH_1):GND
AF73    GND VSS_AF73 @T6G_MB_LIB.T6G(SCH_1):GND
 AG1    GND VSS_AG1 @T6G_MB_LIB.T6G(SCH_1):GND
 AG4    GND VSS_AG4 @T6G_MB_LIB.T6G(SCH_1):GND
 AG6    GND VSS_AG6 @T6G_MB_LIB.T6G(SCH_1):GND
 AG8    GND VSS_AG8 @T6G_MB_LIB.T6G(SCH_1):GND
AG11    GND VSS_AG11 @T6G_MB_LIB.T6G(SCH_1):GND
AG13    GND VSS_AG13 @T6G_MB_LIB.T6G(SCH_1):GND
AG15    GND VSS_AG15 @T6G_MB_LIB.T6G(SCH_1):GND
AG18    GND VSS_AG18 @T6G_MB_LIB.T6G(SCH_1):GND
AG20    GND VSS_AG20 @T6G_MB_LIB.T6G(SCH_1):GND
AG22    GND VSS_AG22 @T6G_MB_LIB.T6G(SCH_1):GND
AG25    GND VSS_AG25 @T6G_MB_LIB.T6G(SCH_1):GND
AG28    GND VSS_AG28 @T6G_MB_LIB.T6G(SCH_1):GND
AG31    GND VSS_AG31 @T6G_MB_LIB.T6G(SCH_1):GND
AG34    GND VSS_AG34 @T6G_MB_LIB.T6G(SCH_1):GND
AG42    GND VSS_AG42 @T6G_MB_LIB.T6G(SCH_1):GND
AG45    GND VSS_AG45 @T6G_MB_LIB.T6G(SCH_1):GND
AG48    GND VSS_AG48 @T6G_MB_LIB.T6G(SCH_1):GND
AG51    GND VSS_AG51 @T6G_MB_LIB.T6G(SCH_1):GND
AG54    GND VSS_AG54 @T6G_MB_LIB.T6G(SCH_1):GND
AG56    GND VSS_AG56 @T6G_MB_LIB.T6G(SCH_1):GND
AG58    GND VSS_AG58 @T6G_MB_LIB.T6G(SCH_1):GND
AG61    GND VSS_AG61 @T6G_MB_LIB.T6G(SCH_1):GND
AG63    GND VSS_AG63 @T6G_MB_LIB.T6G(SCH_1):GND
AG65    GND VSS_AG65 @T6G_MB_LIB.T6G(SCH_1):GND
AG68    GND VSS_AG68 @T6G_MB_LIB.T6G(SCH_1):GND
AG70    GND VSS_AG70 @T6G_MB_LIB.T6G(SCH_1):GND
AG72    GND VSS_AG72 @T6G_MB_LIB.T6G(SCH_1):GND
AG75    GND VSS_AG75 @T6G_MB_LIB.T6G(SCH_1):GND
 AH3    GND VSS_AH3 @T6G_MB_LIB.T6G(SCH_1):GND
 AH5    GND VSS_AH5 @T6G_MB_LIB.T6G(SCH_1):GND
 AH8    GND VSS_AH8 @T6G_MB_LIB.T6G(SCH_1):GND
AH10    GND VSS_AH10 @T6G_MB_LIB.T6G(SCH_1):GND
AH12    GND VSS_AH12 @T6G_MB_LIB.T6G(SCH_1):GND
AH15    GND VSS_AH15 @T6G_MB_LIB.T6G(SCH_1):GND
AH17    GND VSS_AH17 @T6G_MB_LIB.T6G(SCH_1):GND
AH19    GND VSS_AH19 @T6G_MB_LIB.T6G(SCH_1):GND
AH23    GND VSS_AH23 @T6G_MB_LIB.T6G(SCH_1):GND
AH24    GND VSS_AH24 @T6G_MB_LIB.T6G(SCH_1):GND
AH25    GND VSS_AH25 @T6G_MB_LIB.T6G(SCH_1):GND
AH26    GND VSS_AH26 @T6G_MB_LIB.T6G(SCH_1):GND
AH27    GND VSS_AH27 @T6G_MB_LIB.T6G(SCH_1):GND
AH28    GND VSS_AH28 @T6G_MB_LIB.T6G(SCH_1):GND
AH29    GND VSS_AH29 @T6G_MB_LIB.T6G(SCH_1):GND
AH30    GND VSS_AH30 @T6G_MB_LIB.T6G(SCH_1):GND
AH31    GND VSS_AH31 @T6G_MB_LIB.T6G(SCH_1):GND
AH32    GND VSS_AH32 @T6G_MB_LIB.T6G(SCH_1):GND
AH34    GND VSS_AH34 @T6G_MB_LIB.T6G(SCH_1):GND
AH37    GND VSS_AH37 @T6G_MB_LIB.T6G(SCH_1):GND
AH39    GND VSS_AH39 @T6G_MB_LIB.T6G(SCH_1):GND
AH42    GND VSS_AH42 @T6G_MB_LIB.T6G(SCH_1):GND
AH43    GND VSS_AH43 @T6G_MB_LIB.T6G(SCH_1):GND
AH44    GND VSS_AH44 @T6G_MB_LIB.T6G(SCH_1):GND
AH45    GND VSS_AH45 @T6G_MB_LIB.T6G(SCH_1):GND
AH46    GND VSS_AH46 @T6G_MB_LIB.T6G(SCH_1):GND
AH47    GND VSS_AH47 @T6G_MB_LIB.T6G(SCH_1):GND
AH48    GND VSS_AH48 @T6G_MB_LIB.T6G(SCH_1):GND
AH49    GND VSS_AH49 @T6G_MB_LIB.T6G(SCH_1):GND
AH50    GND VSS_AH50 @T6G_MB_LIB.T6G(SCH_1):GND
AH51    GND VSS_AH51 @T6G_MB_LIB.T6G(SCH_1):GND
AH52    GND VSS_AH52 @T6G_MB_LIB.T6G(SCH_1):GND
AH53    GND VSS_AH53 @T6G_MB_LIB.T6G(SCH_1):GND
AH57    GND VSS_AH57 @T6G_MB_LIB.T6G(SCH_1):GND
AH59    GND VSS_AH59 @T6G_MB_LIB.T6G(SCH_1):GND
AH61    GND VSS_AH61 @T6G_MB_LIB.T6G(SCH_1):GND
AH64    GND VSS_AH64 @T6G_MB_LIB.T6G(SCH_1):GND
AH66    GND VSS_AH66 @T6G_MB_LIB.T6G(SCH_1):GND
AH68    GND VSS_AH68 @T6G_MB_LIB.T6G(SCH_1):GND
AH71    GND VSS_AH71 @T6G_MB_LIB.T6G(SCH_1):GND
AH73    GND VSS_AH73 @T6G_MB_LIB.T6G(SCH_1):GND
 AJ1    GND VSS_AJ1 @T6G_MB_LIB.T6G(SCH_1):GND
 AJ6    GND VSS_AJ6 @T6G_MB_LIB.T6G(SCH_1):GND
 AJ8    GND VSS_AJ8 @T6G_MB_LIB.T6G(SCH_1):GND
AJ15    GND VSS_AJ15 @T6G_MB_LIB.T6G(SCH_1):GND
AJ20    GND VSS_AJ20 @T6G_MB_LIB.T6G(SCH_1):GND
AJ22    GND VSS_AJ22 @T6G_MB_LIB.T6G(SCH_1):GND
AJ25    GND VSS_AJ25 @T6G_MB_LIB.T6G(SCH_1):GND
AJ28    GND VSS_AJ28 @T6G_MB_LIB.T6G(SCH_1):GND
AJ31    GND VSS_AJ31 @T6G_MB_LIB.T6G(SCH_1):GND
AJ34    GND VSS_AJ34 @T6G_MB_LIB.T6G(SCH_1):GND
AJ35    GND VSS_AJ35 @T6G_MB_LIB.T6G(SCH_1):GND
AJ36    GND VSS_AJ36 @T6G_MB_LIB.T6G(SCH_1):GND
AJ40    GND VSS_AJ40 @T6G_MB_LIB.T6G(SCH_1):GND
AJ41    GND VSS_AJ41 @T6G_MB_LIB.T6G(SCH_1):GND
AJ42    GND VSS_AJ42 @T6G_MB_LIB.T6G(SCH_1):GND
AJ45    GND VSS_AJ45 @T6G_MB_LIB.T6G(SCH_1):GND
AJ48    GND VSS_AJ48 @T6G_MB_LIB.T6G(SCH_1):GND
AJ51    GND VSS_AJ51 @T6G_MB_LIB.T6G(SCH_1):GND
AJ54    GND VSS_AJ54 @T6G_MB_LIB.T6G(SCH_1):GND
AJ56    GND VSS_AJ56 @T6G_MB_LIB.T6G(SCH_1):GND
AJ61    GND VSS_AJ61 @T6G_MB_LIB.T6G(SCH_1):GND
AJ63    GND VSS_AJ63 @T6G_MB_LIB.T6G(SCH_1):GND
AJ68    GND VSS_AJ68 @T6G_MB_LIB.T6G(SCH_1):GND
AJ70    GND VSS_AJ70 @T6G_MB_LIB.T6G(SCH_1):GND
AJ75    GND VSS_AJ75 @T6G_MB_LIB.T6G(SCH_1):GND
 AK3    GND VSS_AK3 @T6G_MB_LIB.T6G(SCH_1):GND
 AK5    GND VSS_AK5 @T6G_MB_LIB.T6G(SCH_1):GND
 AK8    GND VSS_AK8 @T6G_MB_LIB.T6G(SCH_1):GND

GENOA_SP5-SOCKET6096_13568-001,SMLF,IO,DGA^6000030  I12  U26
AB68    GND VSS_AB68 @T6G_MB_LIB.T6G(SCH_1):GND
AB71    GND VSS_AB71 @T6G_MB_LIB.T6G(SCH_1):GND
AB73    GND VSS_AB73 @T6G_MB_LIB.T6G(SCH_1):GND
 AC1    GND VSS_AC1 @T6G_MB_LIB.T6G(SCH_1):GND
 AC6    GND VSS_AC6 @T6G_MB_LIB.T6G(SCH_1):GND
 AC8    GND VSS_AC8 @T6G_MB_LIB.T6G(SCH_1):GND
AC13    GND VSS_AC13 @T6G_MB_LIB.T6G(SCH_1):GND
AC15    GND VSS_AC15 @T6G_MB_LIB.T6G(SCH_1):GND
AC20    GND VSS_AC20 @T6G_MB_LIB.T6G(SCH_1):GND
AC22    GND VSS_AC22 @T6G_MB_LIB.T6G(SCH_1):GND
AC25    GND VSS_AC25 @T6G_MB_LIB.T6G(SCH_1):GND
AC28    GND VSS_AC28 @T6G_MB_LIB.T6G(SCH_1):GND
AC31    GND VSS_AC31 @T6G_MB_LIB.T6G(SCH_1):GND
AC34    GND VSS_AC34 @T6G_MB_LIB.T6G(SCH_1):GND
AC42    GND VSS_AC42 @T6G_MB_LIB.T6G(SCH_1):GND
AC45    GND VSS_AC45 @T6G_MB_LIB.T6G(SCH_1):GND
AC48    GND VSS_AC48 @T6G_MB_LIB.T6G(SCH_1):GND
AC51    GND VSS_AC51 @T6G_MB_LIB.T6G(SCH_1):GND
AC54    GND VSS_AC54 @T6G_MB_LIB.T6G(SCH_1):GND
AC56    GND VSS_AC56 @T6G_MB_LIB.T6G(SCH_1):GND
AC61    GND VSS_AC61 @T6G_MB_LIB.T6G(SCH_1):GND
AC63    GND VSS_AC63 @T6G_MB_LIB.T6G(SCH_1):GND
AC68    GND VSS_AC68 @T6G_MB_LIB.T6G(SCH_1):GND
AC70    GND VSS_AC70 @T6G_MB_LIB.T6G(SCH_1):GND
AC75    GND VSS_AC75 @T6G_MB_LIB.T6G(SCH_1):GND
 AD3    GND VSS_AD3 @T6G_MB_LIB.T6G(SCH_1):GND
 AD5    GND VSS_AD5 @T6G_MB_LIB.T6G(SCH_1):GND
 AD8    GND VSS_AD8 @T6G_MB_LIB.T6G(SCH_1):GND
AD10    GND VSS_AD10 @T6G_MB_LIB.T6G(SCH_1):GND
AD12    GND VSS_AD12 @T6G_MB_LIB.T6G(SCH_1):GND
AD15    GND VSS_AD15 @T6G_MB_LIB.T6G(SCH_1):GND
AD17    GND VSS_AD17 @T6G_MB_LIB.T6G(SCH_1):GND
AD19    GND VSS_AD19 @T6G_MB_LIB.T6G(SCH_1):GND
AD23    GND VSS_AD23 @T6G_MB_LIB.T6G(SCH_1):GND
AD24    GND VSS_AD24 @T6G_MB_LIB.T6G(SCH_1):GND
AD25    GND VSS_AD25 @T6G_MB_LIB.T6G(SCH_1):GND
AD26    GND VSS_AD26 @T6G_MB_LIB.T6G(SCH_1):GND
AD27    GND VSS_AD27 @T6G_MB_LIB.T6G(SCH_1):GND
AD28    GND VSS_AD28 @T6G_MB_LIB.T6G(SCH_1):GND
AD29    GND VSS_AD29 @T6G_MB_LIB.T6G(SCH_1):GND
AD30    GND VSS_AD30 @T6G_MB_LIB.T6G(SCH_1):GND
AD32    GND VSS_AD32 @T6G_MB_LIB.T6G(SCH_1):GND
AD33    GND VSS_AD33 @T6G_MB_LIB.T6G(SCH_1):GND
AD34    GND VSS_AD34 @T6G_MB_LIB.T6G(SCH_1):GND
AD37    GND VSS_AD37 @T6G_MB_LIB.T6G(SCH_1):GND
AD39    GND VSS_AD39 @T6G_MB_LIB.T6G(SCH_1):GND
AD42    GND VSS_AD42 @T6G_MB_LIB.T6G(SCH_1):GND
AD43    GND VSS_AD43 @T6G_MB_LIB.T6G(SCH_1):GND
AD44    GND VSS_AD44 @T6G_MB_LIB.T6G(SCH_1):GND
AD45    GND VSS_AD45 @T6G_MB_LIB.T6G(SCH_1):GND
AD46    GND VSS_AD46 @T6G_MB_LIB.T6G(SCH_1):GND
AD47    GND VSS_AD47 @T6G_MB_LIB.T6G(SCH_1):GND
AD48    GND VSS_AD48 @T6G_MB_LIB.T6G(SCH_1):GND
 T66    GND VSS_T66 @T6G_MB_LIB.T6G(SCH_1):GND
 T68    GND VSS_T68 @T6G_MB_LIB.T6G(SCH_1):GND
 T71    GND VSS_T71 @T6G_MB_LIB.T6G(SCH_1):GND
 T73    GND VSS_T73 @T6G_MB_LIB.T6G(SCH_1):GND
  U1    GND VSS_U1 @T6G_MB_LIB.T6G(SCH_1):GND
  U6    GND VSS_U6 @T6G_MB_LIB.T6G(SCH_1):GND
  U8    GND VSS_U8 @T6G_MB_LIB.T6G(SCH_1):GND
 U13    GND VSS_U13 @T6G_MB_LIB.T6G(SCH_1):GND
 U15    GND VSS_U15 @T6G_MB_LIB.T6G(SCH_1):GND
 U20    GND VSS_U20 @T6G_MB_LIB.T6G(SCH_1):GND
 U22    GND VSS_U22 @T6G_MB_LIB.T6G(SCH_1):GND
 U25    GND VSS_U25 @T6G_MB_LIB.T6G(SCH_1):GND
 U28    GND VSS_U28 @T6G_MB_LIB.T6G(SCH_1):GND
 U31    GND VSS_U31 @T6G_MB_LIB.T6G(SCH_1):GND
 U34    GND VSS_U34 @T6G_MB_LIB.T6G(SCH_1):GND
 U42    GND VSS_U42 @T6G_MB_LIB.T6G(SCH_1):GND
 U45    GND VSS_U45 @T6G_MB_LIB.T6G(SCH_1):GND
 U48    GND VSS_U48 @T6G_MB_LIB.T6G(SCH_1):GND
 U51    GND VSS_U51 @T6G_MB_LIB.T6G(SCH_1):GND
 U54    GND VSS_U54 @T6G_MB_LIB.T6G(SCH_1):GND
 U56    GND VSS_U56 @T6G_MB_LIB.T6G(SCH_1):GND
 U61    GND VSS_U61 @T6G_MB_LIB.T6G(SCH_1):GND
 U63    GND VSS_U63 @T6G_MB_LIB.T6G(SCH_1):GND
 U68    GND VSS_U68 @T6G_MB_LIB.T6G(SCH_1):GND
 U70    GND VSS_U70 @T6G_MB_LIB.T6G(SCH_1):GND
 U75    GND VSS_U75 @T6G_MB_LIB.T6G(SCH_1):GND
  V3    GND VSS_V3 @T6G_MB_LIB.T6G(SCH_1):GND
  V5    GND VSS_V5 @T6G_MB_LIB.T6G(SCH_1):GND
  V8    GND VSS_V8 @T6G_MB_LIB.T6G(SCH_1):GND
 V10    GND VSS_V10 @T6G_MB_LIB.T6G(SCH_1):GND
 V12    GND VSS_V12 @T6G_MB_LIB.T6G(SCH_1):GND
 V15    GND VSS_V15 @T6G_MB_LIB.T6G(SCH_1):GND
 V17    GND VSS_V17 @T6G_MB_LIB.T6G(SCH_1):GND
 V19    GND VSS_V19 @T6G_MB_LIB.T6G(SCH_1):GND
 V23    GND VSS_V23 @T6G_MB_LIB.T6G(SCH_1):GND
 V24    GND VSS_V24 @T6G_MB_LIB.T6G(SCH_1):GND
 V25    GND VSS_V25 @T6G_MB_LIB.T6G(SCH_1):GND
 V26    GND VSS_V26 @T6G_MB_LIB.T6G(SCH_1):GND
 V28    GND VSS_V28 @T6G_MB_LIB.T6G(SCH_1):GND
 V29    GND VSS_V29 @T6G_MB_LIB.T6G(SCH_1):GND
 V30    GND VSS_V30 @T6G_MB_LIB.T6G(SCH_1):GND
 V31    GND VSS_V31 @T6G_MB_LIB.T6G(SCH_1):GND
 V32    GND VSS_V32 @T6G_MB_LIB.T6G(SCH_1):GND
 V33    GND VSS_V33 @T6G_MB_LIB.T6G(SCH_1):GND
 V34    GND VSS_V34 @T6G_MB_LIB.T6G(SCH_1):GND
 V37    GND VSS_V37 @T6G_MB_LIB.T6G(SCH_1):GND
 V39    GND VSS_V39 @T6G_MB_LIB.T6G(SCH_1):GND
 V42    GND VSS_V42 @T6G_MB_LIB.T6G(SCH_1):GND
 V43    GND VSS_V43 @T6G_MB_LIB.T6G(SCH_1):GND
 V44    GND VSS_V44 @T6G_MB_LIB.T6G(SCH_1):GND
 V45    GND VSS_V45 @T6G_MB_LIB.T6G(SCH_1):GND
 V46    GND VSS_V46 @T6G_MB_LIB.T6G(SCH_1):GND
 V47    GND VSS_V47 @T6G_MB_LIB.T6G(SCH_1):GND
 V48    GND VSS_V48 @T6G_MB_LIB.T6G(SCH_1):GND
 V49    GND VSS_V49 @T6G_MB_LIB.T6G(SCH_1):GND
 V50    GND VSS_V50 @T6G_MB_LIB.T6G(SCH_1):GND
 V51    GND VSS_V51 @T6G_MB_LIB.T6G(SCH_1):GND
 V52    GND VSS_V52 @T6G_MB_LIB.T6G(SCH_1):GND
 V53    GND VSS_V53 @T6G_MB_LIB.T6G(SCH_1):GND
 V57    GND VSS_V57 @T6G_MB_LIB.T6G(SCH_1):GND
 V59    GND VSS_V59 @T6G_MB_LIB.T6G(SCH_1):GND
 V61    GND VSS_V61 @T6G_MB_LIB.T6G(SCH_1):GND
 V64    GND VSS_V64 @T6G_MB_LIB.T6G(SCH_1):GND
 V66    GND VSS_V66 @T6G_MB_LIB.T6G(SCH_1):GND
 V71    GND VSS_V71 @T6G_MB_LIB.T6G(SCH_1):GND
 V73    GND VSS_V73 @T6G_MB_LIB.T6G(SCH_1):GND
  W1    GND VSS_W1 @T6G_MB_LIB.T6G(SCH_1):GND
  W4    GND VSS_W4 @T6G_MB_LIB.T6G(SCH_1):GND
  W6    GND VSS_W6 @T6G_MB_LIB.T6G(SCH_1):GND
  W8    GND VSS_W8 @T6G_MB_LIB.T6G(SCH_1):GND
 W11    GND VSS_W11 @T6G_MB_LIB.T6G(SCH_1):GND
 W13    GND VSS_W13 @T6G_MB_LIB.T6G(SCH_1):GND
 W15    GND VSS_W15 @T6G_MB_LIB.T6G(SCH_1):GND
 W18    GND VSS_W18 @T6G_MB_LIB.T6G(SCH_1):GND
 W20    GND VSS_W20 @T6G_MB_LIB.T6G(SCH_1):GND
 W22    GND VSS_W22 @T6G_MB_LIB.T6G(SCH_1):GND
 W25    GND VSS_W25 @T6G_MB_LIB.T6G(SCH_1):GND
 W28    GND VSS_W28 @T6G_MB_LIB.T6G(SCH_1):GND
 W34    GND VSS_W34 @T6G_MB_LIB.T6G(SCH_1):GND
 W35    GND VSS_W35 @T6G_MB_LIB.T6G(SCH_1):GND
 W36    GND VSS_W36 @T6G_MB_LIB.T6G(SCH_1):GND
 W40    GND VSS_W40 @T6G_MB_LIB.T6G(SCH_1):GND
 W41    GND VSS_W41 @T6G_MB_LIB.T6G(SCH_1):GND
 W42    GND VSS_W42 @T6G_MB_LIB.T6G(SCH_1):GND
 W45    GND VSS_W45 @T6G_MB_LIB.T6G(SCH_1):GND
 W48    GND VSS_W48 @T6G_MB_LIB.T6G(SCH_1):GND
 W51    GND VSS_W51 @T6G_MB_LIB.T6G(SCH_1):GND
 W54    GND VSS_W54 @T6G_MB_LIB.T6G(SCH_1):GND
 W56    GND VSS_W56 @T6G_MB_LIB.T6G(SCH_1):GND
 W58    GND VSS_W58 @T6G_MB_LIB.T6G(SCH_1):GND
 W61    GND VSS_W61 @T6G_MB_LIB.T6G(SCH_1):GND
 W63    GND VSS_W63 @T6G_MB_LIB.T6G(SCH_1):GND
 W65    GND VSS_W65 @T6G_MB_LIB.T6G(SCH_1):GND
 W68    GND VSS_W68 @T6G_MB_LIB.T6G(SCH_1):GND
 W70    GND VSS_W70 @T6G_MB_LIB.T6G(SCH_1):GND
 W72    GND VSS_W72 @T6G_MB_LIB.T6G(SCH_1):GND
 W75    GND VSS_W75 @T6G_MB_LIB.T6G(SCH_1):GND
  Y3    GND VSS_Y3 @T6G_MB_LIB.T6G(SCH_1):GND
  Y8    GND VSS_Y8 @T6G_MB_LIB.T6G(SCH_1):GND
 Y10    GND VSS_Y10 @T6G_MB_LIB.T6G(SCH_1):GND
 Y15    GND VSS_Y15 @T6G_MB_LIB.T6G(SCH_1):GND
 Y17    GND VSS_Y17 @T6G_MB_LIB.T6G(SCH_1):GND
 Y22    GND VSS_Y22 @T6G_MB_LIB.T6G(SCH_1):GND
 Y23    GND VSS_Y23 @T6G_MB_LIB.T6G(SCH_1):GND
 Y24    GND VSS_Y24 @T6G_MB_LIB.T6G(SCH_1):GND
 Y25    GND VSS_Y25 @T6G_MB_LIB.T6G(SCH_1):GND
 Y26    GND VSS_Y26 @T6G_MB_LIB.T6G(SCH_1):GND
 Y27    GND VSS_Y27 @T6G_MB_LIB.T6G(SCH_1):GND
 Y28    GND VSS_Y28 @T6G_MB_LIB.T6G(SCH_1):GND
 Y31    GND VSS_Y31 @T6G_MB_LIB.T6G(SCH_1):GND
 Y32    GND VSS_Y32 @T6G_MB_LIB.T6G(SCH_1):GND
 Y33    GND VSS_Y33 @T6G_MB_LIB.T6G(SCH_1):GND
 Y34    GND VSS_Y34 @T6G_MB_LIB.T6G(SCH_1):GND
 Y37    GND VSS_Y37 @T6G_MB_LIB.T6G(SCH_1):GND
 Y39    GND VSS_Y39 @T6G_MB_LIB.T6G(SCH_1):GND
 Y42    GND VSS_Y42 @T6G_MB_LIB.T6G(SCH_1):GND
 Y43    GND VSS_Y43 @T6G_MB_LIB.T6G(SCH_1):GND
 Y44    GND VSS_Y44 @T6G_MB_LIB.T6G(SCH_1):GND
 Y45    GND VSS_Y45 @T6G_MB_LIB.T6G(SCH_1):GND
 Y48    GND VSS_Y48 @T6G_MB_LIB.T6G(SCH_1):GND
 Y49    GND VSS_Y49 @T6G_MB_LIB.T6G(SCH_1):GND
 Y50    GND VSS_Y50 @T6G_MB_LIB.T6G(SCH_1):GND
 Y51    GND VSS_Y51 @T6G_MB_LIB.T6G(SCH_1):GND
 Y52    GND VSS_Y52 @T6G_MB_LIB.T6G(SCH_1):GND
 Y53    GND VSS_Y53 @T6G_MB_LIB.T6G(SCH_1):GND
 Y54    GND VSS_Y54 @T6G_MB_LIB.T6G(SCH_1):GND
 Y59    GND VSS_Y59 @T6G_MB_LIB.T6G(SCH_1):GND
 Y61    GND VSS_Y61 @T6G_MB_LIB.T6G(SCH_1):GND
 Y66    GND VSS_Y66 @T6G_MB_LIB.T6G(SCH_1):GND
 Y68    GND VSS_Y68 @T6G_MB_LIB.T6G(SCH_1):GND
 Y73    GND VSS_Y73 @T6G_MB_LIB.T6G(SCH_1):GND
 AA1    GND VSS_AA1 @T6G_MB_LIB.T6G(SCH_1):GND
 AA4    GND VSS_AA4 @T6G_MB_LIB.T6G(SCH_1):GND
 AA6    GND VSS_AA6 @T6G_MB_LIB.T6G(SCH_1):GND
 AA8    GND VSS_AA8 @T6G_MB_LIB.T6G(SCH_1):GND
AA11    GND VSS_AA11 @T6G_MB_LIB.T6G(SCH_1):GND
AA13    GND VSS_AA13 @T6G_MB_LIB.T6G(SCH_1):GND
AA15    GND VSS_AA15 @T6G_MB_LIB.T6G(SCH_1):GND
AA18    GND VSS_AA18 @T6G_MB_LIB.T6G(SCH_1):GND
AA20    GND VSS_AA20 @T6G_MB_LIB.T6G(SCH_1):GND
AA31    GND VSS_AA31 @T6G_MB_LIB.T6G(SCH_1):GND
AA34    GND VSS_AA34 @T6G_MB_LIB.T6G(SCH_1):GND
AA35    GND VSS_AA35 @T6G_MB_LIB.T6G(SCH_1):GND
AA36    GND VSS_AA36 @T6G_MB_LIB.T6G(SCH_1):GND
AA40    GND VSS_AA40 @T6G_MB_LIB.T6G(SCH_1):GND
AA41    GND VSS_AA41 @T6G_MB_LIB.T6G(SCH_1):GND
AA45    GND VSS_AA45 @T6G_MB_LIB.T6G(SCH_1):GND
AA56    GND VSS_AA56 @T6G_MB_LIB.T6G(SCH_1):GND
AA58    GND VSS_AA58 @T6G_MB_LIB.T6G(SCH_1):GND
AA61    GND VSS_AA61 @T6G_MB_LIB.T6G(SCH_1):GND
AA63    GND VSS_AA63 @T6G_MB_LIB.T6G(SCH_1):GND
AA65    GND VSS_AA65 @T6G_MB_LIB.T6G(SCH_1):GND
AA68    GND VSS_AA68 @T6G_MB_LIB.T6G(SCH_1):GND
AA70    GND VSS_AA70 @T6G_MB_LIB.T6G(SCH_1):GND
AA75    GND VSS_AA75 @T6G_MB_LIB.T6G(SCH_1):GND
 AB3    GND VSS_AB3 @T6G_MB_LIB.T6G(SCH_1):GND
 AB5    GND VSS_AB5 @T6G_MB_LIB.T6G(SCH_1):GND
 AB8    GND VSS_AB8 @T6G_MB_LIB.T6G(SCH_1):GND
AB10    GND VSS_AB10 @T6G_MB_LIB.T6G(SCH_1):GND
AB12    GND VSS_AB12 @T6G_MB_LIB.T6G(SCH_1):GND
AB15    GND VSS_AB15 @T6G_MB_LIB.T6G(SCH_1):GND
AB17    GND VSS_AB17 @T6G_MB_LIB.T6G(SCH_1):GND
AB19    GND VSS_AB19 @T6G_MB_LIB.T6G(SCH_1):GND
AB22    GND VSS_AB22 @T6G_MB_LIB.T6G(SCH_1):GND
AB25    GND VSS_AB25 @T6G_MB_LIB.T6G(SCH_1):GND
AB28    GND VSS_AB28 @T6G_MB_LIB.T6G(SCH_1):GND
AB31    GND VSS_AB31 @T6G_MB_LIB.T6G(SCH_1):GND
AB34    GND VSS_AB34 @T6G_MB_LIB.T6G(SCH_1):GND
AB37    GND VSS_AB37 @T6G_MB_LIB.T6G(SCH_1):GND
AB39    GND VSS_AB39 @T6G_MB_LIB.T6G(SCH_1):GND
AB42    GND VSS_AB42 @T6G_MB_LIB.T6G(SCH_1):GND
AB45    GND VSS_AB45 @T6G_MB_LIB.T6G(SCH_1):GND
AB48    GND VSS_AB48 @T6G_MB_LIB.T6G(SCH_1):GND
AB51    GND VSS_AB51 @T6G_MB_LIB.T6G(SCH_1):GND
AB54    GND VSS_AB54 @T6G_MB_LIB.T6G(SCH_1):GND
AB57    GND VSS_AB57 @T6G_MB_LIB.T6G(SCH_1):GND
AB59    GND VSS_AB59 @T6G_MB_LIB.T6G(SCH_1):GND
AB61    GND VSS_AB61 @T6G_MB_LIB.T6G(SCH_1):GND
AB64    GND VSS_AB64 @T6G_MB_LIB.T6G(SCH_1):GND
AB66    GND VSS_AB66 @T6G_MB_LIB.T6G(SCH_1):GND

GENOA_SP5-SOCKET6096_13568-001,SMLF,IO,DGA^6000030  I15  U26
 R48    GND VSS_R48 @T6G_MB_LIB.T6G(SCH_1):GND
 R51    GND VSS_R51 @T6G_MB_LIB.T6G(SCH_1):GND
 R54    GND VSS_R54 @T6G_MB_LIB.T6G(SCH_1):GND
 R56    GND VSS_R56 @T6G_MB_LIB.T6G(SCH_1):GND
 R58    GND VSS_R58 @T6G_MB_LIB.T6G(SCH_1):GND
 R61    GND VSS_R61 @T6G_MB_LIB.T6G(SCH_1):GND
 R63    GND VSS_R63 @T6G_MB_LIB.T6G(SCH_1):GND
 R65    GND VSS_R65 @T6G_MB_LIB.T6G(SCH_1):GND
 R68    GND VSS_R68 @T6G_MB_LIB.T6G(SCH_1):GND
 R70    GND VSS_R70 @T6G_MB_LIB.T6G(SCH_1):GND
 R72    GND VSS_R72 @T6G_MB_LIB.T6G(SCH_1):GND
 R75    GND VSS_R75 @T6G_MB_LIB.T6G(SCH_1):GND
  T3    GND VSS_T3 @T6G_MB_LIB.T6G(SCH_1):GND
  T5    GND VSS_T5 @T6G_MB_LIB.T6G(SCH_1):GND
  T8    GND VSS_T8 @T6G_MB_LIB.T6G(SCH_1):GND
 T10    GND VSS_T10 @T6G_MB_LIB.T6G(SCH_1):GND
 T12    GND VSS_T12 @T6G_MB_LIB.T6G(SCH_1):GND
 T15    GND VSS_T15 @T6G_MB_LIB.T6G(SCH_1):GND
 T17    GND VSS_T17 @T6G_MB_LIB.T6G(SCH_1):GND
 T19    GND VSS_T19 @T6G_MB_LIB.T6G(SCH_1):GND
 T22    GND VSS_T22 @T6G_MB_LIB.T6G(SCH_1):GND
 T25    GND VSS_T25 @T6G_MB_LIB.T6G(SCH_1):GND
 T28    GND VSS_T28 @T6G_MB_LIB.T6G(SCH_1):GND
 T31    GND VSS_T31 @T6G_MB_LIB.T6G(SCH_1):GND
 T34    GND VSS_T34 @T6G_MB_LIB.T6G(SCH_1):GND
 T37    GND VSS_T37 @T6G_MB_LIB.T6G(SCH_1):GND
 T39    GND VSS_T39 @T6G_MB_LIB.T6G(SCH_1):GND
 T42    GND VSS_T42 @T6G_MB_LIB.T6G(SCH_1):GND
 T45    GND VSS_T45 @T6G_MB_LIB.T6G(SCH_1):GND
 T48    GND VSS_T48 @T6G_MB_LIB.T6G(SCH_1):GND
 T51    GND VSS_T51 @T6G_MB_LIB.T6G(SCH_1):GND
 T54    GND VSS_T54 @T6G_MB_LIB.T6G(SCH_1):GND
 T57    GND VSS_T57 @T6G_MB_LIB.T6G(SCH_1):GND
 T59    GND VSS_T59 @T6G_MB_LIB.T6G(SCH_1):GND
 T61    GND VSS_T61 @T6G_MB_LIB.T6G(SCH_1):GND
 T64    GND VSS_T64 @T6G_MB_LIB.T6G(SCH_1):GND
 J15    GND VSS_J15 @T6G_MB_LIB.T6G(SCH_1):GND
 J18    GND VSS_J18 @T6G_MB_LIB.T6G(SCH_1):GND
 J20    GND VSS_J20 @T6G_MB_LIB.T6G(SCH_1):GND
 J22    GND VSS_J22 @T6G_MB_LIB.T6G(SCH_1):GND
 J25    GND VSS_J25 @T6G_MB_LIB.T6G(SCH_1):GND
 J28    GND VSS_J28 @T6G_MB_LIB.T6G(SCH_1):GND
 J31    GND VSS_J31 @T6G_MB_LIB.T6G(SCH_1):GND
 J34    GND VSS_J34 @T6G_MB_LIB.T6G(SCH_1):GND
 J42    GND VSS_J42 @T6G_MB_LIB.T6G(SCH_1):GND
 J45    GND VSS_J45 @T6G_MB_LIB.T6G(SCH_1):GND
 J48    GND VSS_J48 @T6G_MB_LIB.T6G(SCH_1):GND
 J51    GND VSS_J51 @T6G_MB_LIB.T6G(SCH_1):GND
 J54    GND VSS_J54 @T6G_MB_LIB.T6G(SCH_1):GND
 J56    GND VSS_J56 @T6G_MB_LIB.T6G(SCH_1):GND
 J58    GND VSS_J58 @T6G_MB_LIB.T6G(SCH_1):GND
 J61    GND VSS_J61 @T6G_MB_LIB.T6G(SCH_1):GND
 J63    GND VSS_J63 @T6G_MB_LIB.T6G(SCH_1):GND
 J65    GND VSS_J65 @T6G_MB_LIB.T6G(SCH_1):GND
 J68    GND VSS_J68 @T6G_MB_LIB.T6G(SCH_1):GND
 J70    GND VSS_J70 @T6G_MB_LIB.T6G(SCH_1):GND
 J72    GND VSS_J72 @T6G_MB_LIB.T6G(SCH_1):GND
 J75    GND VSS_J75 @T6G_MB_LIB.T6G(SCH_1):GND
  K3    GND VSS_K3 @T6G_MB_LIB.T6G(SCH_1):GND
  K5    GND VSS_K5 @T6G_MB_LIB.T6G(SCH_1):GND
  K8    GND VSS_K8 @T6G_MB_LIB.T6G(SCH_1):GND
 K10    GND VSS_K10 @T6G_MB_LIB.T6G(SCH_1):GND
 K12    GND VSS_K12 @T6G_MB_LIB.T6G(SCH_1):GND
 K15    GND VSS_K15 @T6G_MB_LIB.T6G(SCH_1):GND
 K17    GND VSS_K17 @T6G_MB_LIB.T6G(SCH_1):GND
 K19    GND VSS_K19 @T6G_MB_LIB.T6G(SCH_1):GND
 K24    GND VSS_K24 @T6G_MB_LIB.T6G(SCH_1):GND
 K25    GND VSS_K25 @T6G_MB_LIB.T6G(SCH_1):GND
 K26    GND VSS_K26 @T6G_MB_LIB.T6G(SCH_1):GND
 K27    GND VSS_K27 @T6G_MB_LIB.T6G(SCH_1):GND
 K28    GND VSS_K28 @T6G_MB_LIB.T6G(SCH_1):GND
 K29    GND VSS_K29 @T6G_MB_LIB.T6G(SCH_1):GND
 K30    GND VSS_K30 @T6G_MB_LIB.T6G(SCH_1):GND
 K31    GND VSS_K31 @T6G_MB_LIB.T6G(SCH_1):GND
 K32    GND VSS_K32 @T6G_MB_LIB.T6G(SCH_1):GND
 K33    GND VSS_K33 @T6G_MB_LIB.T6G(SCH_1):GND
 K34    GND VSS_K34 @T6G_MB_LIB.T6G(SCH_1):GND
 K37    GND VSS_K37 @T6G_MB_LIB.T6G(SCH_1):GND
 K39    GND VSS_K39 @T6G_MB_LIB.T6G(SCH_1):GND
 K42    GND VSS_K42 @T6G_MB_LIB.T6G(SCH_1):GND
 K43    GND VSS_K43 @T6G_MB_LIB.T6G(SCH_1):GND
 K44    GND VSS_K44 @T6G_MB_LIB.T6G(SCH_1):GND
 K45    GND VSS_K45 @T6G_MB_LIB.T6G(SCH_1):GND
 K46    GND VSS_K46 @T6G_MB_LIB.T6G(SCH_1):GND
 K47    GND VSS_K47 @T6G_MB_LIB.T6G(SCH_1):GND
 K48    GND VSS_K48 @T6G_MB_LIB.T6G(SCH_1):GND
 K49    GND VSS_K49 @T6G_MB_LIB.T6G(SCH_1):GND
 K50    GND VSS_K50 @T6G_MB_LIB.T6G(SCH_1):GND
 K51    GND VSS_K51 @T6G_MB_LIB.T6G(SCH_1):GND
 K52    GND VSS_K52 @T6G_MB_LIB.T6G(SCH_1):GND
 K53    GND VSS_K53 @T6G_MB_LIB.T6G(SCH_1):GND
 K57    GND VSS_K57 @T6G_MB_LIB.T6G(SCH_1):GND
 K61    GND VSS_K61 @T6G_MB_LIB.T6G(SCH_1):GND
 K64    GND VSS_K64 @T6G_MB_LIB.T6G(SCH_1):GND
 K66    GND VSS_K66 @T6G_MB_LIB.T6G(SCH_1):GND
 K68    GND VSS_K68 @T6G_MB_LIB.T6G(SCH_1):GND
 K71    GND VSS_K71 @T6G_MB_LIB.T6G(SCH_1):GND
 K73    GND VSS_K73 @T6G_MB_LIB.T6G(SCH_1):GND
  L1    GND VSS_L1 @T6G_MB_LIB.T6G(SCH_1):GND
  L6    GND VSS_L6 @T6G_MB_LIB.T6G(SCH_1):GND
  L8    GND VSS_L8 @T6G_MB_LIB.T6G(SCH_1):GND
 L13    GND VSS_L13 @T6G_MB_LIB.T6G(SCH_1):GND
 L15    GND VSS_L15 @T6G_MB_LIB.T6G(SCH_1):GND
 L20    GND VSS_L20 @T6G_MB_LIB.T6G(SCH_1):GND
 L22    GND VSS_L22 @T6G_MB_LIB.T6G(SCH_1):GND
 L25    GND VSS_L25 @T6G_MB_LIB.T6G(SCH_1):GND
 L28    GND VSS_L28 @T6G_MB_LIB.T6G(SCH_1):GND
 L31    GND VSS_L31 @T6G_MB_LIB.T6G(SCH_1):GND
 L34    GND VSS_L34 @T6G_MB_LIB.T6G(SCH_1):GND
 L35    GND VSS_L35 @T6G_MB_LIB.T6G(SCH_1):GND
 L36    GND VSS_L36 @T6G_MB_LIB.T6G(SCH_1):GND
 L40    GND VSS_L40 @T6G_MB_LIB.T6G(SCH_1):GND
 L41    GND VSS_L41 @T6G_MB_LIB.T6G(SCH_1):GND
 L42    GND VSS_L42 @T6G_MB_LIB.T6G(SCH_1):GND
 L45    GND VSS_L45 @T6G_MB_LIB.T6G(SCH_1):GND
 L48    GND VSS_L48 @T6G_MB_LIB.T6G(SCH_1):GND
 L51    GND VSS_L51 @T6G_MB_LIB.T6G(SCH_1):GND
 L54    GND VSS_L54 @T6G_MB_LIB.T6G(SCH_1):GND
 L56    GND VSS_L56 @T6G_MB_LIB.T6G(SCH_1):GND
 L61    GND VSS_L61 @T6G_MB_LIB.T6G(SCH_1):GND
 L63    GND VSS_L63 @T6G_MB_LIB.T6G(SCH_1):GND
 L68    GND VSS_L68 @T6G_MB_LIB.T6G(SCH_1):GND
 L70    GND VSS_L70 @T6G_MB_LIB.T6G(SCH_1):GND
 L75    GND VSS_L75 @T6G_MB_LIB.T6G(SCH_1):GND
  M3    GND VSS_M3 @T6G_MB_LIB.T6G(SCH_1):GND
  M5    GND VSS_M5 @T6G_MB_LIB.T6G(SCH_1):GND
  M8    GND VSS_M8 @T6G_MB_LIB.T6G(SCH_1):GND
 M10    GND VSS_M10 @T6G_MB_LIB.T6G(SCH_1):GND
 M12    GND VSS_M12 @T6G_MB_LIB.T6G(SCH_1):GND
 M15    GND VSS_M15 @T6G_MB_LIB.T6G(SCH_1):GND
 M17    GND VSS_M17 @T6G_MB_LIB.T6G(SCH_1):GND
 M19    GND VSS_M19 @T6G_MB_LIB.T6G(SCH_1):GND
 M22    GND VSS_M22 @T6G_MB_LIB.T6G(SCH_1):GND
 M25    GND VSS_M25 @T6G_MB_LIB.T6G(SCH_1):GND
 M28    GND VSS_M28 @T6G_MB_LIB.T6G(SCH_1):GND
 M31    GND VSS_M31 @T6G_MB_LIB.T6G(SCH_1):GND
 M34    GND VSS_M34 @T6G_MB_LIB.T6G(SCH_1):GND
 M37    GND VSS_M37 @T6G_MB_LIB.T6G(SCH_1):GND
 M39    GND VSS_M39 @T6G_MB_LIB.T6G(SCH_1):GND
 M42    GND VSS_M42 @T6G_MB_LIB.T6G(SCH_1):GND
 M45    GND VSS_M45 @T6G_MB_LIB.T6G(SCH_1):GND
 M48    GND VSS_M48 @T6G_MB_LIB.T6G(SCH_1):GND
 M51    GND VSS_M51 @T6G_MB_LIB.T6G(SCH_1):GND
 M54    GND VSS_M54 @T6G_MB_LIB.T6G(SCH_1):GND
 M57    GND VSS_M57 @T6G_MB_LIB.T6G(SCH_1):GND
 M59    GND VSS_M59 @T6G_MB_LIB.T6G(SCH_1):GND
 M61    GND VSS_M61 @T6G_MB_LIB.T6G(SCH_1):GND
 M64    GND VSS_M64 @T6G_MB_LIB.T6G(SCH_1):GND
 M66    GND VSS_M66 @T6G_MB_LIB.T6G(SCH_1):GND
 M68    GND VSS_M68 @T6G_MB_LIB.T6G(SCH_1):GND
 M71    GND VSS_M71 @T6G_MB_LIB.T6G(SCH_1):GND
 M73    GND VSS_M73 @T6G_MB_LIB.T6G(SCH_1):GND
  N1    GND VSS_N1 @T6G_MB_LIB.T6G(SCH_1):GND
  N4    GND VSS_N4 @T6G_MB_LIB.T6G(SCH_1):GND
  N6    GND VSS_N6 @T6G_MB_LIB.T6G(SCH_1):GND
  N8    GND VSS_N8 @T6G_MB_LIB.T6G(SCH_1):GND
 N11    GND VSS_N11 @T6G_MB_LIB.T6G(SCH_1):GND
 N13    GND VSS_N13 @T6G_MB_LIB.T6G(SCH_1):GND
 N15    GND VSS_N15 @T6G_MB_LIB.T6G(SCH_1):GND
 N18    GND VSS_N18 @T6G_MB_LIB.T6G(SCH_1):GND
 N20    GND VSS_N20 @T6G_MB_LIB.T6G(SCH_1):GND
 N22    GND VSS_N22 @T6G_MB_LIB.T6G(SCH_1):GND
 N25    GND VSS_N25 @T6G_MB_LIB.T6G(SCH_1):GND
 N28    GND VSS_N28 @T6G_MB_LIB.T6G(SCH_1):GND
 N31    GND VSS_N31 @T6G_MB_LIB.T6G(SCH_1):GND
 N34    GND VSS_N34 @T6G_MB_LIB.T6G(SCH_1):GND
 N42    GND VSS_N42 @T6G_MB_LIB.T6G(SCH_1):GND
 N45    GND VSS_N45 @T6G_MB_LIB.T6G(SCH_1):GND
 N48    GND VSS_N48 @T6G_MB_LIB.T6G(SCH_1):GND
 N51    GND VSS_N51 @T6G_MB_LIB.T6G(SCH_1):GND
 N54    GND VSS_N54 @T6G_MB_LIB.T6G(SCH_1):GND
 N56    GND VSS_N56 @T6G_MB_LIB.T6G(SCH_1):GND
 N58    GND VSS_N58 @T6G_MB_LIB.T6G(SCH_1):GND
 N61    GND VSS_N61 @T6G_MB_LIB.T6G(SCH_1):GND
 N63    GND VSS_N63 @T6G_MB_LIB.T6G(SCH_1):GND
 N65    GND VSS_N65 @T6G_MB_LIB.T6G(SCH_1):GND
 N68    GND VSS_N68 @T6G_MB_LIB.T6G(SCH_1):GND
 N70    GND VSS_N70 @T6G_MB_LIB.T6G(SCH_1):GND
 N72    GND VSS_N72 @T6G_MB_LIB.T6G(SCH_1):GND
 N75    GND VSS_N75 @T6G_MB_LIB.T6G(SCH_1):GND
  P3    GND VSS_P3 @T6G_MB_LIB.T6G(SCH_1):GND
  P8    GND VSS_P8 @T6G_MB_LIB.T6G(SCH_1):GND
 P10    GND VSS_P10 @T6G_MB_LIB.T6G(SCH_1):GND
 P15    GND VSS_P15 @T6G_MB_LIB.T6G(SCH_1):GND
 P17    GND VSS_P17 @T6G_MB_LIB.T6G(SCH_1):GND
 P23    GND VSS_P23 @T6G_MB_LIB.T6G(SCH_1):GND
 P24    GND VSS_P24 @T6G_MB_LIB.T6G(SCH_1):GND
 P26    GND VSS_P26 @T6G_MB_LIB.T6G(SCH_1):GND
 P27    GND VSS_P27 @T6G_MB_LIB.T6G(SCH_1):GND
 P28    GND VSS_P28 @T6G_MB_LIB.T6G(SCH_1):GND
 P29    GND VSS_P29 @T6G_MB_LIB.T6G(SCH_1):GND
 P30    GND VSS_P30 @T6G_MB_LIB.T6G(SCH_1):GND
 P31    GND VSS_P31 @T6G_MB_LIB.T6G(SCH_1):GND
 P32    GND VSS_P32 @T6G_MB_LIB.T6G(SCH_1):GND
 P33    GND VSS_P33 @T6G_MB_LIB.T6G(SCH_1):GND
 P34    GND VSS_P34 @T6G_MB_LIB.T6G(SCH_1):GND
 P37    GND VSS_P37 @T6G_MB_LIB.T6G(SCH_1):GND
 P39    GND VSS_P39 @T6G_MB_LIB.T6G(SCH_1):GND
 P42    GND VSS_P42 @T6G_MB_LIB.T6G(SCH_1):GND
 P43    GND VSS_P43 @T6G_MB_LIB.T6G(SCH_1):GND
 P44    GND VSS_P44 @T6G_MB_LIB.T6G(SCH_1):GND
 P45    GND VSS_P45 @T6G_MB_LIB.T6G(SCH_1):GND
 P46    GND VSS_P46 @T6G_MB_LIB.T6G(SCH_1):GND
 P47    GND VSS_P47 @T6G_MB_LIB.T6G(SCH_1):GND
 P48    GND VSS_P48 @T6G_MB_LIB.T6G(SCH_1):GND
 P49    GND VSS_P49 @T6G_MB_LIB.T6G(SCH_1):GND
 P50    GND VSS_P50 @T6G_MB_LIB.T6G(SCH_1):GND
 P51    GND VSS_P51 @T6G_MB_LIB.T6G(SCH_1):GND
 P52    GND VSS_P52 @T6G_MB_LIB.T6G(SCH_1):GND
 P53    GND VSS_P53 @T6G_MB_LIB.T6G(SCH_1):GND
 P59    GND VSS_P59 @T6G_MB_LIB.T6G(SCH_1):GND
 P61    GND VSS_P61 @T6G_MB_LIB.T6G(SCH_1):GND
 P66    GND VSS_P66 @T6G_MB_LIB.T6G(SCH_1):GND
 P73    GND VSS_P73 @T6G_MB_LIB.T6G(SCH_1):GND
  R1    GND VSS_R1 @T6G_MB_LIB.T6G(SCH_1):GND
  R4    GND VSS_R4 @T6G_MB_LIB.T6G(SCH_1):GND
  R6    GND VSS_R6 @T6G_MB_LIB.T6G(SCH_1):GND
  R8    GND VSS_R8 @T6G_MB_LIB.T6G(SCH_1):GND
 R11    GND VSS_R11 @T6G_MB_LIB.T6G(SCH_1):GND
 R13    GND VSS_R13 @T6G_MB_LIB.T6G(SCH_1):GND
 R15    GND VSS_R15 @T6G_MB_LIB.T6G(SCH_1):GND
 R18    GND VSS_R18 @T6G_MB_LIB.T6G(SCH_1):GND
 R20    GND VSS_R20 @T6G_MB_LIB.T6G(SCH_1):GND
 R22    GND VSS_R22 @T6G_MB_LIB.T6G(SCH_1):GND
 R25    GND VSS_R25 @T6G_MB_LIB.T6G(SCH_1):GND
 R28    GND VSS_R28 @T6G_MB_LIB.T6G(SCH_1):GND
 R31    GND VSS_R31 @T6G_MB_LIB.T6G(SCH_1):GND
 R34    GND VSS_R34 @T6G_MB_LIB.T6G(SCH_1):GND
 R35    GND VSS_R35 @T6G_MB_LIB.T6G(SCH_1):GND
 R36    GND VSS_R36 @T6G_MB_LIB.T6G(SCH_1):GND
 R40    GND VSS_R40 @T6G_MB_LIB.T6G(SCH_1):GND
 R41    GND VSS_R41 @T6G_MB_LIB.T6G(SCH_1):GND
 R42    GND VSS_R42 @T6G_MB_LIB.T6G(SCH_1):GND
 R45    GND VSS_R45 @T6G_MB_LIB.T6G(SCH_1):GND


DRAWING: @T6G_MB_LIB.T6G(SCH_1):PAGE59 

GENOA_SP5-SOCKET6096_13568-001,SMLF,IO,DGA^6000030  I1  U26
BV37    GND VSS_BV37 @T6G_MB_LIB.T6G(SCH_1):GND
BL26    GND VSS_BL26 @T6G_MB_LIB.T6G(SCH_1):GND
BL28    GND VSS_BL28 @T6G_MB_LIB.T6G(SCH_1):GND
BL49    GND VSS_BL49 @T6G_MB_LIB.T6G(SCH_1):GND
BL51    GND VSS_BL51 @T6G_MB_LIB.T6G(SCH_1):GND
BL53    GND VSS_BL53 @T6G_MB_LIB.T6G(SCH_1):GND
BL56    GND VSS_BL56 @T6G_MB_LIB.T6G(SCH_1):GND
BL58    GND VSS_BL58 @T6G_MB_LIB.T6G(SCH_1):GND
BL61    GND VSS_BL61 @T6G_MB_LIB.T6G(SCH_1):GND
BL63    GND VSS_BL63 @T6G_MB_LIB.T6G(SCH_1):GND
BL65    GND VSS_BL65 @T6G_MB_LIB.T6G(SCH_1):GND
BL68    GND VSS_BL68 @T6G_MB_LIB.T6G(SCH_1):GND
BL70    GND VSS_BL70 @T6G_MB_LIB.T6G(SCH_1):GND
BL72    GND VSS_BL72 @T6G_MB_LIB.T6G(SCH_1):GND
BL75    GND VSS_BL75 @T6G_MB_LIB.T6G(SCH_1):GND
 BM3    GND VSS_BM3 @T6G_MB_LIB.T6G(SCH_1):GND
 BM8    GND VSS_BM8 @T6G_MB_LIB.T6G(SCH_1):GND
BM10    GND VSS_BM10 @T6G_MB_LIB.T6G(SCH_1):GND
BM15    GND VSS_BM15 @T6G_MB_LIB.T6G(SCH_1):GND
BM17    GND VSS_BM17 @T6G_MB_LIB.T6G(SCH_1):GND
BM23    GND VSS_BM23 @T6G_MB_LIB.T6G(SCH_1):GND
BM25    GND VSS_BM25 @T6G_MB_LIB.T6G(SCH_1):GND
BM27    GND VSS_BM27 @T6G_MB_LIB.T6G(SCH_1):GND
BM29    GND VSS_BM29 @T6G_MB_LIB.T6G(SCH_1):GND
BM31    GND VSS_BM31 @T6G_MB_LIB.T6G(SCH_1):GND
BM33    GND VSS_BM33 @T6G_MB_LIB.T6G(SCH_1):GND
BM35    GND VSS_BM35 @T6G_MB_LIB.T6G(SCH_1):GND
BM37    GND VSS_BM37 @T6G_MB_LIB.T6G(SCH_1):GND
BM40    GND VSS_BM40 @T6G_MB_LIB.T6G(SCH_1):GND
BM42    GND VSS_BM42 @T6G_MB_LIB.T6G(SCH_1):GND
BM44    GND VSS_BM44 @T6G_MB_LIB.T6G(SCH_1):GND
BM46    GND VSS_BM46 @T6G_MB_LIB.T6G(SCH_1):GND
BM48    GND VSS_BM48 @T6G_MB_LIB.T6G(SCH_1):GND
BM50    GND VSS_BM50 @T6G_MB_LIB.T6G(SCH_1):GND
BM52    GND VSS_BM52 @T6G_MB_LIB.T6G(SCH_1):GND
BM54    GND VSS_BM54 @T6G_MB_LIB.T6G(SCH_1):GND
BM59    GND VSS_BM59 @T6G_MB_LIB.T6G(SCH_1):GND
BM61    GND VSS_BM61 @T6G_MB_LIB.T6G(SCH_1):GND
BM66    GND VSS_BM66 @T6G_MB_LIB.T6G(SCH_1):GND
BM68    GND VSS_BM68 @T6G_MB_LIB.T6G(SCH_1):GND
BM73    GND VSS_BM73 @T6G_MB_LIB.T6G(SCH_1):GND
 BN1    GND VSS_BN1 @T6G_MB_LIB.T6G(SCH_1):GND
 BN4    GND VSS_BN4 @T6G_MB_LIB.T6G(SCH_1):GND
 BN6    GND VSS_BN6 @T6G_MB_LIB.T6G(SCH_1):GND
 BN8    GND VSS_BN8 @T6G_MB_LIB.T6G(SCH_1):GND
BN11    GND VSS_BN11 @T6G_MB_LIB.T6G(SCH_1):GND
BN13    GND VSS_BN13 @T6G_MB_LIB.T6G(SCH_1):GND
BN15    GND VSS_BN15 @T6G_MB_LIB.T6G(SCH_1):GND
BN18    GND VSS_BN18 @T6G_MB_LIB.T6G(SCH_1):GND
BN20    GND VSS_BN20 @T6G_MB_LIB.T6G(SCH_1):GND
BN22    GND VSS_BN22 @T6G_MB_LIB.T6G(SCH_1):GND
BN24    GND VSS_BN24 @T6G_MB_LIB.T6G(SCH_1):GND
BN26    GND VSS_BN26 @T6G_MB_LIB.T6G(SCH_1):GND
BN28    GND VSS_BN28 @T6G_MB_LIB.T6G(SCH_1):GND
BN30    GND VSS_BN30 @T6G_MB_LIB.T6G(SCH_1):GND
BN32    GND VSS_BN32 @T6G_MB_LIB.T6G(SCH_1):GND
BN34    GND VSS_BN34 @T6G_MB_LIB.T6G(SCH_1):GND
BN36    GND VSS_BN36 @T6G_MB_LIB.T6G(SCH_1):GND
BN41    GND VSS_BN41 @T6G_MB_LIB.T6G(SCH_1):GND
BN43    GND VSS_BN43 @T6G_MB_LIB.T6G(SCH_1):GND
BN45    GND VSS_BN45 @T6G_MB_LIB.T6G(SCH_1):GND
BN47    GND VSS_BN47 @T6G_MB_LIB.T6G(SCH_1):GND
BN49    GND VSS_BN49 @T6G_MB_LIB.T6G(SCH_1):GND
BN51    GND VSS_BN51 @T6G_MB_LIB.T6G(SCH_1):GND
BN53    GND VSS_BN53 @T6G_MB_LIB.T6G(SCH_1):GND
BN56    GND VSS_BN56 @T6G_MB_LIB.T6G(SCH_1):GND
BN58    GND VSS_BN58 @T6G_MB_LIB.T6G(SCH_1):GND
BN61    GND VSS_BN61 @T6G_MB_LIB.T6G(SCH_1):GND
BN63    GND VSS_BN63 @T6G_MB_LIB.T6G(SCH_1):GND
BN65    GND VSS_BN65 @T6G_MB_LIB.T6G(SCH_1):GND
BN68    GND VSS_BN68 @T6G_MB_LIB.T6G(SCH_1):GND
BN70    GND VSS_BN70 @T6G_MB_LIB.T6G(SCH_1):GND
BN72    GND VSS_BN72 @T6G_MB_LIB.T6G(SCH_1):GND
BN75    GND VSS_BN75 @T6G_MB_LIB.T6G(SCH_1):GND
 BP3    GND VSS_BP3 @T6G_MB_LIB.T6G(SCH_1):GND
 BP5    GND VSS_BP5 @T6G_MB_LIB.T6G(SCH_1):GND
 BP8    GND VSS_BP8 @T6G_MB_LIB.T6G(SCH_1):GND
BP10    GND VSS_BP10 @T6G_MB_LIB.T6G(SCH_1):GND
BP12    GND VSS_BP12 @T6G_MB_LIB.T6G(SCH_1):GND
BP15    GND VSS_BP15 @T6G_MB_LIB.T6G(SCH_1):GND
BP17    GND VSS_BP17 @T6G_MB_LIB.T6G(SCH_1):GND
BP19    GND VSS_BP19 @T6G_MB_LIB.T6G(SCH_1):GND
BP23    GND VSS_BP23 @T6G_MB_LIB.T6G(SCH_1):GND
BP25    GND VSS_BP25 @T6G_MB_LIB.T6G(SCH_1):GND
BP27    GND VSS_BP27 @T6G_MB_LIB.T6G(SCH_1):GND
BP29    GND VSS_BP29 @T6G_MB_LIB.T6G(SCH_1):GND
BP31    GND VSS_BP31 @T6G_MB_LIB.T6G(SCH_1):GND
BP33    GND VSS_BP33 @T6G_MB_LIB.T6G(SCH_1):GND
BP35    GND VSS_BP35 @T6G_MB_LIB.T6G(SCH_1):GND
BP37    GND VSS_BP37 @T6G_MB_LIB.T6G(SCH_1):GND
BP40    GND VSS_BP40 @T6G_MB_LIB.T6G(SCH_1):GND
BP42    GND VSS_BP42 @T6G_MB_LIB.T6G(SCH_1):GND
BP44    GND VSS_BP44 @T6G_MB_LIB.T6G(SCH_1):GND
BP46    GND VSS_BP46 @T6G_MB_LIB.T6G(SCH_1):GND
BP48    GND VSS_BP48 @T6G_MB_LIB.T6G(SCH_1):GND
BP50    GND VSS_BP50 @T6G_MB_LIB.T6G(SCH_1):GND
BP52    GND VSS_BP52 @T6G_MB_LIB.T6G(SCH_1):GND
BP54    GND VSS_BP54 @T6G_MB_LIB.T6G(SCH_1):GND
BP57    GND VSS_BP57 @T6G_MB_LIB.T6G(SCH_1):GND
BP59    GND VSS_BP59 @T6G_MB_LIB.T6G(SCH_1):GND
BP61    GND VSS_BP61 @T6G_MB_LIB.T6G(SCH_1):GND
BP64    GND VSS_BP64 @T6G_MB_LIB.T6G(SCH_1):GND
BP66    GND VSS_BP66 @T6G_MB_LIB.T6G(SCH_1):GND
BP68    GND VSS_BP68 @T6G_MB_LIB.T6G(SCH_1):GND
BP71    GND VSS_BP71 @T6G_MB_LIB.T6G(SCH_1):GND
BP73    GND VSS_BP73 @T6G_MB_LIB.T6G(SCH_1):GND
 BR1    GND VSS_BR1 @T6G_MB_LIB.T6G(SCH_1):GND
 BR3    GND VSS_BR3 @T6G_MB_LIB.T6G(SCH_1):GND
 BR6    GND VSS_BR6 @T6G_MB_LIB.T6G(SCH_1):GND
 BR7    GND VSS_BR7 @T6G_MB_LIB.T6G(SCH_1):GND
 BR8    GND VSS_BR8 @T6G_MB_LIB.T6G(SCH_1):GND
BR10    GND VSS_BR10 @T6G_MB_LIB.T6G(SCH_1):GND
BR13    GND VSS_BR13 @T6G_MB_LIB.T6G(SCH_1):GND
BR14    GND VSS_BR14 @T6G_MB_LIB.T6G(SCH_1):GND
BR15    GND VSS_BR15 @T6G_MB_LIB.T6G(SCH_1):GND
BR17    GND VSS_BR17 @T6G_MB_LIB.T6G(SCH_1):GND
BR20    GND VSS_BR20 @T6G_MB_LIB.T6G(SCH_1):GND
BR21    GND VSS_BR21 @T6G_MB_LIB.T6G(SCH_1):GND
BR22    GND VSS_BR22 @T6G_MB_LIB.T6G(SCH_1):GND
BR24    GND VSS_BR24 @T6G_MB_LIB.T6G(SCH_1):GND
BR26    GND VSS_BR26 @T6G_MB_LIB.T6G(SCH_1):GND
BR28    GND VSS_BR28 @T6G_MB_LIB.T6G(SCH_1):GND
BR30    GND VSS_BR30 @T6G_MB_LIB.T6G(SCH_1):GND
BR32    GND VSS_BR32 @T6G_MB_LIB.T6G(SCH_1):GND
BR34    GND VSS_BR34 @T6G_MB_LIB.T6G(SCH_1):GND
BR36    GND VSS_BR36 @T6G_MB_LIB.T6G(SCH_1):GND
BR41    GND VSS_BR41 @T6G_MB_LIB.T6G(SCH_1):GND
BR43    GND VSS_BR43 @T6G_MB_LIB.T6G(SCH_1):GND
BR45    GND VSS_BR45 @T6G_MB_LIB.T6G(SCH_1):GND
BR47    GND VSS_BR47 @T6G_MB_LIB.T6G(SCH_1):GND
BR49    GND VSS_BR49 @T6G_MB_LIB.T6G(SCH_1):GND
BR51    GND VSS_BR51 @T6G_MB_LIB.T6G(SCH_1):GND
BR55    GND VSS_BR55 @T6G_MB_LIB.T6G(SCH_1):GND
BR56    GND VSS_BR56 @T6G_MB_LIB.T6G(SCH_1):GND
BR59    GND VSS_BR59 @T6G_MB_LIB.T6G(SCH_1):GND
BR61    GND VSS_BR61 @T6G_MB_LIB.T6G(SCH_1):GND
BR62    GND VSS_BR62 @T6G_MB_LIB.T6G(SCH_1):GND
BR63    GND VSS_BR63 @T6G_MB_LIB.T6G(SCH_1):GND
BR66    GND VSS_BR66 @T6G_MB_LIB.T6G(SCH_1):GND
BR68    GND VSS_BR68 @T6G_MB_LIB.T6G(SCH_1):GND
BR69    GND VSS_BR69 @T6G_MB_LIB.T6G(SCH_1):GND
BR70    GND VSS_BR70 @T6G_MB_LIB.T6G(SCH_1):GND
BR73    GND VSS_BR73 @T6G_MB_LIB.T6G(SCH_1):GND
BR75    GND VSS_BR75 @T6G_MB_LIB.T6G(SCH_1):GND
 BT3    GND VSS_BT3 @T6G_MB_LIB.T6G(SCH_1):GND
 BT4    GND VSS_BT4 @T6G_MB_LIB.T6G(SCH_1):GND
 BT5    GND VSS_BT5 @T6G_MB_LIB.T6G(SCH_1):GND
 BT7    GND VSS_BT7 @T6G_MB_LIB.T6G(SCH_1):GND
 BT8    GND VSS_BT8 @T6G_MB_LIB.T6G(SCH_1):GND
BT10    GND VSS_BT10 @T6G_MB_LIB.T6G(SCH_1):GND
BT11    GND VSS_BT11 @T6G_MB_LIB.T6G(SCH_1):GND
BT12    GND VSS_BT12 @T6G_MB_LIB.T6G(SCH_1):GND
BT14    GND VSS_BT14 @T6G_MB_LIB.T6G(SCH_1):GND
BT15    GND VSS_BT15 @T6G_MB_LIB.T6G(SCH_1):GND
BT17    GND VSS_BT17 @T6G_MB_LIB.T6G(SCH_1):GND
BT18    GND VSS_BT18 @T6G_MB_LIB.T6G(SCH_1):GND
BT19    GND VSS_BT19 @T6G_MB_LIB.T6G(SCH_1):GND
BT21    GND VSS_BT21 @T6G_MB_LIB.T6G(SCH_1):GND
BT22    GND VSS_BT22 @T6G_MB_LIB.T6G(SCH_1):GND
BT25    GND VSS_BT25 @T6G_MB_LIB.T6G(SCH_1):GND
BT28    GND VSS_BT28 @T6G_MB_LIB.T6G(SCH_1):GND
BT31    GND VSS_BT31 @T6G_MB_LIB.T6G(SCH_1):GND
BT34    GND VSS_BT34 @T6G_MB_LIB.T6G(SCH_1):GND
BT37    GND VSS_BT37 @T6G_MB_LIB.T6G(SCH_1):GND
BT39    GND VSS_BT39 @T6G_MB_LIB.T6G(SCH_1):GND
BT42    GND VSS_BT42 @T6G_MB_LIB.T6G(SCH_1):GND
BT45    GND VSS_BT45 @T6G_MB_LIB.T6G(SCH_1):GND
BT48    GND VSS_BT48 @T6G_MB_LIB.T6G(SCH_1):GND
BT51    GND VSS_BT51 @T6G_MB_LIB.T6G(SCH_1):GND
BT54    GND VSS_BT54 @T6G_MB_LIB.T6G(SCH_1):GND
BT55    GND VSS_BT55 @T6G_MB_LIB.T6G(SCH_1):GND
BT57    GND VSS_BT57 @T6G_MB_LIB.T6G(SCH_1):GND
BT58    GND VSS_BT58 @T6G_MB_LIB.T6G(SCH_1):GND
BT59    GND VSS_BT59 @T6G_MB_LIB.T6G(SCH_1):GND
BT61    GND VSS_BT61 @T6G_MB_LIB.T6G(SCH_1):GND
BT62    GND VSS_BT62 @T6G_MB_LIB.T6G(SCH_1):GND
BT64    GND VSS_BT64 @T6G_MB_LIB.T6G(SCH_1):GND
BT65    GND VSS_BT65 @T6G_MB_LIB.T6G(SCH_1):GND
BT66    GND VSS_BT66 @T6G_MB_LIB.T6G(SCH_1):GND
BT68    GND VSS_BT68 @T6G_MB_LIB.T6G(SCH_1):GND
BT69    GND VSS_BT69 @T6G_MB_LIB.T6G(SCH_1):GND
BT71    GND VSS_BT71 @T6G_MB_LIB.T6G(SCH_1):GND
BT72    GND VSS_BT72 @T6G_MB_LIB.T6G(SCH_1):GND
BT73    GND VSS_BT73 @T6G_MB_LIB.T6G(SCH_1):GND
 BU1    GND VSS_BU1 @T6G_MB_LIB.T6G(SCH_1):GND
 BU4    GND VSS_BU4 @T6G_MB_LIB.T6G(SCH_1):GND
 BU6    GND VSS_BU6 @T6G_MB_LIB.T6G(SCH_1):GND
 BU8    GND VSS_BU8 @T6G_MB_LIB.T6G(SCH_1):GND
BU11    GND VSS_BU11 @T6G_MB_LIB.T6G(SCH_1):GND
BU13    GND VSS_BU13 @T6G_MB_LIB.T6G(SCH_1):GND
BU15    GND VSS_BU15 @T6G_MB_LIB.T6G(SCH_1):GND
BU18    GND VSS_BU18 @T6G_MB_LIB.T6G(SCH_1):GND
BU20    GND VSS_BU20 @T6G_MB_LIB.T6G(SCH_1):GND
BU22    GND VSS_BU22 @T6G_MB_LIB.T6G(SCH_1):GND
BU25    GND VSS_BU25 @T6G_MB_LIB.T6G(SCH_1):GND
BU28    GND VSS_BU28 @T6G_MB_LIB.T6G(SCH_1):GND
BU31    GND VSS_BU31 @T6G_MB_LIB.T6G(SCH_1):GND
BU34    GND VSS_BU34 @T6G_MB_LIB.T6G(SCH_1):GND
BU35    GND VSS_BU35 @T6G_MB_LIB.T6G(SCH_1):GND
BU36    GND VSS_BU36 @T6G_MB_LIB.T6G(SCH_1):GND
BU40    GND VSS_BU40 @T6G_MB_LIB.T6G(SCH_1):GND
BU41    GND VSS_BU41 @T6G_MB_LIB.T6G(SCH_1):GND
BU42    GND VSS_BU42 @T6G_MB_LIB.T6G(SCH_1):GND
BU45    GND VSS_BU45 @T6G_MB_LIB.T6G(SCH_1):GND
BU48    GND VSS_BU48 @T6G_MB_LIB.T6G(SCH_1):GND
BU51    GND VSS_BU51 @T6G_MB_LIB.T6G(SCH_1):GND
BU54    GND VSS_BU54 @T6G_MB_LIB.T6G(SCH_1):GND
BU56    GND VSS_BU56 @T6G_MB_LIB.T6G(SCH_1):GND
BU58    GND VSS_BU58 @T6G_MB_LIB.T6G(SCH_1):GND
BU61    GND VSS_BU61 @T6G_MB_LIB.T6G(SCH_1):GND
BU63    GND VSS_BU63 @T6G_MB_LIB.T6G(SCH_1):GND
BU65    GND VSS_BU65 @T6G_MB_LIB.T6G(SCH_1):GND
BU68    GND VSS_BU68 @T6G_MB_LIB.T6G(SCH_1):GND
BU70    GND VSS_BU70 @T6G_MB_LIB.T6G(SCH_1):GND
BU72    GND VSS_BU72 @T6G_MB_LIB.T6G(SCH_1):GND
BU75    GND VSS_BU75 @T6G_MB_LIB.T6G(SCH_1):GND
 BV3    GND VSS_BV3 @T6G_MB_LIB.T6G(SCH_1):GND
 BV8    GND VSS_BV8 @T6G_MB_LIB.T6G(SCH_1):GND
BV10    GND VSS_BV10 @T6G_MB_LIB.T6G(SCH_1):GND
BV15    GND VSS_BV15 @T6G_MB_LIB.T6G(SCH_1):GND
BV17    GND VSS_BV17 @T6G_MB_LIB.T6G(SCH_1):GND
BV23    GND VSS_BV23 @T6G_MB_LIB.T6G(SCH_1):GND
BV24    GND VSS_BV24 @T6G_MB_LIB.T6G(SCH_1):GND
BV25    GND VSS_BV25 @T6G_MB_LIB.T6G(SCH_1):GND
BV26    GND VSS_BV26 @T6G_MB_LIB.T6G(SCH_1):GND
BV27    GND VSS_BV27 @T6G_MB_LIB.T6G(SCH_1):GND
BV28    GND VSS_BV28 @T6G_MB_LIB.T6G(SCH_1):GND
BV29    GND VSS_BV29 @T6G_MB_LIB.T6G(SCH_1):GND
BV30    GND VSS_BV30 @T6G_MB_LIB.T6G(SCH_1):GND
BV31    GND VSS_BV31 @T6G_MB_LIB.T6G(SCH_1):GND
BV32    GND VSS_BV32 @T6G_MB_LIB.T6G(SCH_1):GND
BV33    GND VSS_BV33 @T6G_MB_LIB.T6G(SCH_1):GND
BV34    GND VSS_BV34 @T6G_MB_LIB.T6G(SCH_1):GND
BV39    GND VSS_BV39 @T6G_MB_LIB.T6G(SCH_1):GND
BV43    GND VSS_BV43 @T6G_MB_LIB.T6G(SCH_1):GND
BV44    GND VSS_BV44 @T6G_MB_LIB.T6G(SCH_1):GND
BV45    GND VSS_BV45 @T6G_MB_LIB.T6G(SCH_1):GND

GENOA_SP5-SOCKET6096_13568-001,SMLF,IO,DGA^6000030  I2  U26
BV46    GND VSS_BV46 @T6G_MB_LIB.T6G(SCH_1):GND
BV47    GND VSS_BV47 @T6G_MB_LIB.T6G(SCH_1):GND
BV48    GND VSS_BV48 @T6G_MB_LIB.T6G(SCH_1):GND
BV49    GND VSS_BV49 @T6G_MB_LIB.T6G(SCH_1):GND
BV50    GND VSS_BV50 @T6G_MB_LIB.T6G(SCH_1):GND
BV51    GND VSS_BV51 @T6G_MB_LIB.T6G(SCH_1):GND
BV52    GND VSS_BV52 @T6G_MB_LIB.T6G(SCH_1):GND
BV53    GND VSS_BV53 @T6G_MB_LIB.T6G(SCH_1):GND
BV59    GND VSS_BV59 @T6G_MB_LIB.T6G(SCH_1):GND
BV61    GND VSS_BV61 @T6G_MB_LIB.T6G(SCH_1):GND
BV66    GND VSS_BV66 @T6G_MB_LIB.T6G(SCH_1):GND
BV68    GND VSS_BV68 @T6G_MB_LIB.T6G(SCH_1):GND
BV73    GND VSS_BV73 @T6G_MB_LIB.T6G(SCH_1):GND
 BW1    GND VSS_BW1 @T6G_MB_LIB.T6G(SCH_1):GND
 BW4    GND VSS_BW4 @T6G_MB_LIB.T6G(SCH_1):GND
 BW6    GND VSS_BW6 @T6G_MB_LIB.T6G(SCH_1):GND
 BW8    GND VSS_BW8 @T6G_MB_LIB.T6G(SCH_1):GND
BW11    GND VSS_BW11 @T6G_MB_LIB.T6G(SCH_1):GND
BW13    GND VSS_BW13 @T6G_MB_LIB.T6G(SCH_1):GND
BW15    GND VSS_BW15 @T6G_MB_LIB.T6G(SCH_1):GND
BW18    GND VSS_BW18 @T6G_MB_LIB.T6G(SCH_1):GND
BW20    GND VSS_BW20 @T6G_MB_LIB.T6G(SCH_1):GND
BW22    GND VSS_BW22 @T6G_MB_LIB.T6G(SCH_1):GND
BW28    GND VSS_BW28 @T6G_MB_LIB.T6G(SCH_1):GND
BW31    GND VSS_BW31 @T6G_MB_LIB.T6G(SCH_1):GND
BW34    GND VSS_BW34 @T6G_MB_LIB.T6G(SCH_1):GND
BW42    GND VSS_BW42 @T6G_MB_LIB.T6G(SCH_1):GND
BW45    GND VSS_BW45 @T6G_MB_LIB.T6G(SCH_1):GND
BW48    GND VSS_BW48 @T6G_MB_LIB.T6G(SCH_1):GND
BW51    GND VSS_BW51 @T6G_MB_LIB.T6G(SCH_1):GND
BW54    GND VSS_BW54 @T6G_MB_LIB.T6G(SCH_1):GND
BW56    GND VSS_BW56 @T6G_MB_LIB.T6G(SCH_1):GND
BW58    GND VSS_BW58 @T6G_MB_LIB.T6G(SCH_1):GND
BW61    GND VSS_BW61 @T6G_MB_LIB.T6G(SCH_1):GND
BW63    GND VSS_BW63 @T6G_MB_LIB.T6G(SCH_1):GND
BW65    GND VSS_BW65 @T6G_MB_LIB.T6G(SCH_1):GND
BW68    GND VSS_BW68 @T6G_MB_LIB.T6G(SCH_1):GND
BW70    GND VSS_BW70 @T6G_MB_LIB.T6G(SCH_1):GND
BW72    GND VSS_BW72 @T6G_MB_LIB.T6G(SCH_1):GND
BW75    GND VSS_BW75 @T6G_MB_LIB.T6G(SCH_1):GND
 BY3    GND VSS_BY3 @T6G_MB_LIB.T6G(SCH_1):GND
 BY5    GND VSS_BY5 @T6G_MB_LIB.T6G(SCH_1):GND
 BY8    GND VSS_BY8 @T6G_MB_LIB.T6G(SCH_1):GND
BY10    GND VSS_BY10 @T6G_MB_LIB.T6G(SCH_1):GND
BY12    GND VSS_BY12 @T6G_MB_LIB.T6G(SCH_1):GND
BY15    GND VSS_BY15 @T6G_MB_LIB.T6G(SCH_1):GND
BY17    GND VSS_BY17 @T6G_MB_LIB.T6G(SCH_1):GND
BY19    GND VSS_BY19 @T6G_MB_LIB.T6G(SCH_1):GND
BY22    GND VSS_BY22 @T6G_MB_LIB.T6G(SCH_1):GND
BY25    GND VSS_BY25 @T6G_MB_LIB.T6G(SCH_1):GND
BY28    GND VSS_BY28 @T6G_MB_LIB.T6G(SCH_1):GND
BY31    GND VSS_BY31 @T6G_MB_LIB.T6G(SCH_1):GND
BY34    GND VSS_BY34 @T6G_MB_LIB.T6G(SCH_1):GND
BY37    GND VSS_BY37 @T6G_MB_LIB.T6G(SCH_1):GND
BY39    GND VSS_BY39 @T6G_MB_LIB.T6G(SCH_1):GND
BY42    GND VSS_BY42 @T6G_MB_LIB.T6G(SCH_1):GND
BY45    GND VSS_BY45 @T6G_MB_LIB.T6G(SCH_1):GND
BY48    GND VSS_BY48 @T6G_MB_LIB.T6G(SCH_1):GND
BY51    GND VSS_BY51 @T6G_MB_LIB.T6G(SCH_1):GND
BY54    GND VSS_BY54 @T6G_MB_LIB.T6G(SCH_1):GND
BY57    GND VSS_BY57 @T6G_MB_LIB.T6G(SCH_1):GND
BY59    GND VSS_BY59 @T6G_MB_LIB.T6G(SCH_1):GND
BY61    GND VSS_BY61 @T6G_MB_LIB.T6G(SCH_1):GND
BY64    GND VSS_BY64 @T6G_MB_LIB.T6G(SCH_1):GND
BY66    GND VSS_BY66 @T6G_MB_LIB.T6G(SCH_1):GND
BY68    GND VSS_BY68 @T6G_MB_LIB.T6G(SCH_1):GND
BY71    GND VSS_BY71 @T6G_MB_LIB.T6G(SCH_1):GND
BY73    GND VSS_BY73 @T6G_MB_LIB.T6G(SCH_1):GND
 CA1    GND VSS_CA1 @T6G_MB_LIB.T6G(SCH_1):GND
 CA6    GND VSS_CA6 @T6G_MB_LIB.T6G(SCH_1):GND
 CA8    GND VSS_CA8 @T6G_MB_LIB.T6G(SCH_1):GND
CA13    GND VSS_CA13 @T6G_MB_LIB.T6G(SCH_1):GND
CA15    GND VSS_CA15 @T6G_MB_LIB.T6G(SCH_1):GND
CA20    GND VSS_CA20 @T6G_MB_LIB.T6G(SCH_1):GND
CA22    GND VSS_CA22 @T6G_MB_LIB.T6G(SCH_1):GND
CA25    GND VSS_CA25 @T6G_MB_LIB.T6G(SCH_1):GND
CA28    GND VSS_CA28 @T6G_MB_LIB.T6G(SCH_1):GND
CA31    GND VSS_CA31 @T6G_MB_LIB.T6G(SCH_1):GND
CA34    GND VSS_CA34 @T6G_MB_LIB.T6G(SCH_1):GND
CA35    GND VSS_CA35 @T6G_MB_LIB.T6G(SCH_1):GND
CA36    GND VSS_CA36 @T6G_MB_LIB.T6G(SCH_1):GND
CA40    GND VSS_CA40 @T6G_MB_LIB.T6G(SCH_1):GND
CA41    GND VSS_CA41 @T6G_MB_LIB.T6G(SCH_1):GND
CA42    GND VSS_CA42 @T6G_MB_LIB.T6G(SCH_1):GND
CA45    GND VSS_CA45 @T6G_MB_LIB.T6G(SCH_1):GND
CA48    GND VSS_CA48 @T6G_MB_LIB.T6G(SCH_1):GND
CA51    GND VSS_CA51 @T6G_MB_LIB.T6G(SCH_1):GND
CA54    GND VSS_CA54 @T6G_MB_LIB.T6G(SCH_1):GND
CA56    GND VSS_CA56 @T6G_MB_LIB.T6G(SCH_1):GND
CA61    GND VSS_CA61 @T6G_MB_LIB.T6G(SCH_1):GND
CA63    GND VSS_CA63 @T6G_MB_LIB.T6G(SCH_1):GND
CA68    GND VSS_CA68 @T6G_MB_LIB.T6G(SCH_1):GND
CA70    GND VSS_CA70 @T6G_MB_LIB.T6G(SCH_1):GND
CA75    GND VSS_CA75 @T6G_MB_LIB.T6G(SCH_1):GND
 CB3    GND VSS_CB3 @T6G_MB_LIB.T6G(SCH_1):GND
 CB5    GND VSS_CB5 @T6G_MB_LIB.T6G(SCH_1):GND
 CB8    GND VSS_CB8 @T6G_MB_LIB.T6G(SCH_1):GND
CB10    GND VSS_CB10 @T6G_MB_LIB.T6G(SCH_1):GND
CB12    GND VSS_CB12 @T6G_MB_LIB.T6G(SCH_1):GND
CB15    GND VSS_CB15 @T6G_MB_LIB.T6G(SCH_1):GND
CB17    GND VSS_CB17 @T6G_MB_LIB.T6G(SCH_1):GND
CB19    GND VSS_CB19 @T6G_MB_LIB.T6G(SCH_1):GND
CB23    GND VSS_CB23 @T6G_MB_LIB.T6G(SCH_1):GND
CB24    GND VSS_CB24 @T6G_MB_LIB.T6G(SCH_1):GND
CB25    GND VSS_CB25 @T6G_MB_LIB.T6G(SCH_1):GND
CB26    GND VSS_CB26 @T6G_MB_LIB.T6G(SCH_1):GND
CB27    GND VSS_CB27 @T6G_MB_LIB.T6G(SCH_1):GND
CB28    GND VSS_CB28 @T6G_MB_LIB.T6G(SCH_1):GND
CB29    GND VSS_CB29 @T6G_MB_LIB.T6G(SCH_1):GND
CB30    GND VSS_CB30 @T6G_MB_LIB.T6G(SCH_1):GND
CB31    GND VSS_CB31 @T6G_MB_LIB.T6G(SCH_1):GND
CB32    GND VSS_CB32 @T6G_MB_LIB.T6G(SCH_1):GND
CB33    GND VSS_CB33 @T6G_MB_LIB.T6G(SCH_1):GND
CB34    GND VSS_CB34 @T6G_MB_LIB.T6G(SCH_1):GND
CB37    GND VSS_CB37 @T6G_MB_LIB.T6G(SCH_1):GND
CB39    GND VSS_CB39 @T6G_MB_LIB.T6G(SCH_1):GND
CB42    GND VSS_CB42 @T6G_MB_LIB.T6G(SCH_1):GND
CB43    GND VSS_CB43 @T6G_MB_LIB.T6G(SCH_1):GND
CB45    GND VSS_CB45 @T6G_MB_LIB.T6G(SCH_1):GND
CB46    GND VSS_CB46 @T6G_MB_LIB.T6G(SCH_1):GND
CB47    GND VSS_CB47 @T6G_MB_LIB.T6G(SCH_1):GND
CB48    GND VSS_CB48 @T6G_MB_LIB.T6G(SCH_1):GND
CB49    GND VSS_CB49 @T6G_MB_LIB.T6G(SCH_1):GND
CB50    GND VSS_CB50 @T6G_MB_LIB.T6G(SCH_1):GND
CB51    GND VSS_CB51 @T6G_MB_LIB.T6G(SCH_1):GND
CB52    GND VSS_CB52 @T6G_MB_LIB.T6G(SCH_1):GND
CB53    GND VSS_CB53 @T6G_MB_LIB.T6G(SCH_1):GND
CB57    GND VSS_CB57 @T6G_MB_LIB.T6G(SCH_1):GND
CB59    GND VSS_CB59 @T6G_MB_LIB.T6G(SCH_1):GND
CB61    GND VSS_CB61 @T6G_MB_LIB.T6G(SCH_1):GND
CB64    GND VSS_CB64 @T6G_MB_LIB.T6G(SCH_1):GND
CB66    GND VSS_CB66 @T6G_MB_LIB.T6G(SCH_1):GND
CB68    GND VSS_CB68 @T6G_MB_LIB.T6G(SCH_1):GND
CB71    GND VSS_CB71 @T6G_MB_LIB.T6G(SCH_1):GND
CB73    GND VSS_CB73 @T6G_MB_LIB.T6G(SCH_1):GND
 CC1    GND VSS_CC1 @T6G_MB_LIB.T6G(SCH_1):GND
 CC4    GND VSS_CC4 @T6G_MB_LIB.T6G(SCH_1):GND
 CC6    GND VSS_CC6 @T6G_MB_LIB.T6G(SCH_1):GND
 CC8    GND VSS_CC8 @T6G_MB_LIB.T6G(SCH_1):GND
CC11    GND VSS_CC11 @T6G_MB_LIB.T6G(SCH_1):GND
CC13    GND VSS_CC13 @T6G_MB_LIB.T6G(SCH_1):GND
CC15    GND VSS_CC15 @T6G_MB_LIB.T6G(SCH_1):GND
CC18    GND VSS_CC18 @T6G_MB_LIB.T6G(SCH_1):GND
CC20    GND VSS_CC20 @T6G_MB_LIB.T6G(SCH_1):GND
CC25    GND VSS_CC25 @T6G_MB_LIB.T6G(SCH_1):GND
CC28    GND VSS_CC28 @T6G_MB_LIB.T6G(SCH_1):GND
CC31    GND VSS_CC31 @T6G_MB_LIB.T6G(SCH_1):GND
CC34    GND VSS_CC34 @T6G_MB_LIB.T6G(SCH_1):GND
CC42    GND VSS_CC42 @T6G_MB_LIB.T6G(SCH_1):GND
CC45    GND VSS_CC45 @T6G_MB_LIB.T6G(SCH_1):GND
CC48    GND VSS_CC48 @T6G_MB_LIB.T6G(SCH_1):GND
CC51    GND VSS_CC51 @T6G_MB_LIB.T6G(SCH_1):GND
CC54    GND VSS_CC54 @T6G_MB_LIB.T6G(SCH_1):GND
CC56    GND VSS_CC56 @T6G_MB_LIB.T6G(SCH_1):GND
CC58    GND VSS_CC58 @T6G_MB_LIB.T6G(SCH_1):GND
CC61    GND VSS_CC61 @T6G_MB_LIB.T6G(SCH_1):GND
CC63    GND VSS_CC63 @T6G_MB_LIB.T6G(SCH_1):GND
CC65    GND VSS_CC65 @T6G_MB_LIB.T6G(SCH_1):GND
CC68    GND VSS_CC68 @T6G_MB_LIB.T6G(SCH_1):GND
CC70    GND VSS_CC70 @T6G_MB_LIB.T6G(SCH_1):GND
CC72    GND VSS_CC72 @T6G_MB_LIB.T6G(SCH_1):GND
CC75    GND VSS_CC75 @T6G_MB_LIB.T6G(SCH_1):GND
 CD3    GND VSS_CD3 @T6G_MB_LIB.T6G(SCH_1):GND
 CD8    GND VSS_CD8 @T6G_MB_LIB.T6G(SCH_1):GND
CD10    GND VSS_CD10 @T6G_MB_LIB.T6G(SCH_1):GND
CD15    GND VSS_CD15 @T6G_MB_LIB.T6G(SCH_1):GND
CD17    GND VSS_CD17 @T6G_MB_LIB.T6G(SCH_1):GND
CD22    GND VSS_CD22 @T6G_MB_LIB.T6G(SCH_1):GND
CD25    GND VSS_CD25 @T6G_MB_LIB.T6G(SCH_1):GND
CD28    GND VSS_CD28 @T6G_MB_LIB.T6G(SCH_1):GND
CD31    GND VSS_CD31 @T6G_MB_LIB.T6G(SCH_1):GND
CD34    GND VSS_CD34 @T6G_MB_LIB.T6G(SCH_1):GND
CD37    GND VSS_CD37 @T6G_MB_LIB.T6G(SCH_1):GND
CD39    GND VSS_CD39 @T6G_MB_LIB.T6G(SCH_1):GND
CD42    GND VSS_CD42 @T6G_MB_LIB.T6G(SCH_1):GND
CD45    GND VSS_CD45 @T6G_MB_LIB.T6G(SCH_1):GND
CD48    GND VSS_CD48 @T6G_MB_LIB.T6G(SCH_1):GND
CD51    GND VSS_CD51 @T6G_MB_LIB.T6G(SCH_1):GND
CD54    GND VSS_CD54 @T6G_MB_LIB.T6G(SCH_1):GND
CD59    GND VSS_CD59 @T6G_MB_LIB.T6G(SCH_1):GND
CD61    GND VSS_CD61 @T6G_MB_LIB.T6G(SCH_1):GND
CD66    GND VSS_CD66 @T6G_MB_LIB.T6G(SCH_1):GND
CD68    GND VSS_CD68 @T6G_MB_LIB.T6G(SCH_1):GND
CD73    GND VSS_CD73 @T6G_MB_LIB.T6G(SCH_1):GND
 CE1    GND VSS_CE1 @T6G_MB_LIB.T6G(SCH_1):GND
 CE4    GND VSS_CE4 @T6G_MB_LIB.T6G(SCH_1):GND
 CE6    GND VSS_CE6 @T6G_MB_LIB.T6G(SCH_1):GND
 CE8    GND VSS_CE8 @T6G_MB_LIB.T6G(SCH_1):GND
CE11    GND VSS_CE11 @T6G_MB_LIB.T6G(SCH_1):GND
CE13    GND VSS_CE13 @T6G_MB_LIB.T6G(SCH_1):GND
CE15    GND VSS_CE15 @T6G_MB_LIB.T6G(SCH_1):GND
CE18    GND VSS_CE18 @T6G_MB_LIB.T6G(SCH_1):GND
CE20    GND VSS_CE20 @T6G_MB_LIB.T6G(SCH_1):GND
CE22    GND VSS_CE22 @T6G_MB_LIB.T6G(SCH_1):GND
CE25    GND VSS_CE25 @T6G_MB_LIB.T6G(SCH_1):GND
CE28    GND VSS_CE28 @T6G_MB_LIB.T6G(SCH_1):GND
CE31    GND VSS_CE31 @T6G_MB_LIB.T6G(SCH_1):GND
CE34    GND VSS_CE34 @T6G_MB_LIB.T6G(SCH_1):GND
CE35    GND VSS_CE35 @T6G_MB_LIB.T6G(SCH_1):GND
CE36    GND VSS_CE36 @T6G_MB_LIB.T6G(SCH_1):GND
CE40    GND VSS_CE40 @T6G_MB_LIB.T6G(SCH_1):GND
CE41    GND VSS_CE41 @T6G_MB_LIB.T6G(SCH_1):GND
CE42    GND VSS_CE42 @T6G_MB_LIB.T6G(SCH_1):GND
CE45    GND VSS_CE45 @T6G_MB_LIB.T6G(SCH_1):GND
CE48    GND VSS_CE48 @T6G_MB_LIB.T6G(SCH_1):GND
CE51    GND VSS_CE51 @T6G_MB_LIB.T6G(SCH_1):GND
CE54    GND VSS_CE54 @T6G_MB_LIB.T6G(SCH_1):GND
CE56    GND VSS_CE56 @T6G_MB_LIB.T6G(SCH_1):GND
CE58    GND VSS_CE58 @T6G_MB_LIB.T6G(SCH_1):GND
CE61    GND VSS_CE61 @T6G_MB_LIB.T6G(SCH_1):GND
CE63    GND VSS_CE63 @T6G_MB_LIB.T6G(SCH_1):GND
CE65    GND VSS_CE65 @T6G_MB_LIB.T6G(SCH_1):GND
CE68    GND VSS_CE68 @T6G_MB_LIB.T6G(SCH_1):GND
CE70    GND VSS_CE70 @T6G_MB_LIB.T6G(SCH_1):GND
CE72    GND VSS_CE72 @T6G_MB_LIB.T6G(SCH_1):GND
CE75    GND VSS_CE75 @T6G_MB_LIB.T6G(SCH_1):GND
 CF3    GND VSS_CF3 @T6G_MB_LIB.T6G(SCH_1):GND
 CF5    GND VSS_CF5 @T6G_MB_LIB.T6G(SCH_1):GND
 CF8    GND VSS_CF8 @T6G_MB_LIB.T6G(SCH_1):GND
CF10    GND VSS_CF10 @T6G_MB_LIB.T6G(SCH_1):GND
CF12    GND VSS_CF12 @T6G_MB_LIB.T6G(SCH_1):GND
CF15    GND VSS_CF15 @T6G_MB_LIB.T6G(SCH_1):GND
CF17    GND VSS_CF17 @T6G_MB_LIB.T6G(SCH_1):GND
CF19    GND VSS_CF19 @T6G_MB_LIB.T6G(SCH_1):GND
CF23    GND VSS_CF23 @T6G_MB_LIB.T6G(SCH_1):GND
CF24    GND VSS_CF24 @T6G_MB_LIB.T6G(SCH_1):GND
CF25    GND VSS_CF25 @T6G_MB_LIB.T6G(SCH_1):GND
CF26    GND VSS_CF26 @T6G_MB_LIB.T6G(SCH_1):GND
CF27    GND VSS_CF27 @T6G_MB_LIB.T6G(SCH_1):GND
CF28    GND VSS_CF28 @T6G_MB_LIB.T6G(SCH_1):GND
CF29    GND VSS_CF29 @T6G_MB_LIB.T6G(SCH_1):GND
CF30    GND VSS_CF30 @T6G_MB_LIB.T6G(SCH_1):GND
CF31    GND VSS_CF31 @T6G_MB_LIB.T6G(SCH_1):GND
CF32    GND VSS_CF32 @T6G_MB_LIB.T6G(SCH_1):GND
CF33    GND VSS_CF33 @T6G_MB_LIB.T6G(SCH_1):GND

GENOA_SP5-SOCKET6096_13568-001,SMLF,IO,DGA^6000030  I3  U26
CN56    GND VSS_CN56 @T6G_MB_LIB.T6G(SCH_1):GND
CN20    GND VSS_CN20 @T6G_MB_LIB.T6G(SCH_1):GND
CM61    GND VSS_CM61 @T6G_MB_LIB.T6G(SCH_1):GND
CM34    GND VSS_CM34 @T6G_MB_LIB.T6G(SCH_1):GND
CK33    GND VSS_CK33 @T6G_MB_LIB.T6G(SCH_1):GND
CK15    GND VSS_CK15 @T6G_MB_LIB.T6G(SCH_1):GND
CJ58    GND VSS_CJ58 @T6G_MB_LIB.T6G(SCH_1):GND
CJ20    GND VSS_CJ20 @T6G_MB_LIB.T6G(SCH_1):GND
CH68    GND VSS_CH68 @T6G_MB_LIB.T6G(SCH_1):GND
CH39    GND VSS_CH39 @T6G_MB_LIB.T6G(SCH_1):GND
CH10    GND VSS_CH10 @T6G_MB_LIB.T6G(SCH_1):GND
CN22    GND VSS_CN22 @T6G_MB_LIB.T6G(SCH_1):GND
CM64    GND VSS_CM64 @T6G_MB_LIB.T6G(SCH_1):GND
CM37    GND VSS_CM37 @T6G_MB_LIB.T6G(SCH_1):GND
CM24    GND VSS_CM24 @T6G_MB_LIB.T6G(SCH_1):GND
CK17    GND VSS_CK17 @T6G_MB_LIB.T6G(SCH_1):GND
CJ61    GND VSS_CJ61 @T6G_MB_LIB.T6G(SCH_1):GND
CJ23    GND VSS_CJ23 @T6G_MB_LIB.T6G(SCH_1):GND
CH71    GND VSS_CH71 @T6G_MB_LIB.T6G(SCH_1):GND
CH42    GND VSS_CH42 @T6G_MB_LIB.T6G(SCH_1):GND
CH12    GND VSS_CH12 @T6G_MB_LIB.T6G(SCH_1):GND
CM66    GND VSS_CM66 @T6G_MB_LIB.T6G(SCH_1):GND
CM39    GND VSS_CM39 @T6G_MB_LIB.T6G(SCH_1):GND
CM25    GND VSS_CM25 @T6G_MB_LIB.T6G(SCH_1):GND
CL75    GND VSS_CL75 @T6G_MB_LIB.T6G(SCH_1):GND
CJ63    GND VSS_CJ63 @T6G_MB_LIB.T6G(SCH_1):GND
CJ31    GND VSS_CJ31 @T6G_MB_LIB.T6G(SCH_1):GND
CH73    GND VSS_CH73 @T6G_MB_LIB.T6G(SCH_1):GND
CH45    GND VSS_CH45 @T6G_MB_LIB.T6G(SCH_1):GND
CH15    GND VSS_CH15 @T6G_MB_LIB.T6G(SCH_1):GND
CM42    GND VSS_CM42 @T6G_MB_LIB.T6G(SCH_1):GND
CM26    GND VSS_CM26 @T6G_MB_LIB.T6G(SCH_1):GND
 CM3    GND VSS_CM3 @T6G_MB_LIB.T6G(SCH_1):GND
CL51    GND VSS_CL51 @T6G_MB_LIB.T6G(SCH_1):GND
CJ34    GND VSS_CJ34 @T6G_MB_LIB.T6G(SCH_1):GND
 CJ1    GND VSS_CJ1 @T6G_MB_LIB.T6G(SCH_1):GND
CH48    GND VSS_CH48 @T6G_MB_LIB.T6G(SCH_1):GND
CH17    GND VSS_CH17 @T6G_MB_LIB.T6G(SCH_1):GND
CM43    GND VSS_CM43 @T6G_MB_LIB.T6G(SCH_1):GND
CM27    GND VSS_CM27 @T6G_MB_LIB.T6G(SCH_1):GND
 CM5    GND VSS_CM5 @T6G_MB_LIB.T6G(SCH_1):GND
CL54    GND VSS_CL54 @T6G_MB_LIB.T6G(SCH_1):GND
CL28    GND VSS_CL28 @T6G_MB_LIB.T6G(SCH_1):GND
 CJ4    GND VSS_CJ4 @T6G_MB_LIB.T6G(SCH_1):GND
CH51    GND VSS_CH51 @T6G_MB_LIB.T6G(SCH_1):GND
CH19    GND VSS_CH19 @T6G_MB_LIB.T6G(SCH_1):GND
CF34    GND VSS_CF34 @T6G_MB_LIB.T6G(SCH_1):GND
CF37    GND VSS_CF37 @T6G_MB_LIB.T6G(SCH_1):GND
CF39    GND VSS_CF39 @T6G_MB_LIB.T6G(SCH_1):GND
CF42    GND VSS_CF42 @T6G_MB_LIB.T6G(SCH_1):GND
CF43    GND VSS_CF43 @T6G_MB_LIB.T6G(SCH_1):GND
CF44    GND VSS_CF44 @T6G_MB_LIB.T6G(SCH_1):GND
CF45    GND VSS_CF45 @T6G_MB_LIB.T6G(SCH_1):GND
CF47    GND VSS_CF47 @T6G_MB_LIB.T6G(SCH_1):GND
CF48    GND VSS_CF48 @T6G_MB_LIB.T6G(SCH_1):GND
CF49    GND VSS_CF49 @T6G_MB_LIB.T6G(SCH_1):GND
CF50    GND VSS_CF50 @T6G_MB_LIB.T6G(SCH_1):GND
CF51    GND VSS_CF51 @T6G_MB_LIB.T6G(SCH_1):GND
CF52    GND VSS_CF52 @T6G_MB_LIB.T6G(SCH_1):GND
CF53    GND VSS_CF53 @T6G_MB_LIB.T6G(SCH_1):GND
CF57    GND VSS_CF57 @T6G_MB_LIB.T6G(SCH_1):GND
CF59    GND VSS_CF59 @T6G_MB_LIB.T6G(SCH_1):GND
CF61    GND VSS_CF61 @T6G_MB_LIB.T6G(SCH_1):GND
CF64    GND VSS_CF64 @T6G_MB_LIB.T6G(SCH_1):GND
CF66    GND VSS_CF66 @T6G_MB_LIB.T6G(SCH_1):GND
CF68    GND VSS_CF68 @T6G_MB_LIB.T6G(SCH_1):GND
CF71    GND VSS_CF71 @T6G_MB_LIB.T6G(SCH_1):GND
CF73    GND VSS_CF73 @T6G_MB_LIB.T6G(SCH_1):GND
 CG1    GND VSS_CG1 @T6G_MB_LIB.T6G(SCH_1):GND
 CG6    GND VSS_CG6 @T6G_MB_LIB.T6G(SCH_1):GND
 CG8    GND VSS_CG8 @T6G_MB_LIB.T6G(SCH_1):GND
CG13    GND VSS_CG13 @T6G_MB_LIB.T6G(SCH_1):GND
CG15    GND VSS_CG15 @T6G_MB_LIB.T6G(SCH_1):GND
CG20    GND VSS_CG20 @T6G_MB_LIB.T6G(SCH_1):GND
CG22    GND VSS_CG22 @T6G_MB_LIB.T6G(SCH_1):GND
CG25    GND VSS_CG25 @T6G_MB_LIB.T6G(SCH_1):GND
CG28    GND VSS_CG28 @T6G_MB_LIB.T6G(SCH_1):GND
CG31    GND VSS_CG31 @T6G_MB_LIB.T6G(SCH_1):GND
CG34    GND VSS_CG34 @T6G_MB_LIB.T6G(SCH_1):GND
CG45    GND VSS_CG45 @T6G_MB_LIB.T6G(SCH_1):GND
CG48    GND VSS_CG48 @T6G_MB_LIB.T6G(SCH_1):GND
CG51    GND VSS_CG51 @T6G_MB_LIB.T6G(SCH_1):GND
CG54    GND VSS_CG54 @T6G_MB_LIB.T6G(SCH_1):GND
CG56    GND VSS_CG56 @T6G_MB_LIB.T6G(SCH_1):GND
CG61    GND VSS_CG61 @T6G_MB_LIB.T6G(SCH_1):GND
CG63    GND VSS_CG63 @T6G_MB_LIB.T6G(SCH_1):GND
CG68    GND VSS_CG68 @T6G_MB_LIB.T6G(SCH_1):GND
CG70    GND VSS_CG70 @T6G_MB_LIB.T6G(SCH_1):GND
CG75    GND VSS_CG75 @T6G_MB_LIB.T6G(SCH_1):GND
 CH3    GND VSS_CH3 @T6G_MB_LIB.T6G(SCH_1):GND
 CH5    GND VSS_CH5 @T6G_MB_LIB.T6G(SCH_1):GND
 CH8    GND VSS_CH8 @T6G_MB_LIB.T6G(SCH_1):GND
CH22    GND VSS_CH22 @T6G_MB_LIB.T6G(SCH_1):GND
CH25    GND VSS_CH25 @T6G_MB_LIB.T6G(SCH_1):GND
CH28    GND VSS_CH28 @T6G_MB_LIB.T6G(SCH_1):GND
CH31    GND VSS_CH31 @T6G_MB_LIB.T6G(SCH_1):GND
CH34    GND VSS_CH34 @T6G_MB_LIB.T6G(SCH_1):GND
CH37    GND VSS_CH37 @T6G_MB_LIB.T6G(SCH_1):GND
CH54    GND VSS_CH54 @T6G_MB_LIB.T6G(SCH_1):GND
CH57    GND VSS_CH57 @T6G_MB_LIB.T6G(SCH_1):GND
CH59    GND VSS_CH59 @T6G_MB_LIB.T6G(SCH_1):GND
CH61    GND VSS_CH61 @T6G_MB_LIB.T6G(SCH_1):GND
CH64    GND VSS_CH64 @T6G_MB_LIB.T6G(SCH_1):GND
CH66    GND VSS_CH66 @T6G_MB_LIB.T6G(SCH_1):GND
 CJ6    GND VSS_CJ6 @T6G_MB_LIB.T6G(SCH_1):GND
 CJ8    GND VSS_CJ8 @T6G_MB_LIB.T6G(SCH_1):GND
CJ11    GND VSS_CJ11 @T6G_MB_LIB.T6G(SCH_1):GND
CJ13    GND VSS_CJ13 @T6G_MB_LIB.T6G(SCH_1):GND
CJ15    GND VSS_CJ15 @T6G_MB_LIB.T6G(SCH_1):GND
CJ18    GND VSS_CJ18 @T6G_MB_LIB.T6G(SCH_1):GND
CJ35    GND VSS_CJ35 @T6G_MB_LIB.T6G(SCH_1):GND
CJ36    GND VSS_CJ36 @T6G_MB_LIB.T6G(SCH_1):GND
CJ40    GND VSS_CJ40 @T6G_MB_LIB.T6G(SCH_1):GND
CJ41    GND VSS_CJ41 @T6G_MB_LIB.T6G(SCH_1):GND
CJ42    GND VSS_CJ42 @T6G_MB_LIB.T6G(SCH_1):GND
CJ45    GND VSS_CJ45 @T6G_MB_LIB.T6G(SCH_1):GND
CJ56    GND VSS_CJ56 @T6G_MB_LIB.T6G(SCH_1):GND
CJ65    GND VSS_CJ65 @T6G_MB_LIB.T6G(SCH_1):GND
CJ68    GND VSS_CJ68 @T6G_MB_LIB.T6G(SCH_1):GND
CJ70    GND VSS_CJ70 @T6G_MB_LIB.T6G(SCH_1):GND
CJ72    GND VSS_CJ72 @T6G_MB_LIB.T6G(SCH_1):GND
CJ75    GND VSS_CJ75 @T6G_MB_LIB.T6G(SCH_1):GND
 CK3    GND VSS_CK3 @T6G_MB_LIB.T6G(SCH_1):GND
 CK8    GND VSS_CK8 @T6G_MB_LIB.T6G(SCH_1):GND
CK22    GND VSS_CK22 @T6G_MB_LIB.T6G(SCH_1):GND
CK23    GND VSS_CK23 @T6G_MB_LIB.T6G(SCH_1):GND
CK24    GND VSS_CK24 @T6G_MB_LIB.T6G(SCH_1):GND
CK25    GND VSS_CK25 @T6G_MB_LIB.T6G(SCH_1):GND
CK26    GND VSS_CK26 @T6G_MB_LIB.T6G(SCH_1):GND
CK27    GND VSS_CK27 @T6G_MB_LIB.T6G(SCH_1):GND
CK28    GND VSS_CK28 @T6G_MB_LIB.T6G(SCH_1):GND
CK32    GND VSS_CK32 @T6G_MB_LIB.T6G(SCH_1):GND
CK34    GND VSS_CK34 @T6G_MB_LIB.T6G(SCH_1):GND
CK37    GND VSS_CK37 @T6G_MB_LIB.T6G(SCH_1):GND
CK39    GND VSS_CK39 @T6G_MB_LIB.T6G(SCH_1):GND
CK42    GND VSS_CK42 @T6G_MB_LIB.T6G(SCH_1):GND
CK43    GND VSS_CK43 @T6G_MB_LIB.T6G(SCH_1):GND
CK44    GND VSS_CK44 @T6G_MB_LIB.T6G(SCH_1):GND
CK45    GND VSS_CK45 @T6G_MB_LIB.T6G(SCH_1):GND
CK48    GND VSS_CK48 @T6G_MB_LIB.T6G(SCH_1):GND
CK49    GND VSS_CK49 @T6G_MB_LIB.T6G(SCH_1):GND
CK50    GND VSS_CK50 @T6G_MB_LIB.T6G(SCH_1):GND
CK51    GND VSS_CK51 @T6G_MB_LIB.T6G(SCH_1):GND
CK52    GND VSS_CK52 @T6G_MB_LIB.T6G(SCH_1):GND
CK53    GND VSS_CK53 @T6G_MB_LIB.T6G(SCH_1):GND
CK54    GND VSS_CK54 @T6G_MB_LIB.T6G(SCH_1):GND
CK59    GND VSS_CK59 @T6G_MB_LIB.T6G(SCH_1):GND
CK61    GND VSS_CK61 @T6G_MB_LIB.T6G(SCH_1):GND
CK66    GND VSS_CK66 @T6G_MB_LIB.T6G(SCH_1):GND
CK68    GND VSS_CK68 @T6G_MB_LIB.T6G(SCH_1):GND
CK73    GND VSS_CK73 @T6G_MB_LIB.T6G(SCH_1):GND
 CL1    GND VSS_CL1 @T6G_MB_LIB.T6G(SCH_1):GND
 CL4    GND VSS_CL4 @T6G_MB_LIB.T6G(SCH_1):GND
 CL6    GND VSS_CL6 @T6G_MB_LIB.T6G(SCH_1):GND
 CL8    GND VSS_CL8 @T6G_MB_LIB.T6G(SCH_1):GND
CL11    GND VSS_CL11 @T6G_MB_LIB.T6G(SCH_1):GND
CL13    GND VSS_CL13 @T6G_MB_LIB.T6G(SCH_1):GND
CL15    GND VSS_CL15 @T6G_MB_LIB.T6G(SCH_1):GND
CL18    GND VSS_CL18 @T6G_MB_LIB.T6G(SCH_1):GND
CL20    GND VSS_CL20 @T6G_MB_LIB.T6G(SCH_1):GND
CL22    GND VSS_CL22 @T6G_MB_LIB.T6G(SCH_1):GND
CL25    GND VSS_CL25 @T6G_MB_LIB.T6G(SCH_1):GND
CL31    GND VSS_CL31 @T6G_MB_LIB.T6G(SCH_1):GND
CL34    GND VSS_CL34 @T6G_MB_LIB.T6G(SCH_1):GND
CL35    GND VSS_CL35 @T6G_MB_LIB.T6G(SCH_1):GND
CL36    GND VSS_CL36 @T6G_MB_LIB.T6G(SCH_1):GND
CL40    GND VSS_CL40 @T6G_MB_LIB.T6G(SCH_1):GND
CL41    GND VSS_CL41 @T6G_MB_LIB.T6G(SCH_1):GND
CL42    GND VSS_CL42 @T6G_MB_LIB.T6G(SCH_1):GND
CL45    GND VSS_CL45 @T6G_MB_LIB.T6G(SCH_1):GND
CL48    GND VSS_CL48 @T6G_MB_LIB.T6G(SCH_1):GND
CL56    GND VSS_CL56 @T6G_MB_LIB.T6G(SCH_1):GND
CL58    GND VSS_CL58 @T6G_MB_LIB.T6G(SCH_1):GND
CL61    GND VSS_CL61 @T6G_MB_LIB.T6G(SCH_1):GND
CL63    GND VSS_CL63 @T6G_MB_LIB.T6G(SCH_1):GND
CL65    GND VSS_CL65 @T6G_MB_LIB.T6G(SCH_1):GND
CL68    GND VSS_CL68 @T6G_MB_LIB.T6G(SCH_1):GND
CL70    GND VSS_CL70 @T6G_MB_LIB.T6G(SCH_1):GND
CL72    GND VSS_CL72 @T6G_MB_LIB.T6G(SCH_1):GND
 CM8    GND VSS_CM8 @T6G_MB_LIB.T6G(SCH_1):GND
CM10    GND VSS_CM10 @T6G_MB_LIB.T6G(SCH_1):GND
CM12    GND VSS_CM12 @T6G_MB_LIB.T6G(SCH_1):GND
CM15    GND VSS_CM15 @T6G_MB_LIB.T6G(SCH_1):GND
CM17    GND VSS_CM17 @T6G_MB_LIB.T6G(SCH_1):GND
CM19    GND VSS_CM19 @T6G_MB_LIB.T6G(SCH_1):GND
CM23    GND VSS_CM23 @T6G_MB_LIB.T6G(SCH_1):GND
CM28    GND VSS_CM28 @T6G_MB_LIB.T6G(SCH_1):GND
CM29    GND VSS_CM29 @T6G_MB_LIB.T6G(SCH_1):GND
CM30    GND VSS_CM30 @T6G_MB_LIB.T6G(SCH_1):GND
CM31    GND VSS_CM31 @T6G_MB_LIB.T6G(SCH_1):GND
CM32    GND VSS_CM32 @T6G_MB_LIB.T6G(SCH_1):GND
CM33    GND VSS_CM33 @T6G_MB_LIB.T6G(SCH_1):GND
CM44    GND VSS_CM44 @T6G_MB_LIB.T6G(SCH_1):GND
CM45    GND VSS_CM45 @T6G_MB_LIB.T6G(SCH_1):GND
CM46    GND VSS_CM46 @T6G_MB_LIB.T6G(SCH_1):GND
CM47    GND VSS_CM47 @T6G_MB_LIB.T6G(SCH_1):GND
CM48    GND VSS_CM48 @T6G_MB_LIB.T6G(SCH_1):GND
CM49    GND VSS_CM49 @T6G_MB_LIB.T6G(SCH_1):GND
CM51    GND VSS_CM51 @T6G_MB_LIB.T6G(SCH_1):GND
CM52    GND VSS_CM52 @T6G_MB_LIB.T6G(SCH_1):GND
CM53    GND VSS_CM53 @T6G_MB_LIB.T6G(SCH_1):GND
CM57    GND VSS_CM57 @T6G_MB_LIB.T6G(SCH_1):GND
CM59    GND VSS_CM59 @T6G_MB_LIB.T6G(SCH_1):GND
CM68    GND VSS_CM68 @T6G_MB_LIB.T6G(SCH_1):GND
CM71    GND VSS_CM71 @T6G_MB_LIB.T6G(SCH_1):GND
CM73    GND VSS_CM73 @T6G_MB_LIB.T6G(SCH_1):GND
 CN1    GND VSS_CN1 @T6G_MB_LIB.T6G(SCH_1):GND
 CN6    GND VSS_CN6 @T6G_MB_LIB.T6G(SCH_1):GND
 CN8    GND VSS_CN8 @T6G_MB_LIB.T6G(SCH_1):GND
CN13    GND VSS_CN13 @T6G_MB_LIB.T6G(SCH_1):GND
CN15    GND VSS_CN15 @T6G_MB_LIB.T6G(SCH_1):GND
CN25    GND VSS_CN25 @T6G_MB_LIB.T6G(SCH_1):GND
CN28    GND VSS_CN28 @T6G_MB_LIB.T6G(SCH_1):GND
CN31    GND VSS_CN31 @T6G_MB_LIB.T6G(SCH_1):GND
CN34    GND VSS_CN34 @T6G_MB_LIB.T6G(SCH_1):GND
CN42    GND VSS_CN42 @T6G_MB_LIB.T6G(SCH_1):GND
CN45    GND VSS_CN45 @T6G_MB_LIB.T6G(SCH_1):GND
CN48    GND VSS_CN48 @T6G_MB_LIB.T6G(SCH_1):GND
CN51    GND VSS_CN51 @T6G_MB_LIB.T6G(SCH_1):GND
CN61    GND VSS_CN61 @T6G_MB_LIB.T6G(SCH_1):GND
CN63    GND VSS_CN63 @T6G_MB_LIB.T6G(SCH_1):GND
CN68    GND VSS_CN68 @T6G_MB_LIB.T6G(SCH_1):GND
CN70    GND VSS_CN70 @T6G_MB_LIB.T6G(SCH_1):GND
CN75    GND VSS_CN75 @T6G_MB_LIB.T6G(SCH_1):GND
 CP3    GND VSS_CP3 @T6G_MB_LIB.T6G(SCH_1):GND
 CP5    GND VSS_CP5 @T6G_MB_LIB.T6G(SCH_1):GND
 CP8    GND VSS_CP8 @T6G_MB_LIB.T6G(SCH_1):GND
CP10    GND VSS_CP10 @T6G_MB_LIB.T6G(SCH_1):GND
CP12    GND VSS_CP12 @T6G_MB_LIB.T6G(SCH_1):GND
CP15    GND VSS_CP15 @T6G_MB_LIB.T6G(SCH_1):GND
CP17    GND VSS_CP17 @T6G_MB_LIB.T6G(SCH_1):GND
CP19    GND VSS_CP19 @T6G_MB_LIB.T6G(SCH_1):GND

GENOA_SP5-SOCKET6096_13568-001,SMLF,IO,DGA^6000030  I4  U26
CP22    GND VSS_CP22 @T6G_MB_LIB.T6G(SCH_1):GND
CP42    GND VSS_CP42 @T6G_MB_LIB.T6G(SCH_1):GND
CP45    GND VSS_CP45 @T6G_MB_LIB.T6G(SCH_1):GND
CP48    GND VSS_CP48 @T6G_MB_LIB.T6G(SCH_1):GND
CP51    GND VSS_CP51 @T6G_MB_LIB.T6G(SCH_1):GND
CP54    GND VSS_CP54 @T6G_MB_LIB.T6G(SCH_1):GND
CP71    GND VSS_CP71 @T6G_MB_LIB.T6G(SCH_1):GND
CP73    GND VSS_CP73 @T6G_MB_LIB.T6G(SCH_1):GND
 CR1    GND VSS_CR1 @T6G_MB_LIB.T6G(SCH_1):GND
 CR4    GND VSS_CR4 @T6G_MB_LIB.T6G(SCH_1):GND
 CR6    GND VSS_CR6 @T6G_MB_LIB.T6G(SCH_1):GND
CR22    GND VSS_CR22 @T6G_MB_LIB.T6G(SCH_1):GND
CR25    GND VSS_CR25 @T6G_MB_LIB.T6G(SCH_1):GND
CR28    GND VSS_CR28 @T6G_MB_LIB.T6G(SCH_1):GND
CR31    GND VSS_CR31 @T6G_MB_LIB.T6G(SCH_1):GND
CR34    GND VSS_CR34 @T6G_MB_LIB.T6G(SCH_1):GND
CR48    GND VSS_CR48 @T6G_MB_LIB.T6G(SCH_1):GND
CR51    GND VSS_CR51 @T6G_MB_LIB.T6G(SCH_1):GND
CR54    GND VSS_CR54 @T6G_MB_LIB.T6G(SCH_1):GND
CR56    GND VSS_CR56 @T6G_MB_LIB.T6G(SCH_1):GND
CR58    GND VSS_CR58 @T6G_MB_LIB.T6G(SCH_1):GND
CR75    GND VSS_CR75 @T6G_MB_LIB.T6G(SCH_1):GND
 CT3    GND VSS_CT3 @T6G_MB_LIB.T6G(SCH_1):GND
 CT8    GND VSS_CT8 @T6G_MB_LIB.T6G(SCH_1):GND
CT10    GND VSS_CT10 @T6G_MB_LIB.T6G(SCH_1):GND
CT15    GND VSS_CT15 @T6G_MB_LIB.T6G(SCH_1):GND
CT48    GND VSS_CT48 @T6G_MB_LIB.T6G(SCH_1):GND
CT73    GND VSS_CT73 @T6G_MB_LIB.T6G(SCH_1):GND
 CU1    GND VSS_CU1 @T6G_MB_LIB.T6G(SCH_1):GND
CU22    GND VSS_CU22 @T6G_MB_LIB.T6G(SCH_1):GND
CU25    GND VSS_CU25 @T6G_MB_LIB.T6G(SCH_1):GND
CU28    GND VSS_CU28 @T6G_MB_LIB.T6G(SCH_1):GND
CU56    GND VSS_CU56 @T6G_MB_LIB.T6G(SCH_1):GND
CU61    GND VSS_CU61 @T6G_MB_LIB.T6G(SCH_1):GND
CU63    GND VSS_CU63 @T6G_MB_LIB.T6G(SCH_1):GND
 CV5    GND VSS_CV5 @T6G_MB_LIB.T6G(SCH_1):GND
 CV8    GND VSS_CV8 @T6G_MB_LIB.T6G(SCH_1):GND
CV10    GND VSS_CV10 @T6G_MB_LIB.T6G(SCH_1):GND
CV12    GND VSS_CV12 @T6G_MB_LIB.T6G(SCH_1):GND
CV15    GND VSS_CV15 @T6G_MB_LIB.T6G(SCH_1):GND
CV34    GND VSS_CV34 @T6G_MB_LIB.T6G(SCH_1):GND
CV37    GND VSS_CV37 @T6G_MB_LIB.T6G(SCH_1):GND
CV39    GND VSS_CV39 @T6G_MB_LIB.T6G(SCH_1):GND
CV42    GND VSS_CV42 @T6G_MB_LIB.T6G(SCH_1):GND
CV45    GND VSS_CV45 @T6G_MB_LIB.T6G(SCH_1):GND
CV64    GND VSS_CV64 @T6G_MB_LIB.T6G(SCH_1):GND
CV66    GND VSS_CV66 @T6G_MB_LIB.T6G(SCH_1):GND
CV68    GND VSS_CV68 @T6G_MB_LIB.T6G(SCH_1):GND
CV71    GND VSS_CV71 @T6G_MB_LIB.T6G(SCH_1):GND
CV73    GND VSS_CV73 @T6G_MB_LIB.T6G(SCH_1):GND
CW22    GND VSS_CW22 @T6G_MB_LIB.T6G(SCH_1):GND
CW25    GND VSS_CW25 @T6G_MB_LIB.T6G(SCH_1):GND
CW28    GND VSS_CW28 @T6G_MB_LIB.T6G(SCH_1):GND
CW31    GND VSS_CW31 @T6G_MB_LIB.T6G(SCH_1):GND
CW34    GND VSS_CW34 @T6G_MB_LIB.T6G(SCH_1):GND
CY32    GND VSS_CY32 @T6G_MB_LIB.T6G(SCH_1):GND
CY47    GND VSS_CY47 @T6G_MB_LIB.T6G(SCH_1):GND
CY48    GND VSS_CY48 @T6G_MB_LIB.T6G(SCH_1):GND
CY64    GND VSS_CY64 @T6G_MB_LIB.T6G(SCH_1):GND
CY66    GND VSS_CY66 @T6G_MB_LIB.T6G(SCH_1):GND
CY68    GND VSS_CY68 @T6G_MB_LIB.T6G(SCH_1):GND
DA13    GND VSS_DA13 @T6G_MB_LIB.T6G(SCH_1):GND
DA15    GND VSS_DA15 @T6G_MB_LIB.T6G(SCH_1):GND
DA18    GND VSS_DA18 @T6G_MB_LIB.T6G(SCH_1):GND
DA20    GND VSS_DA20 @T6G_MB_LIB.T6G(SCH_1):GND
DA45    GND VSS_DA45 @T6G_MB_LIB.T6G(SCH_1):GND
DA48    GND VSS_DA48 @T6G_MB_LIB.T6G(SCH_1):GND
DA51    GND VSS_DA51 @T6G_MB_LIB.T6G(SCH_1):GND
DA54    GND VSS_DA54 @T6G_MB_LIB.T6G(SCH_1):GND
CP25    GND VSS_CP25 @T6G_MB_LIB.T6G(SCH_1):GND
CP28    GND VSS_CP28 @T6G_MB_LIB.T6G(SCH_1):GND
CP31    GND VSS_CP31 @T6G_MB_LIB.T6G(SCH_1):GND
CP34    GND VSS_CP34 @T6G_MB_LIB.T6G(SCH_1):GND
CP37    GND VSS_CP37 @T6G_MB_LIB.T6G(SCH_1):GND
CP39    GND VSS_CP39 @T6G_MB_LIB.T6G(SCH_1):GND
CP57    GND VSS_CP57 @T6G_MB_LIB.T6G(SCH_1):GND
CP59    GND VSS_CP59 @T6G_MB_LIB.T6G(SCH_1):GND
CP61    GND VSS_CP61 @T6G_MB_LIB.T6G(SCH_1):GND
CP64    GND VSS_CP64 @T6G_MB_LIB.T6G(SCH_1):GND
CP66    GND VSS_CP66 @T6G_MB_LIB.T6G(SCH_1):GND
CP68    GND VSS_CP68 @T6G_MB_LIB.T6G(SCH_1):GND
 CR8    GND VSS_CR8 @T6G_MB_LIB.T6G(SCH_1):GND
CR11    GND VSS_CR11 @T6G_MB_LIB.T6G(SCH_1):GND
CR13    GND VSS_CR13 @T6G_MB_LIB.T6G(SCH_1):GND
CR15    GND VSS_CR15 @T6G_MB_LIB.T6G(SCH_1):GND
CR18    GND VSS_CR18 @T6G_MB_LIB.T6G(SCH_1):GND
CR20    GND VSS_CR20 @T6G_MB_LIB.T6G(SCH_1):GND
CR35    GND VSS_CR35 @T6G_MB_LIB.T6G(SCH_1):GND
CR36    GND VSS_CR36 @T6G_MB_LIB.T6G(SCH_1):GND
CR40    GND VSS_CR40 @T6G_MB_LIB.T6G(SCH_1):GND
CR41    GND VSS_CR41 @T6G_MB_LIB.T6G(SCH_1):GND
CR42    GND VSS_CR42 @T6G_MB_LIB.T6G(SCH_1):GND
CR45    GND VSS_CR45 @T6G_MB_LIB.T6G(SCH_1):GND
CR61    GND VSS_CR61 @T6G_MB_LIB.T6G(SCH_1):GND
CR63    GND VSS_CR63 @T6G_MB_LIB.T6G(SCH_1):GND
CR65    GND VSS_CR65 @T6G_MB_LIB.T6G(SCH_1):GND
CR68    GND VSS_CR68 @T6G_MB_LIB.T6G(SCH_1):GND
CR70    GND VSS_CR70 @T6G_MB_LIB.T6G(SCH_1):GND
CR72    GND VSS_CR72 @T6G_MB_LIB.T6G(SCH_1):GND
CT17    GND VSS_CT17 @T6G_MB_LIB.T6G(SCH_1):GND
CT23    GND VSS_CT23 @T6G_MB_LIB.T6G(SCH_1):GND
CT24    GND VSS_CT24 @T6G_MB_LIB.T6G(SCH_1):GND
CT25    GND VSS_CT25 @T6G_MB_LIB.T6G(SCH_1):GND
CT26    GND VSS_CT26 @T6G_MB_LIB.T6G(SCH_1):GND
CT27    GND VSS_CT27 @T6G_MB_LIB.T6G(SCH_1):GND
CT28    GND VSS_CT28 @T6G_MB_LIB.T6G(SCH_1):GND
CT29    GND VSS_CT29 @T6G_MB_LIB.T6G(SCH_1):GND
CT30    GND VSS_CT30 @T6G_MB_LIB.T6G(SCH_1):GND
CT31    GND VSS_CT31 @T6G_MB_LIB.T6G(SCH_1):GND
CT32    GND VSS_CT32 @T6G_MB_LIB.T6G(SCH_1):GND
CT33    GND VSS_CT33 @T6G_MB_LIB.T6G(SCH_1):GND
CT34    GND VSS_CT34 @T6G_MB_LIB.T6G(SCH_1):GND
CT37    GND VSS_CT37 @T6G_MB_LIB.T6G(SCH_1):GND
CT39    GND VSS_CT39 @T6G_MB_LIB.T6G(SCH_1):GND
CT42    GND VSS_CT42 @T6G_MB_LIB.T6G(SCH_1):GND
CT43    GND VSS_CT43 @T6G_MB_LIB.T6G(SCH_1):GND
CT44    GND VSS_CT44 @T6G_MB_LIB.T6G(SCH_1):GND
CT45    GND VSS_CT45 @T6G_MB_LIB.T6G(SCH_1):GND
CT46    GND VSS_CT46 @T6G_MB_LIB.T6G(SCH_1):GND
CT47    GND VSS_CT47 @T6G_MB_LIB.T6G(SCH_1):GND
CT49    GND VSS_CT49 @T6G_MB_LIB.T6G(SCH_1):GND
CT50    GND VSS_CT50 @T6G_MB_LIB.T6G(SCH_1):GND
CT51    GND VSS_CT51 @T6G_MB_LIB.T6G(SCH_1):GND
CT53    GND VSS_CT53 @T6G_MB_LIB.T6G(SCH_1):GND
CT59    GND VSS_CT59 @T6G_MB_LIB.T6G(SCH_1):GND
CT61    GND VSS_CT61 @T6G_MB_LIB.T6G(SCH_1):GND
CT66    GND VSS_CT66 @T6G_MB_LIB.T6G(SCH_1):GND
CT68    GND VSS_CT68 @T6G_MB_LIB.T6G(SCH_1):GND
 CU4    GND VSS_CU4 @T6G_MB_LIB.T6G(SCH_1):GND
 CU6    GND VSS_CU6 @T6G_MB_LIB.T6G(SCH_1):GND
 CU8    GND VSS_CU8 @T6G_MB_LIB.T6G(SCH_1):GND
CU11    GND VSS_CU11 @T6G_MB_LIB.T6G(SCH_1):GND
CU13    GND VSS_CU13 @T6G_MB_LIB.T6G(SCH_1):GND
CU15    GND VSS_CU15 @T6G_MB_LIB.T6G(SCH_1):GND
CU18    GND VSS_CU18 @T6G_MB_LIB.T6G(SCH_1):GND
CU20    GND VSS_CU20 @T6G_MB_LIB.T6G(SCH_1):GND
CU31    GND VSS_CU31 @T6G_MB_LIB.T6G(SCH_1):GND
CU34    GND VSS_CU34 @T6G_MB_LIB.T6G(SCH_1):GND
CU42    GND VSS_CU42 @T6G_MB_LIB.T6G(SCH_1):GND
CU45    GND VSS_CU45 @T6G_MB_LIB.T6G(SCH_1):GND
CU48    GND VSS_CU48 @T6G_MB_LIB.T6G(SCH_1):GND
CU51    GND VSS_CU51 @T6G_MB_LIB.T6G(SCH_1):GND
CU54    GND VSS_CU54 @T6G_MB_LIB.T6G(SCH_1):GND
CU65    GND VSS_CU65 @T6G_MB_LIB.T6G(SCH_1):GND
CU68    GND VSS_CU68 @T6G_MB_LIB.T6G(SCH_1):GND
CU70    GND VSS_CU70 @T6G_MB_LIB.T6G(SCH_1):GND
CU72    GND VSS_CU72 @T6G_MB_LIB.T6G(SCH_1):GND
CU75    GND VSS_CU75 @T6G_MB_LIB.T6G(SCH_1):GND
 CV3    GND VSS_CV3 @T6G_MB_LIB.T6G(SCH_1):GND
CV17    GND VSS_CV17 @T6G_MB_LIB.T6G(SCH_1):GND
CV19    GND VSS_CV19 @T6G_MB_LIB.T6G(SCH_1):GND
CV22    GND VSS_CV22 @T6G_MB_LIB.T6G(SCH_1):GND
CV25    GND VSS_CV25 @T6G_MB_LIB.T6G(SCH_1):GND
CV28    GND VSS_CV28 @T6G_MB_LIB.T6G(SCH_1):GND
CV31    GND VSS_CV31 @T6G_MB_LIB.T6G(SCH_1):GND
CV48    GND VSS_CV48 @T6G_MB_LIB.T6G(SCH_1):GND
CV51    GND VSS_CV51 @T6G_MB_LIB.T6G(SCH_1):GND
CV54    GND VSS_CV54 @T6G_MB_LIB.T6G(SCH_1):GND
CV57    GND VSS_CV57 @T6G_MB_LIB.T6G(SCH_1):GND
CV59    GND VSS_CV59 @T6G_MB_LIB.T6G(SCH_1):GND
CV61    GND VSS_CV61 @T6G_MB_LIB.T6G(SCH_1):GND
 CW1    GND VSS_CW1 @T6G_MB_LIB.T6G(SCH_1):GND
 CW6    GND VSS_CW6 @T6G_MB_LIB.T6G(SCH_1):GND
 CW8    GND VSS_CW8 @T6G_MB_LIB.T6G(SCH_1):GND
CW13    GND VSS_CW13 @T6G_MB_LIB.T6G(SCH_1):GND
CW15    GND VSS_CW15 @T6G_MB_LIB.T6G(SCH_1):GND
CW20    GND VSS_CW20 @T6G_MB_LIB.T6G(SCH_1):GND
CW35    GND VSS_CW35 @T6G_MB_LIB.T6G(SCH_1):GND
CW36    GND VSS_CW36 @T6G_MB_LIB.T6G(SCH_1):GND
CW40    GND VSS_CW40 @T6G_MB_LIB.T6G(SCH_1):GND
CW41    GND VSS_CW41 @T6G_MB_LIB.T6G(SCH_1):GND
CW42    GND VSS_CW42 @T6G_MB_LIB.T6G(SCH_1):GND
CW45    GND VSS_CW45 @T6G_MB_LIB.T6G(SCH_1):GND
CW48    GND VSS_CW48 @T6G_MB_LIB.T6G(SCH_1):GND
CW51    GND VSS_CW51 @T6G_MB_LIB.T6G(SCH_1):GND
CW54    GND VSS_CW54 @T6G_MB_LIB.T6G(SCH_1):GND
CW56    GND VSS_CW56 @T6G_MB_LIB.T6G(SCH_1):GND
CW61    GND VSS_CW61 @T6G_MB_LIB.T6G(SCH_1):GND
CW63    GND VSS_CW63 @T6G_MB_LIB.T6G(SCH_1):GND
CW68    GND VSS_CW68 @T6G_MB_LIB.T6G(SCH_1):GND
CW70    GND VSS_CW70 @T6G_MB_LIB.T6G(SCH_1):GND
CW75    GND VSS_CW75 @T6G_MB_LIB.T6G(SCH_1):GND
 CY3    GND VSS_CY3 @T6G_MB_LIB.T6G(SCH_1):GND
 CY5    GND VSS_CY5 @T6G_MB_LIB.T6G(SCH_1):GND
 CY8    GND VSS_CY8 @T6G_MB_LIB.T6G(SCH_1):GND
CY10    GND VSS_CY10 @T6G_MB_LIB.T6G(SCH_1):GND
CY12    GND VSS_CY12 @T6G_MB_LIB.T6G(SCH_1):GND
CY15    GND VSS_CY15 @T6G_MB_LIB.T6G(SCH_1):GND
CY17    GND VSS_CY17 @T6G_MB_LIB.T6G(SCH_1):GND
CY19    GND VSS_CY19 @T6G_MB_LIB.T6G(SCH_1):GND
CY23    GND VSS_CY23 @T6G_MB_LIB.T6G(SCH_1):GND
CY24    GND VSS_CY24 @T6G_MB_LIB.T6G(SCH_1):GND
CY25    GND VSS_CY25 @T6G_MB_LIB.T6G(SCH_1):GND
CY26    GND VSS_CY26 @T6G_MB_LIB.T6G(SCH_1):GND
CY27    GND VSS_CY27 @T6G_MB_LIB.T6G(SCH_1):GND
CY28    GND VSS_CY28 @T6G_MB_LIB.T6G(SCH_1):GND
CY29    GND VSS_CY29 @T6G_MB_LIB.T6G(SCH_1):GND
CY30    GND VSS_CY30 @T6G_MB_LIB.T6G(SCH_1):GND
CY31    GND VSS_CY31 @T6G_MB_LIB.T6G(SCH_1):GND
CY33    GND VSS_CY33 @T6G_MB_LIB.T6G(SCH_1):GND
CY34    GND VSS_CY34 @T6G_MB_LIB.T6G(SCH_1):GND
CY37    GND VSS_CY37 @T6G_MB_LIB.T6G(SCH_1):GND
CY39    GND VSS_CY39 @T6G_MB_LIB.T6G(SCH_1):GND
CY42    GND VSS_CY42 @T6G_MB_LIB.T6G(SCH_1):GND
CY43    GND VSS_CY43 @T6G_MB_LIB.T6G(SCH_1):GND
CY44    GND VSS_CY44 @T6G_MB_LIB.T6G(SCH_1):GND
CY45    GND VSS_CY45 @T6G_MB_LIB.T6G(SCH_1):GND
CY46    GND VSS_CY46 @T6G_MB_LIB.T6G(SCH_1):GND
CY49    GND VSS_CY49 @T6G_MB_LIB.T6G(SCH_1):GND
CY50    GND VSS_CY50 @T6G_MB_LIB.T6G(SCH_1):GND
CY51    GND VSS_CY51 @T6G_MB_LIB.T6G(SCH_1):GND
CY52    GND VSS_CY52 @T6G_MB_LIB.T6G(SCH_1):GND
CY53    GND VSS_CY53 @T6G_MB_LIB.T6G(SCH_1):GND
CY59    GND VSS_CY59 @T6G_MB_LIB.T6G(SCH_1):GND
CY61    GND VSS_CY61 @T6G_MB_LIB.T6G(SCH_1):GND
CY71    GND VSS_CY71 @T6G_MB_LIB.T6G(SCH_1):GND
CY73    GND VSS_CY73 @T6G_MB_LIB.T6G(SCH_1):GND
 DA1    GND VSS_DA1 @T6G_MB_LIB.T6G(SCH_1):GND
 DA4    GND VSS_DA4 @T6G_MB_LIB.T6G(SCH_1):GND
 DA6    GND VSS_DA6 @T6G_MB_LIB.T6G(SCH_1):GND
 DA8    GND VSS_DA8 @T6G_MB_LIB.T6G(SCH_1):GND
DA11    GND VSS_DA11 @T6G_MB_LIB.T6G(SCH_1):GND
DA22    GND VSS_DA22 @T6G_MB_LIB.T6G(SCH_1):GND
DA25    GND VSS_DA25 @T6G_MB_LIB.T6G(SCH_1):GND
DA28    GND VSS_DA28 @T6G_MB_LIB.T6G(SCH_1):GND
DA31    GND VSS_DA31 @T6G_MB_LIB.T6G(SCH_1):GND
DA34    GND VSS_DA34 @T6G_MB_LIB.T6G(SCH_1):GND
DA42    GND VSS_DA42 @T6G_MB_LIB.T6G(SCH_1):GND
DA58    GND VSS_DA58 @T6G_MB_LIB.T6G(SCH_1):GND
DA61    GND VSS_DA61 @T6G_MB_LIB.T6G(SCH_1):GND
DA63    GND VSS_DA63 @T6G_MB_LIB.T6G(SCH_1):GND
DA65    GND VSS_DA65 @T6G_MB_LIB.T6G(SCH_1):GND
DA68    GND VSS_DA68 @T6G_MB_LIB.T6G(SCH_1):GND
DA70    GND VSS_DA70 @T6G_MB_LIB.T6G(SCH_1):GND


DRAWING: @T6G_MB_LIB.T6G(SCH_1):PAGE60 

GENOA_SP5-SOCKET6096_13568-001,SMLF,IO,DGA^6000030  I3  U26
DB15    GND VSS_DB15 @T6G_MB_LIB.T6G(SCH_1):GND
DB17    GND VSS_DB17 @T6G_MB_LIB.T6G(SCH_1):GND
DB22    GND VSS_DB22 @T6G_MB_LIB.T6G(SCH_1):GND
DB25    GND VSS_DB25 @T6G_MB_LIB.T6G(SCH_1):GND
DB48    GND VSS_DB48 @T6G_MB_LIB.T6G(SCH_1):GND
DB51    GND VSS_DB51 @T6G_MB_LIB.T6G(SCH_1):GND
DB54    GND VSS_DB54 @T6G_MB_LIB.T6G(SCH_1):GND
DB59    GND VSS_DB59 @T6G_MB_LIB.T6G(SCH_1):GND
DC13    GND VSS_DC13 @T6G_MB_LIB.T6G(SCH_1):GND
DC15    GND VSS_DC15 @T6G_MB_LIB.T6G(SCH_1):GND
DC45    GND VSS_DC45 @T6G_MB_LIB.T6G(SCH_1):GND
DC48    GND VSS_DC48 @T6G_MB_LIB.T6G(SCH_1):GND
DC51    GND VSS_DC51 @T6G_MB_LIB.T6G(SCH_1):GND
DC70    GND VSS_DC70 @T6G_MB_LIB.T6G(SCH_1):GND
DC72    GND VSS_DC72 @T6G_MB_LIB.T6G(SCH_1):GND
DC75    GND VSS_DC75 @T6G_MB_LIB.T6G(SCH_1):GND
 DD3    GND VSS_DD3 @T6G_MB_LIB.T6G(SCH_1):GND
DD23    GND VSS_DD23 @T6G_MB_LIB.T6G(SCH_1):GND
DD24    GND VSS_DD24 @T6G_MB_LIB.T6G(SCH_1):GND
DD26    GND VSS_DD26 @T6G_MB_LIB.T6G(SCH_1):GND
DD27    GND VSS_DD27 @T6G_MB_LIB.T6G(SCH_1):GND
DD39    GND VSS_DD39 @T6G_MB_LIB.T6G(SCH_1):GND
DD40    GND VSS_DD40 @T6G_MB_LIB.T6G(SCH_1):GND
DD41    GND VSS_DD41 @T6G_MB_LIB.T6G(SCH_1):GND
DD43    GND VSS_DD43 @T6G_MB_LIB.T6G(SCH_1):GND
DD57    GND VSS_DD57 @T6G_MB_LIB.T6G(SCH_1):GND
DD59    GND VSS_DD59 @T6G_MB_LIB.T6G(SCH_1):GND
DD61    GND VSS_DD61 @T6G_MB_LIB.T6G(SCH_1):GND
DD64    GND VSS_DD64 @T6G_MB_LIB.T6G(SCH_1):GND
DE13    GND VSS_DE13 @T6G_MB_LIB.T6G(SCH_1):GND
DE15    GND VSS_DE15 @T6G_MB_LIB.T6G(SCH_1):GND
DE20    GND VSS_DE20 @T6G_MB_LIB.T6G(SCH_1):GND
DE23    GND VSS_DE23 @T6G_MB_LIB.T6G(SCH_1):GND
DE70    GND VSS_DE70 @T6G_MB_LIB.T6G(SCH_1):GND
DE75    GND VSS_DE75 @T6G_MB_LIB.T6G(SCH_1):GND
 DF3    GND VSS_DF3 @T6G_MB_LIB.T6G(SCH_1):GND
 DF4    GND VSS_DF4 @T6G_MB_LIB.T6G(SCH_1):GND
DF15    GND VSS_DF15 @T6G_MB_LIB.T6G(SCH_1):GND
DF17    GND VSS_DF17 @T6G_MB_LIB.T6G(SCH_1):GND
DF18    GND VSS_DF18 @T6G_MB_LIB.T6G(SCH_1):GND
DF19    GND VSS_DF19 @T6G_MB_LIB.T6G(SCH_1):GND
DF43    GND VSS_DF43 @T6G_MB_LIB.T6G(SCH_1):GND
DF53    GND VSS_DF53 @T6G_MB_LIB.T6G(SCH_1):GND
DF54    GND VSS_DF54 @T6G_MB_LIB.T6G(SCH_1):GND
DF66    GND VSS_DF66 @T6G_MB_LIB.T6G(SCH_1):GND
DF68    GND VSS_DF68 @T6G_MB_LIB.T6G(SCH_1):GND
DF70    GND VSS_DF70 @T6G_MB_LIB.T6G(SCH_1):GND
 DG8    GND VSS_DG8 @T6G_MB_LIB.T6G(SCH_1):GND
 DG9    GND VSS_DG9 @T6G_MB_LIB.T6G(SCH_1):GND
DG13    GND VSS_DG13 @T6G_MB_LIB.T6G(SCH_1):GND
DG14    GND VSS_DG14 @T6G_MB_LIB.T6G(SCH_1):GND
DG30    GND VSS_DG30 @T6G_MB_LIB.T6G(SCH_1):GND
DG33    GND VSS_DG33 @T6G_MB_LIB.T6G(SCH_1):GND
DG41    GND VSS_DG41 @T6G_MB_LIB.T6G(SCH_1):GND
DG43    GND VSS_DG43 @T6G_MB_LIB.T6G(SCH_1):GND
DG61    GND VSS_DG61 @T6G_MB_LIB.T6G(SCH_1):GND
DG62    GND VSS_DG62 @T6G_MB_LIB.T6G(SCH_1):GND
DG63    GND VSS_DG63 @T6G_MB_LIB.T6G(SCH_1):GND
DG65    GND VSS_DG65 @T6G_MB_LIB.T6G(SCH_1):GND
 DH5    GND VSS_DH5 @T6G_MB_LIB.T6G(SCH_1):GND
DH11    GND VSS_DH11 @T6G_MB_LIB.T6G(SCH_1):GND
DH18    GND VSS_DH18 @T6G_MB_LIB.T6G(SCH_1):GND
DH37    GND VSS_DH37 @T6G_MB_LIB.T6G(SCH_1):GND
DH61    GND VSS_DH61 @T6G_MB_LIB.T6G(SCH_1):GND
DH63    GND VSS_DH63 @T6G_MB_LIB.T6G(SCH_1):GND
DH64    GND VSS_DH64 @T6G_MB_LIB.T6G(SCH_1):GND
DH66    GND VSS_DH66 @T6G_MB_LIB.T6G(SCH_1):GND
DA72    GND VSS_DA72 @T6G_MB_LIB.T6G(SCH_1):GND
DA75    GND VSS_DA75 @T6G_MB_LIB.T6G(SCH_1):GND
 DB3    GND VSS_DB3 @T6G_MB_LIB.T6G(SCH_1):GND
 DB8    GND VSS_DB8 @T6G_MB_LIB.T6G(SCH_1):GND
DB10    GND VSS_DB10 @T6G_MB_LIB.T6G(SCH_1):GND
DB28    GND VSS_DB28 @T6G_MB_LIB.T6G(SCH_1):GND
DB31    GND VSS_DB31 @T6G_MB_LIB.T6G(SCH_1):GND
DB34    GND VSS_DB34 @T6G_MB_LIB.T6G(SCH_1):GND
DB37    GND VSS_DB37 @T6G_MB_LIB.T6G(SCH_1):GND
DB39    GND VSS_DB39 @T6G_MB_LIB.T6G(SCH_1):GND
DB42    GND VSS_DB42 @T6G_MB_LIB.T6G(SCH_1):GND
DB45    GND VSS_DB45 @T6G_MB_LIB.T6G(SCH_1):GND
DB61    GND VSS_DB61 @T6G_MB_LIB.T6G(SCH_1):GND
DB66    GND VSS_DB66 @T6G_MB_LIB.T6G(SCH_1):GND
DB68    GND VSS_DB68 @T6G_MB_LIB.T6G(SCH_1):GND
DB73    GND VSS_DB73 @T6G_MB_LIB.T6G(SCH_1):GND
 DC1    GND VSS_DC1 @T6G_MB_LIB.T6G(SCH_1):GND
 DC4    GND VSS_DC4 @T6G_MB_LIB.T6G(SCH_1):GND
 DC6    GND VSS_DC6 @T6G_MB_LIB.T6G(SCH_1):GND
 DC8    GND VSS_DC8 @T6G_MB_LIB.T6G(SCH_1):GND
DC11    GND VSS_DC11 @T6G_MB_LIB.T6G(SCH_1):GND
DC18    GND VSS_DC18 @T6G_MB_LIB.T6G(SCH_1):GND
DC20    GND VSS_DC20 @T6G_MB_LIB.T6G(SCH_1):GND
DC22    GND VSS_DC22 @T6G_MB_LIB.T6G(SCH_1):GND
DC25    GND VSS_DC25 @T6G_MB_LIB.T6G(SCH_1):GND
DC28    GND VSS_DC28 @T6G_MB_LIB.T6G(SCH_1):GND
DC31    GND VSS_DC31 @T6G_MB_LIB.T6G(SCH_1):GND
DC34    GND VSS_DC34 @T6G_MB_LIB.T6G(SCH_1):GND
DC42    GND VSS_DC42 @T6G_MB_LIB.T6G(SCH_1):GND
DC54    GND VSS_DC54 @T6G_MB_LIB.T6G(SCH_1):GND
DC56    GND VSS_DC56 @T6G_MB_LIB.T6G(SCH_1):GND
DC58    GND VSS_DC58 @T6G_MB_LIB.T6G(SCH_1):GND
DC61    GND VSS_DC61 @T6G_MB_LIB.T6G(SCH_1):GND
DC63    GND VSS_DC63 @T6G_MB_LIB.T6G(SCH_1):GND
DC65    GND VSS_DC65 @T6G_MB_LIB.T6G(SCH_1):GND
DC68    GND VSS_DC68 @T6G_MB_LIB.T6G(SCH_1):GND
 DD5    GND VSS_DD5 @T6G_MB_LIB.T6G(SCH_1):GND
 DD8    GND VSS_DD8 @T6G_MB_LIB.T6G(SCH_1):GND
DD10    GND VSS_DD10 @T6G_MB_LIB.T6G(SCH_1):GND
DD12    GND VSS_DD12 @T6G_MB_LIB.T6G(SCH_1):GND
DD15    GND VSS_DD15 @T6G_MB_LIB.T6G(SCH_1):GND
DD17    GND VSS_DD17 @T6G_MB_LIB.T6G(SCH_1):GND
DD19    GND VSS_DD19 @T6G_MB_LIB.T6G(SCH_1):GND
DD29    GND VSS_DD29 @T6G_MB_LIB.T6G(SCH_1):GND
DD30    GND VSS_DD30 @T6G_MB_LIB.T6G(SCH_1):GND
DD32    GND VSS_DD32 @T6G_MB_LIB.T6G(SCH_1):GND
DD33    GND VSS_DD33 @T6G_MB_LIB.T6G(SCH_1):GND
DD35    GND VSS_DD35 @T6G_MB_LIB.T6G(SCH_1):GND
DD36    GND VSS_DD36 @T6G_MB_LIB.T6G(SCH_1):GND
DD37    GND VSS_DD37 @T6G_MB_LIB.T6G(SCH_1):GND
DD44    GND VSS_DD44 @T6G_MB_LIB.T6G(SCH_1):GND
DD46    GND VSS_DD46 @T6G_MB_LIB.T6G(SCH_1):GND
DD47    GND VSS_DD47 @T6G_MB_LIB.T6G(SCH_1):GND
DD49    GND VSS_DD49 @T6G_MB_LIB.T6G(SCH_1):GND
DD50    GND VSS_DD50 @T6G_MB_LIB.T6G(SCH_1):GND
DD52    GND VSS_DD52 @T6G_MB_LIB.T6G(SCH_1):GND
DD53    GND VSS_DD53 @T6G_MB_LIB.T6G(SCH_1):GND
DD66    GND VSS_DD66 @T6G_MB_LIB.T6G(SCH_1):GND
DD68    GND VSS_DD68 @T6G_MB_LIB.T6G(SCH_1):GND
DD71    GND VSS_DD71 @T6G_MB_LIB.T6G(SCH_1):GND
DD73    GND VSS_DD73 @T6G_MB_LIB.T6G(SCH_1):GND
 DE1    GND VSS_DE1 @T6G_MB_LIB.T6G(SCH_1):GND
 DE6    GND VSS_DE6 @T6G_MB_LIB.T6G(SCH_1):GND
 DE8    GND VSS_DE8 @T6G_MB_LIB.T6G(SCH_1):GND
DE26    GND VSS_DE26 @T6G_MB_LIB.T6G(SCH_1):GND
DE29    GND VSS_DE29 @T6G_MB_LIB.T6G(SCH_1):GND
DE33    GND VSS_DE33 @T6G_MB_LIB.T6G(SCH_1):GND
DE56    GND VSS_DE56 @T6G_MB_LIB.T6G(SCH_1):GND
DE61    GND VSS_DE61 @T6G_MB_LIB.T6G(SCH_1):GND
DE63    GND VSS_DE63 @T6G_MB_LIB.T6G(SCH_1):GND
DE68    GND VSS_DE68 @T6G_MB_LIB.T6G(SCH_1):GND
 DF5    GND VSS_DF5 @T6G_MB_LIB.T6G(SCH_1):GND
 DF6    GND VSS_DF6 @T6G_MB_LIB.T6G(SCH_1):GND
 DF8    GND VSS_DF8 @T6G_MB_LIB.T6G(SCH_1):GND
DF10    GND VSS_DF10 @T6G_MB_LIB.T6G(SCH_1):GND
DF11    GND VSS_DF11 @T6G_MB_LIB.T6G(SCH_1):GND
DF12    GND VSS_DF12 @T6G_MB_LIB.T6G(SCH_1):GND
DF13    GND VSS_DF13 @T6G_MB_LIB.T6G(SCH_1):GND
DF20    GND VSS_DF20 @T6G_MB_LIB.T6G(SCH_1):GND
DF22    GND VSS_DF22 @T6G_MB_LIB.T6G(SCH_1):GND
DF23    GND VSS_DF23 @T6G_MB_LIB.T6G(SCH_1):GND
DF26    GND VSS_DF26 @T6G_MB_LIB.T6G(SCH_1):GND
DF29    GND VSS_DF29 @T6G_MB_LIB.T6G(SCH_1):GND
DF32    GND VSS_DF32 @T6G_MB_LIB.T6G(SCH_1):GND
DF35    GND VSS_DF35 @T6G_MB_LIB.T6G(SCH_1):GND
DF37    GND VSS_DF37 @T6G_MB_LIB.T6G(SCH_1):GND
DF39    GND VSS_DF39 @T6G_MB_LIB.T6G(SCH_1):GND
DF42    GND VSS_DF42 @T6G_MB_LIB.T6G(SCH_1):GND
DF44    GND VSS_DF44 @T6G_MB_LIB.T6G(SCH_1):GND
DF45    GND VSS_DF45 @T6G_MB_LIB.T6G(SCH_1):GND
DF46    GND VSS_DF46 @T6G_MB_LIB.T6G(SCH_1):GND
DF47    GND VSS_DF47 @T6G_MB_LIB.T6G(SCH_1):GND
DF48    GND VSS_DF48 @T6G_MB_LIB.T6G(SCH_1):GND
DF49    GND VSS_DF49 @T6G_MB_LIB.T6G(SCH_1):GND
DF50    GND VSS_DF50 @T6G_MB_LIB.T6G(SCH_1):GND
DF51    GND VSS_DF51 @T6G_MB_LIB.T6G(SCH_1):GND
DF52    GND VSS_DF52 @T6G_MB_LIB.T6G(SCH_1):GND
DF56    GND VSS_DF56 @T6G_MB_LIB.T6G(SCH_1):GND
DF57    GND VSS_DF57 @T6G_MB_LIB.T6G(SCH_1):GND
DF58    GND VSS_DF58 @T6G_MB_LIB.T6G(SCH_1):GND
DF59    GND VSS_DF59 @T6G_MB_LIB.T6G(SCH_1):GND
DF61    GND VSS_DF61 @T6G_MB_LIB.T6G(SCH_1):GND
DF63    GND VSS_DF63 @T6G_MB_LIB.T6G(SCH_1):GND
DF64    GND VSS_DF64 @T6G_MB_LIB.T6G(SCH_1):GND
DF65    GND VSS_DF65 @T6G_MB_LIB.T6G(SCH_1):GND
DF71    GND VSS_DF71 @T6G_MB_LIB.T6G(SCH_1):GND
DF72    GND VSS_DF72 @T6G_MB_LIB.T6G(SCH_1):GND
DF73    GND VSS_DF73 @T6G_MB_LIB.T6G(SCH_1):GND
 DG1    GND VSS_DG1 @T6G_MB_LIB.T6G(SCH_1):GND
 DG2    GND VSS_DG2 @T6G_MB_LIB.T6G(SCH_1):GND
 DG6    GND VSS_DG6 @T6G_MB_LIB.T6G(SCH_1):GND
 DG7    GND VSS_DG7 @T6G_MB_LIB.T6G(SCH_1):GND
DG15    GND VSS_DG15 @T6G_MB_LIB.T6G(SCH_1):GND
DG16    GND VSS_DG16 @T6G_MB_LIB.T6G(SCH_1):GND
DG18    GND VSS_DG18 @T6G_MB_LIB.T6G(SCH_1):GND
DG20    GND VSS_DG20 @T6G_MB_LIB.T6G(SCH_1):GND
DG21    GND VSS_DG21 @T6G_MB_LIB.T6G(SCH_1):GND
DG24    GND VSS_DG24 @T6G_MB_LIB.T6G(SCH_1):GND
DG27    GND VSS_DG27 @T6G_MB_LIB.T6G(SCH_1):GND
DG46    GND VSS_DG46 @T6G_MB_LIB.T6G(SCH_1):GND
DG49    GND VSS_DG49 @T6G_MB_LIB.T6G(SCH_1):GND
DG52    GND VSS_DG52 @T6G_MB_LIB.T6G(SCH_1):GND
DG55    GND VSS_DG55 @T6G_MB_LIB.T6G(SCH_1):GND
DG56    GND VSS_DG56 @T6G_MB_LIB.T6G(SCH_1):GND
DG59    GND VSS_DG59 @T6G_MB_LIB.T6G(SCH_1):GND
DG60    GND VSS_DG60 @T6G_MB_LIB.T6G(SCH_1):GND
DG66    GND VSS_DG66 @T6G_MB_LIB.T6G(SCH_1):GND
DG67    GND VSS_DG67 @T6G_MB_LIB.T6G(SCH_1):GND
DG68    GND VSS_DG68 @T6G_MB_LIB.T6G(SCH_1):GND
DG69    GND VSS_DG69 @T6G_MB_LIB.T6G(SCH_1):GND
DG70    GND VSS_DG70 @T6G_MB_LIB.T6G(SCH_1):GND
DG74    GND VSS_DG74 @T6G_MB_LIB.T6G(SCH_1):GND
DG75    GND VSS_DG75 @T6G_MB_LIB.T6G(SCH_1):GND
DH39    GND VSS_DH39 @T6G_MB_LIB.T6G(SCH_1):GND
DH43    GND VSS_DH43 @T6G_MB_LIB.T6G(SCH_1):GND
DH46    GND VSS_DH46 @T6G_MB_LIB.T6G(SCH_1):GND
DH49    GND VSS_DH49 @T6G_MB_LIB.T6G(SCH_1):GND
DH52    GND VSS_DH52 @T6G_MB_LIB.T6G(SCH_1):GND
DH55    GND VSS_DH55 @T6G_MB_LIB.T6G(SCH_1):GND
DH59    GND VSS_DH59 @T6G_MB_LIB.T6G(SCH_1):GND
DH68    GND VSS_DH68 @T6G_MB_LIB.T6G(SCH_1):GND
DH70    GND VSS_DH70 @T6G_MB_LIB.T6G(SCH_1):GND
 DJ7    GND VSS_DJ7 @T6G_MB_LIB.T6G(SCH_1):GND
DJ15    GND VSS_DJ15 @T6G_MB_LIB.T6G(SCH_1):GND
DJ19    GND VSS_DJ19 @T6G_MB_LIB.T6G(SCH_1):GND
DJ43    GND VSS_DJ43 @T6G_MB_LIB.T6G(SCH_1):GND
DJ49    GND VSS_DJ49 @T6G_MB_LIB.T6G(SCH_1):GND
DJ59    GND VSS_DJ59 @T6G_MB_LIB.T6G(SCH_1):GND
DJ61    GND VSS_DJ61 @T6G_MB_LIB.T6G(SCH_1):GND
DJ63    GND VSS_DJ63 @T6G_MB_LIB.T6G(SCH_1):GND
DJ66    GND VSS_DJ66 @T6G_MB_LIB.T6G(SCH_1):GND
DJ68    GND VSS_DJ68 @T6G_MB_LIB.T6G(SCH_1):GND
DJ73    GND VSS_DJ73 @T6G_MB_LIB.T6G(SCH_1):GND
CY57    GND VSS_CY57 @T6G_MB_LIB.T6G(SCH_1):GND
CK31    GND VSS_CK31 @T6G_MB_LIB.T6G(SCH_1):GND
CB44    GND VSS_CB44 @T6G_MB_LIB.T6G(SCH_1):GND
AM37    GND VSS_AM37 @T6G_MB_LIB.T6G(SCH_1):GND
 K23    GND VSS_K23 @T6G_MB_LIB.T6G(SCH_1):GND
CN54    GND VSS_CN54 @T6G_MB_LIB.T6G(SCH_1):GND
CK10    GND VSS_CK10 @T6G_MB_LIB.T6G(SCH_1):GND
AA72    GND VSS_AA72 @T6G_MB_LIB.T6G(SCH_1):GND
AJ13    GND VSS_AJ13 @T6G_MB_LIB.T6G(SCH_1):GND
AD31    GND VSS_AD31 @T6G_MB_LIB.T6G(SCH_1):GND
AA42    GND VSS_AA42 @T6G_MB_LIB.T6G(SCH_1):GND
 V27    GND VSS_V27 @T6G_MB_LIB.T6G(SCH_1):GND
CF46    GND VSS_CF46 @T6G_MB_LIB.T6G(SCH_1):GND
CC22    GND VSS_CC22 @T6G_MB_LIB.T6G(SCH_1):GND
AN20    GND VSS_AN20 @T6G_MB_LIB.T6G(SCH_1):GND
 P68    GND VSS_P68 @T6G_MB_LIB.T6G(SCH_1):GND
 P25    GND VSS_P25 @T6G_MB_LIB.T6G(SCH_1):GND
CU58    GND VSS_CU58 @T6G_MB_LIB.T6G(SCH_1):GND
BW25    GND VSS_BW25 @T6G_MB_LIB.T6G(SCH_1):GND
AH33    GND VSS_AH33 @T6G_MB_LIB.T6G(SCH_1):GND
 AE4    GND VSS_AE4 @T6G_MB_LIB.T6G(SCH_1):GND
CG42    GND VSS_CG42 @T6G_MB_LIB.T6G(SCH_1):GND
DA56    GND VSS_DA56 @T6G_MB_LIB.T6G(SCH_1):GND
 K59    GND VSS_K59 @T6G_MB_LIB.T6G(SCH_1):GND
CM50    GND VSS_CM50 @T6G_MB_LIB.T6G(SCH_1):GND
CT52    GND VSS_CT52 @T6G_MB_LIB.T6G(SCH_1):GND
BV42    GND VSS_BV42 @T6G_MB_LIB.T6G(SCH_1):GND
 V68    GND VSS_V68 @T6G_MB_LIB.T6G(SCH_1):GND


DRAWING: @T6G_MB_LIB.T6G(SCH_1):PAGE67 

Q_CAP_C0402-22UF,4V,20%,X6S,CH622KMEB02  I83  C3888
   1 PVDDCR_SOC_P0      A @T6G_MB_LIB.T6G(SCH_1):PVDDCR_SOC_P0
   2    GND      B @T6G_MB_LIB.T6G(SCH_1):GND

Q_CAP_C0402-22UF,4V,20%,X6S,CH622KMEB02  I85  C2130
   1 PVDDCR_SOC_P0      A @T6G_MB_LIB.T6G(SCH_1):PVDDCR_SOC_P0
   2    GND      B @T6G_MB_LIB.T6G(SCH_1):GND

Q_CAP_C0402-22UF,4V,20%,X6S,CH622KMEB02  I86  C3889
   1 PVDDCR_SOC_P0      A @T6G_MB_LIB.T6G(SCH_1):PVDDCR_SOC_P0
   2    GND      B @T6G_MB_LIB.T6G(SCH_1):GND

Q_CAP_C0402-22UF,4V,20%,X6S,CH622KMEB02  I87  C2135
   1 PVDDCR_SOC_P0      A @T6G_MB_LIB.T6G(SCH_1):PVDDCR_SOC_P0
   2    GND      B @T6G_MB_LIB.T6G(SCH_1):GND

Q_CAP_C0402-22UF,4V,20%,X6S,CH622KMEB02  I89  C2129
   1 PVDDCR_SOC_P0      A @T6G_MB_LIB.T6G(SCH_1):PVDDCR_SOC_P0
   2    GND      B @T6G_MB_LIB.T6G(SCH_1):GND

Q_CAP_C0402-22UF,4V,20%,X6S,CH622KMEB02  I90  C2134
   1 PVDDCR_SOC_P0      A @T6G_MB_LIB.T6G(SCH_1):PVDDCR_SOC_P0
   2    GND      B @T6G_MB_LIB.T6G(SCH_1):GND

Q_CAP_C0402-22UF,4V,20%,X6S,CH622KMEB02  I92  C2140
   1 PVDDCR_SOC_P0      A @T6G_MB_LIB.T6G(SCH_1):PVDDCR_SOC_P0
   2    GND      B @T6G_MB_LIB.T6G(SCH_1):GND

Q_CAP_C0402-22UF,4V,20%,X6S,CH622KMEB02  I93  C2144
   1 PVDDCR_SOC_P0      A @T6G_MB_LIB.T6G(SCH_1):PVDDCR_SOC_P0
   2    GND      B @T6G_MB_LIB.T6G(SCH_1):GND

Q_CAP_C0402-22UF,4V,20%,X6S,CH622KMEB02  I94  C2148
   1 PVDDCR_SOC_P0      A @T6G_MB_LIB.T6G(SCH_1):PVDDCR_SOC_P0
   2    GND      B @T6G_MB_LIB.T6G(SCH_1):GND

Q_CAP_C0402-22UF,4V,20%,X6S,CH622KMEB02  I95  C2139
   1 PVDDCR_SOC_P0      A @T6G_MB_LIB.T6G(SCH_1):PVDDCR_SOC_P0
   2    GND      B @T6G_MB_LIB.T6G(SCH_1):GND

Q_CAP_C0402-22UF,4V,20%,X6S,CH622KMEB02  I96  C2143
   1 PVDDCR_SOC_P0      A @T6G_MB_LIB.T6G(SCH_1):PVDDCR_SOC_P0
   2    GND      B @T6G_MB_LIB.T6G(SCH_1):GND

Q_CAP_C0402-22UF,4V,20%,X6S,CH622KMEB02  I97  C2152
   1 PVDDCR_SOC_P0      A @T6G_MB_LIB.T6G(SCH_1):PVDDCR_SOC_P0
   2    GND      B @T6G_MB_LIB.T6G(SCH_1):GND

Q_CAP_C0402-22UF,4V,20%,X6S,CH622KMEB02  I98  C2155
   1 PVDDCR_SOC_P0      A @T6G_MB_LIB.T6G(SCH_1):PVDDCR_SOC_P0
   2    GND      B @T6G_MB_LIB.T6G(SCH_1):GND

Q_CAP_C0402-22UF,4V,20%,X6S,CH622KMEB02  I99  C2151
   1 PVDDCR_SOC_P0      A @T6G_MB_LIB.T6G(SCH_1):PVDDCR_SOC_P0
   2    GND      B @T6G_MB_LIB.T6G(SCH_1):GND

Q_CAP_C0402-22UF,4V,20%,X6S,CH622KMEB02  I100  C2154
   1 PVDDCR_SOC_P0      A @T6G_MB_LIB.T6G(SCH_1):PVDDCR_SOC_P0
   2    GND      B @T6G_MB_LIB.T6G(SCH_1):GND

Q_CAP_C0402-22UF,4V,20%,X6S,CH622KMEB02  I101  C3894
   1 PVDDCR_SOC_P0      A @T6G_MB_LIB.T6G(SCH_1):PVDDCR_SOC_P0
   2    GND      B @T6G_MB_LIB.T6G(SCH_1):GND

Q_CAP_C0402-22UF,4V,20%,X6S,CH622KMEB02  I102  C3895
   1 PVDDCR_SOC_P0      A @T6G_MB_LIB.T6G(SCH_1):PVDDCR_SOC_P0
   2    GND      B @T6G_MB_LIB.T6G(SCH_1):GND

Q_CAP_C0402-22UF,4V,20%,X6S,CH622KMEB02  I103  C2157
   1 PVDDCR_SOC_P0      A @T6G_MB_LIB.T6G(SCH_1):PVDDCR_SOC_P0
   2    GND      B @T6G_MB_LIB.T6G(SCH_1):GND

Q_CAP_C0402-22UF,4V,20%,X6S,CH622KMEB02  I104  C2159
   1 PVDDCR_SOC_P0      A @T6G_MB_LIB.T6G(SCH_1):PVDDCR_SOC_P0
   2    GND      B @T6G_MB_LIB.T6G(SCH_1):GND

Q_CAP_C0402-22UF,4V,20%,X6S,CH622KMEB02  I106  C3896
   1 PVDDCR_SOC_P0      A @T6G_MB_LIB.T6G(SCH_1):PVDDCR_SOC_P0
   2    GND      B @T6G_MB_LIB.T6G(SCH_1):GND

Q_CAP_C0402-22UF,4V,20%,X6S,CH622KMEB02  I108  C2161
   1 PVDDCR_SOC_P0      A @T6G_MB_LIB.T6G(SCH_1):PVDDCR_SOC_P0
   2    GND      B @T6G_MB_LIB.T6G(SCH_1):GND

Q_CAP_C0402-22UF,4V,20%,X6S,CH622KMEB02  I109  C2147
   1 PVDDCR_SOC_P0      A @T6G_MB_LIB.T6G(SCH_1):PVDDCR_SOC_P0
   2    GND      B @T6G_MB_LIB.T6G(SCH_1):GND

Q_CAP_C0402-22UF,4V,20%,X6S,CH622KMEB02  I110  C2133
   1 PVDD11_S3_P0      A @T6G_MB_LIB.T6G(SCH_1):PVDD11_S3_P0
   2    GND      B @T6G_MB_LIB.T6G(SCH_1):GND

Q_CAP_C0402-22UF,4V,20%,X6S,CH622KMEB02  I112  C2138
   1 PVDD11_S3_P0      A @T6G_MB_LIB.T6G(SCH_1):PVDD11_S3_P0
   2    GND      B @T6G_MB_LIB.T6G(SCH_1):GND

Q_CAP_C0402-22UF,4V,20%,X6S,CH622KMEB02  I113  C2132
   1 PVDD11_S3_P0      A @T6G_MB_LIB.T6G(SCH_1):PVDD11_S3_P0
   2    GND      B @T6G_MB_LIB.T6G(SCH_1):GND

Q_CAP_C0402-22UF,4V,20%,X6S,CH622KMEB02  I115  C2137
   1 PVDD11_S3_P0      A @T6G_MB_LIB.T6G(SCH_1):PVDD11_S3_P0
   2    GND      B @T6G_MB_LIB.T6G(SCH_1):GND

Q_CAP_C0402-22UF,4V,20%,X6S,CH622KMEB02  I116  C3890
   1 PVDD11_S3_P0      A @T6G_MB_LIB.T6G(SCH_1):PVDD11_S3_P0
   2    GND      B @T6G_MB_LIB.T6G(SCH_1):GND

Q_CAP_C0402-22UF,4V,20%,X6S,CH622KMEB02  I117  C3891
   1 PVDD11_S3_P0      A @T6G_MB_LIB.T6G(SCH_1):PVDD11_S3_P0
   2    GND      B @T6G_MB_LIB.T6G(SCH_1):GND

Q_CAP_C0402-22UF,4V,20%,X6S,CH622KMEB02  I118  C3892
   1 PVDD11_S3_P0      A @T6G_MB_LIB.T6G(SCH_1):PVDD11_S3_P0
   2    GND      B @T6G_MB_LIB.T6G(SCH_1):GND

Q_CAP_C0402-22UF,4V,20%,X6S,CH622KMEB02  I120  C3893
   1 PVDD11_S3_P0      A @T6G_MB_LIB.T6G(SCH_1):PVDD11_S3_P0
   2    GND      B @T6G_MB_LIB.T6G(SCH_1):GND

Q_CAP_C0402-22UF,4V,20%,X6S,CH622KMEB02  I121  C2142
   1 PVDD11_S3_P0      A @T6G_MB_LIB.T6G(SCH_1):PVDD11_S3_P0
   2    GND      B @T6G_MB_LIB.T6G(SCH_1):GND

Q_CAP_C0402-22UF,4V,20%,X6S,CH622KMEB02  I122  C2146
   1 PVDD11_S3_P0      A @T6G_MB_LIB.T6G(SCH_1):PVDD11_S3_P0
   2    GND      B @T6G_MB_LIB.T6G(SCH_1):GND

Q_CAP_C0402-22UF,4V,20%,X6S,CH622KMEB02  I123  C2150
   1 PVDD11_S3_P0      A @T6G_MB_LIB.T6G(SCH_1):PVDD11_S3_P0
   2    GND      B @T6G_MB_LIB.T6G(SCH_1):GND

Q_CAP_C0402-22UF,4V,20%,X6S,CH622KMEB02  I124  C2153
   1 PVDD11_S3_P0      A @T6G_MB_LIB.T6G(SCH_1):PVDD11_S3_P0
   2    GND      B @T6G_MB_LIB.T6G(SCH_1):GND

Q_CAP_C0402-22UF,4V,20%,X6S,CH622KMEB02  I125  C2156
   1 PVDD11_S3_P0      A @T6G_MB_LIB.T6G(SCH_1):PVDD11_S3_P0
   2    GND      B @T6G_MB_LIB.T6G(SCH_1):GND

Q_CAP_C0402-22UF,4V,20%,X6S,CH622KMEB02  I127  C2158
   1 PVDD11_S3_P0      A @T6G_MB_LIB.T6G(SCH_1):PVDD11_S3_P0
   2    GND      B @T6G_MB_LIB.T6G(SCH_1):GND

Q_CAP_C0402-22UF,4V,20%,X6S,CH622KMEB02  I128  C2160
   1 PVDD11_S3_P0      A @T6G_MB_LIB.T6G(SCH_1):PVDD11_S3_P0
   2    GND      B @T6G_MB_LIB.T6G(SCH_1):GND

Q_CAP_C0402-22UF,4V,20%,X6S,CH622KMEB02  I129  C2162
   1 PVDD11_S3_P0      A @T6G_MB_LIB.T6G(SCH_1):PVDD11_S3_P0
   2    GND      B @T6G_MB_LIB.T6G(SCH_1):GND

Q_CAP_C0402-22UF,4V,20%,X6S,CH622KMEB02  I131  C2163
   1 PVDD18_S5_P0      A @T6G_MB_LIB.T6G(SCH_1):PVDD18_S5_P0
   2    GND      B @T6G_MB_LIB.T6G(SCH_1):GND

Q_CAP_C0402-22UF,4V,20%,X6S,CH622KMEB02  I133  C2164
   1 PVDD18_S5_P0      A @T6G_MB_LIB.T6G(SCH_1):PVDD18_S5_P0
   2    GND      B @T6G_MB_LIB.T6G(SCH_1):GND

Q_CAP_C0402-22UF,4V,20%,X6S,CH622KMEB02  I134  C3897
   1 PVDD18_S5_P0      A @T6G_MB_LIB.T6G(SCH_1):PVDD18_S5_P0
   2    GND      B @T6G_MB_LIB.T6G(SCH_1):GND

Q_CAP_C0402-22UF,4V,20%,X6S,CH622KMEB02  I135  C2131
   1 PVDDIO_P0      A @T6G_MB_LIB.T6G(SCH_1):PVDDIO_P0
   2    GND      B @T6G_MB_LIB.T6G(SCH_1):GND

Q_CAP_C0402-22UF,4V,20%,X6S,CH622KMEB02  I136  C2136
   1 PVDDIO_P0      A @T6G_MB_LIB.T6G(SCH_1):PVDDIO_P0
   2    GND      B @T6G_MB_LIB.T6G(SCH_1):GND

Q_CAP_C0402-22UF,4V,20%,X6S,CH622KMEB02  I137  C2141
   1 PVDDIO_P0      A @T6G_MB_LIB.T6G(SCH_1):PVDDIO_P0
   2    GND      B @T6G_MB_LIB.T6G(SCH_1):GND

Q_CAP_C0402-22UF,4V,20%,X6S,CH622KMEB02  I138  C2145
   1 PVDDIO_P0      A @T6G_MB_LIB.T6G(SCH_1):PVDDIO_P0
   2    GND      B @T6G_MB_LIB.T6G(SCH_1):GND

Q_CAP_C0402-22UF,4V,20%,X6S,CH622KMEB02  I139  C2149
   1 PVDDIO_P0      A @T6G_MB_LIB.T6G(SCH_1):PVDDIO_P0
   2    GND      B @T6G_MB_LIB.T6G(SCH_1):GND

Q_CAP_C0402-22UF,4V,20%,X6S,CH622KMEB02  I141  C3898
   1 PVDDIO_P0      A @T6G_MB_LIB.T6G(SCH_1):PVDDIO_P0
   2    GND      B @T6G_MB_LIB.T6G(SCH_1):GND

Q_CAP_C0402-22UF,4V,20%,X6S,CH622KMEB02  I143  C3899
   1 PVDDIO_P0      A @T6G_MB_LIB.T6G(SCH_1):PVDDIO_P0
   2    GND      B @T6G_MB_LIB.T6G(SCH_1):GND


DRAWING: @T6G_MB_LIB.T6G(SCH_1):PAGE68 

Q_CAP_C0402-22UF,4V,20%,X6S,CH622KMEB02  I1  C2167
   1 PVDDCR_CPU0_P0      A @T6G_MB_LIB.T6G(SCH_1):PVDDCR_CPU0_P0
   2    GND      B @T6G_MB_LIB.T6G(SCH_1):GND

Q_CAP_C0402-22UF,4V,20%,X6S,CH622KMEB02  I2  C2171
   1 PVDDCR_CPU0_P0      A @T6G_MB_LIB.T6G(SCH_1):PVDDCR_CPU0_P0
   2    GND      B @T6G_MB_LIB.T6G(SCH_1):GND

Q_CAP_C0402-22UF,4V,20%,X6S,CH622KMEB02  I4  C2166
   1 PVDDCR_CPU0_P0      A @T6G_MB_LIB.T6G(SCH_1):PVDDCR_CPU0_P0
   2    GND      B @T6G_MB_LIB.T6G(SCH_1):GND

Q_CAP_C0402-22UF,4V,20%,X6S,CH622KMEB02  I5  C2170
   1 PVDDCR_CPU0_P0      A @T6G_MB_LIB.T6G(SCH_1):PVDDCR_CPU0_P0
   2    GND      B @T6G_MB_LIB.T6G(SCH_1):GND

Q_CAP_C0402-22UF,4V,20%,X6S,CH622KMEB02  I7  C2165
   1 PVDDCR_CPU0_P0      A @T6G_MB_LIB.T6G(SCH_1):PVDDCR_CPU0_P0
   2    GND      B @T6G_MB_LIB.T6G(SCH_1):GND

Q_CAP_C0402-22UF,4V,20%,X6S,CH622KMEB02  I9  C2169
   1 PVDDCR_CPU0_P0      A @T6G_MB_LIB.T6G(SCH_1):PVDDCR_CPU0_P0
   2    GND      B @T6G_MB_LIB.T6G(SCH_1):GND

Q_CAP_C0402-22UF,4V,20%,X6S,CH622KMEB02  I10  C246
   1 PVDDCR_CPU0_P0      A @T6G_MB_LIB.T6G(SCH_1):PVDDCR_CPU0_P0
   2    GND      B @T6G_MB_LIB.T6G(SCH_1):GND

Q_CAP_C0402-22UF,4V,20%,X6S,CH622KMEB02  I12  C252
   1 PVDDCR_CPU0_P0      A @T6G_MB_LIB.T6G(SCH_1):PVDDCR_CPU0_P0
   2    GND      B @T6G_MB_LIB.T6G(SCH_1):GND

Q_CAP_C0402-22UF,4V,20%,X6S,CH622KMEB02  I14  C245
   1 PVDDCR_CPU0_P0      A @T6G_MB_LIB.T6G(SCH_1):PVDDCR_CPU0_P0
   2    GND      B @T6G_MB_LIB.T6G(SCH_1):GND

Q_CAP_C0402-22UF,4V,20%,X6S,CH622KMEB02  I15  C251
   1 PVDDCR_CPU0_P0      A @T6G_MB_LIB.T6G(SCH_1):PVDDCR_CPU0_P0
   2    GND      B @T6G_MB_LIB.T6G(SCH_1):GND

Q_CAP_C0402-22UF,4V,20%,X6S,CH622KMEB02  I16  C2175
   1 PVDDCR_CPU0_P0      A @T6G_MB_LIB.T6G(SCH_1):PVDDCR_CPU0_P0
   2    GND      B @T6G_MB_LIB.T6G(SCH_1):GND

Q_CAP_C0402-22UF,4V,20%,X6S,CH622KMEB02  I17  C10179
   1 PVDDCR_CPU0_P0      A @T6G_MB_LIB.T6G(SCH_1):PVDDCR_CPU0_P0
   2    GND      B @T6G_MB_LIB.T6G(SCH_1):GND

Q_CAP_C0402-22UF,4V,20%,X6S,CH622KMEB02  I19  C2183
   1 PVDDCR_CPU0_P0      A @T6G_MB_LIB.T6G(SCH_1):PVDDCR_CPU0_P0
   2    GND      B @T6G_MB_LIB.T6G(SCH_1):GND

Q_CAP_C0402-22UF,4V,20%,X6S,CH622KMEB02  I20  C2174
   1 PVDDCR_CPU0_P0      A @T6G_MB_LIB.T6G(SCH_1):PVDDCR_CPU0_P0
   2    GND      B @T6G_MB_LIB.T6G(SCH_1):GND

Q_CAP_C0402-22UF,4V,20%,X6S,CH622KMEB02  I21  C2178
   1 PVDDCR_CPU0_P0      A @T6G_MB_LIB.T6G(SCH_1):PVDDCR_CPU0_P0
   2    GND      B @T6G_MB_LIB.T6G(SCH_1):GND

Q_CAP_C0402-22UF,4V,20%,X6S,CH622KMEB02  I22  C2173
   1 PVDDCR_CPU0_P0      A @T6G_MB_LIB.T6G(SCH_1):PVDDCR_CPU0_P0
   2    GND      B @T6G_MB_LIB.T6G(SCH_1):GND

Q_CAP_C0402-22UF,4V,20%,X6S,CH622KMEB02  I23  C2177
   1 PVDDCR_CPU0_P0      A @T6G_MB_LIB.T6G(SCH_1):PVDDCR_CPU0_P0
   2    GND      B @T6G_MB_LIB.T6G(SCH_1):GND

Q_CAP_C0402-22UF,4V,20%,X6S,CH622KMEB02  I24  C2182
   1 PVDDCR_CPU0_P0      A @T6G_MB_LIB.T6G(SCH_1):PVDDCR_CPU0_P0
   2    GND      B @T6G_MB_LIB.T6G(SCH_1):GND

Q_CAP_C0402-22UF,4V,20%,X6S,CH622KMEB02  I25  C2181
   1 PVDDCR_CPU0_P0      A @T6G_MB_LIB.T6G(SCH_1):PVDDCR_CPU0_P0
   2    GND      B @T6G_MB_LIB.T6G(SCH_1):GND

Q_CAP_C0402-22UF,4V,20%,X6S,CH622KMEB02  I26  C2186
   1 PVDDCR_CPU0_P0      A @T6G_MB_LIB.T6G(SCH_1):PVDDCR_CPU0_P0
   2    GND      B @T6G_MB_LIB.T6G(SCH_1):GND

Q_CAP_C0402-22UF,4V,20%,X6S,CH622KMEB02  I27  C2190
   1 PVDDCR_CPU0_P0      A @T6G_MB_LIB.T6G(SCH_1):PVDDCR_CPU0_P0
   2    GND      B @T6G_MB_LIB.T6G(SCH_1):GND

Q_CAP_C0402-22UF,4V,20%,X6S,CH622KMEB02  I28  C2185
   1 PVDDCR_CPU0_P0      A @T6G_MB_LIB.T6G(SCH_1):PVDDCR_CPU0_P0
   2    GND      B @T6G_MB_LIB.T6G(SCH_1):GND

Q_CAP_C0402-22UF,4V,20%,X6S,CH622KMEB02  I29  C2189
   1 PVDDCR_CPU0_P0      A @T6G_MB_LIB.T6G(SCH_1):PVDDCR_CPU0_P0
   2    GND      B @T6G_MB_LIB.T6G(SCH_1):GND

Q_CAP_C0402-22UF,4V,20%,X6S,CH622KMEB02  I30  C2205
   1 PVDDCR_CPU1_P0      A @T6G_MB_LIB.T6G(SCH_1):PVDDCR_CPU1_P0
   2    GND      B @T6G_MB_LIB.T6G(SCH_1):GND

Q_CAP_C0402-22UF,4V,20%,X6S,CH622KMEB02  I31  C2193
   1 PVDDCR_CPU0_P0      A @T6G_MB_LIB.T6G(SCH_1):PVDDCR_CPU0_P0
   2    GND      B @T6G_MB_LIB.T6G(SCH_1):GND

Q_CAP_C0402-22UF,4V,20%,X6S,CH622KMEB02  I32  C2196
   1 PVDDCR_CPU0_P0      A @T6G_MB_LIB.T6G(SCH_1):PVDDCR_CPU0_P0
   2    GND      B @T6G_MB_LIB.T6G(SCH_1):GND

Q_CAP_C0402-22UF,4V,20%,X6S,CH622KMEB02  I33  C2192
   1 PVDDCR_CPU0_P0      A @T6G_MB_LIB.T6G(SCH_1):PVDDCR_CPU0_P0
   2    GND      B @T6G_MB_LIB.T6G(SCH_1):GND

Q_CAP_C0402-22UF,4V,20%,X6S,CH622KMEB02  I34  C2195
   1 PVDDCR_CPU0_P0      A @T6G_MB_LIB.T6G(SCH_1):PVDDCR_CPU0_P0
   2    GND      B @T6G_MB_LIB.T6G(SCH_1):GND

Q_CAP_C0402-22UF,4V,20%,X6S,CH622KMEB02  I36  C2199
   1 PVDDCR_CPU0_P0      A @T6G_MB_LIB.T6G(SCH_1):PVDDCR_CPU0_P0
   2    GND      B @T6G_MB_LIB.T6G(SCH_1):GND

Q_CAP_C0402-22UF,4V,20%,X6S,CH622KMEB02  I38  C2204
   1 PVDDCR_CPU1_P0      A @T6G_MB_LIB.T6G(SCH_1):PVDDCR_CPU1_P0
   2    GND      B @T6G_MB_LIB.T6G(SCH_1):GND

Q_CAP_C0402-22UF,4V,20%,X6S,CH622KMEB02  I40  C2198
   1 PVDDCR_CPU0_P0      A @T6G_MB_LIB.T6G(SCH_1):PVDDCR_CPU0_P0
   2    GND      B @T6G_MB_LIB.T6G(SCH_1):GND

Q_CAP_C0402-22UF,4V,20%,X6S,CH622KMEB02  I43  C2203
   1 PVDDCR_CPU1_P0      A @T6G_MB_LIB.T6G(SCH_1):PVDDCR_CPU1_P0
   2    GND      B @T6G_MB_LIB.T6G(SCH_1):GND

Q_CAP_C0402-22UF,4V,20%,X6S,CH622KMEB02  I45  C1922
   1 PVDDCR_CPU0_P0      A @T6G_MB_LIB.T6G(SCH_1):PVDDCR_CPU0_P0
   2    GND      B @T6G_MB_LIB.T6G(SCH_1):GND

Q_CAP_C0402-22UF,4V,20%,X6S,CH622KMEB02  I46  C263
   1 PVDDCR_CPU0_P0      A @T6G_MB_LIB.T6G(SCH_1):PVDDCR_CPU0_P0
   2    GND      B @T6G_MB_LIB.T6G(SCH_1):GND

Q_CAP_C0402-22UF,4V,20%,X6S,CH622KMEB02  I47  C4178
   1 PVDDCR_CPU0_P0      A @T6G_MB_LIB.T6G(SCH_1):PVDDCR_CPU0_P0
   2    GND      B @T6G_MB_LIB.T6G(SCH_1):GND

Q_CAP_C0402-22UF,4V,20%,X6S,CH622KMEB02  I48  C4179
   1 PVDDCR_CPU0_P0      A @T6G_MB_LIB.T6G(SCH_1):PVDDCR_CPU0_P0
   2    GND      B @T6G_MB_LIB.T6G(SCH_1):GND

Q_CAP_C0402-22UF,4V,20%,X6S,CH622KMEB02  I49  C268
   1 PVDDCR_CPU0_P0      A @T6G_MB_LIB.T6G(SCH_1):PVDDCR_CPU0_P0
   2    GND      B @T6G_MB_LIB.T6G(SCH_1):GND

Q_CAP_C0402-22UF,4V,20%,X6S,CH622KMEB02  I50  C267
   1 PVDDCR_CPU0_P0      A @T6G_MB_LIB.T6G(SCH_1):PVDDCR_CPU0_P0
   2    GND      B @T6G_MB_LIB.T6G(SCH_1):GND

Q_CAP_C0402-22UF,4V,20%,X6S,CH622KMEB02  I51  C271
   1 PVDDCR_CPU0_P0      A @T6G_MB_LIB.T6G(SCH_1):PVDDCR_CPU0_P0
   2    GND      B @T6G_MB_LIB.T6G(SCH_1):GND

Q_CAP_C0402-22UF,4V,20%,X6S,CH622KMEB02  I52  C273
   1 PVDDCR_CPU0_P0      A @T6G_MB_LIB.T6G(SCH_1):PVDDCR_CPU0_P0
   2    GND      B @T6G_MB_LIB.T6G(SCH_1):GND

Q_CAP_C0402-22UF,4V,20%,X6S,CH622KMEB02  I53  C270
   1 PVDDCR_CPU0_P0      A @T6G_MB_LIB.T6G(SCH_1):PVDDCR_CPU0_P0
   2    GND      B @T6G_MB_LIB.T6G(SCH_1):GND

Q_CAP_C0402-22UF,4V,20%,X6S,CH622KMEB02  I54  C275
   1 PVDDCR_CPU0_P0      A @T6G_MB_LIB.T6G(SCH_1):PVDDCR_CPU0_P0
   2    GND      B @T6G_MB_LIB.T6G(SCH_1):GND

Q_CAP_C0402-22UF,4V,20%,X6S,CH622KMEB02  I55  C277
   1 PVDDCR_CPU0_P0      A @T6G_MB_LIB.T6G(SCH_1):PVDDCR_CPU0_P0
   2    GND      B @T6G_MB_LIB.T6G(SCH_1):GND

Q_CAP_C0402-22UF,4V,20%,X6S,CH622KMEB02  I56  C274
   1 PVDDCR_CPU0_P0      A @T6G_MB_LIB.T6G(SCH_1):PVDDCR_CPU0_P0
   2    GND      B @T6G_MB_LIB.T6G(SCH_1):GND

Q_CAP_C0402-22UF,4V,20%,X6S,CH622KMEB02  I57  C276
   1 PVDDCR_CPU0_P0      A @T6G_MB_LIB.T6G(SCH_1):PVDDCR_CPU0_P0
   2    GND      B @T6G_MB_LIB.T6G(SCH_1):GND

Q_CAP_C0402-22UF,4V,20%,X6S,CH622KMEB02  I58  C279
   1 PVDDCR_CPU0_P0      A @T6G_MB_LIB.T6G(SCH_1):PVDDCR_CPU0_P0
   2    GND      B @T6G_MB_LIB.T6G(SCH_1):GND

Q_CAP_C0402-22UF,4V,20%,X6S,CH622KMEB02  I60  C2202
   1 PVDDCR_CPU1_P0      A @T6G_MB_LIB.T6G(SCH_1):PVDDCR_CPU1_P0
   2    GND      B @T6G_MB_LIB.T6G(SCH_1):GND

Q_CAP_C0402-22UF,4V,20%,X6S,CH622KMEB02  I62  C278
   1 PVDDCR_CPU0_P0      A @T6G_MB_LIB.T6G(SCH_1):PVDDCR_CPU0_P0
   2    GND      B @T6G_MB_LIB.T6G(SCH_1):GND

Q_CAP_C0402-22UF,4V,20%,X6S,CH622KMEB02  I63  C2201
   1 PVDDCR_CPU1_P0      A @T6G_MB_LIB.T6G(SCH_1):PVDDCR_CPU1_P0
   2    GND      B @T6G_MB_LIB.T6G(SCH_1):GND

Q_CAP_C0402-22UF,4V,20%,X6S,CH622KMEB02  I65  C2211
   1 PVDDCR_CPU1_P0      A @T6G_MB_LIB.T6G(SCH_1):PVDDCR_CPU1_P0
   2    GND      B @T6G_MB_LIB.T6G(SCH_1):GND

Q_CAP_C0402-22UF,4V,20%,X6S,CH622KMEB02  I66  C2217
   1 PVDDCR_CPU1_P0      A @T6G_MB_LIB.T6G(SCH_1):PVDDCR_CPU1_P0
   2    GND      B @T6G_MB_LIB.T6G(SCH_1):GND

Q_CAP_C0402-22UF,4V,20%,X6S,CH622KMEB02  I67  C2223
   1 PVDDCR_CPU1_P0      A @T6G_MB_LIB.T6G(SCH_1):PVDDCR_CPU1_P0
   2    GND      B @T6G_MB_LIB.T6G(SCH_1):GND

Q_CAP_C0402-22UF,4V,20%,X6S,CH622KMEB02  I69  C2229
   1 PVDDCR_CPU1_P0      A @T6G_MB_LIB.T6G(SCH_1):PVDDCR_CPU1_P0
   2    GND      B @T6G_MB_LIB.T6G(SCH_1):GND

Q_CAP_C0402-22UF,4V,20%,X6S,CH622KMEB02  I70  C2210
   1 PVDDCR_CPU1_P0      A @T6G_MB_LIB.T6G(SCH_1):PVDDCR_CPU1_P0
   2    GND      B @T6G_MB_LIB.T6G(SCH_1):GND

Q_CAP_C0402-22UF,4V,20%,X6S,CH622KMEB02  I71  C2216
   1 PVDDCR_CPU1_P0      A @T6G_MB_LIB.T6G(SCH_1):PVDDCR_CPU1_P0
   2    GND      B @T6G_MB_LIB.T6G(SCH_1):GND

Q_CAP_C0402-22UF,4V,20%,X6S,CH622KMEB02  I72  C2209
   1 PVDDCR_CPU1_P0      A @T6G_MB_LIB.T6G(SCH_1):PVDDCR_CPU1_P0
   2    GND      B @T6G_MB_LIB.T6G(SCH_1):GND

Q_CAP_C0402-22UF,4V,20%,X6S,CH622KMEB02  I73  C2215
   1 PVDDCR_CPU1_P0      A @T6G_MB_LIB.T6G(SCH_1):PVDDCR_CPU1_P0
   2    GND      B @T6G_MB_LIB.T6G(SCH_1):GND

Q_CAP_C0402-22UF,4V,20%,X6S,CH622KMEB02  I74  C2222
   1 PVDDCR_CPU1_P0      A @T6G_MB_LIB.T6G(SCH_1):PVDDCR_CPU1_P0
   2    GND      B @T6G_MB_LIB.T6G(SCH_1):GND

Q_CAP_C0402-22UF,4V,20%,X6S,CH622KMEB02  I75  C2228
   1 PVDDCR_CPU1_P0      A @T6G_MB_LIB.T6G(SCH_1):PVDDCR_CPU1_P0
   2    GND      B @T6G_MB_LIB.T6G(SCH_1):GND

Q_CAP_C0402-22UF,4V,20%,X6S,CH622KMEB02  I76  C2234
   1 PVDDCR_CPU1_P0      A @T6G_MB_LIB.T6G(SCH_1):PVDDCR_CPU1_P0
   2    GND      B @T6G_MB_LIB.T6G(SCH_1):GND

Q_CAP_C0402-22UF,4V,20%,X6S,CH622KMEB02  I77  C2221
   1 PVDDCR_CPU1_P0      A @T6G_MB_LIB.T6G(SCH_1):PVDDCR_CPU1_P0
   2    GND      B @T6G_MB_LIB.T6G(SCH_1):GND

Q_CAP_C0402-22UF,4V,20%,X6S,CH622KMEB02  I78  C2227
   1 PVDDCR_CPU1_P0      A @T6G_MB_LIB.T6G(SCH_1):PVDDCR_CPU1_P0
   2    GND      B @T6G_MB_LIB.T6G(SCH_1):GND

Q_CAP_C0402-22UF,4V,20%,X6S,CH622KMEB02  I79  C2233
   1 PVDDCR_CPU1_P0      A @T6G_MB_LIB.T6G(SCH_1):PVDDCR_CPU1_P0
   2    GND      B @T6G_MB_LIB.T6G(SCH_1):GND

Q_CAP_C0402-22UF,4V,20%,X6S,CH622KMEB02  I80  C2240
   1 PVDDCR_CPU1_P0      A @T6G_MB_LIB.T6G(SCH_1):PVDDCR_CPU1_P0
   2    GND      B @T6G_MB_LIB.T6G(SCH_1):GND

Q_CAP_C0402-22UF,4V,20%,X6S,CH622KMEB02  I81  C2246
   1 PVDDCR_CPU1_P0      A @T6G_MB_LIB.T6G(SCH_1):PVDDCR_CPU1_P0
   2    GND      B @T6G_MB_LIB.T6G(SCH_1):GND

Q_CAP_C0402-22UF,4V,20%,X6S,CH622KMEB02  I82  C2239
   1 PVDDCR_CPU1_P0      A @T6G_MB_LIB.T6G(SCH_1):PVDDCR_CPU1_P0
   2    GND      B @T6G_MB_LIB.T6G(SCH_1):GND

Q_CAP_C0402-22UF,4V,20%,X6S,CH622KMEB02  I83  C2245
   1 PVDDCR_CPU1_P0      A @T6G_MB_LIB.T6G(SCH_1):PVDDCR_CPU1_P0
   2    GND      B @T6G_MB_LIB.T6G(SCH_1):GND

Q_CAP_C0402-22UF,4V,20%,X6S,CH622KMEB02  I84  C2251
   1 PVDDCR_CPU1_P0      A @T6G_MB_LIB.T6G(SCH_1):PVDDCR_CPU1_P0
   2    GND      B @T6G_MB_LIB.T6G(SCH_1):GND

Q_CAP_C0402-22UF,4V,20%,X6S,CH622KMEB02  I86  C2256
   1 PVDDCR_CPU1_P0      A @T6G_MB_LIB.T6G(SCH_1):PVDDCR_CPU1_P0
   2    GND      B @T6G_MB_LIB.T6G(SCH_1):GND

Q_CAP_C0402-22UF,4V,20%,X6S,CH622KMEB02  I87  C2250
   1 PVDDCR_CPU1_P0      A @T6G_MB_LIB.T6G(SCH_1):PVDDCR_CPU1_P0
   2    GND      B @T6G_MB_LIB.T6G(SCH_1):GND

Q_CAP_C0402-22UF,4V,20%,X6S,CH622KMEB02  I89  C2255
   1 PVDDCR_CPU1_P0      A @T6G_MB_LIB.T6G(SCH_1):PVDDCR_CPU1_P0
   2    GND      B @T6G_MB_LIB.T6G(SCH_1):GND

Q_CAP_C0402-22UF,4V,20%,X6S,CH622KMEB02  I91  C2208
   1 PVDDCR_CPU1_P0      A @T6G_MB_LIB.T6G(SCH_1):PVDDCR_CPU1_P0
   2    GND      B @T6G_MB_LIB.T6G(SCH_1):GND

Q_CAP_C0402-22UF,4V,20%,X6S,CH622KMEB02  I92  C2214
   1 PVDDCR_CPU1_P0      A @T6G_MB_LIB.T6G(SCH_1):PVDDCR_CPU1_P0
   2    GND      B @T6G_MB_LIB.T6G(SCH_1):GND

Q_CAP_C0402-22UF,4V,20%,X6S,CH622KMEB02  I93  C2207
   1 PVDDCR_CPU1_P0      A @T6G_MB_LIB.T6G(SCH_1):PVDDCR_CPU1_P0
   2    GND      B @T6G_MB_LIB.T6G(SCH_1):GND

Q_CAP_C0402-22UF,4V,20%,X6S,CH622KMEB02  I94  C2213
   1 PVDDCR_CPU1_P0      A @T6G_MB_LIB.T6G(SCH_1):PVDDCR_CPU1_P0
   2    GND      B @T6G_MB_LIB.T6G(SCH_1):GND

Q_CAP_C0402-22UF,4V,20%,X6S,CH622KMEB02  I95  C2220
   1 PVDDCR_CPU1_P0      A @T6G_MB_LIB.T6G(SCH_1):PVDDCR_CPU1_P0
   2    GND      B @T6G_MB_LIB.T6G(SCH_1):GND

Q_CAP_C0402-22UF,4V,20%,X6S,CH622KMEB02  I96  C2226
   1 PVDDCR_CPU1_P0      A @T6G_MB_LIB.T6G(SCH_1):PVDDCR_CPU1_P0
   2    GND      B @T6G_MB_LIB.T6G(SCH_1):GND

Q_CAP_C0402-22UF,4V,20%,X6S,CH622KMEB02  I97  C2232
   1 PVDDCR_CPU1_P0      A @T6G_MB_LIB.T6G(SCH_1):PVDDCR_CPU1_P0
   2    GND      B @T6G_MB_LIB.T6G(SCH_1):GND

Q_CAP_C0402-22UF,4V,20%,X6S,CH622KMEB02  I98  C2219
   1 PVDDCR_CPU1_P0      A @T6G_MB_LIB.T6G(SCH_1):PVDDCR_CPU1_P0
   2    GND      B @T6G_MB_LIB.T6G(SCH_1):GND

Q_CAP_C0402-22UF,4V,20%,X6S,CH622KMEB02  I99  C2225
   1 PVDDCR_CPU1_P0      A @T6G_MB_LIB.T6G(SCH_1):PVDDCR_CPU1_P0
   2    GND      B @T6G_MB_LIB.T6G(SCH_1):GND

Q_CAP_C0402-22UF,4V,20%,X6S,CH622KMEB02  I100  C2231
   1 PVDDCR_CPU1_P0      A @T6G_MB_LIB.T6G(SCH_1):PVDDCR_CPU1_P0
   2    GND      B @T6G_MB_LIB.T6G(SCH_1):GND

Q_CAP_C0402-22UF,4V,20%,X6S,CH622KMEB02  I101  C2238
   1 PVDDCR_CPU1_P0      A @T6G_MB_LIB.T6G(SCH_1):PVDDCR_CPU1_P0
   2    GND      B @T6G_MB_LIB.T6G(SCH_1):GND

Q_CAP_C0402-22UF,4V,20%,X6S,CH622KMEB02  I102  C2244
   1 PVDDCR_CPU1_P0      A @T6G_MB_LIB.T6G(SCH_1):PVDDCR_CPU1_P0
   2    GND      B @T6G_MB_LIB.T6G(SCH_1):GND

Q_CAP_C0402-22UF,4V,20%,X6S,CH622KMEB02  I103  C2237
   1 PVDDCR_CPU1_P0      A @T6G_MB_LIB.T6G(SCH_1):PVDDCR_CPU1_P0
   2    GND      B @T6G_MB_LIB.T6G(SCH_1):GND

Q_CAP_C0402-22UF,4V,20%,X6S,CH622KMEB02  I104  C2243
   1 PVDDCR_CPU1_P0      A @T6G_MB_LIB.T6G(SCH_1):PVDDCR_CPU1_P0
   2    GND      B @T6G_MB_LIB.T6G(SCH_1):GND

Q_CAP_C0402-22UF,4V,20%,X6S,CH622KMEB02  I105  C2249
   1 PVDDCR_CPU1_P0      A @T6G_MB_LIB.T6G(SCH_1):PVDDCR_CPU1_P0
   2    GND      B @T6G_MB_LIB.T6G(SCH_1):GND

Q_CAP_C0402-22UF,4V,20%,X6S,CH622KMEB02  I106  C2254
   1 PVDDCR_CPU1_P0      A @T6G_MB_LIB.T6G(SCH_1):PVDDCR_CPU1_P0
   2    GND      B @T6G_MB_LIB.T6G(SCH_1):GND

Q_CAP_C0402-22UF,4V,20%,X6S,CH622KMEB02  I108  C2248
   1 PVDDCR_CPU1_P0      A @T6G_MB_LIB.T6G(SCH_1):PVDDCR_CPU1_P0
   2    GND      B @T6G_MB_LIB.T6G(SCH_1):GND

Q_CAP_C0402-22UF,4V,20%,X6S,CH622KMEB02  I109  C2253
   1 PVDDCR_CPU1_P0      A @T6G_MB_LIB.T6G(SCH_1):PVDDCR_CPU1_P0
   2    GND      B @T6G_MB_LIB.T6G(SCH_1):GND

Q_CAP_C0402-22UF,4V,20%,X6S,CH622KMEB02  I110  C272
   1 PVDDCR_CPU0_P0      A @T6G_MB_LIB.T6G(SCH_1):PVDDCR_CPU0_P0
   2    GND      B @T6G_MB_LIB.T6G(SCH_1):GND


DRAWING: @T6G_MB_LIB.T6G(SCH_1):PAGE69 

Q_CAP_C0402-22UF,4V,20%,X6S,CH622KMEB02  I1  C3925
   1 PVDDCR_SOC_P0      A @T6G_MB_LIB.T6G(SCH_1):PVDDCR_SOC_P0
   2    GND      B @T6G_MB_LIB.T6G(SCH_1):GND

Q_CAP_C0402-22UF,4V,20%,X6S,CH622KMEB02  I3  C3926
   1 PVDDCR_SOC_P0      A @T6G_MB_LIB.T6G(SCH_1):PVDDCR_SOC_P0
   2    GND      B @T6G_MB_LIB.T6G(SCH_1):GND

Q_CAP_C0402-22UF,4V,20%,X6S,CH622KMEB02  I4  C2533
   1 PVDDCR_SOC_P0      A @T6G_MB_LIB.T6G(SCH_1):PVDDCR_SOC_P0
   2    GND      B @T6G_MB_LIB.T6G(SCH_1):GND

Q_CAP_C0402-22UF,4V,20%,X6S,CH622KMEB02  I6  C2540
   1 PVDDCR_SOC_P0      A @T6G_MB_LIB.T6G(SCH_1):PVDDCR_SOC_P0
   2    GND      B @T6G_MB_LIB.T6G(SCH_1):GND

Q_CAP_C0402-22UF,4V,20%,X6S,CH622KMEB02  I7  C2532
   1 PVDDCR_SOC_P0      A @T6G_MB_LIB.T6G(SCH_1):PVDDCR_SOC_P0
   2    GND      B @T6G_MB_LIB.T6G(SCH_1):GND

Q_CAP_C0402-22UF,4V,20%,X6S,CH622KMEB02  I9  C2531
   1 PVDDCR_SOC_P0      A @T6G_MB_LIB.T6G(SCH_1):PVDDCR_SOC_P0
   2    GND      B @T6G_MB_LIB.T6G(SCH_1):GND

Q_CAP_C0402-22UF,4V,20%,X6S,CH622KMEB02  I10  C2539
   1 PVDDCR_SOC_P0      A @T6G_MB_LIB.T6G(SCH_1):PVDDCR_SOC_P0
   2    GND      B @T6G_MB_LIB.T6G(SCH_1):GND

Q_CAP_C0402-22UF,4V,20%,X6S,CH622KMEB02  I11  C2538
   1 PVDDCR_SOC_P0      A @T6G_MB_LIB.T6G(SCH_1):PVDDCR_SOC_P0
   2    GND      B @T6G_MB_LIB.T6G(SCH_1):GND

Q_CAP_C0402-22UF,4V,20%,X6S,CH622KMEB02  I13  C2530
   1 PVDDCR_SOC_P0      A @T6G_MB_LIB.T6G(SCH_1):PVDDCR_SOC_P0
   2    GND      B @T6G_MB_LIB.T6G(SCH_1):GND

Q_CAP_C0402-22UF,4V,20%,X6S,CH622KMEB02  I15  C2537
   1 PVDDCR_SOC_P0      A @T6G_MB_LIB.T6G(SCH_1):PVDDCR_SOC_P0
   2    GND      B @T6G_MB_LIB.T6G(SCH_1):GND

Q_CAP_C0402-22UF,4V,20%,X6S,CH622KMEB02  I16  C2529
   1 PVDDCR_SOC_P0      A @T6G_MB_LIB.T6G(SCH_1):PVDDCR_SOC_P0
   2    GND      B @T6G_MB_LIB.T6G(SCH_1):GND

Q_CAP_C0402-22UF,4V,20%,X6S,CH622KMEB02  I18  C2528
   1 PVDDCR_SOC_P0      A @T6G_MB_LIB.T6G(SCH_1):PVDDCR_SOC_P0
   2    GND      B @T6G_MB_LIB.T6G(SCH_1):GND

Q_CAP_C0402-22UF,4V,20%,X6S,CH622KMEB02  I19  C2536
   1 PVDDCR_SOC_P0      A @T6G_MB_LIB.T6G(SCH_1):PVDDCR_SOC_P0
   2    GND      B @T6G_MB_LIB.T6G(SCH_1):GND

Q_CAP_C0402-22UF,4V,20%,X6S,CH622KMEB02  I20  C2535
   1 PVDDCR_SOC_P0      A @T6G_MB_LIB.T6G(SCH_1):PVDDCR_SOC_P0
   2    GND      B @T6G_MB_LIB.T6G(SCH_1):GND

Q_CAP_C0402-22UF,4V,20%,X6S,CH622KMEB02  I22  C2527
   1 PVDDCR_SOC_P0      A @T6G_MB_LIB.T6G(SCH_1):PVDDCR_SOC_P0
   2    GND      B @T6G_MB_LIB.T6G(SCH_1):GND

Q_CAP_C0402-22UF,4V,20%,X6S,CH622KMEB02  I24  C2534
   1 PVDDCR_SOC_P0      A @T6G_MB_LIB.T6G(SCH_1):PVDDCR_SOC_P0
   2    GND      B @T6G_MB_LIB.T6G(SCH_1):GND

Q_CAP_C0402-22UF,4V,20%,X6S,CH622KMEB02  I25  C3927
   1 PVDDCR_SOC_P0      A @T6G_MB_LIB.T6G(SCH_1):PVDDCR_SOC_P0
   2    GND      B @T6G_MB_LIB.T6G(SCH_1):GND

Q_CAP_C0402-22UF,4V,20%,X6S,CH622KMEB02  I26  C3928
   1 PVDDCR_SOC_P0      A @T6G_MB_LIB.T6G(SCH_1):PVDDCR_SOC_P0
   2    GND      B @T6G_MB_LIB.T6G(SCH_1):GND

Q_CAP_C0402-22UF,4V,20%,X6S,CH622KMEB02  I27  C3929
   1 PVDDCR_SOC_P0      A @T6G_MB_LIB.T6G(SCH_1):PVDDCR_SOC_P0
   2    GND      B @T6G_MB_LIB.T6G(SCH_1):GND

Q_CAP_C0402-22UF,4V,20%,X6S,CH622KMEB02  I28  C2547
   1 PVDDCR_SOC_P0      A @T6G_MB_LIB.T6G(SCH_1):PVDDCR_SOC_P0
   2    GND      B @T6G_MB_LIB.T6G(SCH_1):GND

Q_CAP_C0402-22UF,4V,20%,X6S,CH622KMEB02  I29  C2554
   1 PVDDCR_SOC_P0      A @T6G_MB_LIB.T6G(SCH_1):PVDDCR_SOC_P0
   2    GND      B @T6G_MB_LIB.T6G(SCH_1):GND

Q_CAP_C0402-22UF,4V,20%,X6S,CH622KMEB02  I30  C2561
   1 PVDDCR_SOC_P0      A @T6G_MB_LIB.T6G(SCH_1):PVDDCR_SOC_P0
   2    GND      B @T6G_MB_LIB.T6G(SCH_1):GND

Q_CAP_C0402-22UF,4V,20%,X6S,CH622KMEB02  I31  C3930
   1 PVDDCR_SOC_P0      A @T6G_MB_LIB.T6G(SCH_1):PVDDCR_SOC_P0
   2    GND      B @T6G_MB_LIB.T6G(SCH_1):GND

Q_CAP_C0402-22UF,4V,20%,X6S,CH622KMEB02  I33  C3931
   1 PVDDCR_SOC_P0      A @T6G_MB_LIB.T6G(SCH_1):PVDDCR_SOC_P0
   2    GND      B @T6G_MB_LIB.T6G(SCH_1):GND

Q_CAP_C0402-22UF,4V,20%,X6S,CH622KMEB02  I34  C2568
   1 PVDDCR_SOC_P0      A @T6G_MB_LIB.T6G(SCH_1):PVDDCR_SOC_P0
   2    GND      B @T6G_MB_LIB.T6G(SCH_1):GND

Q_CAP_C0402-22UF,4V,20%,X6S,CH622KMEB02  I35  C2575
   1 PVDDCR_SOC_P0      A @T6G_MB_LIB.T6G(SCH_1):PVDDCR_SOC_P0
   2    GND      B @T6G_MB_LIB.T6G(SCH_1):GND

Q_CAP_C0402-22UF,4V,20%,X6S,CH622KMEB02  I36  C2546
   1 PVDDCR_SOC_P0      A @T6G_MB_LIB.T6G(SCH_1):PVDDCR_SOC_P0
   2    GND      B @T6G_MB_LIB.T6G(SCH_1):GND

Q_CAP_C0402-22UF,4V,20%,X6S,CH622KMEB02  I37  C2545
   1 PVDDCR_SOC_P0      A @T6G_MB_LIB.T6G(SCH_1):PVDDCR_SOC_P0
   2    GND      B @T6G_MB_LIB.T6G(SCH_1):GND

Q_CAP_C0402-22UF,4V,20%,X6S,CH622KMEB02  I38  C2553
   1 PVDDCR_SOC_P0      A @T6G_MB_LIB.T6G(SCH_1):PVDDCR_SOC_P0
   2    GND      B @T6G_MB_LIB.T6G(SCH_1):GND

Q_CAP_C0402-22UF,4V,20%,X6S,CH622KMEB02  I39  C2560
   1 PVDDCR_SOC_P0      A @T6G_MB_LIB.T6G(SCH_1):PVDDCR_SOC_P0
   2    GND      B @T6G_MB_LIB.T6G(SCH_1):GND

Q_CAP_C0402-22UF,4V,20%,X6S,CH622KMEB02  I40  C2552
   1 PVDDCR_SOC_P0      A @T6G_MB_LIB.T6G(SCH_1):PVDDCR_SOC_P0
   2    GND      B @T6G_MB_LIB.T6G(SCH_1):GND

Q_CAP_C0402-22UF,4V,20%,X6S,CH622KMEB02  I41  C2559
   1 PVDDCR_SOC_P0      A @T6G_MB_LIB.T6G(SCH_1):PVDDCR_SOC_P0
   2    GND      B @T6G_MB_LIB.T6G(SCH_1):GND

Q_CAP_C0402-22UF,4V,20%,X6S,CH622KMEB02  I42  C2544
   1 PVDDCR_SOC_P0      A @T6G_MB_LIB.T6G(SCH_1):PVDDCR_SOC_P0
   2    GND      B @T6G_MB_LIB.T6G(SCH_1):GND

Q_CAP_C0402-22UF,4V,20%,X6S,CH622KMEB02  I43  C2551
   1 PVDDCR_SOC_P0      A @T6G_MB_LIB.T6G(SCH_1):PVDDCR_SOC_P0
   2    GND      B @T6G_MB_LIB.T6G(SCH_1):GND

Q_CAP_C0402-22UF,4V,20%,X6S,CH622KMEB02  I44  C2558
   1 PVDDCR_SOC_P0      A @T6G_MB_LIB.T6G(SCH_1):PVDDCR_SOC_P0
   2    GND      B @T6G_MB_LIB.T6G(SCH_1):GND

Q_CAP_C0402-22UF,4V,20%,X6S,CH622KMEB02  I45  C2567
   1 PVDDCR_SOC_P0      A @T6G_MB_LIB.T6G(SCH_1):PVDDCR_SOC_P0
   2    GND      B @T6G_MB_LIB.T6G(SCH_1):GND

Q_CAP_C0402-22UF,4V,20%,X6S,CH622KMEB02  I46  C2566
   1 PVDDCR_SOC_P0      A @T6G_MB_LIB.T6G(SCH_1):PVDDCR_SOC_P0
   2    GND      B @T6G_MB_LIB.T6G(SCH_1):GND

Q_CAP_C0402-22UF,4V,20%,X6S,CH622KMEB02  I47  C2574
   1 PVDDCR_SOC_P0      A @T6G_MB_LIB.T6G(SCH_1):PVDDCR_SOC_P0
   2    GND      B @T6G_MB_LIB.T6G(SCH_1):GND

Q_CAP_C0402-22UF,4V,20%,X6S,CH622KMEB02  I48  C2573
   1 PVDDCR_SOC_P0      A @T6G_MB_LIB.T6G(SCH_1):PVDDCR_SOC_P0
   2    GND      B @T6G_MB_LIB.T6G(SCH_1):GND

Q_CAP_C0402-22UF,4V,20%,X6S,CH622KMEB02  I49  C2565
   1 PVDDCR_SOC_P0      A @T6G_MB_LIB.T6G(SCH_1):PVDDCR_SOC_P0
   2    GND      B @T6G_MB_LIB.T6G(SCH_1):GND

Q_CAP_C0402-22UF,4V,20%,X6S,CH622KMEB02  I50  C2572
   1 PVDDCR_SOC_P0      A @T6G_MB_LIB.T6G(SCH_1):PVDDCR_SOC_P0
   2    GND      B @T6G_MB_LIB.T6G(SCH_1):GND

Q_CAP_C0402-22UF,4V,20%,X6S,CH622KMEB02  I51  C2582
   1 PVDDCR_SOC_P0      A @T6G_MB_LIB.T6G(SCH_1):PVDDCR_SOC_P0
   2    GND      B @T6G_MB_LIB.T6G(SCH_1):GND

Q_CAP_C0402-22UF,4V,20%,X6S,CH622KMEB02  I52  C2589
   1 PVDDCR_SOC_P0      A @T6G_MB_LIB.T6G(SCH_1):PVDDCR_SOC_P0
   2    GND      B @T6G_MB_LIB.T6G(SCH_1):GND

Q_CAP_C0402-22UF,4V,20%,X6S,CH622KMEB02  I53  C3932
   1 PVDD11_S3_P0      A @T6G_MB_LIB.T6G(SCH_1):PVDD11_S3_P0
   2    GND      B @T6G_MB_LIB.T6G(SCH_1):GND

Q_CAP_C0402-22UF,4V,20%,X6S,CH622KMEB02  I56  C2596
   1 PVDDCR_SOC_P0      A @T6G_MB_LIB.T6G(SCH_1):PVDDCR_SOC_P0
   2    GND      B @T6G_MB_LIB.T6G(SCH_1):GND

Q_CAP_C0402-22UF,4V,20%,X6S,CH622KMEB02  I58  C2603
   1 PVDD11_S3_P0      A @T6G_MB_LIB.T6G(SCH_1):PVDD11_S3_P0
   2    GND      B @T6G_MB_LIB.T6G(SCH_1):GND

Q_CAP_C0402-22UF,4V,20%,X6S,CH622KMEB02  I60  C2602
   1 PVDD11_S3_P0      A @T6G_MB_LIB.T6G(SCH_1):PVDD11_S3_P0
   2    GND      B @T6G_MB_LIB.T6G(SCH_1):GND

Q_CAP_C0402-22UF,4V,20%,X6S,CH622KMEB02  I61  C2581
   1 PVDDCR_SOC_P0      A @T6G_MB_LIB.T6G(SCH_1):PVDDCR_SOC_P0
   2    GND      B @T6G_MB_LIB.T6G(SCH_1):GND

Q_CAP_C0402-22UF,4V,20%,X6S,CH622KMEB02  I62  C2580
   1 PVDDCR_SOC_P0      A @T6G_MB_LIB.T6G(SCH_1):PVDDCR_SOC_P0
   2    GND      B @T6G_MB_LIB.T6G(SCH_1):GND

Q_CAP_C0402-22UF,4V,20%,X6S,CH622KMEB02  I63  C2588
   1 PVDDCR_SOC_P0      A @T6G_MB_LIB.T6G(SCH_1):PVDDCR_SOC_P0
   2    GND      B @T6G_MB_LIB.T6G(SCH_1):GND

Q_CAP_C0402-22UF,4V,20%,X6S,CH622KMEB02  I64  C2587
   1 PVDDCR_SOC_P0      A @T6G_MB_LIB.T6G(SCH_1):PVDDCR_SOC_P0
   2    GND      B @T6G_MB_LIB.T6G(SCH_1):GND

Q_CAP_C0402-22UF,4V,20%,X6S,CH622KMEB02  I65  C2579
   1 PVDDCR_SOC_P0      A @T6G_MB_LIB.T6G(SCH_1):PVDDCR_SOC_P0
   2    GND      B @T6G_MB_LIB.T6G(SCH_1):GND

Q_CAP_C0402-22UF,4V,20%,X6S,CH622KMEB02  I66  C2586
   1 PVDDCR_SOC_P0      A @T6G_MB_LIB.T6G(SCH_1):PVDDCR_SOC_P0
   2    GND      B @T6G_MB_LIB.T6G(SCH_1):GND

Q_CAP_C0402-22UF,4V,20%,X6S,CH622KMEB02  I67  C2595
   1 PVDDCR_SOC_P0      A @T6G_MB_LIB.T6G(SCH_1):PVDDCR_SOC_P0
   2    GND      B @T6G_MB_LIB.T6G(SCH_1):GND

Q_CAP_C0402-22UF,4V,20%,X6S,CH622KMEB02  I69  C2594
   1 PVDDCR_SOC_P0      A @T6G_MB_LIB.T6G(SCH_1):PVDDCR_SOC_P0
   2    GND      B @T6G_MB_LIB.T6G(SCH_1):GND

Q_CAP_C0402-22UF,4V,20%,X6S,CH622KMEB02  I71  C2601
   1 PVDD11_S3_P0      A @T6G_MB_LIB.T6G(SCH_1):PVDD11_S3_P0
   2    GND      B @T6G_MB_LIB.T6G(SCH_1):GND

Q_CAP_C0402-22UF,4V,20%,X6S,CH622KMEB02  I74  C2593
   1 PVDDCR_SOC_P0      A @T6G_MB_LIB.T6G(SCH_1):PVDDCR_SOC_P0
   2    GND      B @T6G_MB_LIB.T6G(SCH_1):GND

Q_CAP_C0402-22UF,4V,20%,X6S,CH622KMEB02  I76  C2600
   1 PVDD11_S3_P0      A @T6G_MB_LIB.T6G(SCH_1):PVDD11_S3_P0
   2    GND      B @T6G_MB_LIB.T6G(SCH_1):GND

Q_CAP_C0402-22UF,4V,20%,X6S,CH622KMEB02  I78  C2543
   1 PVDDCR_SOC_P0      A @T6G_MB_LIB.T6G(SCH_1):PVDDCR_SOC_P0
   2    GND      B @T6G_MB_LIB.T6G(SCH_1):GND

Q_CAP_C0402-22UF,4V,20%,X6S,CH622KMEB02  I79  C2542
   1 PVDDCR_SOC_P0      A @T6G_MB_LIB.T6G(SCH_1):PVDDCR_SOC_P0
   2    GND      B @T6G_MB_LIB.T6G(SCH_1):GND

Q_CAP_C0402-22UF,4V,20%,X6S,CH622KMEB02  I80  C2550
   1 PVDDCR_SOC_P0      A @T6G_MB_LIB.T6G(SCH_1):PVDDCR_SOC_P0
   2    GND      B @T6G_MB_LIB.T6G(SCH_1):GND

Q_CAP_C0402-22UF,4V,20%,X6S,CH622KMEB02  I81  C2549
   1 PVDDCR_SOC_P0      A @T6G_MB_LIB.T6G(SCH_1):PVDDCR_SOC_P0
   2    GND      B @T6G_MB_LIB.T6G(SCH_1):GND

Q_CAP_C0402-22UF,4V,20%,X6S,CH622KMEB02  I82  C2557
   1 PVDDCR_SOC_P0      A @T6G_MB_LIB.T6G(SCH_1):PVDDCR_SOC_P0
   2    GND      B @T6G_MB_LIB.T6G(SCH_1):GND

Q_CAP_C0402-22UF,4V,20%,X6S,CH622KMEB02  I83  C2556
   1 PVDDCR_SOC_P0      A @T6G_MB_LIB.T6G(SCH_1):PVDDCR_SOC_P0
   2    GND      B @T6G_MB_LIB.T6G(SCH_1):GND

Q_CAP_C0402-22UF,4V,20%,X6S,CH622KMEB02  I84  C2541
   1 PVDDCR_SOC_P0      A @T6G_MB_LIB.T6G(SCH_1):PVDDCR_SOC_P0
   2    GND      B @T6G_MB_LIB.T6G(SCH_1):GND

Q_CAP_C0402-22UF,4V,20%,X6S,CH622KMEB02  I85  C2548
   1 PVDDCR_SOC_P0      A @T6G_MB_LIB.T6G(SCH_1):PVDDCR_SOC_P0
   2    GND      B @T6G_MB_LIB.T6G(SCH_1):GND

Q_CAP_C0402-22UF,4V,20%,X6S,CH622KMEB02  I86  C2555
   1 PVDDCR_SOC_P0      A @T6G_MB_LIB.T6G(SCH_1):PVDDCR_SOC_P0
   2    GND      B @T6G_MB_LIB.T6G(SCH_1):GND

Q_CAP_C0402-22UF,4V,20%,X6S,CH622KMEB02  I87  C2564
   1 PVDDCR_SOC_P0      A @T6G_MB_LIB.T6G(SCH_1):PVDDCR_SOC_P0
   2    GND      B @T6G_MB_LIB.T6G(SCH_1):GND

Q_CAP_C0402-22UF,4V,20%,X6S,CH622KMEB02  I88  C2563
   1 PVDDCR_SOC_P0      A @T6G_MB_LIB.T6G(SCH_1):PVDDCR_SOC_P0
   2    GND      B @T6G_MB_LIB.T6G(SCH_1):GND

Q_CAP_C0402-22UF,4V,20%,X6S,CH622KMEB02  I89  C2571
   1 PVDDCR_SOC_P0      A @T6G_MB_LIB.T6G(SCH_1):PVDDCR_SOC_P0
   2    GND      B @T6G_MB_LIB.T6G(SCH_1):GND

Q_CAP_C0402-22UF,4V,20%,X6S,CH622KMEB02  I90  C2570
   1 PVDDCR_SOC_P0      A @T6G_MB_LIB.T6G(SCH_1):PVDDCR_SOC_P0
   2    GND      B @T6G_MB_LIB.T6G(SCH_1):GND

Q_CAP_C0402-22UF,4V,20%,X6S,CH622KMEB02  I91  C2562
   1 PVDDCR_SOC_P0      A @T6G_MB_LIB.T6G(SCH_1):PVDDCR_SOC_P0
   2    GND      B @T6G_MB_LIB.T6G(SCH_1):GND

Q_CAP_C0402-22UF,4V,20%,X6S,CH622KMEB02  I92  C2569
   1 PVDDCR_SOC_P0      A @T6G_MB_LIB.T6G(SCH_1):PVDDCR_SOC_P0
   2    GND      B @T6G_MB_LIB.T6G(SCH_1):GND

Q_CAP_C0402-22UF,4V,20%,X6S,CH622KMEB02  I93  C2578
   1 PVDDCR_SOC_P0      A @T6G_MB_LIB.T6G(SCH_1):PVDDCR_SOC_P0
   2    GND      B @T6G_MB_LIB.T6G(SCH_1):GND

Q_CAP_C0402-22UF,4V,20%,X6S,CH622KMEB02  I94  C2577
   1 PVDDCR_SOC_P0      A @T6G_MB_LIB.T6G(SCH_1):PVDDCR_SOC_P0
   2    GND      B @T6G_MB_LIB.T6G(SCH_1):GND

Q_CAP_C0402-22UF,4V,20%,X6S,CH622KMEB02  I95  C2585
   1 PVDDCR_SOC_P0      A @T6G_MB_LIB.T6G(SCH_1):PVDDCR_SOC_P0
   2    GND      B @T6G_MB_LIB.T6G(SCH_1):GND

Q_CAP_C0402-22UF,4V,20%,X6S,CH622KMEB02  I96  C2584
   1 PVDDCR_SOC_P0      A @T6G_MB_LIB.T6G(SCH_1):PVDDCR_SOC_P0
   2    GND      B @T6G_MB_LIB.T6G(SCH_1):GND

Q_CAP_C0402-22UF,4V,20%,X6S,CH622KMEB02  I97  C2576
   1 PVDDCR_SOC_P0      A @T6G_MB_LIB.T6G(SCH_1):PVDDCR_SOC_P0
   2    GND      B @T6G_MB_LIB.T6G(SCH_1):GND

Q_CAP_C0402-22UF,4V,20%,X6S,CH622KMEB02  I98  C2583
   1 PVDDCR_SOC_P0      A @T6G_MB_LIB.T6G(SCH_1):PVDDCR_SOC_P0
   2    GND      B @T6G_MB_LIB.T6G(SCH_1):GND

Q_CAP_C0402-22UF,4V,20%,X6S,CH622KMEB02  I99  C2592
   1 PVDDCR_SOC_P0      A @T6G_MB_LIB.T6G(SCH_1):PVDDCR_SOC_P0
   2    GND      B @T6G_MB_LIB.T6G(SCH_1):GND

Q_CAP_C0402-22UF,4V,20%,X6S,CH622KMEB02  I101  C2591
   1 PVDDCR_SOC_P0      A @T6G_MB_LIB.T6G(SCH_1):PVDDCR_SOC_P0
   2    GND      B @T6G_MB_LIB.T6G(SCH_1):GND

Q_CAP_C0402-22UF,4V,20%,X6S,CH622KMEB02  I102  C2599
   1 PVDDIO_P0      A @T6G_MB_LIB.T6G(SCH_1):PVDDIO_P0
   2    GND      B @T6G_MB_LIB.T6G(SCH_1):GND

Q_CAP_C0402-22UF,4V,20%,X6S,CH622KMEB02  I104  C2598
   1 PVDDIO_P0      A @T6G_MB_LIB.T6G(SCH_1):PVDDIO_P0
   2    GND      B @T6G_MB_LIB.T6G(SCH_1):GND

Q_CAP_C0402-22UF,4V,20%,X6S,CH622KMEB02  I106  C2590
   1 PVDDCR_SOC_P0      A @T6G_MB_LIB.T6G(SCH_1):PVDDCR_SOC_P0
   2    GND      B @T6G_MB_LIB.T6G(SCH_1):GND

Q_CAP_C0402-22UF,4V,20%,X6S,CH622KMEB02  I108  C2597
   1 PVDDIO_P0      A @T6G_MB_LIB.T6G(SCH_1):PVDDIO_P0
   2    GND      B @T6G_MB_LIB.T6G(SCH_1):GND

Q_CAP_C0402-22UF,4V,20%,X6S,CH622KMEB02  I111  C3933
   1 PVDD11_S3_P0      A @T6G_MB_LIB.T6G(SCH_1):PVDD11_S3_P0
   2    GND      B @T6G_MB_LIB.T6G(SCH_1):GND

Q_CAP_C0402-22UF,4V,20%,X6S,CH622KMEB02  I112  C2610
   1 PVDD11_S3_P0      A @T6G_MB_LIB.T6G(SCH_1):PVDD11_S3_P0
   2    GND      B @T6G_MB_LIB.T6G(SCH_1):GND

Q_CAP_C0402-22UF,4V,20%,X6S,CH622KMEB02  I113  C2609
   1 PVDD11_S3_P0      A @T6G_MB_LIB.T6G(SCH_1):PVDD11_S3_P0
   2    GND      B @T6G_MB_LIB.T6G(SCH_1):GND

Q_CAP_C0402-22UF,4V,20%,X6S,CH622KMEB02  I114  C2617
   1 PVDD11_S3_P0      A @T6G_MB_LIB.T6G(SCH_1):PVDD11_S3_P0
   2    GND      B @T6G_MB_LIB.T6G(SCH_1):GND

Q_CAP_C0402-22UF,4V,20%,X6S,CH622KMEB02  I115  C2616
   1 PVDD11_S3_P0      A @T6G_MB_LIB.T6G(SCH_1):PVDD11_S3_P0
   2    GND      B @T6G_MB_LIB.T6G(SCH_1):GND

Q_CAP_C0402-22UF,4V,20%,X6S,CH622KMEB02  I116  C2624
   1 PVDD11_S3_P0      A @T6G_MB_LIB.T6G(SCH_1):PVDD11_S3_P0
   2    GND      B @T6G_MB_LIB.T6G(SCH_1):GND

Q_CAP_C0402-22UF,4V,20%,X6S,CH622KMEB02  I117  C2623
   1 PVDD11_S3_P0      A @T6G_MB_LIB.T6G(SCH_1):PVDD11_S3_P0
   2    GND      B @T6G_MB_LIB.T6G(SCH_1):GND

Q_CAP_C0402-22UF,4V,20%,X6S,CH622KMEB02  I118  C2630
   1 PVDD11_S3_P0      A @T6G_MB_LIB.T6G(SCH_1):PVDD11_S3_P0
   2    GND      B @T6G_MB_LIB.T6G(SCH_1):GND

Q_CAP_C0402-22UF,4V,20%,X6S,CH622KMEB02  I119  C2629
   1 PVDD11_S3_P0      A @T6G_MB_LIB.T6G(SCH_1):PVDD11_S3_P0
   2    GND      B @T6G_MB_LIB.T6G(SCH_1):GND

Q_CAP_C0402-22UF,4V,20%,X6S,CH622KMEB02  I120  C2636
   1 PVDD11_S3_P0      A @T6G_MB_LIB.T6G(SCH_1):PVDD11_S3_P0
   2    GND      B @T6G_MB_LIB.T6G(SCH_1):GND

Q_CAP_C0402-22UF,4V,20%,X6S,CH622KMEB02  I121  C2635
   1 PVDD11_S3_P0      A @T6G_MB_LIB.T6G(SCH_1):PVDD11_S3_P0
   2    GND      B @T6G_MB_LIB.T6G(SCH_1):GND

Q_CAP_C0402-22UF,4V,20%,X6S,CH622KMEB02  I122  C2608
   1 PVDD11_S3_P0      A @T6G_MB_LIB.T6G(SCH_1):PVDD11_S3_P0
   2    GND      B @T6G_MB_LIB.T6G(SCH_1):GND

Q_CAP_C0402-22UF,4V,20%,X6S,CH622KMEB02  I123  C2615
   1 PVDD11_S3_P0      A @T6G_MB_LIB.T6G(SCH_1):PVDD11_S3_P0
   2    GND      B @T6G_MB_LIB.T6G(SCH_1):GND

Q_CAP_C0402-22UF,4V,20%,X6S,CH622KMEB02  I124  C2607
   1 PVDD11_S3_P0      A @T6G_MB_LIB.T6G(SCH_1):PVDD11_S3_P0
   2    GND      B @T6G_MB_LIB.T6G(SCH_1):GND

Q_CAP_C0402-22UF,4V,20%,X6S,CH622KMEB02  I125  C2614
   1 PVDD11_S3_P0      A @T6G_MB_LIB.T6G(SCH_1):PVDD11_S3_P0
   2    GND      B @T6G_MB_LIB.T6G(SCH_1):GND

Q_CAP_C0402-22UF,4V,20%,X6S,CH622KMEB02  I126  C2622
   1 PVDD11_S3_P0      A @T6G_MB_LIB.T6G(SCH_1):PVDD11_S3_P0
   2    GND      B @T6G_MB_LIB.T6G(SCH_1):GND

Q_CAP_C0402-22UF,4V,20%,X6S,CH622KMEB02  I127  C2621
   1 PVDD11_S3_P0      A @T6G_MB_LIB.T6G(SCH_1):PVDD11_S3_P0
   2    GND      B @T6G_MB_LIB.T6G(SCH_1):GND

Q_CAP_C0402-22UF,4V,20%,X6S,CH622KMEB02  I129  C2628
   1 PVDD11_S3_P0      A @T6G_MB_LIB.T6G(SCH_1):PVDD11_S3_P0
   2    GND      B @T6G_MB_LIB.T6G(SCH_1):GND

Q_CAP_C0402-22UF,4V,20%,X6S,CH622KMEB02  I130  C2634
   1 PVDD11_S3_P0      A @T6G_MB_LIB.T6G(SCH_1):PVDD11_S3_P0
   2    GND      B @T6G_MB_LIB.T6G(SCH_1):GND

Q_CAP_C0402-22UF,4V,20%,X6S,CH622KMEB02  I131  C2627
   1 PVDD11_S3_P0      A @T6G_MB_LIB.T6G(SCH_1):PVDD11_S3_P0
   2    GND      B @T6G_MB_LIB.T6G(SCH_1):GND

Q_CAP_C0402-22UF,4V,20%,X6S,CH622KMEB02  I132  C2633
   1 PVDD11_S3_P0      A @T6G_MB_LIB.T6G(SCH_1):PVDD11_S3_P0
   2    GND      B @T6G_MB_LIB.T6G(SCH_1):GND

Q_CAP_C0402-22UF,4V,20%,X6S,CH622KMEB02  I133  C2642
   1 PVDD11_S3_P0      A @T6G_MB_LIB.T6G(SCH_1):PVDD11_S3_P0
   2    GND      B @T6G_MB_LIB.T6G(SCH_1):GND

Q_CAP_C0402-22UF,4V,20%,X6S,CH622KMEB02  I134  C2641
   1 PVDD11_S3_P0      A @T6G_MB_LIB.T6G(SCH_1):PVDD11_S3_P0
   2    GND      B @T6G_MB_LIB.T6G(SCH_1):GND

Q_CAP_C0402-22UF,4V,20%,X6S,CH622KMEB02  I135  C2648
   1 PVDD11_S3_P0      A @T6G_MB_LIB.T6G(SCH_1):PVDD11_S3_P0
   2    GND      B @T6G_MB_LIB.T6G(SCH_1):GND

Q_CAP_C0402-22UF,4V,20%,X6S,CH622KMEB02  I136  C2647
   1 PVDD11_S3_P0      A @T6G_MB_LIB.T6G(SCH_1):PVDD11_S3_P0
   2    GND      B @T6G_MB_LIB.T6G(SCH_1):GND

Q_CAP_C0402-22UF,4V,20%,X6S,CH622KMEB02  I138  C3934
   1 PVDD11_S3_P0      A @T6G_MB_LIB.T6G(SCH_1):PVDD11_S3_P0
   2    GND      B @T6G_MB_LIB.T6G(SCH_1):GND

Q_CAP_C0402-22UF,4V,20%,X6S,CH622KMEB02  I139  C2653
   1 PVDD11_S3_P0      A @T6G_MB_LIB.T6G(SCH_1):PVDD11_S3_P0
   2    GND      B @T6G_MB_LIB.T6G(SCH_1):GND

Q_CAP_C0402-22UF,4V,20%,X6S,CH622KMEB02  I140  C3935
   1 PVDD11_S3_P0      A @T6G_MB_LIB.T6G(SCH_1):PVDD11_S3_P0
   2    GND      B @T6G_MB_LIB.T6G(SCH_1):GND

Q_CAP_C0402-22UF,4V,20%,X6S,CH622KMEB02  I142  C2658
   1 PVDD11_S3_P0      A @T6G_MB_LIB.T6G(SCH_1):PVDD11_S3_P0
   2    GND      B @T6G_MB_LIB.T6G(SCH_1):GND

Q_CAP_C0402-22UF,4V,20%,X6S,CH622KMEB02  I143  C2640
   1 PVDD11_S3_P0      A @T6G_MB_LIB.T6G(SCH_1):PVDD11_S3_P0
   2    GND      B @T6G_MB_LIB.T6G(SCH_1):GND

Q_CAP_C0402-22UF,4V,20%,X6S,CH622KMEB02  I144  C2646
   1 PVDD11_S3_P0      A @T6G_MB_LIB.T6G(SCH_1):PVDD11_S3_P0
   2    GND      B @T6G_MB_LIB.T6G(SCH_1):GND

Q_CAP_C0402-22UF,4V,20%,X6S,CH622KMEB02  I145  C2639
   1 PVDD11_S3_P0      A @T6G_MB_LIB.T6G(SCH_1):PVDD11_S3_P0
   2    GND      B @T6G_MB_LIB.T6G(SCH_1):GND

Q_CAP_C0402-22UF,4V,20%,X6S,CH622KMEB02  I146  C2645
   1 PVDD11_S3_P0      A @T6G_MB_LIB.T6G(SCH_1):PVDD11_S3_P0
   2    GND      B @T6G_MB_LIB.T6G(SCH_1):GND

Q_CAP_C0402-22UF,4V,20%,X6S,CH622KMEB02  I147  C2652
   1 PVDD11_S3_P0      A @T6G_MB_LIB.T6G(SCH_1):PVDD11_S3_P0
   2    GND      B @T6G_MB_LIB.T6G(SCH_1):GND

Q_CAP_C0402-22UF,4V,20%,X6S,CH622KMEB02  I149  C2657
   1 PVDD11_S3_P0      A @T6G_MB_LIB.T6G(SCH_1):PVDD11_S3_P0
   2    GND      B @T6G_MB_LIB.T6G(SCH_1):GND

Q_CAP_C0402-22UF,4V,20%,X6S,CH622KMEB02  I151  C2651
   1 PVDD11_S3_P0      A @T6G_MB_LIB.T6G(SCH_1):PVDD11_S3_P0
   2    GND      B @T6G_MB_LIB.T6G(SCH_1):GND

Q_CAP_C0402-22UF,4V,20%,X6S,CH622KMEB02  I152  C2656
   1 PVDD11_S3_P0      A @T6G_MB_LIB.T6G(SCH_1):PVDD11_S3_P0
   2    GND      B @T6G_MB_LIB.T6G(SCH_1):GND

Q_CAP_C0402-22UF,4V,20%,X6S,CH622KMEB02  I153  C2606
   1 PVDDIO_P0      A @T6G_MB_LIB.T6G(SCH_1):PVDDIO_P0
   2    GND      B @T6G_MB_LIB.T6G(SCH_1):GND

Q_CAP_C0402-22UF,4V,20%,X6S,CH622KMEB02  I154  C2605
   1 PVDDIO_P0      A @T6G_MB_LIB.T6G(SCH_1):PVDDIO_P0
   2    GND      B @T6G_MB_LIB.T6G(SCH_1):GND

Q_CAP_C0402-22UF,4V,20%,X6S,CH622KMEB02  I155  C2613
   1 PVDDIO_P0      A @T6G_MB_LIB.T6G(SCH_1):PVDDIO_P0
   2    GND      B @T6G_MB_LIB.T6G(SCH_1):GND

Q_CAP_C0402-22UF,4V,20%,X6S,CH622KMEB02  I156  C2612
   1 PVDDIO_P0      A @T6G_MB_LIB.T6G(SCH_1):PVDDIO_P0
   2    GND      B @T6G_MB_LIB.T6G(SCH_1):GND

Q_CAP_C0402-22UF,4V,20%,X6S,CH622KMEB02  I157  C2619
   1 PVDDIO_P0      A @T6G_MB_LIB.T6G(SCH_1):PVDDIO_P0
   2    GND      B @T6G_MB_LIB.T6G(SCH_1):GND

Q_CAP_C0402-22UF,4V,20%,X6S,CH622KMEB02  I158  C2604
   1 PVDDIO_P0      A @T6G_MB_LIB.T6G(SCH_1):PVDDIO_P0
   2    GND      B @T6G_MB_LIB.T6G(SCH_1):GND

Q_CAP_C0402-22UF,4V,20%,X6S,CH622KMEB02  I159  C2611
   1 PVDDIO_P0      A @T6G_MB_LIB.T6G(SCH_1):PVDDIO_P0
   2    GND      B @T6G_MB_LIB.T6G(SCH_1):GND

Q_CAP_C0402-22UF,4V,20%,X6S,CH622KMEB02  I160  C2618
   1 PVDDIO_P0      A @T6G_MB_LIB.T6G(SCH_1):PVDDIO_P0
   2    GND      B @T6G_MB_LIB.T6G(SCH_1):GND

Q_CAP_C0402-22UF,4V,20%,X6S,CH622KMEB02  I161  C2620
   1 PVDDIO_P0      A @T6G_MB_LIB.T6G(SCH_1):PVDDIO_P0
   2    GND      B @T6G_MB_LIB.T6G(SCH_1):GND

Q_CAP_C0402-22UF,4V,20%,X6S,CH622KMEB02  I162  C2626
   1 PVDDIO_P0      A @T6G_MB_LIB.T6G(SCH_1):PVDDIO_P0
   2    GND      B @T6G_MB_LIB.T6G(SCH_1):GND

Q_CAP_C0402-22UF,4V,20%,X6S,CH622KMEB02  I163  C2632
   1 PVDDIO_P0      A @T6G_MB_LIB.T6G(SCH_1):PVDDIO_P0
   2    GND      B @T6G_MB_LIB.T6G(SCH_1):GND

Q_CAP_C0402-22UF,4V,20%,X6S,CH622KMEB02  I164  C2625
   1 PVDDIO_P0      A @T6G_MB_LIB.T6G(SCH_1):PVDDIO_P0
   2    GND      B @T6G_MB_LIB.T6G(SCH_1):GND

Q_CAP_C0402-22UF,4V,20%,X6S,CH622KMEB02  I165  C2631
   1 PVDDIO_P0      A @T6G_MB_LIB.T6G(SCH_1):PVDDIO_P0
   2    GND      B @T6G_MB_LIB.T6G(SCH_1):GND

Q_CAP_C0402-22UF,4V,20%,X6S,CH622KMEB02  I166  C2638
   1 PVDDIO_P0      A @T6G_MB_LIB.T6G(SCH_1):PVDDIO_P0
   2    GND      B @T6G_MB_LIB.T6G(SCH_1):GND

Q_CAP_C0402-22UF,4V,20%,X6S,CH622KMEB02  I167  C2644
   1 PVDDIO_P0      A @T6G_MB_LIB.T6G(SCH_1):PVDDIO_P0
   2    GND      B @T6G_MB_LIB.T6G(SCH_1):GND

Q_CAP_C0402-22UF,4V,20%,X6S,CH622KMEB02  I168  C2637
   1 PVDDIO_P0      A @T6G_MB_LIB.T6G(SCH_1):PVDDIO_P0
   2    GND      B @T6G_MB_LIB.T6G(SCH_1):GND

Q_CAP_C0402-22UF,4V,20%,X6S,CH622KMEB02  I169  C2643
   1 PVDDIO_P0      A @T6G_MB_LIB.T6G(SCH_1):PVDDIO_P0
   2    GND      B @T6G_MB_LIB.T6G(SCH_1):GND

Q_CAP_C0402-22UF,4V,20%,X6S,CH622KMEB02  I170  C2650
   1 PVDDIO_P0      A @T6G_MB_LIB.T6G(SCH_1):PVDDIO_P0
   2    GND      B @T6G_MB_LIB.T6G(SCH_1):GND

Q_CAP_C0402-22UF,4V,20%,X6S,CH622KMEB02  I172  C2655
   1 PVDDIO_P0      A @T6G_MB_LIB.T6G(SCH_1):PVDDIO_P0
   2    GND      B @T6G_MB_LIB.T6G(SCH_1):GND

Q_CAP_C0402-22UF,4V,20%,X6S,CH622KMEB02  I173  C2649
   1 PVDDIO_P0      A @T6G_MB_LIB.T6G(SCH_1):PVDDIO_P0
   2    GND      B @T6G_MB_LIB.T6G(SCH_1):GND

Q_CAP_C0402-22UF,4V,20%,X6S,CH622KMEB02  I175  C2654
   1 PVDDIO_P0      A @T6G_MB_LIB.T6G(SCH_1):PVDDIO_P0
   2    GND      B @T6G_MB_LIB.T6G(SCH_1):GND


DRAWING: @T6G_MB_LIB.T6G(SCH_1):PAGE70 

Q_CAP_C0402-22UF,4V,20%,X6S,CH622KMEB02  I1  C2514
   1 PVDD18_S5_P0      A @T6G_MB_LIB.T6G(SCH_1):PVDD18_S5_P0
   2    GND      B @T6G_MB_LIB.T6G(SCH_1):GND

Q_CAP_C0402-22UF,4V,20%,X6S,CH622KMEB02  I3  C2513
   1 PVDD18_S5_P0      A @T6G_MB_LIB.T6G(SCH_1):PVDD18_S5_P0
   2    GND      B @T6G_MB_LIB.T6G(SCH_1):GND

Q_CAP_C0402-22UF,4V,20%,X6S,CH622KMEB02  I8  C2517
   1 PVDD18_S5_P0      A @T6G_MB_LIB.T6G(SCH_1):PVDD18_S5_P0
   2    GND      B @T6G_MB_LIB.T6G(SCH_1):GND

Q_CAP_C0402-22UF,4V,20%,X6S,CH622KMEB02  I9  C2516
   1 PVDD18_S5_P0      A @T6G_MB_LIB.T6G(SCH_1):PVDD18_S5_P0
   2    GND      B @T6G_MB_LIB.T6G(SCH_1):GND

Q_CAP_C0402-22UF,4V,20%,X6S,CH622KMEB02  I10  C2518
   1 PVDD18_S5_P0      A @T6G_MB_LIB.T6G(SCH_1):PVDD18_S5_P0
   2    GND      B @T6G_MB_LIB.T6G(SCH_1):GND

Q_CAP_C0402-22UF,4V,20%,X6S,CH622KMEB02  I11  C2520
   1 PVDD18_S5_P0      A @T6G_MB_LIB.T6G(SCH_1):PVDD18_S5_P0
   2    GND      B @T6G_MB_LIB.T6G(SCH_1):GND

Q_CAP_C0402-22UF,4V,20%,X6S,CH622KMEB02  I12  C2521
   1 PVDD18_S5_P0      A @T6G_MB_LIB.T6G(SCH_1):PVDD18_S5_P0
   2    GND      B @T6G_MB_LIB.T6G(SCH_1):GND

Q_CAP_C0402-22UF,4V,20%,X6S,CH622KMEB02  I13  C2522
   1 PVDD18_S5_P0      A @T6G_MB_LIB.T6G(SCH_1):PVDD18_S5_P0
   2    GND      B @T6G_MB_LIB.T6G(SCH_1):GND

Q_CAP_C0402-22UF,4V,20%,X6S,CH622KMEB02  I14  C2523
   1 PVDD18_S5_P0      A @T6G_MB_LIB.T6G(SCH_1):PVDD18_S5_P0
   2    GND      B @T6G_MB_LIB.T6G(SCH_1):GND

Q_CAP_C0402-22UF,4V,20%,X6S,CH622KMEB02  I15  C2524
   1 PVDD18_S5_P0      A @T6G_MB_LIB.T6G(SCH_1):PVDD18_S5_P0
   2    GND      B @T6G_MB_LIB.T6G(SCH_1):GND

Q_CAP_C0402-22UF,4V,20%,X6S,CH622KMEB02  I16  C2525
   1 PVDD18_S5_P0      A @T6G_MB_LIB.T6G(SCH_1):PVDD18_S5_P0
   2    GND      B @T6G_MB_LIB.T6G(SCH_1):GND

Q_CAP_C0402-22UF,4V,20%,X6S,CH622KMEB02  I18  C2526
   1 PVDD18_S5_P0      A @T6G_MB_LIB.T6G(SCH_1):PVDD18_S5_P0
   2    GND      B @T6G_MB_LIB.T6G(SCH_1):GND

Q_CAP_C0402-10UF,6.3V,20%,X6S,CH6101MEB01  I25  C2515
   1 PVDD_33_S5      A @T6G_MB_LIB.T6G(SCH_1):PVDD_33_S5
   2    GND      B @T6G_MB_LIB.T6G(SCH_1):GND

Q_CAP_C0402-10UF,6.3V,20%,X6S,CH6101MEB01  I26  C2512
   1 PVDD_33_S5      A @T6G_MB_LIB.T6G(SCH_1):PVDD_33_S5
   2    GND      B @T6G_MB_LIB.T6G(SCH_1):GND


DRAWING: @T6G_MB_LIB.T6G(SCH_1):PAGE71 

Q_CAP_C0402-22UF,4V,20%,X6S,CH622KMEB02  I1  C2262
   1 PVDD11_S3_P1      A @T6G_MB_LIB.T6G(SCH_1):PVDD11_S3_P1
   2    GND      B @T6G_MB_LIB.T6G(SCH_1):GND

Q_CAP_C0402-22UF,4V,20%,X6S,CH622KMEB02  I3  C2261
   1 PVDD11_S3_P1      A @T6G_MB_LIB.T6G(SCH_1):PVDD11_S3_P1
   2    GND      B @T6G_MB_LIB.T6G(SCH_1):GND

Q_CAP_C0402-22UF,4V,20%,X6S,CH622KMEB02  I5  C3900
   1 PVDDCR_SOC_P1      A @T6G_MB_LIB.T6G(SCH_1):PVDDCR_SOC_P1
   2    GND      B @T6G_MB_LIB.T6G(SCH_1):GND

Q_CAP_C0402-22UF,4V,20%,X6S,CH622KMEB02  I7  C2259
   1 PVDDCR_SOC_P1      A @T6G_MB_LIB.T6G(SCH_1):PVDDCR_SOC_P1
   2    GND      B @T6G_MB_LIB.T6G(SCH_1):GND

Q_CAP_C0402-22UF,4V,20%,X6S,CH622KMEB02  I9  C2258
   1 PVDDCR_SOC_P1      A @T6G_MB_LIB.T6G(SCH_1):PVDDCR_SOC_P1
   2    GND      B @T6G_MB_LIB.T6G(SCH_1):GND

Q_CAP_C0402-22UF,4V,20%,X6S,CH622KMEB02  I11  C2267
   1 PVDD11_S3_P1      A @T6G_MB_LIB.T6G(SCH_1):PVDD11_S3_P1
   2    GND      B @T6G_MB_LIB.T6G(SCH_1):GND

Q_CAP_C0402-22UF,4V,20%,X6S,CH622KMEB02  I12  C3902
   1 PVDD11_S3_P1      A @T6G_MB_LIB.T6G(SCH_1):PVDD11_S3_P1
   2    GND      B @T6G_MB_LIB.T6G(SCH_1):GND

Q_CAP_C0402-22UF,4V,20%,X6S,CH622KMEB02  I13  C2266
   1 PVDD11_S3_P1      A @T6G_MB_LIB.T6G(SCH_1):PVDD11_S3_P1
   2    GND      B @T6G_MB_LIB.T6G(SCH_1):GND

Q_CAP_C0402-22UF,4V,20%,X6S,CH622KMEB02  I14  C2271
   1 PVDD11_S3_P1      A @T6G_MB_LIB.T6G(SCH_1):PVDD11_S3_P1
   2    GND      B @T6G_MB_LIB.T6G(SCH_1):GND

Q_CAP_C0402-22UF,4V,20%,X6S,CH622KMEB02  I15  C3903
   1 PVDD11_S3_P1      A @T6G_MB_LIB.T6G(SCH_1):PVDD11_S3_P1
   2    GND      B @T6G_MB_LIB.T6G(SCH_1):GND

Q_CAP_C0402-22UF,4V,20%,X6S,CH622KMEB02  I16  C3904
   1 PVDD11_S3_P1      A @T6G_MB_LIB.T6G(SCH_1):PVDD11_S3_P1
   2    GND      B @T6G_MB_LIB.T6G(SCH_1):GND

Q_CAP_C0402-22UF,4V,20%,X6S,CH622KMEB02  I18  C3905
   1 PVDD11_S3_P1      A @T6G_MB_LIB.T6G(SCH_1):PVDD11_S3_P1
   2    GND      B @T6G_MB_LIB.T6G(SCH_1):GND

Q_CAP_C0402-22UF,4V,20%,X6S,CH622KMEB02  I19  C2275
   1 PVDD11_S3_P1      A @T6G_MB_LIB.T6G(SCH_1):PVDD11_S3_P1
   2    GND      B @T6G_MB_LIB.T6G(SCH_1):GND

Q_CAP_C0402-22UF,4V,20%,X6S,CH622KMEB02  I20  C2279
   1 PVDD11_S3_P1      A @T6G_MB_LIB.T6G(SCH_1):PVDD11_S3_P1
   2    GND      B @T6G_MB_LIB.T6G(SCH_1):GND

Q_CAP_C0402-22UF,4V,20%,X6S,CH622KMEB02  I21  C2282
   1 PVDD11_S3_P1      A @T6G_MB_LIB.T6G(SCH_1):PVDD11_S3_P1
   2    GND      B @T6G_MB_LIB.T6G(SCH_1):GND

Q_CAP_C0402-22UF,4V,20%,X6S,CH622KMEB02  I23  C3901
   1 PVDDCR_SOC_P1      A @T6G_MB_LIB.T6G(SCH_1):PVDDCR_SOC_P1
   2    GND      B @T6G_MB_LIB.T6G(SCH_1):GND

Q_CAP_C0402-22UF,4V,20%,X6S,CH622KMEB02  I24  C2285
   1 PVDD11_S3_P1      A @T6G_MB_LIB.T6G(SCH_1):PVDD11_S3_P1
   2    GND      B @T6G_MB_LIB.T6G(SCH_1):GND

Q_CAP_C0402-22UF,4V,20%,X6S,CH622KMEB02  I25  C2287
   1 PVDD11_S3_P1      A @T6G_MB_LIB.T6G(SCH_1):PVDD11_S3_P1
   2    GND      B @T6G_MB_LIB.T6G(SCH_1):GND

Q_CAP_C0402-22UF,4V,20%,X6S,CH622KMEB02  I26  C2289
   1 PVDD11_S3_P1      A @T6G_MB_LIB.T6G(SCH_1):PVDD11_S3_P1
   2    GND      B @T6G_MB_LIB.T6G(SCH_1):GND

Q_CAP_C0402-22UF,4V,20%,X6S,CH622KMEB02  I28  C2291
   1 PVDD11_S3_P1      A @T6G_MB_LIB.T6G(SCH_1):PVDD11_S3_P1
   2    GND      B @T6G_MB_LIB.T6G(SCH_1):GND

Q_CAP_C0402-22UF,4V,20%,X6S,CH622KMEB02  I30  C2264
   1 PVDDCR_SOC_P1      A @T6G_MB_LIB.T6G(SCH_1):PVDDCR_SOC_P1
   2    GND      B @T6G_MB_LIB.T6G(SCH_1):GND

Q_CAP_C0402-22UF,4V,20%,X6S,CH622KMEB02  I31  C2263
   1 PVDDCR_SOC_P1      A @T6G_MB_LIB.T6G(SCH_1):PVDDCR_SOC_P1
   2    GND      B @T6G_MB_LIB.T6G(SCH_1):GND

Q_CAP_C0402-22UF,4V,20%,X6S,CH622KMEB02  I32  C2269
   1 PVDDCR_SOC_P1      A @T6G_MB_LIB.T6G(SCH_1):PVDDCR_SOC_P1
   2    GND      B @T6G_MB_LIB.T6G(SCH_1):GND

Q_CAP_C0402-22UF,4V,20%,X6S,CH622KMEB02  I33  C2268
   1 PVDDCR_SOC_P1      A @T6G_MB_LIB.T6G(SCH_1):PVDDCR_SOC_P1
   2    GND      B @T6G_MB_LIB.T6G(SCH_1):GND

Q_CAP_C0402-22UF,4V,20%,X6S,CH622KMEB02  I34  C2272
   1 PVDDCR_SOC_P1      A @T6G_MB_LIB.T6G(SCH_1):PVDDCR_SOC_P1
   2    GND      B @T6G_MB_LIB.T6G(SCH_1):GND

Q_CAP_C0402-22UF,4V,20%,X6S,CH622KMEB02  I35  C2273
   1 PVDDCR_SOC_P1      A @T6G_MB_LIB.T6G(SCH_1):PVDDCR_SOC_P1
   2    GND      B @T6G_MB_LIB.T6G(SCH_1):GND

Q_CAP_C0402-22UF,4V,20%,X6S,CH622KMEB02  I36  C2277
   1 PVDDCR_SOC_P1      A @T6G_MB_LIB.T6G(SCH_1):PVDDCR_SOC_P1
   2    GND      B @T6G_MB_LIB.T6G(SCH_1):GND

Q_CAP_C0402-22UF,4V,20%,X6S,CH622KMEB02  I37  C2281
   1 PVDDCR_SOC_P1      A @T6G_MB_LIB.T6G(SCH_1):PVDDCR_SOC_P1
   2    GND      B @T6G_MB_LIB.T6G(SCH_1):GND

Q_CAP_C0402-22UF,4V,20%,X6S,CH622KMEB02  I38  C2280
   1 PVDDCR_SOC_P1      A @T6G_MB_LIB.T6G(SCH_1):PVDDCR_SOC_P1
   2    GND      B @T6G_MB_LIB.T6G(SCH_1):GND

Q_CAP_C0402-22UF,4V,20%,X6S,CH622KMEB02  I39  C2284
   1 PVDDCR_SOC_P1      A @T6G_MB_LIB.T6G(SCH_1):PVDDCR_SOC_P1
   2    GND      B @T6G_MB_LIB.T6G(SCH_1):GND

Q_CAP_C0402-22UF,4V,20%,X6S,CH622KMEB02  I40  C2283
   1 PVDDCR_SOC_P1      A @T6G_MB_LIB.T6G(SCH_1):PVDDCR_SOC_P1
   2    GND      B @T6G_MB_LIB.T6G(SCH_1):GND

Q_CAP_C0402-22UF,4V,20%,X6S,CH622KMEB02  I41  C3906
   1 PVDDCR_SOC_P1      A @T6G_MB_LIB.T6G(SCH_1):PVDDCR_SOC_P1
   2    GND      B @T6G_MB_LIB.T6G(SCH_1):GND

Q_CAP_C0402-22UF,4V,20%,X6S,CH622KMEB02  I42  C2286
   1 PVDDCR_SOC_P1      A @T6G_MB_LIB.T6G(SCH_1):PVDDCR_SOC_P1
   2    GND      B @T6G_MB_LIB.T6G(SCH_1):GND

Q_CAP_C0402-22UF,4V,20%,X6S,CH622KMEB02  I43  C3907
   1 PVDDCR_SOC_P1      A @T6G_MB_LIB.T6G(SCH_1):PVDDCR_SOC_P1
   2    GND      B @T6G_MB_LIB.T6G(SCH_1):GND

Q_CAP_C0402-22UF,4V,20%,X6S,CH622KMEB02  I44  C2288
   1 PVDDCR_SOC_P1      A @T6G_MB_LIB.T6G(SCH_1):PVDDCR_SOC_P1
   2    GND      B @T6G_MB_LIB.T6G(SCH_1):GND

Q_CAP_C0402-22UF,4V,20%,X6S,CH622KMEB02  I45  C3908
   1 PVDDCR_SOC_P1      A @T6G_MB_LIB.T6G(SCH_1):PVDDCR_SOC_P1
   2    GND      B @T6G_MB_LIB.T6G(SCH_1):GND

Q_CAP_C0402-22UF,4V,20%,X6S,CH622KMEB02  I47  C2290
   1 PVDDCR_SOC_P1      A @T6G_MB_LIB.T6G(SCH_1):PVDDCR_SOC_P1
   2    GND      B @T6G_MB_LIB.T6G(SCH_1):GND

Q_CAP_C0402-22UF,4V,20%,X6S,CH622KMEB02  I49  C2292
   1 PVDD18_S5_P1      A @T6G_MB_LIB.T6G(SCH_1):PVDD18_S5_P1
   2    GND      B @T6G_MB_LIB.T6G(SCH_1):GND

Q_CAP_C0402-22UF,4V,20%,X6S,CH622KMEB02  I50  C2293
   1 PVDD18_S5_P1      A @T6G_MB_LIB.T6G(SCH_1):PVDD18_S5_P1
   2    GND      B @T6G_MB_LIB.T6G(SCH_1):GND

Q_CAP_C0402-22UF,4V,20%,X6S,CH622KMEB02  I52  C3909
   1 PVDD18_S5_P1      A @T6G_MB_LIB.T6G(SCH_1):PVDD18_S5_P1
   2    GND      B @T6G_MB_LIB.T6G(SCH_1):GND

Q_CAP_C0402-22UF,4V,20%,X6S,CH622KMEB02  I53  C2260
   1 PVDDIO_P1      A @T6G_MB_LIB.T6G(SCH_1):PVDDIO_P1
   2    GND      B @T6G_MB_LIB.T6G(SCH_1):GND

Q_CAP_C0402-22UF,4V,20%,X6S,CH622KMEB02  I54  C2265
   1 PVDDIO_P1      A @T6G_MB_LIB.T6G(SCH_1):PVDDIO_P1
   2    GND      B @T6G_MB_LIB.T6G(SCH_1):GND

Q_CAP_C0402-22UF,4V,20%,X6S,CH622KMEB02  I56  C2270
   1 PVDDIO_P1      A @T6G_MB_LIB.T6G(SCH_1):PVDDIO_P1
   2    GND      B @T6G_MB_LIB.T6G(SCH_1):GND

Q_CAP_C0402-22UF,4V,20%,X6S,CH622KMEB02  I57  C2274
   1 PVDDIO_P1      A @T6G_MB_LIB.T6G(SCH_1):PVDDIO_P1
   2    GND      B @T6G_MB_LIB.T6G(SCH_1):GND

Q_CAP_C0402-22UF,4V,20%,X6S,CH622KMEB02  I58  C2278
   1 PVDDIO_P1      A @T6G_MB_LIB.T6G(SCH_1):PVDDIO_P1
   2    GND      B @T6G_MB_LIB.T6G(SCH_1):GND

Q_CAP_C0402-22UF,4V,20%,X6S,CH622KMEB02  I59  C3910
   1 PVDDIO_P1      A @T6G_MB_LIB.T6G(SCH_1):PVDDIO_P1
   2    GND      B @T6G_MB_LIB.T6G(SCH_1):GND

Q_CAP_C0402-22UF,4V,20%,X6S,CH622KMEB02  I61  C3911
   1 PVDDIO_P1      A @T6G_MB_LIB.T6G(SCH_1):PVDDIO_P1
   2    GND      B @T6G_MB_LIB.T6G(SCH_1):GND

Q_CAP_C0402-22UF,4V,20%,X6S,CH622KMEB02  I62  C2276
   1 PVDDCR_SOC_P1      A @T6G_MB_LIB.T6G(SCH_1):PVDDCR_SOC_P1
   2    GND      B @T6G_MB_LIB.T6G(SCH_1):GND


DRAWING: @T6G_MB_LIB.T6G(SCH_1):PAGE72 

Q_CAP_C0402-22UF,4V,20%,X6S,CH622KMEB02  I1  C2298
   1 PVDDCR_CPU0_P1      A @T6G_MB_LIB.T6G(SCH_1):PVDDCR_CPU0_P1
   2    GND      B @T6G_MB_LIB.T6G(SCH_1):GND

Q_CAP_C0402-22UF,4V,20%,X6S,CH622KMEB02  I3  C2304
   1 PVDDCR_CPU0_P1      A @T6G_MB_LIB.T6G(SCH_1):PVDDCR_CPU0_P1
   2    GND      B @T6G_MB_LIB.T6G(SCH_1):GND

Q_CAP_C0402-22UF,4V,20%,X6S,CH622KMEB02  I4  C2310
   1 PVDDCR_CPU0_P1      A @T6G_MB_LIB.T6G(SCH_1):PVDDCR_CPU0_P1
   2    GND      B @T6G_MB_LIB.T6G(SCH_1):GND

Q_CAP_C0402-22UF,4V,20%,X6S,CH622KMEB02  I5  C2297
   1 PVDDCR_CPU0_P1      A @T6G_MB_LIB.T6G(SCH_1):PVDDCR_CPU0_P1
   2    GND      B @T6G_MB_LIB.T6G(SCH_1):GND

Q_CAP_C0402-22UF,4V,20%,X6S,CH622KMEB02  I7  C2296
   1 PVDDCR_CPU0_P1      A @T6G_MB_LIB.T6G(SCH_1):PVDDCR_CPU0_P1
   2    GND      B @T6G_MB_LIB.T6G(SCH_1):GND

Q_CAP_C0402-22UF,4V,20%,X6S,CH622KMEB02  I9  C2295
   1 PVDDCR_CPU0_P1      A @T6G_MB_LIB.T6G(SCH_1):PVDDCR_CPU0_P1
   2    GND      B @T6G_MB_LIB.T6G(SCH_1):GND

Q_CAP_C0402-22UF,4V,20%,X6S,CH622KMEB02  I10  C2303
   1 PVDDCR_CPU0_P1      A @T6G_MB_LIB.T6G(SCH_1):PVDDCR_CPU0_P1
   2    GND      B @T6G_MB_LIB.T6G(SCH_1):GND

Q_CAP_C0402-22UF,4V,20%,X6S,CH622KMEB02  I11  C2309
   1 PVDDCR_CPU0_P1      A @T6G_MB_LIB.T6G(SCH_1):PVDDCR_CPU0_P1
   2    GND      B @T6G_MB_LIB.T6G(SCH_1):GND

Q_CAP_C0402-22UF,4V,20%,X6S,CH622KMEB02  I12  C2302
   1 PVDDCR_CPU0_P1      A @T6G_MB_LIB.T6G(SCH_1):PVDDCR_CPU0_P1
   2    GND      B @T6G_MB_LIB.T6G(SCH_1):GND

Q_CAP_C0402-22UF,4V,20%,X6S,CH622KMEB02  I13  C2301
   1 PVDDCR_CPU0_P1      A @T6G_MB_LIB.T6G(SCH_1):PVDDCR_CPU0_P1
   2    GND      B @T6G_MB_LIB.T6G(SCH_1):GND

Q_CAP_C0402-22UF,4V,20%,X6S,CH622KMEB02  I14  C2308
   1 PVDDCR_CPU0_P1      A @T6G_MB_LIB.T6G(SCH_1):PVDDCR_CPU0_P1
   2    GND      B @T6G_MB_LIB.T6G(SCH_1):GND

Q_CAP_C0402-22UF,4V,20%,X6S,CH622KMEB02  I15  C2307
   1 PVDDCR_CPU0_P1      A @T6G_MB_LIB.T6G(SCH_1):PVDDCR_CPU0_P1
   2    GND      B @T6G_MB_LIB.T6G(SCH_1):GND

Q_CAP_C0402-22UF,4V,20%,X6S,CH622KMEB02  I17  C2294
   1 PVDDCR_CPU0_P1      A @T6G_MB_LIB.T6G(SCH_1):PVDDCR_CPU0_P1
   2    GND      B @T6G_MB_LIB.T6G(SCH_1):GND

Q_CAP_C0402-22UF,4V,20%,X6S,CH622KMEB02  I19  C2300
   1 PVDDCR_CPU0_P1      A @T6G_MB_LIB.T6G(SCH_1):PVDDCR_CPU0_P1
   2    GND      B @T6G_MB_LIB.T6G(SCH_1):GND

Q_CAP_C0402-22UF,4V,20%,X6S,CH622KMEB02  I20  C2306
   1 PVDDCR_CPU0_P1      A @T6G_MB_LIB.T6G(SCH_1):PVDDCR_CPU0_P1
   2    GND      B @T6G_MB_LIB.T6G(SCH_1):GND

Q_CAP_C0402-22UF,4V,20%,X6S,CH622KMEB02  I21  C2316
   1 PVDDCR_CPU0_P1      A @T6G_MB_LIB.T6G(SCH_1):PVDDCR_CPU0_P1
   2    GND      B @T6G_MB_LIB.T6G(SCH_1):GND

Q_CAP_C0402-22UF,4V,20%,X6S,CH622KMEB02  I23  C2322
   1 PVDDCR_CPU0_P1      A @T6G_MB_LIB.T6G(SCH_1):PVDDCR_CPU0_P1
   2    GND      B @T6G_MB_LIB.T6G(SCH_1):GND

Q_CAP_C0402-22UF,4V,20%,X6S,CH622KMEB02  I24  C2315
   1 PVDDCR_CPU0_P1      A @T6G_MB_LIB.T6G(SCH_1):PVDDCR_CPU0_P1
   2    GND      B @T6G_MB_LIB.T6G(SCH_1):GND

Q_CAP_C0402-22UF,4V,20%,X6S,CH622KMEB02  I25  C2321
   1 PVDDCR_CPU0_P1      A @T6G_MB_LIB.T6G(SCH_1):PVDDCR_CPU0_P1
   2    GND      B @T6G_MB_LIB.T6G(SCH_1):GND

Q_CAP_C0402-22UF,4V,20%,X6S,CH622KMEB02  I26  C2327
   1 PVDDCR_CPU0_P1      A @T6G_MB_LIB.T6G(SCH_1):PVDDCR_CPU0_P1
   2    GND      B @T6G_MB_LIB.T6G(SCH_1):GND

Q_CAP_C0402-22UF,4V,20%,X6S,CH622KMEB02  I27  C2314
   1 PVDDCR_CPU0_P1      A @T6G_MB_LIB.T6G(SCH_1):PVDDCR_CPU0_P1
   2    GND      B @T6G_MB_LIB.T6G(SCH_1):GND

Q_CAP_C0402-22UF,4V,20%,X6S,CH622KMEB02  I28  C2313
   1 PVDDCR_CPU0_P1      A @T6G_MB_LIB.T6G(SCH_1):PVDDCR_CPU0_P1
   2    GND      B @T6G_MB_LIB.T6G(SCH_1):GND

Q_CAP_C0402-22UF,4V,20%,X6S,CH622KMEB02  I29  C2320
   1 PVDDCR_CPU0_P1      A @T6G_MB_LIB.T6G(SCH_1):PVDDCR_CPU0_P1
   2    GND      B @T6G_MB_LIB.T6G(SCH_1):GND

Q_CAP_C0402-22UF,4V,20%,X6S,CH622KMEB02  I30  C2326
   1 PVDDCR_CPU0_P1      A @T6G_MB_LIB.T6G(SCH_1):PVDDCR_CPU0_P1
   2    GND      B @T6G_MB_LIB.T6G(SCH_1):GND

Q_CAP_C0402-22UF,4V,20%,X6S,CH622KMEB02  I31  C2319
   1 PVDDCR_CPU0_P1      A @T6G_MB_LIB.T6G(SCH_1):PVDDCR_CPU0_P1
   2    GND      B @T6G_MB_LIB.T6G(SCH_1):GND

Q_CAP_C0402-22UF,4V,20%,X6S,CH622KMEB02  I32  C2325
   1 PVDDCR_CPU0_P1      A @T6G_MB_LIB.T6G(SCH_1):PVDDCR_CPU0_P1
   2    GND      B @T6G_MB_LIB.T6G(SCH_1):GND

Q_CAP_C0402-22UF,4V,20%,X6S,CH622KMEB02  I33  C2333
   1 PVDDCR_CPU0_P1      A @T6G_MB_LIB.T6G(SCH_1):PVDDCR_CPU0_P1
   2    GND      B @T6G_MB_LIB.T6G(SCH_1):GND

Q_CAP_C0402-22UF,4V,20%,X6S,CH622KMEB02  I34  C2338
   1 PVDDCR_CPU0_P1      A @T6G_MB_LIB.T6G(SCH_1):PVDDCR_CPU0_P1
   2    GND      B @T6G_MB_LIB.T6G(SCH_1):GND

Q_CAP_C0402-22UF,4V,20%,X6S,CH622KMEB02  I35  C2332
   1 PVDDCR_CPU0_P1      A @T6G_MB_LIB.T6G(SCH_1):PVDDCR_CPU0_P1
   2    GND      B @T6G_MB_LIB.T6G(SCH_1):GND

Q_CAP_C0402-22UF,4V,20%,X6S,CH622KMEB02  I36  C2331
   1 PVDDCR_CPU0_P1      A @T6G_MB_LIB.T6G(SCH_1):PVDDCR_CPU0_P1
   2    GND      B @T6G_MB_LIB.T6G(SCH_1):GND

Q_CAP_C0402-22UF,4V,20%,X6S,CH622KMEB02  I37  C2337
   1 PVDDCR_CPU0_P1      A @T6G_MB_LIB.T6G(SCH_1):PVDDCR_CPU0_P1
   2    GND      B @T6G_MB_LIB.T6G(SCH_1):GND

Q_CAP_C0402-22UF,4V,20%,X6S,CH622KMEB02  I38  C2336
   1 PVDDCR_CPU0_P1      A @T6G_MB_LIB.T6G(SCH_1):PVDDCR_CPU0_P1
   2    GND      B @T6G_MB_LIB.T6G(SCH_1):GND

Q_CAP_C0402-22UF,4V,20%,X6S,CH622KMEB02  I40  C2354
   1 PVDDCR_CPU1_P1      A @T6G_MB_LIB.T6G(SCH_1):PVDDCR_CPU1_P1
   2    GND      B @T6G_MB_LIB.T6G(SCH_1):GND

Q_CAP_C0402-22UF,4V,20%,X6S,CH622KMEB02  I41  C2360
   1 PVDDCR_CPU1_P1      A @T6G_MB_LIB.T6G(SCH_1):PVDDCR_CPU1_P1
   2    GND      B @T6G_MB_LIB.T6G(SCH_1):GND

Q_CAP_C0402-22UF,4V,20%,X6S,CH622KMEB02  I42  C2343
   1 PVDDCR_CPU0_P1      A @T6G_MB_LIB.T6G(SCH_1):PVDDCR_CPU0_P1
   2    GND      B @T6G_MB_LIB.T6G(SCH_1):GND

Q_CAP_C0402-22UF,4V,20%,X6S,CH622KMEB02  I44  C2348
   1 PVDDCR_CPU0_P1      A @T6G_MB_LIB.T6G(SCH_1):PVDDCR_CPU0_P1
   2    GND      B @T6G_MB_LIB.T6G(SCH_1):GND

Q_CAP_C0402-22UF,4V,20%,X6S,CH622KMEB02  I46  C2342
   1 PVDDCR_CPU0_P1      A @T6G_MB_LIB.T6G(SCH_1):PVDDCR_CPU0_P1
   2    GND      B @T6G_MB_LIB.T6G(SCH_1):GND

Q_CAP_C0402-22UF,4V,20%,X6S,CH622KMEB02  I47  C2341
   1 PVDDCR_CPU0_P1      A @T6G_MB_LIB.T6G(SCH_1):PVDDCR_CPU0_P1
   2    GND      B @T6G_MB_LIB.T6G(SCH_1):GND

Q_CAP_C0402-22UF,4V,20%,X6S,CH622KMEB02  I48  C2347
   1 PVDDCR_CPU0_P1      A @T6G_MB_LIB.T6G(SCH_1):PVDDCR_CPU0_P1
   2    GND      B @T6G_MB_LIB.T6G(SCH_1):GND

Q_CAP_C0402-22UF,4V,20%,X6S,CH622KMEB02  I50  C2346
   1 PVDDCR_CPU0_P1      A @T6G_MB_LIB.T6G(SCH_1):PVDDCR_CPU0_P1
   2    GND      B @T6G_MB_LIB.T6G(SCH_1):GND

Q_CAP_C0402-22UF,4V,20%,X6S,CH622KMEB02  I51  C2353
   1 PVDDCR_CPU1_P1      A @T6G_MB_LIB.T6G(SCH_1):PVDDCR_CPU1_P1
   2    GND      B @T6G_MB_LIB.T6G(SCH_1):GND

Q_CAP_C0402-22UF,4V,20%,X6S,CH622KMEB02  I53  C2359
   1 PVDDCR_CPU1_P1      A @T6G_MB_LIB.T6G(SCH_1):PVDDCR_CPU1_P1
   2    GND      B @T6G_MB_LIB.T6G(SCH_1):GND

Q_CAP_C0402-22UF,4V,20%,X6S,CH622KMEB02  I55  C2352
   1 PVDDCR_CPU1_P1      A @T6G_MB_LIB.T6G(SCH_1):PVDDCR_CPU1_P1
   2    GND      B @T6G_MB_LIB.T6G(SCH_1):GND

Q_CAP_C0402-22UF,4V,20%,X6S,CH622KMEB02  I56  C2351
   1 PVDDCR_CPU1_P1      A @T6G_MB_LIB.T6G(SCH_1):PVDDCR_CPU1_P1
   2    GND      B @T6G_MB_LIB.T6G(SCH_1):GND

Q_CAP_C0402-22UF,4V,20%,X6S,CH622KMEB02  I57  C2358
   1 PVDDCR_CPU1_P1      A @T6G_MB_LIB.T6G(SCH_1):PVDDCR_CPU1_P1
   2    GND      B @T6G_MB_LIB.T6G(SCH_1):GND

Q_CAP_C0402-22UF,4V,20%,X6S,CH622KMEB02  I58  C2357
   1 PVDDCR_CPU1_P1      A @T6G_MB_LIB.T6G(SCH_1):PVDDCR_CPU1_P1
   2    GND      B @T6G_MB_LIB.T6G(SCH_1):GND

Q_CAP_C0402-22UF,4V,20%,X6S,CH622KMEB02  I59  C2312
   1 PVDDCR_CPU0_P1      A @T6G_MB_LIB.T6G(SCH_1):PVDDCR_CPU0_P1
   2    GND      B @T6G_MB_LIB.T6G(SCH_1):GND

Q_CAP_C0402-22UF,4V,20%,X6S,CH622KMEB02  I60  C2318
   1 PVDDCR_CPU0_P1      A @T6G_MB_LIB.T6G(SCH_1):PVDDCR_CPU0_P1
   2    GND      B @T6G_MB_LIB.T6G(SCH_1):GND

Q_CAP_C0402-22UF,4V,20%,X6S,CH622KMEB02  I61  C2324
   1 PVDDCR_CPU0_P1      A @T6G_MB_LIB.T6G(SCH_1):PVDDCR_CPU0_P1
   2    GND      B @T6G_MB_LIB.T6G(SCH_1):GND

Q_CAP_C0402-22UF,4V,20%,X6S,CH622KMEB02  I62  C2330
   1 PVDDCR_CPU0_P1      A @T6G_MB_LIB.T6G(SCH_1):PVDDCR_CPU0_P1
   2    GND      B @T6G_MB_LIB.T6G(SCH_1):GND

Q_CAP_C0402-22UF,4V,20%,X6S,CH622KMEB02  I63  C2335
   1 PVDDCR_CPU0_P1      A @T6G_MB_LIB.T6G(SCH_1):PVDDCR_CPU0_P1
   2    GND      B @T6G_MB_LIB.T6G(SCH_1):GND

Q_CAP_C0402-22UF,4V,20%,X6S,CH622KMEB02  I64  C2340
   1 PVDDCR_CPU0_P1      A @T6G_MB_LIB.T6G(SCH_1):PVDDCR_CPU0_P1
   2    GND      B @T6G_MB_LIB.T6G(SCH_1):GND

Q_CAP_C0402-22UF,4V,20%,X6S,CH622KMEB02  I66  C2345
   1 PVDDCR_CPU0_P1      A @T6G_MB_LIB.T6G(SCH_1):PVDDCR_CPU0_P1
   2    GND      B @T6G_MB_LIB.T6G(SCH_1):GND

Q_CAP_C0402-22UF,4V,20%,X6S,CH622KMEB02  I68  C2356
   1 PVDDCR_CPU1_P1      A @T6G_MB_LIB.T6G(SCH_1):PVDDCR_CPU1_P1
   2    GND      B @T6G_MB_LIB.T6G(SCH_1):GND

Q_CAP_C0402-22UF,4V,20%,X6S,CH622KMEB02  I70  C2366
   1 PVDDCR_CPU1_P1      A @T6G_MB_LIB.T6G(SCH_1):PVDDCR_CPU1_P1
   2    GND      B @T6G_MB_LIB.T6G(SCH_1):GND

Q_CAP_C0402-22UF,4V,20%,X6S,CH622KMEB02  I71  C2372
   1 PVDDCR_CPU1_P1      A @T6G_MB_LIB.T6G(SCH_1):PVDDCR_CPU1_P1
   2    GND      B @T6G_MB_LIB.T6G(SCH_1):GND

Q_CAP_C0402-22UF,4V,20%,X6S,CH622KMEB02  I72  C2378
   1 PVDDCR_CPU1_P1      A @T6G_MB_LIB.T6G(SCH_1):PVDDCR_CPU1_P1
   2    GND      B @T6G_MB_LIB.T6G(SCH_1):GND

Q_CAP_C0402-22UF,4V,20%,X6S,CH622KMEB02  I74  C2365
   1 PVDDCR_CPU1_P1      A @T6G_MB_LIB.T6G(SCH_1):PVDDCR_CPU1_P1
   2    GND      B @T6G_MB_LIB.T6G(SCH_1):GND

Q_CAP_C0402-22UF,4V,20%,X6S,CH622KMEB02  I75  C2371
   1 PVDDCR_CPU1_P1      A @T6G_MB_LIB.T6G(SCH_1):PVDDCR_CPU1_P1
   2    GND      B @T6G_MB_LIB.T6G(SCH_1):GND

Q_CAP_C0402-22UF,4V,20%,X6S,CH622KMEB02  I76  C2364
   1 PVDDCR_CPU1_P1      A @T6G_MB_LIB.T6G(SCH_1):PVDDCR_CPU1_P1
   2    GND      B @T6G_MB_LIB.T6G(SCH_1):GND

Q_CAP_C0402-22UF,4V,20%,X6S,CH622KMEB02  I77  C2363
   1 PVDDCR_CPU1_P1      A @T6G_MB_LIB.T6G(SCH_1):PVDDCR_CPU1_P1
   2    GND      B @T6G_MB_LIB.T6G(SCH_1):GND

Q_CAP_C0402-22UF,4V,20%,X6S,CH622KMEB02  I78  C2370
   1 PVDDCR_CPU1_P1      A @T6G_MB_LIB.T6G(SCH_1):PVDDCR_CPU1_P1
   2    GND      B @T6G_MB_LIB.T6G(SCH_1):GND

Q_CAP_C0402-22UF,4V,20%,X6S,CH622KMEB02  I79  C2369
   1 PVDDCR_CPU1_P1      A @T6G_MB_LIB.T6G(SCH_1):PVDDCR_CPU1_P1
   2    GND      B @T6G_MB_LIB.T6G(SCH_1):GND

Q_CAP_C0402-22UF,4V,20%,X6S,CH622KMEB02  I80  C2376
   1 PVDDCR_CPU1_P1      A @T6G_MB_LIB.T6G(SCH_1):PVDDCR_CPU1_P1
   2    GND      B @T6G_MB_LIB.T6G(SCH_1):GND

Q_CAP_C0402-22UF,4V,20%,X6S,CH622KMEB02  I81  C2377
   1 PVDDCR_CPU1_P1      A @T6G_MB_LIB.T6G(SCH_1):PVDDCR_CPU1_P1
   2    GND      B @T6G_MB_LIB.T6G(SCH_1):GND

Q_CAP_C0402-22UF,4V,20%,X6S,CH622KMEB02  I82  C2383
   1 PVDDCR_CPU1_P1      A @T6G_MB_LIB.T6G(SCH_1):PVDDCR_CPU1_P1
   2    GND      B @T6G_MB_LIB.T6G(SCH_1):GND

Q_CAP_C0402-22UF,4V,20%,X6S,CH622KMEB02  I83  C2389
   1 PVDDCR_CPU1_P1      A @T6G_MB_LIB.T6G(SCH_1):PVDDCR_CPU1_P1
   2    GND      B @T6G_MB_LIB.T6G(SCH_1):GND

Q_CAP_C0402-22UF,4V,20%,X6S,CH622KMEB02  I84  C2382
   1 PVDDCR_CPU1_P1      A @T6G_MB_LIB.T6G(SCH_1):PVDDCR_CPU1_P1
   2    GND      B @T6G_MB_LIB.T6G(SCH_1):GND

Q_CAP_C0402-22UF,4V,20%,X6S,CH622KMEB02  I85  C2375
   1 PVDDCR_CPU1_P1      A @T6G_MB_LIB.T6G(SCH_1):PVDDCR_CPU1_P1
   2    GND      B @T6G_MB_LIB.T6G(SCH_1):GND

Q_CAP_C0402-22UF,4V,20%,X6S,CH622KMEB02  I86  C2381
   1 PVDDCR_CPU1_P1      A @T6G_MB_LIB.T6G(SCH_1):PVDDCR_CPU1_P1
   2    GND      B @T6G_MB_LIB.T6G(SCH_1):GND

Q_CAP_C0402-22UF,4V,20%,X6S,CH622KMEB02  I87  C2388
   1 PVDDCR_CPU1_P1      A @T6G_MB_LIB.T6G(SCH_1):PVDDCR_CPU1_P1
   2    GND      B @T6G_MB_LIB.T6G(SCH_1):GND

Q_CAP_C0402-22UF,4V,20%,X6S,CH622KMEB02  I88  C2387
   1 PVDDCR_CPU1_P1      A @T6G_MB_LIB.T6G(SCH_1):PVDDCR_CPU1_P1
   2    GND      B @T6G_MB_LIB.T6G(SCH_1):GND

Q_CAP_C0402-22UF,4V,20%,X6S,CH622KMEB02  I89  C2395
   1 PVDDCR_CPU1_P1      A @T6G_MB_LIB.T6G(SCH_1):PVDDCR_CPU1_P1
   2    GND      B @T6G_MB_LIB.T6G(SCH_1):GND

Q_CAP_C0402-22UF,4V,20%,X6S,CH622KMEB02  I90  C2400
   1 PVDDCR_CPU1_P1      A @T6G_MB_LIB.T6G(SCH_1):PVDDCR_CPU1_P1
   2    GND      B @T6G_MB_LIB.T6G(SCH_1):GND

Q_CAP_C0402-22UF,4V,20%,X6S,CH622KMEB02  I91  C2394
   1 PVDDCR_CPU1_P1      A @T6G_MB_LIB.T6G(SCH_1):PVDDCR_CPU1_P1
   2    GND      B @T6G_MB_LIB.T6G(SCH_1):GND

Q_CAP_C0402-22UF,4V,20%,X6S,CH622KMEB02  I92  C2393
   1 PVDDCR_CPU1_P1      A @T6G_MB_LIB.T6G(SCH_1):PVDDCR_CPU1_P1
   2    GND      B @T6G_MB_LIB.T6G(SCH_1):GND

Q_CAP_C0402-22UF,4V,20%,X6S,CH622KMEB02  I93  C2399
   1 PVDDCR_CPU1_P1      A @T6G_MB_LIB.T6G(SCH_1):PVDDCR_CPU1_P1
   2    GND      B @T6G_MB_LIB.T6G(SCH_1):GND

Q_CAP_C0402-22UF,4V,20%,X6S,CH622KMEB02  I94  C2398
   1 PVDDCR_CPU1_P1      A @T6G_MB_LIB.T6G(SCH_1):PVDDCR_CPU1_P1
   2    GND      B @T6G_MB_LIB.T6G(SCH_1):GND

Q_CAP_C0402-22UF,4V,20%,X6S,CH622KMEB02  I96  C2405
   1 PVDDCR_CPU1_P1      A @T6G_MB_LIB.T6G(SCH_1):PVDDCR_CPU1_P1
   2    GND      B @T6G_MB_LIB.T6G(SCH_1):GND

Q_CAP_C0402-22UF,4V,20%,X6S,CH622KMEB02  I98  C2404
   1 PVDDCR_CPU1_P1      A @T6G_MB_LIB.T6G(SCH_1):PVDDCR_CPU1_P1
   2    GND      B @T6G_MB_LIB.T6G(SCH_1):GND

Q_CAP_C0402-22UF,4V,20%,X6S,CH622KMEB02  I100  C2403
   1 PVDDCR_CPU1_P1      A @T6G_MB_LIB.T6G(SCH_1):PVDDCR_CPU1_P1
   2    GND      B @T6G_MB_LIB.T6G(SCH_1):GND

Q_CAP_C0402-22UF,4V,20%,X6S,CH622KMEB02  I101  C2362
   1 PVDDCR_CPU1_P1      A @T6G_MB_LIB.T6G(SCH_1):PVDDCR_CPU1_P1
   2    GND      B @T6G_MB_LIB.T6G(SCH_1):GND

Q_CAP_C0402-22UF,4V,20%,X6S,CH622KMEB02  I102  C2368
   1 PVDDCR_CPU1_P1      A @T6G_MB_LIB.T6G(SCH_1):PVDDCR_CPU1_P1
   2    GND      B @T6G_MB_LIB.T6G(SCH_1):GND

Q_CAP_C0402-22UF,4V,20%,X6S,CH622KMEB02  I103  C2374
   1 PVDDCR_CPU1_P1      A @T6G_MB_LIB.T6G(SCH_1):PVDDCR_CPU1_P1
   2    GND      B @T6G_MB_LIB.T6G(SCH_1):GND

Q_CAP_C0402-22UF,4V,20%,X6S,CH622KMEB02  I104  C2380
   1 PVDDCR_CPU1_P1      A @T6G_MB_LIB.T6G(SCH_1):PVDDCR_CPU1_P1
   2    GND      B @T6G_MB_LIB.T6G(SCH_1):GND

Q_CAP_C0402-22UF,4V,20%,X6S,CH622KMEB02  I105  C2386
   1 PVDDCR_CPU1_P1      A @T6G_MB_LIB.T6G(SCH_1):PVDDCR_CPU1_P1
   2    GND      B @T6G_MB_LIB.T6G(SCH_1):GND

Q_CAP_C0402-22UF,4V,20%,X6S,CH622KMEB02  I106  C2392
   1 PVDDCR_CPU1_P1      A @T6G_MB_LIB.T6G(SCH_1):PVDDCR_CPU1_P1
   2    GND      B @T6G_MB_LIB.T6G(SCH_1):GND

Q_CAP_C0402-22UF,4V,20%,X6S,CH622KMEB02  I107  C2397
   1 PVDDCR_CPU1_P1      A @T6G_MB_LIB.T6G(SCH_1):PVDDCR_CPU1_P1
   2    GND      B @T6G_MB_LIB.T6G(SCH_1):GND

Q_CAP_C0402-22UF,4V,20%,X6S,CH622KMEB02  I109  C2402
   1 PVDDCR_CPU1_P1      A @T6G_MB_LIB.T6G(SCH_1):PVDDCR_CPU1_P1
   2    GND      B @T6G_MB_LIB.T6G(SCH_1):GND

Q_CAP_C0402-22UF,4V,20%,X6S,CH622KMEB02  I110  C2350
   1 PVDDCR_CPU1_P1      A @T6G_MB_LIB.T6G(SCH_1):PVDDCR_CPU1_P1
   2    GND      B @T6G_MB_LIB.T6G(SCH_1):GND


DRAWING: @T6G_MB_LIB.T6G(SCH_1):PAGE73 

Q_CAP_C0402-22UF,4V,20%,X6S,CH622KMEB02  I1  C3912
   1 PVDDCR_SOC_P1      A @T6G_MB_LIB.T6G(SCH_1):PVDDCR_SOC_P1
   2    GND      B @T6G_MB_LIB.T6G(SCH_1):GND

Q_CAP_C0402-22UF,4V,20%,X6S,CH622KMEB02  I3  C2413
   1 PVDDCR_SOC_P1      A @T6G_MB_LIB.T6G(SCH_1):PVDDCR_SOC_P1
   2    GND      B @T6G_MB_LIB.T6G(SCH_1):GND

Q_CAP_C0402-22UF,4V,20%,X6S,CH622KMEB02  I4  C3913
   1 PVDDCR_SOC_P1      A @T6G_MB_LIB.T6G(SCH_1):PVDDCR_SOC_P1
   2    GND      B @T6G_MB_LIB.T6G(SCH_1):GND

Q_CAP_C0402-22UF,4V,20%,X6S,CH622KMEB02  I5  C2420
   1 PVDDCR_SOC_P1      A @T6G_MB_LIB.T6G(SCH_1):PVDDCR_SOC_P1
   2    GND      B @T6G_MB_LIB.T6G(SCH_1):GND

Q_CAP_C0402-22UF,4V,20%,X6S,CH622KMEB02  I6  C3914
   1 PVDDCR_SOC_P1      A @T6G_MB_LIB.T6G(SCH_1):PVDDCR_SOC_P1
   2    GND      B @T6G_MB_LIB.T6G(SCH_1):GND

Q_CAP_C0402-22UF,4V,20%,X6S,CH622KMEB02  I7  C2427
   1 PVDDCR_SOC_P1      A @T6G_MB_LIB.T6G(SCH_1):PVDDCR_SOC_P1
   2    GND      B @T6G_MB_LIB.T6G(SCH_1):GND

Q_CAP_C0402-22UF,4V,20%,X6S,CH622KMEB02  I8  C3915
   1 PVDDCR_SOC_P1      A @T6G_MB_LIB.T6G(SCH_1):PVDDCR_SOC_P1
   2    GND      B @T6G_MB_LIB.T6G(SCH_1):GND

Q_CAP_C0402-22UF,4V,20%,X6S,CH622KMEB02  I9  C2434
   1 PVDDCR_SOC_P1      A @T6G_MB_LIB.T6G(SCH_1):PVDDCR_SOC_P1
   2    GND      B @T6G_MB_LIB.T6G(SCH_1):GND

Q_CAP_C0402-22UF,4V,20%,X6S,CH622KMEB02  I11  C2412
   1 PVDDCR_SOC_P1      A @T6G_MB_LIB.T6G(SCH_1):PVDDCR_SOC_P1
   2    GND      B @T6G_MB_LIB.T6G(SCH_1):GND

Q_CAP_C0402-22UF,4V,20%,X6S,CH622KMEB02  I13  C2419
   1 PVDDCR_SOC_P1      A @T6G_MB_LIB.T6G(SCH_1):PVDDCR_SOC_P1
   2    GND      B @T6G_MB_LIB.T6G(SCH_1):GND

Q_CAP_C0402-22UF,4V,20%,X6S,CH622KMEB02  I14  C2411
   1 PVDDCR_SOC_P1      A @T6G_MB_LIB.T6G(SCH_1):PVDDCR_SOC_P1
   2    GND      B @T6G_MB_LIB.T6G(SCH_1):GND

Q_CAP_C0402-22UF,4V,20%,X6S,CH622KMEB02  I16  C2410
   1 PVDDCR_SOC_P1      A @T6G_MB_LIB.T6G(SCH_1):PVDDCR_SOC_P1
   2    GND      B @T6G_MB_LIB.T6G(SCH_1):GND

Q_CAP_C0402-22UF,4V,20%,X6S,CH622KMEB02  I17  C2418
   1 PVDDCR_SOC_P1      A @T6G_MB_LIB.T6G(SCH_1):PVDDCR_SOC_P1
   2    GND      B @T6G_MB_LIB.T6G(SCH_1):GND

Q_CAP_C0402-22UF,4V,20%,X6S,CH622KMEB02  I18  C2417
   1 PVDDCR_SOC_P1      A @T6G_MB_LIB.T6G(SCH_1):PVDDCR_SOC_P1
   2    GND      B @T6G_MB_LIB.T6G(SCH_1):GND

Q_CAP_C0402-22UF,4V,20%,X6S,CH622KMEB02  I19  C2426
   1 PVDDCR_SOC_P1      A @T6G_MB_LIB.T6G(SCH_1):PVDDCR_SOC_P1
   2    GND      B @T6G_MB_LIB.T6G(SCH_1):GND

Q_CAP_C0402-22UF,4V,20%,X6S,CH622KMEB02  I20  C2433
   1 PVDDCR_SOC_P1      A @T6G_MB_LIB.T6G(SCH_1):PVDDCR_SOC_P1
   2    GND      B @T6G_MB_LIB.T6G(SCH_1):GND

Q_CAP_C0402-22UF,4V,20%,X6S,CH622KMEB02  I21  C2425
   1 PVDDCR_SOC_P1      A @T6G_MB_LIB.T6G(SCH_1):PVDDCR_SOC_P1
   2    GND      B @T6G_MB_LIB.T6G(SCH_1):GND

Q_CAP_C0402-22UF,4V,20%,X6S,CH622KMEB02  I22  C2424
   1 PVDDCR_SOC_P1      A @T6G_MB_LIB.T6G(SCH_1):PVDDCR_SOC_P1
   2    GND      B @T6G_MB_LIB.T6G(SCH_1):GND

Q_CAP_C0402-22UF,4V,20%,X6S,CH622KMEB02  I23  C2432
   1 PVDDCR_SOC_P1      A @T6G_MB_LIB.T6G(SCH_1):PVDDCR_SOC_P1
   2    GND      B @T6G_MB_LIB.T6G(SCH_1):GND

Q_CAP_C0402-22UF,4V,20%,X6S,CH622KMEB02  I24  C2431
   1 PVDDCR_SOC_P1      A @T6G_MB_LIB.T6G(SCH_1):PVDDCR_SOC_P1
   2    GND      B @T6G_MB_LIB.T6G(SCH_1):GND

Q_CAP_C0402-22UF,4V,20%,X6S,CH622KMEB02  I25  C3916
   1 PVDDCR_SOC_P1      A @T6G_MB_LIB.T6G(SCH_1):PVDDCR_SOC_P1
   2    GND      B @T6G_MB_LIB.T6G(SCH_1):GND

Q_CAP_C0402-22UF,4V,20%,X6S,CH622KMEB02  I26  C2441
   1 PVDDCR_SOC_P1      A @T6G_MB_LIB.T6G(SCH_1):PVDDCR_SOC_P1
   2    GND      B @T6G_MB_LIB.T6G(SCH_1):GND

Q_CAP_C0402-22UF,4V,20%,X6S,CH622KMEB02  I27  C3917
   1 PVDDCR_SOC_P1      A @T6G_MB_LIB.T6G(SCH_1):PVDDCR_SOC_P1
   2    GND      B @T6G_MB_LIB.T6G(SCH_1):GND

Q_CAP_C0402-22UF,4V,20%,X6S,CH622KMEB02  I28  C2448
   1 PVDDCR_SOC_P1      A @T6G_MB_LIB.T6G(SCH_1):PVDDCR_SOC_P1
   2    GND      B @T6G_MB_LIB.T6G(SCH_1):GND

Q_CAP_C0402-22UF,4V,20%,X6S,CH622KMEB02  I29  C2455
   1 PVDDCR_SOC_P1      A @T6G_MB_LIB.T6G(SCH_1):PVDDCR_SOC_P1
   2    GND      B @T6G_MB_LIB.T6G(SCH_1):GND

Q_CAP_C0402-22UF,4V,20%,X6S,CH622KMEB02  I30  C3918
   1 PVDDCR_SOC_P1      A @T6G_MB_LIB.T6G(SCH_1):PVDDCR_SOC_P1
   2    GND      B @T6G_MB_LIB.T6G(SCH_1):GND

Q_CAP_C0402-22UF,4V,20%,X6S,CH622KMEB02  I32  C2462
   1 PVDDCR_SOC_P1      A @T6G_MB_LIB.T6G(SCH_1):PVDDCR_SOC_P1
   2    GND      B @T6G_MB_LIB.T6G(SCH_1):GND

Q_CAP_C0402-22UF,4V,20%,X6S,CH622KMEB02  I33  C2469
   1 PVDDCR_SOC_P1      A @T6G_MB_LIB.T6G(SCH_1):PVDDCR_SOC_P1
   2    GND      B @T6G_MB_LIB.T6G(SCH_1):GND

Q_CAP_C0402-22UF,4V,20%,X6S,CH622KMEB02  I34  C2440
   1 PVDDCR_SOC_P1      A @T6G_MB_LIB.T6G(SCH_1):PVDDCR_SOC_P1
   2    GND      B @T6G_MB_LIB.T6G(SCH_1):GND

Q_CAP_C0402-22UF,4V,20%,X6S,CH622KMEB02  I35  C2447
   1 PVDDCR_SOC_P1      A @T6G_MB_LIB.T6G(SCH_1):PVDDCR_SOC_P1
   2    GND      B @T6G_MB_LIB.T6G(SCH_1):GND

Q_CAP_C0402-22UF,4V,20%,X6S,CH622KMEB02  I36  C2439
   1 PVDDCR_SOC_P1      A @T6G_MB_LIB.T6G(SCH_1):PVDDCR_SOC_P1
   2    GND      B @T6G_MB_LIB.T6G(SCH_1):GND

Q_CAP_C0402-22UF,4V,20%,X6S,CH622KMEB02  I37  C2438
   1 PVDDCR_SOC_P1      A @T6G_MB_LIB.T6G(SCH_1):PVDDCR_SOC_P1
   2    GND      B @T6G_MB_LIB.T6G(SCH_1):GND

Q_CAP_C0402-22UF,4V,20%,X6S,CH622KMEB02  I38  C2446
   1 PVDDCR_SOC_P1      A @T6G_MB_LIB.T6G(SCH_1):PVDDCR_SOC_P1
   2    GND      B @T6G_MB_LIB.T6G(SCH_1):GND

Q_CAP_C0402-22UF,4V,20%,X6S,CH622KMEB02  I39  C2445
   1 PVDDCR_SOC_P1      A @T6G_MB_LIB.T6G(SCH_1):PVDDCR_SOC_P1
   2    GND      B @T6G_MB_LIB.T6G(SCH_1):GND

Q_CAP_C0402-22UF,4V,20%,X6S,CH622KMEB02  I40  C2452
   1 PVDDCR_SOC_P1      A @T6G_MB_LIB.T6G(SCH_1):PVDDCR_SOC_P1
   2    GND      B @T6G_MB_LIB.T6G(SCH_1):GND

Q_CAP_C0402-22UF,4V,20%,X6S,CH622KMEB02  I41  C2453
   1 PVDDCR_SOC_P1      A @T6G_MB_LIB.T6G(SCH_1):PVDDCR_SOC_P1
   2    GND      B @T6G_MB_LIB.T6G(SCH_1):GND

Q_CAP_C0402-22UF,4V,20%,X6S,CH622KMEB02  I42  C2454
   1 PVDDCR_SOC_P1      A @T6G_MB_LIB.T6G(SCH_1):PVDDCR_SOC_P1
   2    GND      B @T6G_MB_LIB.T6G(SCH_1):GND

Q_CAP_C0402-22UF,4V,20%,X6S,CH622KMEB02  I43  C2461
   1 PVDDCR_SOC_P1      A @T6G_MB_LIB.T6G(SCH_1):PVDDCR_SOC_P1
   2    GND      B @T6G_MB_LIB.T6G(SCH_1):GND

Q_CAP_C0402-22UF,4V,20%,X6S,CH622KMEB02  I44  C2468
   1 PVDDCR_SOC_P1      A @T6G_MB_LIB.T6G(SCH_1):PVDDCR_SOC_P1
   2    GND      B @T6G_MB_LIB.T6G(SCH_1):GND

Q_CAP_C0402-22UF,4V,20%,X6S,CH622KMEB02  I45  C2460
   1 PVDDCR_SOC_P1      A @T6G_MB_LIB.T6G(SCH_1):PVDDCR_SOC_P1
   2    GND      B @T6G_MB_LIB.T6G(SCH_1):GND

Q_CAP_C0402-22UF,4V,20%,X6S,CH622KMEB02  I46  C2459
   1 PVDDCR_SOC_P1      A @T6G_MB_LIB.T6G(SCH_1):PVDDCR_SOC_P1
   2    GND      B @T6G_MB_LIB.T6G(SCH_1):GND

Q_CAP_C0402-22UF,4V,20%,X6S,CH622KMEB02  I47  C2467
   1 PVDDCR_SOC_P1      A @T6G_MB_LIB.T6G(SCH_1):PVDDCR_SOC_P1
   2    GND      B @T6G_MB_LIB.T6G(SCH_1):GND

Q_CAP_C0402-22UF,4V,20%,X6S,CH622KMEB02  I48  C2466
   1 PVDDCR_SOC_P1      A @T6G_MB_LIB.T6G(SCH_1):PVDDCR_SOC_P1
   2    GND      B @T6G_MB_LIB.T6G(SCH_1):GND

Q_CAP_C0402-22UF,4V,20%,X6S,CH622KMEB02  I50  C2409
   1 PVDDCR_SOC_P1      A @T6G_MB_LIB.T6G(SCH_1):PVDDCR_SOC_P1
   2    GND      B @T6G_MB_LIB.T6G(SCH_1):GND

Q_CAP_C0402-22UF,4V,20%,X6S,CH622KMEB02  I52  C2416
   1 PVDDCR_SOC_P1      A @T6G_MB_LIB.T6G(SCH_1):PVDDCR_SOC_P1
   2    GND      B @T6G_MB_LIB.T6G(SCH_1):GND

Q_CAP_C0402-22UF,4V,20%,X6S,CH622KMEB02  I53  C2408
   1 PVDDCR_SOC_P1      A @T6G_MB_LIB.T6G(SCH_1):PVDDCR_SOC_P1
   2    GND      B @T6G_MB_LIB.T6G(SCH_1):GND

Q_CAP_C0402-22UF,4V,20%,X6S,CH622KMEB02  I55  C2407
   1 PVDDCR_SOC_P1      A @T6G_MB_LIB.T6G(SCH_1):PVDDCR_SOC_P1
   2    GND      B @T6G_MB_LIB.T6G(SCH_1):GND

Q_CAP_C0402-22UF,4V,20%,X6S,CH622KMEB02  I56  C2415
   1 PVDDCR_SOC_P1      A @T6G_MB_LIB.T6G(SCH_1):PVDDCR_SOC_P1
   2    GND      B @T6G_MB_LIB.T6G(SCH_1):GND

Q_CAP_C0402-22UF,4V,20%,X6S,CH622KMEB02  I57  C2414
   1 PVDDCR_SOC_P1      A @T6G_MB_LIB.T6G(SCH_1):PVDDCR_SOC_P1
   2    GND      B @T6G_MB_LIB.T6G(SCH_1):GND

Q_CAP_C0402-22UF,4V,20%,X6S,CH622KMEB02  I58  C2423
   1 PVDDCR_SOC_P1      A @T6G_MB_LIB.T6G(SCH_1):PVDDCR_SOC_P1
   2    GND      B @T6G_MB_LIB.T6G(SCH_1):GND

Q_CAP_C0402-22UF,4V,20%,X6S,CH622KMEB02  I59  C2430
   1 PVDDCR_SOC_P1      A @T6G_MB_LIB.T6G(SCH_1):PVDDCR_SOC_P1
   2    GND      B @T6G_MB_LIB.T6G(SCH_1):GND

Q_CAP_C0402-22UF,4V,20%,X6S,CH622KMEB02  I60  C2422
   1 PVDDCR_SOC_P1      A @T6G_MB_LIB.T6G(SCH_1):PVDDCR_SOC_P1
   2    GND      B @T6G_MB_LIB.T6G(SCH_1):GND

Q_CAP_C0402-22UF,4V,20%,X6S,CH622KMEB02  I61  C2421
   1 PVDDCR_SOC_P1      A @T6G_MB_LIB.T6G(SCH_1):PVDDCR_SOC_P1
   2    GND      B @T6G_MB_LIB.T6G(SCH_1):GND

Q_CAP_C0402-22UF,4V,20%,X6S,CH622KMEB02  I62  C2429
   1 PVDDCR_SOC_P1      A @T6G_MB_LIB.T6G(SCH_1):PVDDCR_SOC_P1
   2    GND      B @T6G_MB_LIB.T6G(SCH_1):GND

Q_CAP_C0402-22UF,4V,20%,X6S,CH622KMEB02  I64  C2437
   1 PVDDCR_SOC_P1      A @T6G_MB_LIB.T6G(SCH_1):PVDDCR_SOC_P1
   2    GND      B @T6G_MB_LIB.T6G(SCH_1):GND

Q_CAP_C0402-22UF,4V,20%,X6S,CH622KMEB02  I65  C2444
   1 PVDDCR_SOC_P1      A @T6G_MB_LIB.T6G(SCH_1):PVDDCR_SOC_P1
   2    GND      B @T6G_MB_LIB.T6G(SCH_1):GND

Q_CAP_C0402-22UF,4V,20%,X6S,CH622KMEB02  I66  C2436
   1 PVDDCR_SOC_P1      A @T6G_MB_LIB.T6G(SCH_1):PVDDCR_SOC_P1
   2    GND      B @T6G_MB_LIB.T6G(SCH_1):GND

Q_CAP_C0402-22UF,4V,20%,X6S,CH622KMEB02  I67  C2443
   1 PVDDCR_SOC_P1      A @T6G_MB_LIB.T6G(SCH_1):PVDDCR_SOC_P1
   2    GND      B @T6G_MB_LIB.T6G(SCH_1):GND

Q_CAP_C0402-22UF,4V,20%,X6S,CH622KMEB02  I68  C2449
   1 PVDDCR_SOC_P1      A @T6G_MB_LIB.T6G(SCH_1):PVDDCR_SOC_P1
   2    GND      B @T6G_MB_LIB.T6G(SCH_1):GND

Q_CAP_C0402-22UF,4V,20%,X6S,CH622KMEB02  I69  C2450
   1 PVDDCR_SOC_P1      A @T6G_MB_LIB.T6G(SCH_1):PVDDCR_SOC_P1
   2    GND      B @T6G_MB_LIB.T6G(SCH_1):GND

Q_CAP_C0402-22UF,4V,20%,X6S,CH622KMEB02  I70  C2451
   1 PVDDCR_SOC_P1      A @T6G_MB_LIB.T6G(SCH_1):PVDDCR_SOC_P1
   2    GND      B @T6G_MB_LIB.T6G(SCH_1):GND

Q_CAP_C0402-22UF,4V,20%,X6S,CH622KMEB02  I71  C2458
   1 PVDDCR_SOC_P1      A @T6G_MB_LIB.T6G(SCH_1):PVDDCR_SOC_P1
   2    GND      B @T6G_MB_LIB.T6G(SCH_1):GND

Q_CAP_C0402-22UF,4V,20%,X6S,CH622KMEB02  I72  C2465
   1 PVDDCR_SOC_P1      A @T6G_MB_LIB.T6G(SCH_1):PVDDCR_SOC_P1
   2    GND      B @T6G_MB_LIB.T6G(SCH_1):GND

Q_CAP_C0402-22UF,4V,20%,X6S,CH622KMEB02  I73  C2457
   1 PVDDCR_SOC_P1      A @T6G_MB_LIB.T6G(SCH_1):PVDDCR_SOC_P1
   2    GND      B @T6G_MB_LIB.T6G(SCH_1):GND

Q_CAP_C0402-22UF,4V,20%,X6S,CH622KMEB02  I74  C2456
   1 PVDDCR_SOC_P1      A @T6G_MB_LIB.T6G(SCH_1):PVDDCR_SOC_P1
   2    GND      B @T6G_MB_LIB.T6G(SCH_1):GND

Q_CAP_C0402-22UF,4V,20%,X6S,CH622KMEB02  I75  C2464
   1 PVDDCR_SOC_P1      A @T6G_MB_LIB.T6G(SCH_1):PVDDCR_SOC_P1
   2    GND      B @T6G_MB_LIB.T6G(SCH_1):GND

Q_CAP_C0402-22UF,4V,20%,X6S,CH622KMEB02  I76  C2463
   1 PVDDCR_SOC_P1      A @T6G_MB_LIB.T6G(SCH_1):PVDDCR_SOC_P1
   2    GND      B @T6G_MB_LIB.T6G(SCH_1):GND

Q_CAP_C0402-22UF,4V,20%,X6S,CH622KMEB02  I77  C3919
   1 PVDD11_S3_P1      A @T6G_MB_LIB.T6G(SCH_1):PVDD11_S3_P1
   2    GND      B @T6G_MB_LIB.T6G(SCH_1):GND

Q_CAP_C0402-22UF,4V,20%,X6S,CH622KMEB02  I79  C2476
   1 PVDDCR_SOC_P1      A @T6G_MB_LIB.T6G(SCH_1):PVDDCR_SOC_P1
   2    GND      B @T6G_MB_LIB.T6G(SCH_1):GND

Q_CAP_C0402-22UF,4V,20%,X6S,CH622KMEB02  I81  C2483
   1 PVDD11_S3_P1      A @T6G_MB_LIB.T6G(SCH_1):PVDD11_S3_P1
   2    GND      B @T6G_MB_LIB.T6G(SCH_1):GND

Q_CAP_C0402-22UF,4V,20%,X6S,CH622KMEB02  I84  C3920
   1 PVDD11_S3_P1      A @T6G_MB_LIB.T6G(SCH_1):PVDD11_S3_P1
   2    GND      B @T6G_MB_LIB.T6G(SCH_1):GND

Q_CAP_C0402-22UF,4V,20%,X6S,CH622KMEB02  I85  C2488
   1 PVDD11_S3_P1      A @T6G_MB_LIB.T6G(SCH_1):PVDD11_S3_P1
   2    GND      B @T6G_MB_LIB.T6G(SCH_1):GND

Q_CAP_C0402-22UF,4V,20%,X6S,CH622KMEB02  I86  C2492
   1 PVDD11_S3_P1      A @T6G_MB_LIB.T6G(SCH_1):PVDD11_S3_P1
   2    GND      B @T6G_MB_LIB.T6G(SCH_1):GND

Q_CAP_C0402-22UF,4V,20%,X6S,CH622KMEB02  I88  C2475
   1 PVDDCR_SOC_P1      A @T6G_MB_LIB.T6G(SCH_1):PVDDCR_SOC_P1
   2    GND      B @T6G_MB_LIB.T6G(SCH_1):GND

Q_CAP_C0402-22UF,4V,20%,X6S,CH622KMEB02  I90  C2482
   1 PVDD11_S3_P1      A @T6G_MB_LIB.T6G(SCH_1):PVDD11_S3_P1
   2    GND      B @T6G_MB_LIB.T6G(SCH_1):GND

Q_CAP_C0402-22UF,4V,20%,X6S,CH622KMEB02  I92  C2481
   1 PVDD11_S3_P1      A @T6G_MB_LIB.T6G(SCH_1):PVDD11_S3_P1
   2    GND      B @T6G_MB_LIB.T6G(SCH_1):GND

Q_CAP_C0402-22UF,4V,20%,X6S,CH622KMEB02  I94  C2474
   1 PVDDCR_SOC_P1      A @T6G_MB_LIB.T6G(SCH_1):PVDDCR_SOC_P1
   2    GND      B @T6G_MB_LIB.T6G(SCH_1):GND

Q_CAP_C0402-22UF,4V,20%,X6S,CH622KMEB02  I96  C2473
   1 PVDDCR_SOC_P1      A @T6G_MB_LIB.T6G(SCH_1):PVDDCR_SOC_P1
   2    GND      B @T6G_MB_LIB.T6G(SCH_1):GND

Q_CAP_C0402-22UF,4V,20%,X6S,CH622KMEB02  I97  C2480
   1 PVDD11_S3_P1      A @T6G_MB_LIB.T6G(SCH_1):PVDD11_S3_P1
   2    GND      B @T6G_MB_LIB.T6G(SCH_1):GND

Q_CAP_C0402-22UF,4V,20%,X6S,CH622KMEB02  I99  C2487
   1 PVDD11_S3_P1      A @T6G_MB_LIB.T6G(SCH_1):PVDD11_S3_P1
   2    GND      B @T6G_MB_LIB.T6G(SCH_1):GND

Q_CAP_C0402-22UF,4V,20%,X6S,CH622KMEB02  I100  C2486
   1 PVDD11_S3_P1      A @T6G_MB_LIB.T6G(SCH_1):PVDD11_S3_P1
   2    GND      B @T6G_MB_LIB.T6G(SCH_1):GND

Q_CAP_C0402-22UF,4V,20%,X6S,CH622KMEB02  I101  C2491
   1 PVDD11_S3_P1      A @T6G_MB_LIB.T6G(SCH_1):PVDD11_S3_P1
   2    GND      B @T6G_MB_LIB.T6G(SCH_1):GND

Q_CAP_C0402-22UF,4V,20%,X6S,CH622KMEB02  I102  C2490
   1 PVDD11_S3_P1      A @T6G_MB_LIB.T6G(SCH_1):PVDD11_S3_P1
   2    GND      B @T6G_MB_LIB.T6G(SCH_1):GND

Q_CAP_C0402-22UF,4V,20%,X6S,CH622KMEB02  I103  C2485
   1 PVDD11_S3_P1      A @T6G_MB_LIB.T6G(SCH_1):PVDD11_S3_P1
   2    GND      B @T6G_MB_LIB.T6G(SCH_1):GND

Q_CAP_C0402-22UF,4V,20%,X6S,CH622KMEB02  I104  C2489
   1 PVDD11_S3_P1      A @T6G_MB_LIB.T6G(SCH_1):PVDD11_S3_P1
   2    GND      B @T6G_MB_LIB.T6G(SCH_1):GND

Q_CAP_C0402-22UF,4V,20%,X6S,CH622KMEB02  I105  C2497
   1 PVDD11_S3_P1      A @T6G_MB_LIB.T6G(SCH_1):PVDD11_S3_P1
   2    GND      B @T6G_MB_LIB.T6G(SCH_1):GND

Q_CAP_C0402-22UF,4V,20%,X6S,CH622KMEB02  I106  C2502
   1 PVDD11_S3_P1      A @T6G_MB_LIB.T6G(SCH_1):PVDD11_S3_P1
   2    GND      B @T6G_MB_LIB.T6G(SCH_1):GND

Q_CAP_C0402-22UF,4V,20%,X6S,CH622KMEB02  I107  C2506
   1 PVDD11_S3_P1      A @T6G_MB_LIB.T6G(SCH_1):PVDD11_S3_P1
   2    GND      B @T6G_MB_LIB.T6G(SCH_1):GND

Q_CAP_C0402-22UF,4V,20%,X6S,CH622KMEB02  I108  C2115
   1 PVDD11_S3_P1      A @T6G_MB_LIB.T6G(SCH_1):PVDD11_S3_P1
   2    GND      B @T6G_MB_LIB.T6G(SCH_1):GND

Q_CAP_C0402-22UF,4V,20%,X6S,CH622KMEB02  I109  C2121
   1 PVDD11_S3_P1      A @T6G_MB_LIB.T6G(SCH_1):PVDD11_S3_P1
   2    GND      B @T6G_MB_LIB.T6G(SCH_1):GND

Q_CAP_C0402-22UF,4V,20%,X6S,CH622KMEB02  I110  C2496
   1 PVDD11_S3_P1      A @T6G_MB_LIB.T6G(SCH_1):PVDD11_S3_P1
   2    GND      B @T6G_MB_LIB.T6G(SCH_1):GND

Q_CAP_C0402-22UF,4V,20%,X6S,CH622KMEB02  I111  C2495
   1 PVDD11_S3_P1      A @T6G_MB_LIB.T6G(SCH_1):PVDD11_S3_P1
   2    GND      B @T6G_MB_LIB.T6G(SCH_1):GND

Q_CAP_C0402-22UF,4V,20%,X6S,CH622KMEB02  I112  C2501
   1 PVDD11_S3_P1      A @T6G_MB_LIB.T6G(SCH_1):PVDD11_S3_P1
   2    GND      B @T6G_MB_LIB.T6G(SCH_1):GND

Q_CAP_C0402-22UF,4V,20%,X6S,CH622KMEB02  I113  C2500
   1 PVDD11_S3_P1      A @T6G_MB_LIB.T6G(SCH_1):PVDD11_S3_P1
   2    GND      B @T6G_MB_LIB.T6G(SCH_1):GND

Q_CAP_C0402-22UF,4V,20%,X6S,CH622KMEB02  I114  C2494
   1 PVDD11_S3_P1      A @T6G_MB_LIB.T6G(SCH_1):PVDD11_S3_P1
   2    GND      B @T6G_MB_LIB.T6G(SCH_1):GND

Q_CAP_C0402-22UF,4V,20%,X6S,CH622KMEB02  I116  C2499
   1 PVDD11_S3_P1      A @T6G_MB_LIB.T6G(SCH_1):PVDD11_S3_P1
   2    GND      B @T6G_MB_LIB.T6G(SCH_1):GND

Q_CAP_C0402-22UF,4V,20%,X6S,CH622KMEB02  I117  C2505
   1 PVDD11_S3_P1      A @T6G_MB_LIB.T6G(SCH_1):PVDD11_S3_P1
   2    GND      B @T6G_MB_LIB.T6G(SCH_1):GND

Q_CAP_C0402-22UF,4V,20%,X6S,CH622KMEB02  I118  C2504
   1 PVDD11_S3_P1      A @T6G_MB_LIB.T6G(SCH_1):PVDD11_S3_P1
   2    GND      B @T6G_MB_LIB.T6G(SCH_1):GND

Q_CAP_C0402-22UF,4V,20%,X6S,CH622KMEB02  I119  C2113
   1 PVDD11_S3_P1      A @T6G_MB_LIB.T6G(SCH_1):PVDD11_S3_P1
   2    GND      B @T6G_MB_LIB.T6G(SCH_1):GND

Q_CAP_C0402-22UF,4V,20%,X6S,CH622KMEB02  I120  C2114
   1 PVDD11_S3_P1      A @T6G_MB_LIB.T6G(SCH_1):PVDD11_S3_P1
   2    GND      B @T6G_MB_LIB.T6G(SCH_1):GND

Q_CAP_C0402-22UF,4V,20%,X6S,CH622KMEB02  I121  C2120
   1 PVDD11_S3_P1      A @T6G_MB_LIB.T6G(SCH_1):PVDD11_S3_P1
   2    GND      B @T6G_MB_LIB.T6G(SCH_1):GND

Q_CAP_C0402-22UF,4V,20%,X6S,CH622KMEB02  I122  C2119
   1 PVDD11_S3_P1      A @T6G_MB_LIB.T6G(SCH_1):PVDD11_S3_P1
   2    GND      B @T6G_MB_LIB.T6G(SCH_1):GND

Q_CAP_C0402-22UF,4V,20%,X6S,CH622KMEB02  I123  C2503
   1 PVDD11_S3_P1      A @T6G_MB_LIB.T6G(SCH_1):PVDD11_S3_P1
   2    GND      B @T6G_MB_LIB.T6G(SCH_1):GND

Q_CAP_C0402-22UF,4V,20%,X6S,CH622KMEB02  I124  C2508
   1 PVDD11_S3_P1      A @T6G_MB_LIB.T6G(SCH_1):PVDD11_S3_P1
   2    GND      B @T6G_MB_LIB.T6G(SCH_1):GND

Q_CAP_C0402-22UF,4V,20%,X6S,CH622KMEB02  I125  C2118
   1 PVDD11_S3_P1      A @T6G_MB_LIB.T6G(SCH_1):PVDD11_S3_P1
   2    GND      B @T6G_MB_LIB.T6G(SCH_1):GND

Q_CAP_C0402-22UF,4V,20%,X6S,CH622KMEB02  I127  C2472
   1 PVDDCR_SOC_P1      A @T6G_MB_LIB.T6G(SCH_1):PVDDCR_SOC_P1
   2    GND      B @T6G_MB_LIB.T6G(SCH_1):GND

Q_CAP_C0402-22UF,4V,20%,X6S,CH622KMEB02  I129  C2479
   1 PVDDIO_P1      A @T6G_MB_LIB.T6G(SCH_1):PVDDIO_P1
   2    GND      B @T6G_MB_LIB.T6G(SCH_1):GND

Q_CAP_C0402-22UF,4V,20%,X6S,CH622KMEB02  I131  C2471
   1 PVDDCR_SOC_P1      A @T6G_MB_LIB.T6G(SCH_1):PVDDCR_SOC_P1
   2    GND      B @T6G_MB_LIB.T6G(SCH_1):GND

Q_CAP_C0402-22UF,4V,20%,X6S,CH622KMEB02  I133  C2470
   1 PVDDCR_SOC_P1      A @T6G_MB_LIB.T6G(SCH_1):PVDDCR_SOC_P1
   2    GND      B @T6G_MB_LIB.T6G(SCH_1):GND

Q_CAP_C0402-22UF,4V,20%,X6S,CH622KMEB02  I134  C2478
   1 PVDDIO_P1      A @T6G_MB_LIB.T6G(SCH_1):PVDDIO_P1
   2    GND      B @T6G_MB_LIB.T6G(SCH_1):GND

Q_CAP_C0402-22UF,4V,20%,X6S,CH622KMEB02  I136  C2477
   1 PVDDIO_P1      A @T6G_MB_LIB.T6G(SCH_1):PVDDIO_P1
   2    GND      B @T6G_MB_LIB.T6G(SCH_1):GND

Q_CAP_C0402-22UF,4V,20%,X6S,CH622KMEB02  I137  C2103
   1 PVDDIO_P1      A @T6G_MB_LIB.T6G(SCH_1):PVDDIO_P1
   2    GND      B @T6G_MB_LIB.T6G(SCH_1):GND

Q_CAP_C0402-22UF,4V,20%,X6S,CH622KMEB02  I138  C2106
   1 PVDDIO_P1      A @T6G_MB_LIB.T6G(SCH_1):PVDDIO_P1
   2    GND      B @T6G_MB_LIB.T6G(SCH_1):GND

Q_CAP_C0402-22UF,4V,20%,X6S,CH622KMEB02  I139  C2484
   1 PVDDIO_P1      A @T6G_MB_LIB.T6G(SCH_1):PVDDIO_P1
   2    GND      B @T6G_MB_LIB.T6G(SCH_1):GND

Q_CAP_C0402-22UF,4V,20%,X6S,CH622KMEB02  I140  C2102
   1 PVDDIO_P1      A @T6G_MB_LIB.T6G(SCH_1):PVDDIO_P1
   2    GND      B @T6G_MB_LIB.T6G(SCH_1):GND

Q_CAP_C0402-22UF,4V,20%,X6S,CH622KMEB02  I141  C2105
   1 PVDDIO_P1      A @T6G_MB_LIB.T6G(SCH_1):PVDDIO_P1
   2    GND      B @T6G_MB_LIB.T6G(SCH_1):GND

Q_CAP_C0402-22UF,4V,20%,X6S,CH622KMEB02  I142  C2104
   1 PVDDIO_P1      A @T6G_MB_LIB.T6G(SCH_1):PVDDIO_P1
   2    GND      B @T6G_MB_LIB.T6G(SCH_1):GND

Q_CAP_C0402-22UF,4V,20%,X6S,CH622KMEB02  I144  C2108
   1 PVDDIO_P1      A @T6G_MB_LIB.T6G(SCH_1):PVDDIO_P1
   2    GND      B @T6G_MB_LIB.T6G(SCH_1):GND

Q_CAP_C0402-22UF,4V,20%,X6S,CH622KMEB02  I145  C2107
   1 PVDDIO_P1      A @T6G_MB_LIB.T6G(SCH_1):PVDDIO_P1
   2    GND      B @T6G_MB_LIB.T6G(SCH_1):GND

Q_CAP_C0402-22UF,4V,20%,X6S,CH622KMEB02  I146  C2493
   1 PVDDIO_P1      A @T6G_MB_LIB.T6G(SCH_1):PVDDIO_P1
   2    GND      B @T6G_MB_LIB.T6G(SCH_1):GND

Q_CAP_C0402-22UF,4V,20%,X6S,CH622KMEB02  I147  C2498
   1 PVDDIO_P1      A @T6G_MB_LIB.T6G(SCH_1):PVDDIO_P1
   2    GND      B @T6G_MB_LIB.T6G(SCH_1):GND

Q_CAP_C0402-22UF,4V,20%,X6S,CH622KMEB02  I148  C2109
   1 PVDDIO_P1      A @T6G_MB_LIB.T6G(SCH_1):PVDDIO_P1
   2    GND      B @T6G_MB_LIB.T6G(SCH_1):GND

Q_CAP_C0402-22UF,4V,20%,X6S,CH622KMEB02  I149  C2111
   1 PVDDIO_P1      A @T6G_MB_LIB.T6G(SCH_1):PVDDIO_P1
   2    GND      B @T6G_MB_LIB.T6G(SCH_1):GND

Q_CAP_C0402-22UF,4V,20%,X6S,CH622KMEB02  I150  C2112
   1 PVDDIO_P1      A @T6G_MB_LIB.T6G(SCH_1):PVDDIO_P1
   2    GND      B @T6G_MB_LIB.T6G(SCH_1):GND

Q_CAP_C0402-22UF,4V,20%,X6S,CH622KMEB02  I151  C2110
   1 PVDDIO_P1      A @T6G_MB_LIB.T6G(SCH_1):PVDDIO_P1
   2    GND      B @T6G_MB_LIB.T6G(SCH_1):GND

Q_CAP_C0402-22UF,4V,20%,X6S,CH622KMEB02  I152  C2507
   1 PVDDIO_P1      A @T6G_MB_LIB.T6G(SCH_1):PVDDIO_P1
   2    GND      B @T6G_MB_LIB.T6G(SCH_1):GND

Q_CAP_C0402-22UF,4V,20%,X6S,CH622KMEB02  I153  C2117
   1 PVDDIO_P1      A @T6G_MB_LIB.T6G(SCH_1):PVDDIO_P1
   2    GND      B @T6G_MB_LIB.T6G(SCH_1):GND

Q_CAP_C0402-22UF,4V,20%,X6S,CH622KMEB02  I154  C2116
   1 PVDDIO_P1      A @T6G_MB_LIB.T6G(SCH_1):PVDDIO_P1
   2    GND      B @T6G_MB_LIB.T6G(SCH_1):GND

Q_CAP_C0402-22UF,4V,20%,X6S,CH622KMEB02  I155  C3921
   1 PVDD11_S3_P1      A @T6G_MB_LIB.T6G(SCH_1):PVDD11_S3_P1
   2    GND      B @T6G_MB_LIB.T6G(SCH_1):GND

Q_CAP_C0402-22UF,4V,20%,X6S,CH622KMEB02  I157  C3922
   1 PVDD11_S3_P1      A @T6G_MB_LIB.T6G(SCH_1):PVDD11_S3_P1
   2    GND      B @T6G_MB_LIB.T6G(SCH_1):GND

Q_CAP_C0402-22UF,4V,20%,X6S,CH622KMEB02  I159  C2126
   1 PVDD11_S3_P1      A @T6G_MB_LIB.T6G(SCH_1):PVDD11_S3_P1
   2    GND      B @T6G_MB_LIB.T6G(SCH_1):GND

Q_CAP_C0402-22UF,4V,20%,X6S,CH622KMEB02  I160  C2125
   1 PVDD11_S3_P1      A @T6G_MB_LIB.T6G(SCH_1):PVDD11_S3_P1
   2    GND      B @T6G_MB_LIB.T6G(SCH_1):GND

Q_CAP_C0402-22UF,4V,20%,X6S,CH622KMEB02  I161  C2511
   1 PVDD11_S3_P1      A @T6G_MB_LIB.T6G(SCH_1):PVDD11_S3_P1
   2    GND      B @T6G_MB_LIB.T6G(SCH_1):GND

Q_CAP_C0402-22UF,4V,20%,X6S,CH622KMEB02  I163  C2510
   1 PVDD11_S3_P1      A @T6G_MB_LIB.T6G(SCH_1):PVDD11_S3_P1
   2    GND      B @T6G_MB_LIB.T6G(SCH_1):GND

Q_CAP_C0402-22UF,4V,20%,X6S,CH622KMEB02  I164  C2124
   1 PVDD11_S3_P1      A @T6G_MB_LIB.T6G(SCH_1):PVDD11_S3_P1
   2    GND      B @T6G_MB_LIB.T6G(SCH_1):GND

Q_CAP_C0402-22UF,4V,20%,X6S,CH622KMEB02  I166  C2128
   1 PVDD11_S3_P1      A @T6G_MB_LIB.T6G(SCH_1):PVDD11_S3_P1
   2    GND      B @T6G_MB_LIB.T6G(SCH_1):GND

Q_CAP_C0402-22UF,4V,20%,X6S,CH622KMEB02  I168  C2123
   1 PVDDIO_P1      A @T6G_MB_LIB.T6G(SCH_1):PVDDIO_P1
   2    GND      B @T6G_MB_LIB.T6G(SCH_1):GND

Q_CAP_C0402-22UF,4V,20%,X6S,CH622KMEB02  I169  C2122
   1 PVDDIO_P1      A @T6G_MB_LIB.T6G(SCH_1):PVDDIO_P1
   2    GND      B @T6G_MB_LIB.T6G(SCH_1):GND

Q_CAP_C0402-22UF,4V,20%,X6S,CH622KMEB02  I170  C2509
   1 PVDDIO_P1      A @T6G_MB_LIB.T6G(SCH_1):PVDDIO_P1
   2    GND      B @T6G_MB_LIB.T6G(SCH_1):GND

Q_CAP_C0402-22UF,4V,20%,X6S,CH622KMEB02  I172  C2127
   1 PVDDIO_P1      A @T6G_MB_LIB.T6G(SCH_1):PVDDIO_P1
   2    GND      B @T6G_MB_LIB.T6G(SCH_1):GND

Q_CAP_C0402-22UF,4V,20%,X6S,CH622KMEB02  I173  C2442
   1 PVDDCR_SOC_P1      A @T6G_MB_LIB.T6G(SCH_1):PVDDCR_SOC_P1
   2    GND      B @T6G_MB_LIB.T6G(SCH_1):GND

Q_CAP_C0402-22UF,4V,20%,X6S,CH622KMEB02  I174  C2435
   1 PVDDCR_SOC_P1      A @T6G_MB_LIB.T6G(SCH_1):PVDDCR_SOC_P1
   2    GND      B @T6G_MB_LIB.T6G(SCH_1):GND

Q_CAP_C0402-22UF,4V,20%,X6S,CH622KMEB02  I175  C2428
   1 PVDDCR_SOC_P1      A @T6G_MB_LIB.T6G(SCH_1):PVDDCR_SOC_P1
   2    GND      B @T6G_MB_LIB.T6G(SCH_1):GND


DRAWING: @T6G_MB_LIB.T6G(SCH_1):PAGE74 

Q_CAP_C0402-22UF,4V,20%,X6S,CH622KMEB02  I1  C2661
   1 PVDD18_S5_P1      A @T6G_MB_LIB.T6G(SCH_1):PVDD18_S5_P1
   2    GND      B @T6G_MB_LIB.T6G(SCH_1):GND

Q_CAP_C0402-22UF,4V,20%,X6S,CH622KMEB02  I3  C2660
   1 PVDD18_S5_P1      A @T6G_MB_LIB.T6G(SCH_1):PVDD18_S5_P1
   2    GND      B @T6G_MB_LIB.T6G(SCH_1):GND

Q_CAP_C0402-22UF,4V,20%,X6S,CH622KMEB02  I8  C2664
   1 PVDD18_S5_P1      A @T6G_MB_LIB.T6G(SCH_1):PVDD18_S5_P1
   2    GND      B @T6G_MB_LIB.T6G(SCH_1):GND

Q_CAP_C0402-22UF,4V,20%,X6S,CH622KMEB02  I9  C2663
   1 PVDD18_S5_P1      A @T6G_MB_LIB.T6G(SCH_1):PVDD18_S5_P1
   2    GND      B @T6G_MB_LIB.T6G(SCH_1):GND

Q_CAP_C0402-22UF,4V,20%,X6S,CH622KMEB02  I10  C2665
   1 PVDD18_S5_P1      A @T6G_MB_LIB.T6G(SCH_1):PVDD18_S5_P1
   2    GND      B @T6G_MB_LIB.T6G(SCH_1):GND

Q_CAP_C0402-22UF,4V,20%,X6S,CH622KMEB02  I11  C2667
   1 PVDD18_S5_P1      A @T6G_MB_LIB.T6G(SCH_1):PVDD18_S5_P1
   2    GND      B @T6G_MB_LIB.T6G(SCH_1):GND

Q_CAP_C0402-22UF,4V,20%,X6S,CH622KMEB02  I12  C2668
   1 PVDD18_S5_P1      A @T6G_MB_LIB.T6G(SCH_1):PVDD18_S5_P1
   2    GND      B @T6G_MB_LIB.T6G(SCH_1):GND

Q_CAP_C0402-22UF,4V,20%,X6S,CH622KMEB02  I13  C2669
   1 PVDD18_S5_P1      A @T6G_MB_LIB.T6G(SCH_1):PVDD18_S5_P1
   2    GND      B @T6G_MB_LIB.T6G(SCH_1):GND

Q_CAP_C0402-22UF,4V,20%,X6S,CH622KMEB02  I14  C2670
   1 PVDD18_S5_P1      A @T6G_MB_LIB.T6G(SCH_1):PVDD18_S5_P1
   2    GND      B @T6G_MB_LIB.T6G(SCH_1):GND

Q_CAP_C0402-22UF,4V,20%,X6S,CH622KMEB02  I15  C2671
   1 PVDD18_S5_P1      A @T6G_MB_LIB.T6G(SCH_1):PVDD18_S5_P1
   2    GND      B @T6G_MB_LIB.T6G(SCH_1):GND

Q_CAP_C0402-22UF,4V,20%,X6S,CH622KMEB02  I16  C2672
   1 PVDD18_S5_P1      A @T6G_MB_LIB.T6G(SCH_1):PVDD18_S5_P1
   2    GND      B @T6G_MB_LIB.T6G(SCH_1):GND

Q_CAP_C0402-22UF,4V,20%,X6S,CH622KMEB02  I18  C2673
   1 PVDD18_S5_P1      A @T6G_MB_LIB.T6G(SCH_1):PVDD18_S5_P1
   2    GND      B @T6G_MB_LIB.T6G(SCH_1):GND

Q_CAP_C0402-10UF,6.3V,20%,X6S,CH6101MEB01  I25  C2662
   1 PVDD_33_S5      A @T6G_MB_LIB.T6G(SCH_1):PVDD_33_S5
   2    GND      B @T6G_MB_LIB.T6G(SCH_1):GND

Q_CAP_C0402-10UF,6.3V,20%,X6S,CH6101MEB01  I26  C2659
   1 PVDD_33_S5      A @T6G_MB_LIB.T6G(SCH_1):PVDD_33_S5
   2    GND      B @T6G_MB_LIB.T6G(SCH_1):GND


DRAWING: @T6G_MB_LIB.T6G(SCH_1):PAGE75 

Q_RES_0402LF-1K,1%,1/16W,CHIP,CS21002FB06  I8  R747
   1    GND      A @T6G_MB_LIB.T6G(SCH_1):GND
   2 UART_CPU0_SCM_UART1_TX      B @T6G_MB_LIB.T6G(SCH_1):UART_CPU0_SCM_UART1_TX

Q_RES_0402LF-10K,5%,1/16W,EMPTY,CS31002JB08  I9  R748
   1    GND      A @T6G_MB_LIB.T6G(SCH_1):GND
   2 CPU0_ROM_TYPE_SELECT      B @T6G_MB_LIB.T6G(SCH_1):CPU0_ROM_TYPE_SELECT

Q_RES_0402LF-10K,5%,1/16W,CHIP,CS31002JB08  I12  R751
   1    GND      A @T6G_MB_LIB.T6G(SCH_1):GND
   2 CLK_CPU0_RTCCLK      B @T6G_MB_LIB.T6G(SCH_1):CLK_CPU0_RTCCLK

Q_RES_0402LF-10K,5%,1/16W,EMPTY,CS31002JB08  I41  R729
   1 PVDD18_S5_P0      A @T6G_MB_LIB.T6G(SCH_1):PVDD18_S5_P0
   2 UART_CPU0_SCM_UART1_TX      B @T6G_MB_LIB.T6G(SCH_1):UART_CPU0_SCM_UART1_TX

Q_RES_0402LF-10K,5%,1/16W,CHIP,CS31002JB08  I43  R737
   1 PVDD18_S5_P0      A @T6G_MB_LIB.T6G(SCH_1):PVDD18_S5_P0
   2 CPU0_ROM_TYPE_SELECT      B @T6G_MB_LIB.T6G(SCH_1):CPU0_ROM_TYPE_SELECT

Q_RES_0402LF-10K,5%,1/16W,EMPTY,CS31002JB08  I44  R740
   1 PVDD18_S5_P0      A @T6G_MB_LIB.T6G(SCH_1):PVDD18_S5_P0
   2 CLK_CPU0_RTCCLK      B @T6G_MB_LIB.T6G(SCH_1):CLK_CPU0_RTCCLK

Q_RES_0402LF-10K,5%,1/16W,EMPTY,CS31002JB08  I45  R739
   1 PVDD18_S5_P0      A @T6G_MB_LIB.T6G(SCH_1):PVDD18_S5_P0
   2 CLK_ESPI_CPU0_CLK1      B @T6G_MB_LIB.T6G(SCH_1):CLK_ESPI_CPU0_CLK1

Q_RES_0402LF-10K,5%,1/16W,EMPTY,CS31002JB08  I46  R742
   1 PVDD18_S5_P0      A @T6G_MB_LIB.T6G(SCH_1):PVDD18_S5_P0
   2 PD_ESPI_CPU0_CLK2      B @T6G_MB_LIB.T6G(SCH_1):PD_ESPI_CPU0_CLK2

Q_RES_0402LF-30K,1%,1/16W,CHIP,CS33002FB02  I74  R750
   1    GND      A @T6G_MB_LIB.T6G(SCH_1):GND
   2 CLK_ESPI_CPU0_CLK1      B @T6G_MB_LIB.T6G(SCH_1):CLK_ESPI_CPU0_CLK1

Q_RES_0402LF-10K,5%,1/16W,CHIP,CS31002JB08  I75  R753
   1    GND      A @T6G_MB_LIB.T6G(SCH_1):GND
   2 PD_ESPI_CPU0_CLK2      B @T6G_MB_LIB.T6G(SCH_1):PD_ESPI_CPU0_CLK2

Q_RES_0402LF-10K,5%,1/16W,CHIP,CS31002JB08  I87  R730
   1 PVDD18_S5_P1      A @T6G_MB_LIB.T6G(SCH_1):PVDD18_S5_P1
   2 SPI_CPU1_CLK      B @T6G_MB_LIB.T6G(SCH_1):SPI_CPU1_CLK

Q_RES_0402LF-10K,5%,1/16W,EMPTY,CS31002JB08  I89  R736
   1 PVDD18_S5_P1      A @T6G_MB_LIB.T6G(SCH_1):PVDD18_S5_P1
   2 PD_ESPI_CPU1_CLK2      B @T6G_MB_LIB.T6G(SCH_1):PD_ESPI_CPU1_CLK2

Q_RES_0402LF-10K,5%,1/16W,EMPTY,CS31002JB08  I90  R1501
   1 PVDD18_S5_P1      A @T6G_MB_LIB.T6G(SCH_1):PVDD18_S5_P1
   2 CLK_CPU1_RTCCLK      B @T6G_MB_LIB.T6G(SCH_1):CLK_CPU1_RTCCLK

Q_RES_0402LF-10K,5%,1/16W,EMPTY,CS31002JB08  I91  R754
   1    GND      A @T6G_MB_LIB.T6G(SCH_1):GND
   2 SPI_CPU1_CLK      B @T6G_MB_LIB.T6G(SCH_1):SPI_CPU1_CLK

Q_RES_0402LF-10K,5%,1/16W,CHIP,CS31002JB08  I92  R760
   1    GND      A @T6G_MB_LIB.T6G(SCH_1):GND
   2 PD_ESPI_CPU1_CLK2      B @T6G_MB_LIB.T6G(SCH_1):PD_ESPI_CPU1_CLK2

Q_RES_0402LF-10K,5%,1/16W,CHIP,CS31002JB08  I94  R1502
   1    GND      A @T6G_MB_LIB.T6G(SCH_1):GND
   2 CLK_CPU1_RTCCLK      B @T6G_MB_LIB.T6G(SCH_1):CLK_CPU1_RTCCLK

Q_RES_0402LF-10K,5%,1/16W,CHIP,CS31002JB08  I97  R743
   1 PVDD18_S5_P0      A @T6G_MB_LIB.T6G(SCH_1):PVDD18_S5_P0
   2 SPI_CPU0_CLK      B @T6G_MB_LIB.T6G(SCH_1):SPI_CPU0_CLK

Q_RES_0402LF-10K,5%,1/16W,EMPTY,CS31002JB08  I99  R6098
   1    GND      A @T6G_MB_LIB.T6G(SCH_1):GND
   2 SPI_CPU0_CLK      B @T6G_MB_LIB.T6G(SCH_1):SPI_CPU0_CLK


DRAWING: @T6G_MB_LIB.T6G(SCH_1):PAGE76 

Q_CAP_0402-0.1UF,25V,10%,X7R,CH4104K1B00  I50  C1104
   1 P3V3_AUX      A @T6G_MB_LIB.T6G(SCH_1):P3V3_AUX
   2    GND      B @T6G_MB_LIB.T6G(SCH_1):GND

Q_CAP_0402-0.1UF,25V,10%,X7R,CH4104K1B00  I53  C1102
   1 PVDD18_S5_P0      A @T6G_MB_LIB.T6G(SCH_1):PVDD18_S5_P0
   2    GND      B @T6G_MB_LIB.T6G(SCH_1):GND

Q_CAP_0402-0.1UF,25V,10%,X7R,CH4104K1B00  I59  C1105
   1 P3V3_AUX      A @T6G_MB_LIB.T6G(SCH_1):P3V3_AUX
   2    GND      B @T6G_MB_LIB.T6G(SCH_1):GND

SN74AVC4T774PWR-SN74AVC4T774PWR,SMLF,IC,AL04T774K00  I63  U53
   1 PVDD18_S5_P0   DIR1 @T6G_MB_LIB.T6G(SCH_1):PVDD18_S5_P0
   2 PVDD18_S5_P0   DIR2 @T6G_MB_LIB.T6G(SCH_1):PVDD18_S5_P0
   3 SPI_CPU0_CS0_N     A1 @T6G_MB_LIB.T6G(SCH_1):SPI_CPU0_CS0_N
   4 SPI_CPU0_CLK     A2 @T6G_MB_LIB.T6G(SCH_1):SPI_CPU0_CLK
   5 SPI_CPU0_CS1_N     A3 @T6G_MB_LIB.T6G(SCH_1):SPI_CPU0_CS1_N
   6 SPI_CPU0_TPM_CS_N     A4 @T6G_MB_LIB.T6G(SCH_1):SPI_CPU0_TPM_CS_N
   7 PVDD18_S5_P0   DIR3 @T6G_MB_LIB.T6G(SCH_1):PVDD18_S5_P0
   8 PVDD18_S5_P0   DIR4 @T6G_MB_LIB.T6G(SCH_1):PVDD18_S5_P0
   9 ROM_SD_LS_OE     OE @T6G_MB_LIB.T6G(SCH_1):ROM_SD_LS_OE
  10    GND    GND @T6G_MB_LIB.T6G(SCH_1):GND
  11 SPI_CPU0_LVC3_R_TPM_CS_N     B4 @T6G_MB_LIB.T6G(SCH_1):SPI_CPU0_LVC3_R_TPM_CS_N
  12 SPI_CPU0_LVC3_CS1_N     B3 @T6G_MB_LIB.T6G(SCH_1):SPI_CPU0_LVC3_CS1_N
  13 SPI_CPU0_LVC3_CLK     B2 @T6G_MB_LIB.T6G(SCH_1):SPI_CPU0_LVC3_CLK
  14 SPI_CPU0_LVC3_CS0_N     B1 @T6G_MB_LIB.T6G(SCH_1):SPI_CPU0_LVC3_CS0_N
  15 P3V3_AUX   VCCB @T6G_MB_LIB.T6G(SCH_1):P3V3_AUX
  16 PVDD18_S5_P0   VCCA @T6G_MB_LIB.T6G(SCH_1):PVDD18_S5_P0

Q_CAP_0402-0.1UF,25V,10%,X7R,CH4104K1B00  I65  C1103
   1 PVDD18_S5_P0      A @T6G_MB_LIB.T6G(SCH_1):PVDD18_S5_P0
   2    GND      B @T6G_MB_LIB.T6G(SCH_1):GND

PI4ULS3V304AZMAEX-PI4ULS3V304AZMAEX,SMLF,IC,AL0003A  I67  U54
   2 SPI_CPU0_R1_D3     A1 @T6G_MB_LIB.T6G(SCH_1):SPI_CPU0_R1_D3
   3 SPI_CPU0_R1_D2     A2 @T6G_MB_LIB.T6G(SCH_1):SPI_CPU0_R1_D2
   4 SPI_CPU0_R1_D0     A3 @T6G_MB_LIB.T6G(SCH_1):SPI_CPU0_R1_D0
  11 P3V3_AUX   VCCB @T6G_MB_LIB.T6G(SCH_1):P3V3_AUX
  12 ROM_LS_EN     EN @T6G_MB_LIB.T6G(SCH_1):ROM_LS_EN
   5 SPI_CPU0_R1_D1     A4 @T6G_MB_LIB.T6G(SCH_1):SPI_CPU0_R1_D1
   1 PVDD18_S5_P0   VCCA @T6G_MB_LIB.T6G(SCH_1):PVDD18_S5_P0
  10 SPI_CPU0_LVC3_D3     B1 @T6G_MB_LIB.T6G(SCH_1):SPI_CPU0_LVC3_D3
   9 SPI_CPU0_LVC3_D2     B2 @T6G_MB_LIB.T6G(SCH_1):SPI_CPU0_LVC3_D2
   8 SPI_CPU0_LVC3_D0     B3 @T6G_MB_LIB.T6G(SCH_1):SPI_CPU0_LVC3_D0
   7 SPI_CPU0_LVC3_D1     B4 @T6G_MB_LIB.T6G(SCH_1):SPI_CPU0_LVC3_D1
   6    GND    GND @T6G_MB_LIB.T6G(SCH_1):GND

Q_RES_0402LF-1K,1%,1/16W,EMPTY,CS21002FB06  I97  R610
   1 P3V3_AUX      A @T6G_MB_LIB.T6G(SCH_1):P3V3_AUX
   2 SPI_CPU0_LVC3_SCM_CS0_N      B @T6G_MB_LIB.T6G(SCH_1):SPI_CPU0_LVC3_SCM_CS0_N

Q_RES_0402LF-1K,1%,1/16W,CHIP,CS21002FB06  I106  R811
   1 PVDD18_S5_P0      A @T6G_MB_LIB.T6G(SCH_1):PVDD18_S5_P0
   2 SPI_CPU0_CS0_N      B @T6G_MB_LIB.T6G(SCH_1):SPI_CPU0_CS0_N

Q_RES_0402LF-1K,1%,1/16W,CHIP,CS21002FB06  I107  R659
   1 PVDD18_S5_P0      A @T6G_MB_LIB.T6G(SCH_1):PVDD18_S5_P0
   2 SPI_CPU0_TPM_CS_N      B @T6G_MB_LIB.T6G(SCH_1):SPI_CPU0_TPM_CS_N

Q_RES_0402LF-1K,1%,1/16W,CHIP,CS21002FB06  I108  R601
   1 PVDD18_S5_P0      A @T6G_MB_LIB.T6G(SCH_1):PVDD18_S5_P0
   2 SPI_CPU0_CS1_N      B @T6G_MB_LIB.T6G(SCH_1):SPI_CPU0_CS1_N

Q_RES_0402LF-10K,1%,1/16W,CHIP,CS31002FB08  I115  R20
   1 P3V3_AUX      A @T6G_MB_LIB.T6G(SCH_1):P3V3_AUX
   2 SPI_CPU0_LVC3_SCM_CLK      B @T6G_MB_LIB.T6G(SCH_1):SPI_CPU0_LVC3_SCM_CLK

Q_RES_0402LF-1K,1%,1/16W,EMPTY,CS21002FB06  I116  R21
   1 P3V3_AUX      A @T6G_MB_LIB.T6G(SCH_1):P3V3_AUX
   2 SPI_CPU0_LVC3_SCM_D0      B @T6G_MB_LIB.T6G(SCH_1):SPI_CPU0_LVC3_SCM_D0

Q_RES_0402LF-1K,1%,1/16W,EMPTY,CS21002FB06  I117  R127
   1 P3V3_AUX      A @T6G_MB_LIB.T6G(SCH_1):P3V3_AUX
   2 SPI_CPU0_LVC3_SCM_D1      B @T6G_MB_LIB.T6G(SCH_1):SPI_CPU0_LVC3_SCM_D1

Q_RES_0402LF-1K,1%,1/16W,EMPTY,CS21002FB06  I118  R128
   1 P3V3_AUX      A @T6G_MB_LIB.T6G(SCH_1):P3V3_AUX
   2 SPI_CPU0_LVC3_SCM_D2      B @T6G_MB_LIB.T6G(SCH_1):SPI_CPU0_LVC3_SCM_D2

Q_RES_0402LF-1K,1%,1/16W,EMPTY,CS21002FB06  I119  R129
   1 P3V3_AUX      A @T6G_MB_LIB.T6G(SCH_1):P3V3_AUX
   2 SPI_CPU0_LVC3_SCM_D3      B @T6G_MB_LIB.T6G(SCH_1):SPI_CPU0_LVC3_SCM_D3

Q_RES_0402LF-1K,1%,1/16W,EMPTY,CS21002FB06  I131  R1532
   1 PVDD18_S5_P0      A @T6G_MB_LIB.T6G(SCH_1):PVDD18_S5_P0
   2 SPI_CPU0_D0      B @T6G_MB_LIB.T6G(SCH_1):SPI_CPU0_D0

Q_RES_0402LF-1K,1%,1/16W,EMPTY,CS21002FB06  I132  R1531
   1 PVDD18_S5_P0      A @T6G_MB_LIB.T6G(SCH_1):PVDD18_S5_P0
   2 SPI_CPU0_D1      B @T6G_MB_LIB.T6G(SCH_1):SPI_CPU0_D1

Q_RES_0402LF-1K,1%,1/16W,EMPTY,CS21002FB06  I133  R1530
   1 PVDD18_S5_P0      A @T6G_MB_LIB.T6G(SCH_1):PVDD18_S5_P0
   2 SPI_CPU0_D2      B @T6G_MB_LIB.T6G(SCH_1):SPI_CPU0_D2

Q_RES_0402LF-1K,1%,1/16W,EMPTY,CS21002FB06  I134  R1529
   1 PVDD18_S5_P0      A @T6G_MB_LIB.T6G(SCH_1):PVDD18_S5_P0
   2 SPI_CPU0_D3      B @T6G_MB_LIB.T6G(SCH_1):SPI_CPU0_D3

Q_RES_0402LF-4.7K,5%,1/16W,CHIP,CS24702JB10  I148  R1547
   1 P3V3_AUX      A @T6G_MB_LIB.T6G(SCH_1):P3V3_AUX
   2 SPI_CPU0_LVC3_TPM_CS_N      B @T6G_MB_LIB.T6G(SCH_1):SPI_CPU0_LVC3_TPM_CS_N

Q_RES_0402LF-4.7K,5%,1/16W,CHIP,CS24702JB10  I150  R1567
   1 PVDD18_S5_P0      A @T6G_MB_LIB.T6G(SCH_1):PVDD18_S5_P0
   2 ROM_LS_EN      B @T6G_MB_LIB.T6G(SCH_1):ROM_LS_EN

Q_RES_0402LF-0,5%,1/16W,CHIP,CS00002JB13  I180  R600
   1 SPI_CPU0_LVC3_CS1_N      A @T6G_MB_LIB.T6G(SCH_1):SPI_CPU0_LVC3_CS1_N
   2 SPI_CPU0_LVC3_SCM_CS1_N      B @T6G_MB_LIB.T6G(SCH_1):SPI_CPU0_LVC3_SCM_CS1_N

Q_RES_0402LF-1K,1%,1/16W,EMPTY,CS21002FB06  I191  R1655
   1 P3V3_AUX      A @T6G_MB_LIB.T6G(SCH_1):P3V3_AUX
   2 SPI_CPU0_LVC3_SCM_CS1_N      B @T6G_MB_LIB.T6G(SCH_1):SPI_CPU0_LVC3_SCM_CS1_N

Q_RES_0402LF-0,5%,1/16W,CHIP,CS00002JB13  I205  R606
   1 SPI_CPU0_LVC3_D2      A @T6G_MB_LIB.T6G(SCH_1):SPI_CPU0_LVC3_D2
   2 SPI_CPU0_LVC3_SCM_D2      B @T6G_MB_LIB.T6G(SCH_1):SPI_CPU0_LVC3_SCM_D2

Q_RES_0402LF-0,5%,1/16W,CHIP,CS00002JB13  I207  R607
   1 SPI_CPU0_LVC3_D3      A @T6G_MB_LIB.T6G(SCH_1):SPI_CPU0_LVC3_D3
   2 SPI_CPU0_LVC3_SCM_D3      B @T6G_MB_LIB.T6G(SCH_1):SPI_CPU0_LVC3_SCM_D3

Q_RES_0402LF-49.9,1%,1/16W,CHIP,CS04992FB07  I219  R605
   1 SPI_CPU0_LVC3_D1      A @T6G_MB_LIB.T6G(SCH_1):SPI_CPU0_LVC3_D1
   2 SPI_CPU0_LVC3_SCM_D1      B @T6G_MB_LIB.T6G(SCH_1):SPI_CPU0_LVC3_SCM_D1

Q_RES_0402LF-33.2,1%,1/16W,CHIP,CS03322FB03  I221  R604
   1 SPI_CPU0_LVC3_D0      A @T6G_MB_LIB.T6G(SCH_1):SPI_CPU0_LVC3_D0
   2 SPI_CPU0_LVC3_SCM_D0      B @T6G_MB_LIB.T6G(SCH_1):SPI_CPU0_LVC3_SCM_D0

Q_RES_0402LF-0,5%,1/16W,CHIP,CS00002JB13  I228  R603
   1 SPI_CPU0_LVC3_CS0_N      A @T6G_MB_LIB.T6G(SCH_1):SPI_CPU0_LVC3_CS0_N
   2 SPI_CPU0_LVC3_SCM_CS0_N      B @T6G_MB_LIB.T6G(SCH_1):SPI_CPU0_LVC3_SCM_CS0_N

Q_RES_0402LF-33,5%,1/16W,CHIP,CS03302JB10  I230  R602
   1 SPI_CPU0_LVC3_CLK      A @T6G_MB_LIB.T6G(SCH_1):SPI_CPU0_LVC3_CLK
   2 SPI_CPU0_LVC3_SCM_CLK      B @T6G_MB_LIB.T6G(SCH_1):SPI_CPU0_LVC3_SCM_CLK

Q_RES_0402LF-33,5%,1/16W,CHIP,CS03302JB10  I234  R8005
   1 SPI_CPU0_D3      A @T6G_MB_LIB.T6G(SCH_1):SPI_CPU0_D3
   2 SPI_CPU0_R1_D3      B @T6G_MB_LIB.T6G(SCH_1):SPI_CPU0_R1_D3

Q_RES_0402LF-33,5%,1/16W,CHIP,CS03302JB10  I239  R8006
   1 SPI_CPU0_D2      A @T6G_MB_LIB.T6G(SCH_1):SPI_CPU0_D2
   2 SPI_CPU0_R1_D2      B @T6G_MB_LIB.T6G(SCH_1):SPI_CPU0_R1_D2

Q_RES_0402LF-33,5%,1/16W,CHIP,CS03302JB10  I240  R8007
   1 SPI_CPU0_D0      A @T6G_MB_LIB.T6G(SCH_1):SPI_CPU0_D0
   2 SPI_CPU0_R1_D0      B @T6G_MB_LIB.T6G(SCH_1):SPI_CPU0_R1_D0

Q_RES_0402LF-33,5%,1/16W,CHIP,CS03302JB10  I241  R8008
   1 SPI_CPU0_D1      A @T6G_MB_LIB.T6G(SCH_1):SPI_CPU0_D1
   2 SPI_CPU0_R1_D1      B @T6G_MB_LIB.T6G(SCH_1):SPI_CPU0_R1_D1

Q_RES_0402LF-33,5%,1/16W,CHIP,CS03302JB10  I242  R608
   1 SPI_CPU0_LVC3_R_TPM_CS_N      A @T6G_MB_LIB.T6G(SCH_1):SPI_CPU0_LVC3_R_TPM_CS_N
   2 SPI_CPU0_LVC3_TPM_CS_N      B @T6G_MB_LIB.T6G(SCH_1):SPI_CPU0_LVC3_TPM_CS_N


DRAWING: @T6G_MB_LIB.T6G(SCH_1):PAGE77 

Q_RES_0402LF-10K,5%,1/16W,EMPTY,CS31002JB08  I1  R702
   1 PWRGD_CPU0_PWROK      A @T6G_MB_LIB.T6G(SCH_1):PWRGD_CPU0_PWROK
   2    GND      B @T6G_MB_LIB.T6G(SCH_1):GND

Q_RES_0402LF-10K,5%,1/16W,EMPTY,CS31002JB08  I5  R703
   1 PWRGD_CPU1_PWROK      A @T6G_MB_LIB.T6G(SCH_1):PWRGD_CPU1_PWROK
   2    GND      B @T6G_MB_LIB.T6G(SCH_1):GND

Q_CAP_0402-0.1UF,25V,10%,X7R,CH4104K1B00  I11  C223
   1 P1V8_AUX      A @T6G_MB_LIB.T6G(SCH_1):P1V8_AUX
   2    GND      B @T6G_MB_LIB.T6G(SCH_1):GND

SN74LVC2G07DCKR_SMLF-SN74LVC2G07DCKR,IC,AL002G07006  I15  U29
   1 PWRGD_CPU0_PWROK     1A @T6G_MB_LIB.T6G(SCH_1):PWRGD_CPU0_PWROK
   3 PWRGD_CPU0_PWROK     2A @T6G_MB_LIB.T6G(SCH_1):PWRGD_CPU0_PWROK
   6 PVDDCR_CPU0_P0_RESET_N     1Y @T6G_MB_LIB.T6G(SCH_1):PVDDCR_CPU0_P0_RESET_N
   4 PVDDCR_CPU1_P0_RESET_N     2Y @T6G_MB_LIB.T6G(SCH_1):PVDDCR_CPU1_P0_RESET_N
   2    GND    GND @T6G_MB_LIB.T6G(SCH_1):GND
   5 P1V8_AUX    VCC @T6G_MB_LIB.T6G(SCH_1):P1V8_AUX

Q_CAP_0402-0.1UF,25V,10%,X7R,CH4104K1B00  I19  C224
   1 P1V8_AUX      A @T6G_MB_LIB.T6G(SCH_1):P1V8_AUX
   2    GND      B @T6G_MB_LIB.T6G(SCH_1):GND

SN74LVC2G07DCKR_SMLF-SN74LVC2G07DCKR,IC,AL002G07006  I21  U40
   1 PWRGD_CPU1_PWROK     1A @T6G_MB_LIB.T6G(SCH_1):PWRGD_CPU1_PWROK
   3 PWRGD_CPU1_PWROK     2A @T6G_MB_LIB.T6G(SCH_1):PWRGD_CPU1_PWROK
   6 PVDDCR_CPU0_P1_RESET_N     1Y @T6G_MB_LIB.T6G(SCH_1):PVDDCR_CPU0_P1_RESET_N
   4 PVDDCR_CPU1_P1_RESET_N     2Y @T6G_MB_LIB.T6G(SCH_1):PVDDCR_CPU1_P1_RESET_N
   2    GND    GND @T6G_MB_LIB.T6G(SCH_1):GND
   5 P1V8_AUX    VCC @T6G_MB_LIB.T6G(SCH_1):P1V8_AUX


DRAWING: @T6G_MB_LIB.T6G(SCH_1):PAGE85 

Q_RES_0402LF-10K,1%,1/16W,CHIP,CS31002FB08  I499  R7
   1 PD_CHA_CPU0_DIMM0_SAA      A @T6G_MB_LIB.T6G(SCH_1):PD_CHA_CPU0_DIMM0_SAA
   2    GND      B @T6G_MB_LIB.T6G(SCH_1):GND

Q_CAP_C0805-10UF,25V,10%,X6S,CH6104KEA00  I519  C89
   1 P12V_MEM_CPU0      A @T6G_MB_LIB.T6G(SCH_1):P12V_MEM_CPU0
   2    GND      B @T6G_MB_LIB.T6G(SCH_1):GND

Q_CAP_0402-0.1UF,25V,10%,X7R,CH4104K1B00  I523  C88
   1 P3V3_AUX      A @T6G_MB_LIB.T6G(SCH_1):P3V3_AUX
   2    GND      B @T6G_MB_LIB.T6G(SCH_1):GND

Q_RES_0402LF-1K,1%,1/16W,CHIP,CS21002FB06  I525  R291
   1 PWRGD_CHA_CPU0_DIMM0      A @T6G_MB_LIB.T6G(SCH_1):PWRGD_CHA_CPU0_DIMM0
   2 PWRGD_CHAF_CPU0      B @T6G_MB_LIB.T6G(SCH_1):PWRGD_CHAF_CPU0

Q_RES_0402LF-1K,1%,1/16W,EMPTY,CS21002FB06  I526  R88
   1   P3V3      A @T6G_MB_LIB.T6G(SCH_1):P3V3
   2 PWRGD_CHAF_CPU0      B @T6G_MB_LIB.T6G(SCH_1):PWRGD_CHAF_CPU0

Q_RES_0402LF-1K,1%,1/16W,EMPTY,CS21002FB06  I528  R89
   1   P3V3      A @T6G_MB_LIB.T6G(SCH_1):P3V3
   2 PWRGD_CHA_CPU0_DIMM0      B @T6G_MB_LIB.T6G(SCH_1):PWRGD_CHA_CPU0_DIMM0

Q_CAP_C0805-10UF,25V,10%,X6S,CH6104KEA00  I534  C142
   1 P12V_MEM_CPU0      A @T6G_MB_LIB.T6G(SCH_1):P12V_MEM_CPU0
   2    GND      B @T6G_MB_LIB.T6G(SCH_1):GND

SCONN288_DDR506112002KQ-SCONN288_DDR506112002KQ,SMA  I536  J1
   3 P3V3_AUX VIN_MGMT @T6G_MB_LIB.T6G(SCH_1):P3V3_AUX
   2     NC   RFU0     NC
 144     NC   RFU1     NC
 149     NC   RFU2     NC
 150     NC   RFU3     NC
 220     NC   RFU4     NC
 231     NC   RFU5     NC
 232     NC   RFU6     NC
 207 M_A_CPU0_RESET_N RESET_N @T6G_MB_LIB.T6G(SCH_1):M_A_CPU0_RESET_N
 147 PWRGD_CHA_CPU0_DIMM0 PWR_GOOD||FAIL_N @T6G_MB_LIB.T6G(SCH_1):PWRGD_CHA_CPU0_DIMM0
 227 M_A_CPU0_SB_PAR  PAR_B @T6G_MB_LIB.T6G(SCH_1):M_A_CPU0_SB_PAR
  74 M_A_CPU0_SA_PAR  PAR_A @T6G_MB_LIB.T6G(SCH_1):M_A_CPU0_SA_PAR
  87 M_A_CPU0_SB_RSP<0> LBS||RSP_B_N @T6G_MB_LIB.T6G(SCH_1):M_A_CPU0_SB_RSP(0)
  86 M_A_CPU0_SA_RSP<0> LBD||RSP_A_N @T6G_MB_LIB.T6G(SCH_1):M_A_CPU0_SA_RSP(0)
   5 I3C_SPD_DDRA_CPU0_SDA   HSDA @T6G_MB_LIB.T6G(SCH_1):I3C_SPD_DDRA_CPU0_SDA
   4 I3C_SPD_DDRA_CPU0_SCL   HSCL @T6G_MB_LIB.T6G(SCH_1):I3C_SPD_DDRA_CPU0_SCL
 148 PD_CHA_CPU0_DIMM0_SAA    HAS @T6G_MB_LIB.T6G(SCH_1):PD_CHA_CPU0_DIMM0_SAA
 100 M_A_CPU0_SB_DQ<0>  DQ0_B @T6G_MB_LIB.T6G(SCH_1):M_A_CPU0_SB_DQ(0)
 102 M_A_CPU0_SB_DQ<1>  DQ1_B @T6G_MB_LIB.T6G(SCH_1):M_A_CPU0_SB_DQ(1)
 245 M_A_CPU0_SB_DQ<2>  DQ2_B @T6G_MB_LIB.T6G(SCH_1):M_A_CPU0_SB_DQ(2)
 247 M_A_CPU0_SB_DQ<3>  DQ3_B @T6G_MB_LIB.T6G(SCH_1):M_A_CPU0_SB_DQ(3)
 107 M_A_CPU0_SB_DQ<4>  DQ4_B @T6G_MB_LIB.T6G(SCH_1):M_A_CPU0_SB_DQ(4)
 109 M_A_CPU0_SB_DQ<5>  DQ5_B @T6G_MB_LIB.T6G(SCH_1):M_A_CPU0_SB_DQ(5)
 252 M_A_CPU0_SB_DQ<6>  DQ6_B @T6G_MB_LIB.T6G(SCH_1):M_A_CPU0_SB_DQ(6)
 254 M_A_CPU0_SB_DQ<7>  DQ7_B @T6G_MB_LIB.T6G(SCH_1):M_A_CPU0_SB_DQ(7)
 111 M_A_CPU0_SB_DQ<8>  DQ8_B @T6G_MB_LIB.T6G(SCH_1):M_A_CPU0_SB_DQ(8)
 113 M_A_CPU0_SB_DQ<9>  DQ9_B @T6G_MB_LIB.T6G(SCH_1):M_A_CPU0_SB_DQ(9)
 256 M_A_CPU0_SB_DQ<10> DQ10_B @T6G_MB_LIB.T6G(SCH_1):M_A_CPU0_SB_DQ(10)
 258 M_A_CPU0_SB_DQ<11> DQ11_B @T6G_MB_LIB.T6G(SCH_1):M_A_CPU0_SB_DQ(11)
 118 M_A_CPU0_SB_DQ<12> DQ12_B @T6G_MB_LIB.T6G(SCH_1):M_A_CPU0_SB_DQ(12)
 120 M_A_CPU0_SB_DQ<13> DQ13_B @T6G_MB_LIB.T6G(SCH_1):M_A_CPU0_SB_DQ(13)
 263 M_A_CPU0_SB_DQ<14> DQ14_B @T6G_MB_LIB.T6G(SCH_1):M_A_CPU0_SB_DQ(14)
 265 M_A_CPU0_SB_DQ<15> DQ15_B @T6G_MB_LIB.T6G(SCH_1):M_A_CPU0_SB_DQ(15)
 122 M_A_CPU0_SB_DQ<16> DQ16_B @T6G_MB_LIB.T6G(SCH_1):M_A_CPU0_SB_DQ(16)
 124 M_A_CPU0_SB_DQ<17> DQ17_B @T6G_MB_LIB.T6G(SCH_1):M_A_CPU0_SB_DQ(17)
 267 M_A_CPU0_SB_DQ<18> DQ18_B @T6G_MB_LIB.T6G(SCH_1):M_A_CPU0_SB_DQ(18)
 269 M_A_CPU0_SB_DQ<19> DQ19_B @T6G_MB_LIB.T6G(SCH_1):M_A_CPU0_SB_DQ(19)
 129 M_A_CPU0_SB_DQ<20> DQ20_B @T6G_MB_LIB.T6G(SCH_1):M_A_CPU0_SB_DQ(20)
 131 M_A_CPU0_SB_DQ<21> DQ21_B @T6G_MB_LIB.T6G(SCH_1):M_A_CPU0_SB_DQ(21)
 274 M_A_CPU0_SB_DQ<22> DQ22_B @T6G_MB_LIB.T6G(SCH_1):M_A_CPU0_SB_DQ(22)
 276 M_A_CPU0_SB_DQ<23> DQ23_B @T6G_MB_LIB.T6G(SCH_1):M_A_CPU0_SB_DQ(23)
 133 M_A_CPU0_SB_DQ<24> DQ24_B @T6G_MB_LIB.T6G(SCH_1):M_A_CPU0_SB_DQ(24)
 135 M_A_CPU0_SB_DQ<25> DQ25_B @T6G_MB_LIB.T6G(SCH_1):M_A_CPU0_SB_DQ(25)
 278 M_A_CPU0_SB_DQ<26> DQ26_B @T6G_MB_LIB.T6G(SCH_1):M_A_CPU0_SB_DQ(26)
 280 M_A_CPU0_SB_DQ<27> DQ27_B @T6G_MB_LIB.T6G(SCH_1):M_A_CPU0_SB_DQ(27)
 140 M_A_CPU0_SB_DQ<28> DQ28_B @T6G_MB_LIB.T6G(SCH_1):M_A_CPU0_SB_DQ(28)
 142 M_A_CPU0_SB_DQ<29> DQ29_B @T6G_MB_LIB.T6G(SCH_1):M_A_CPU0_SB_DQ(29)
 285 M_A_CPU0_SB_DQ<30> DQ30_B @T6G_MB_LIB.T6G(SCH_1):M_A_CPU0_SB_DQ(30)
 287 M_A_CPU0_SB_DQ<31> DQ31_B @T6G_MB_LIB.T6G(SCH_1):M_A_CPU0_SB_DQ(31)
   7 M_A_CPU0_SA_DQ<0>  DQ0_A @T6G_MB_LIB.T6G(SCH_1):M_A_CPU0_SA_DQ(0)
   9 M_A_CPU0_SA_DQ<1>  DQ1_A @T6G_MB_LIB.T6G(SCH_1):M_A_CPU0_SA_DQ(1)
 152 M_A_CPU0_SA_DQ<2>  DQ2_A @T6G_MB_LIB.T6G(SCH_1):M_A_CPU0_SA_DQ(2)
 154 M_A_CPU0_SA_DQ<3>  DQ3_A @T6G_MB_LIB.T6G(SCH_1):M_A_CPU0_SA_DQ(3)
  14 M_A_CPU0_SA_DQ<4>  DQ4_A @T6G_MB_LIB.T6G(SCH_1):M_A_CPU0_SA_DQ(4)
  16 M_A_CPU0_SA_DQ<5>  DQ5_A @T6G_MB_LIB.T6G(SCH_1):M_A_CPU0_SA_DQ(5)
 159 M_A_CPU0_SA_DQ<6>  DQ6_A @T6G_MB_LIB.T6G(SCH_1):M_A_CPU0_SA_DQ(6)
 161 M_A_CPU0_SA_DQ<7>  DQ7_A @T6G_MB_LIB.T6G(SCH_1):M_A_CPU0_SA_DQ(7)
  18 M_A_CPU0_SA_DQ<8>  DQ8_A @T6G_MB_LIB.T6G(SCH_1):M_A_CPU0_SA_DQ(8)
  20 M_A_CPU0_SA_DQ<9>  DQ9_A @T6G_MB_LIB.T6G(SCH_1):M_A_CPU0_SA_DQ(9)
 163 M_A_CPU0_SA_DQ<10> DQ10_A @T6G_MB_LIB.T6G(SCH_1):M_A_CPU0_SA_DQ(10)
 165 M_A_CPU0_SA_DQ<11> DQ11_A @T6G_MB_LIB.T6G(SCH_1):M_A_CPU0_SA_DQ(11)
  25 M_A_CPU0_SA_DQ<12> DQ12_A @T6G_MB_LIB.T6G(SCH_1):M_A_CPU0_SA_DQ(12)
  27 M_A_CPU0_SA_DQ<13> DQ13_A @T6G_MB_LIB.T6G(SCH_1):M_A_CPU0_SA_DQ(13)
 170 M_A_CPU0_SA_DQ<14> DQ14_A @T6G_MB_LIB.T6G(SCH_1):M_A_CPU0_SA_DQ(14)
 172 M_A_CPU0_SA_DQ<15> DQ15_A @T6G_MB_LIB.T6G(SCH_1):M_A_CPU0_SA_DQ(15)
  29 M_A_CPU0_SA_DQ<16> DQ16_A @T6G_MB_LIB.T6G(SCH_1):M_A_CPU0_SA_DQ(16)
  31 M_A_CPU0_SA_DQ<17> DQ17_A @T6G_MB_LIB.T6G(SCH_1):M_A_CPU0_SA_DQ(17)
 174 M_A_CPU0_SA_DQ<18> DQ18_A @T6G_MB_LIB.T6G(SCH_1):M_A_CPU0_SA_DQ(18)
 176 M_A_CPU0_SA_DQ<19> DQ19_A @T6G_MB_LIB.T6G(SCH_1):M_A_CPU0_SA_DQ(19)
  36 M_A_CPU0_SA_DQ<20> DQ20_A @T6G_MB_LIB.T6G(SCH_1):M_A_CPU0_SA_DQ(20)
  38 M_A_CPU0_SA_DQ<21> DQ21_A @T6G_MB_LIB.T6G(SCH_1):M_A_CPU0_SA_DQ(21)
 181 M_A_CPU0_SA_DQ<22> DQ22_A @T6G_MB_LIB.T6G(SCH_1):M_A_CPU0_SA_DQ(22)
 183 M_A_CPU0_SA_DQ<23> DQ23_A @T6G_MB_LIB.T6G(SCH_1):M_A_CPU0_SA_DQ(23)
  40 M_A_CPU0_SA_DQ<24> DQ24_A @T6G_MB_LIB.T6G(SCH_1):M_A_CPU0_SA_DQ(24)
  42 M_A_CPU0_SA_DQ<25> DQ25_A @T6G_MB_LIB.T6G(SCH_1):M_A_CPU0_SA_DQ(25)
 185 M_A_CPU0_SA_DQ<26> DQ26_A @T6G_MB_LIB.T6G(SCH_1):M_A_CPU0_SA_DQ(26)
 187 M_A_CPU0_SA_DQ<27> DQ27_A @T6G_MB_LIB.T6G(SCH_1):M_A_CPU0_SA_DQ(27)
  47 M_A_CPU0_SA_DQ<28> DQ28_A @T6G_MB_LIB.T6G(SCH_1):M_A_CPU0_SA_DQ(28)
  49 M_A_CPU0_SA_DQ<29> DQ29_A @T6G_MB_LIB.T6G(SCH_1):M_A_CPU0_SA_DQ(29)
 192 M_A_CPU0_SA_DQ<30> DQ30_A @T6G_MB_LIB.T6G(SCH_1):M_A_CPU0_SA_DQ(30)
 229 M_A_CPU0_SB_CS_N<1> CS1_B_N @T6G_MB_LIB.T6G(SCH_1):M_A_CPU0_SB_CS_N(1)
 209 M_A_CPU0_SA_CS_N<1> CS1_A_N @T6G_MB_LIB.T6G(SCH_1):M_A_CPU0_SA_CS_N(1)
  84 M_A_CPU0_SB_CS_N<0> CS0_B_N @T6G_MB_LIB.T6G(SCH_1):M_A_CPU0_SB_CS_N(0)
  64 M_A_CPU0_SA_CS_N<0> CS0_A_N @T6G_MB_LIB.T6G(SCH_1):M_A_CPU0_SA_CS_N(0)
 217 M_A_CPU0_CLK_DP<0>   CK_T @T6G_MB_LIB.T6G(SCH_1):M_A_CPU0_CLK_DP(0)
 218 M_A_CPU0_CLK_DN<0>   CK_C @T6G_MB_LIB.T6G(SCH_1):M_A_CPU0_CLK_DN(0)
  96 M_A_CPU0_SB_CB<0>  CB0_B @T6G_MB_LIB.T6G(SCH_1):M_A_CPU0_SB_CB(0)
  98 M_A_CPU0_SB_CB<1>  CB1_B @T6G_MB_LIB.T6G(SCH_1):M_A_CPU0_SB_CB(1)
 241 M_A_CPU0_SB_CB<2>  CB2_B @T6G_MB_LIB.T6G(SCH_1):M_A_CPU0_SB_CB(2)
 243 M_A_CPU0_SB_CB<3>  CB3_B @T6G_MB_LIB.T6G(SCH_1):M_A_CPU0_SB_CB(3)
  89 M_A_CPU0_SB_CB<4>  CB4_B @T6G_MB_LIB.T6G(SCH_1):M_A_CPU0_SB_CB(4)
  91 M_A_CPU0_SB_CB<5>  CB5_B @T6G_MB_LIB.T6G(SCH_1):M_A_CPU0_SB_CB(5)
 234 M_A_CPU0_SB_CB<6>  CB6_B @T6G_MB_LIB.T6G(SCH_1):M_A_CPU0_SB_CB(6)
  51 M_A_CPU0_SA_CB<0>  CB0_A @T6G_MB_LIB.T6G(SCH_1):M_A_CPU0_SA_CB(0)
 196 M_A_CPU0_SA_CB<2>  CB2_A @T6G_MB_LIB.T6G(SCH_1):M_A_CPU0_SA_CB(2)
 198 M_A_CPU0_SA_CB<3>  CB3_A @T6G_MB_LIB.T6G(SCH_1):M_A_CPU0_SA_CB(3)
  60 M_A_CPU0_SA_CB<5>  CB5_A @T6G_MB_LIB.T6G(SCH_1):M_A_CPU0_SA_CB(5)
 203 M_A_CPU0_SA_CB<6>  CB6_A @T6G_MB_LIB.T6G(SCH_1):M_A_CPU0_SA_CB(6)
  82 M_A_CPU0_SB_CA<6>  CA6_B @T6G_MB_LIB.T6G(SCH_1):M_A_CPU0_SB_CA(6)
  72 M_A_CPU0_SA_CA<6>  CA6_A @T6G_MB_LIB.T6G(SCH_1):M_A_CPU0_SA_CA(6)
 225 M_A_CPU0_SB_CA<5>  CA5_B @T6G_MB_LIB.T6G(SCH_1):M_A_CPU0_SB_CA(5)
 215 M_A_CPU0_SA_CA<5>  CA5_A @T6G_MB_LIB.T6G(SCH_1):M_A_CPU0_SA_CA(5)
  80 M_A_CPU0_SB_CA<4>  CA4_B @T6G_MB_LIB.T6G(SCH_1):M_A_CPU0_SB_CA(4)
  70 M_A_CPU0_SA_CA<4>  CA4_A @T6G_MB_LIB.T6G(SCH_1):M_A_CPU0_SA_CA(4)
 223 M_A_CPU0_SB_CA<3>  CA3_B @T6G_MB_LIB.T6G(SCH_1):M_A_CPU0_SB_CA(3)
 213 M_A_CPU0_SA_CA<3>  CA3_A @T6G_MB_LIB.T6G(SCH_1):M_A_CPU0_SA_CA(3)
  78 M_A_CPU0_SB_CA<2>  CA2_B @T6G_MB_LIB.T6G(SCH_1):M_A_CPU0_SB_CA(2)
  68 M_A_CPU0_SA_CA<2>  CA2_A @T6G_MB_LIB.T6G(SCH_1):M_A_CPU0_SA_CA(2)
 221 M_A_CPU0_SB_CA<1>  CA1_B @T6G_MB_LIB.T6G(SCH_1):M_A_CPU0_SB_CA(1)
 211 M_A_CPU0_SA_CA<1>  CA1_A @T6G_MB_LIB.T6G(SCH_1):M_A_CPU0_SA_CA(1)
  76 M_A_CPU0_SB_CA<0>  CA0_B @T6G_MB_LIB.T6G(SCH_1):M_A_CPU0_SB_CA(0)
  66 M_A_CPU0_SA_CA<0>  CA0_A @T6G_MB_LIB.T6G(SCH_1):M_A_CPU0_SA_CA(0)
  62 M_A_CPU0_ALERT_N ALERT_N @T6G_MB_LIB.T6G(SCH_1):M_A_CPU0_ALERT_N
 236 M_A_CPU0_SB_CB<7>  CB7_B @T6G_MB_LIB.T6G(SCH_1):M_A_CPU0_SB_CB(7)
  53 M_A_CPU0_SA_CB<1>  CB1_A @T6G_MB_LIB.T6G(SCH_1):M_A_CPU0_SA_CB(1)
  58 M_A_CPU0_SA_CB<4>  CB4_A @T6G_MB_LIB.T6G(SCH_1):M_A_CPU0_SA_CB(4)
 205 M_A_CPU0_SA_CB<7>  CB7_A @T6G_MB_LIB.T6G(SCH_1):M_A_CPU0_SA_CB(7)
 194 M_A_CPU0_SA_DQ<31> DQ31_A @T6G_MB_LIB.T6G(SCH_1):M_A_CPU0_SA_DQ(31)

SCONN288_DDR506112002KQ-SCONN288_DDR506112002KQ,SMA  I537  J1
  93 M_A_CPU0_SB_DQS_DP<9> DQS9_B_T||TDQS9_B_T||DBI4_B_N @T6G_MB_LIB.T6G(SCH_1):M_A_CPU0_SB_DQS_DP(9)
  94 M_A_CPU0_SB_DQS_DN<9> DQS9_B_C||TDQS9_B_C @T6G_MB_LIB.T6G(SCH_1):M_A_CPU0_SB_DQS_DN(9)
 201 M_A_CPU0_SA_DQS_DP<9> DQS9_A_T||TDQS9_A_T @T6G_MB_LIB.T6G(SCH_1):M_A_CPU0_SA_DQS_DP(9)
 200 M_A_CPU0_SA_DQS_DN<9> DQS9_A_C||TDQS9_A_C @T6G_MB_LIB.T6G(SCH_1):M_A_CPU0_SA_DQS_DN(9)
 190 M_A_CPU0_SA_DQS_DP<8> DQS8_A_T||TDQS8_A_T @T6G_MB_LIB.T6G(SCH_1):M_A_CPU0_SA_DQS_DP(8)
 189 M_A_CPU0_SA_DQS_DN<8> DQS8_A_C||TDQS8_A_C @T6G_MB_LIB.T6G(SCH_1):M_A_CPU0_SA_DQS_DN(8)
 271 M_A_CPU0_SB_DQS_DN<7> DQS7_B_C||TDQS7_B_C @T6G_MB_LIB.T6G(SCH_1):M_A_CPU0_SB_DQS_DN(7)
 179 M_A_CPU0_SA_DQS_DP<7> DQS7_A_T||TDQS7_A_T @T6G_MB_LIB.T6G(SCH_1):M_A_CPU0_SA_DQS_DP(7)
 261 M_A_CPU0_SB_DQS_DP<6> DQS6_B_T||TDQS6_B_T @T6G_MB_LIB.T6G(SCH_1):M_A_CPU0_SB_DQS_DP(6)
 260 M_A_CPU0_SB_DQS_DN<6> DQS6_B_C||TDQS6_B_C @T6G_MB_LIB.T6G(SCH_1):M_A_CPU0_SB_DQS_DN(6)
 167 M_A_CPU0_SA_DQS_DN<6> DQS6_A_C||TDQS6_A_C||DQS6_A_T||TDQS6_A_T @T6G_MB_LIB.T6G(SCH_1):M_A_CPU0_SA_DQS_DN(6)
 250 M_A_CPU0_SB_DQS_DP<5> DQS5_B_T||TDQS5_B_T @T6G_MB_LIB.T6G(SCH_1):M_A_CPU0_SB_DQS_DP(5)
 249 M_A_CPU0_SB_DQS_DN<5> DQS5_B_C||TDQS5_B_C @T6G_MB_LIB.T6G(SCH_1):M_A_CPU0_SB_DQS_DN(5)
 157 M_A_CPU0_SA_DQS_DP<5> DQS5_A_T||TDQS5_A_T @T6G_MB_LIB.T6G(SCH_1):M_A_CPU0_SA_DQS_DP(5)
 156 M_A_CPU0_SA_DQS_DN<5> DQS5_A_C||TDQS5_A_C||DQS5_A_T||TDQS5_A_T @T6G_MB_LIB.T6G(SCH_1):M_A_CPU0_SA_DQS_DN(5)
 239 M_A_CPU0_SB_DQS_DP<4> DQS4_B_T @T6G_MB_LIB.T6G(SCH_1):M_A_CPU0_SB_DQS_DP(4)
 238 M_A_CPU0_SB_DQS_DN<4> DQS4_B_C @T6G_MB_LIB.T6G(SCH_1):M_A_CPU0_SB_DQS_DN(4)
  55 M_A_CPU0_SA_DQS_DP<4> DQS4_A_T @T6G_MB_LIB.T6G(SCH_1):M_A_CPU0_SA_DQS_DP(4)
  56 M_A_CPU0_SA_DQS_DN<4> DQS4_A_C @T6G_MB_LIB.T6G(SCH_1):M_A_CPU0_SA_DQS_DN(4)
 137 M_A_CPU0_SB_DQS_DP<3> DQS3_B_T @T6G_MB_LIB.T6G(SCH_1):M_A_CPU0_SB_DQS_DP(3)
 138 M_A_CPU0_SB_DQS_DN<3> DQS3_B_C @T6G_MB_LIB.T6G(SCH_1):M_A_CPU0_SB_DQS_DN(3)
  44 M_A_CPU0_SA_DQS_DP<3> DQS3_A_T @T6G_MB_LIB.T6G(SCH_1):M_A_CPU0_SA_DQS_DP(3)
  45 M_A_CPU0_SA_DQS_DN<3> DQS3_A_C @T6G_MB_LIB.T6G(SCH_1):M_A_CPU0_SA_DQS_DN(3)
 126 M_A_CPU0_SB_DQS_DP<2> DQS2_B_T @T6G_MB_LIB.T6G(SCH_1):M_A_CPU0_SB_DQS_DP(2)
 127 M_A_CPU0_SB_DQS_DN<2> DQS2_B_C @T6G_MB_LIB.T6G(SCH_1):M_A_CPU0_SB_DQS_DN(2)
  33 M_A_CPU0_SA_DQS_DP<2> DQS2_A_T @T6G_MB_LIB.T6G(SCH_1):M_A_CPU0_SA_DQS_DP(2)
  34 M_A_CPU0_SA_DQS_DN<2> DQS2_A_C @T6G_MB_LIB.T6G(SCH_1):M_A_CPU0_SA_DQS_DN(2)
 115 M_A_CPU0_SB_DQS_DP<1> DQS1_B_T @T6G_MB_LIB.T6G(SCH_1):M_A_CPU0_SB_DQS_DP(1)
 116 M_A_CPU0_SB_DQS_DN<1> DQS1_B_C @T6G_MB_LIB.T6G(SCH_1):M_A_CPU0_SB_DQS_DN(1)
  22 M_A_CPU0_SA_DQS_DP<1> DQS1_A_T @T6G_MB_LIB.T6G(SCH_1):M_A_CPU0_SA_DQS_DP(1)
  23 M_A_CPU0_SA_DQS_DN<1> DQS1_A_C @T6G_MB_LIB.T6G(SCH_1):M_A_CPU0_SA_DQS_DN(1)
 104 M_A_CPU0_SB_DQS_DP<0> DQS0_B_T @T6G_MB_LIB.T6G(SCH_1):M_A_CPU0_SB_DQS_DP(0)
 105 M_A_CPU0_SB_DQS_DN<0> DQS0_B_C @T6G_MB_LIB.T6G(SCH_1):M_A_CPU0_SB_DQS_DN(0)
  11 M_A_CPU0_SA_DQS_DP<0> DQS0_A_T @T6G_MB_LIB.T6G(SCH_1):M_A_CPU0_SA_DQS_DP(0)
  12 M_A_CPU0_SA_DQS_DN<0> DQS0_A_C @T6G_MB_LIB.T6G(SCH_1):M_A_CPU0_SA_DQS_DN(0)
 272 M_A_CPU0_SB_DQS_DP<7> DQS7_B_T||TDQS7_B_T @T6G_MB_LIB.T6G(SCH_1):M_A_CPU0_SB_DQS_DP(7)
 282 M_A_CPU0_SB_DQS_DN<8> DQS8_B_C||TDQS8_B_C @T6G_MB_LIB.T6G(SCH_1):M_A_CPU0_SB_DQS_DN(8)
 283 M_A_CPU0_SB_DQS_DP<8> DQS8_B_T||TDQS8_B_T @T6G_MB_LIB.T6G(SCH_1):M_A_CPU0_SB_DQS_DP(8)
 168 M_A_CPU0_SA_DQS_DP<6> DQS6_A_T||TDQS6_A_T @T6G_MB_LIB.T6G(SCH_1):M_A_CPU0_SA_DQS_DP(6)
 178 M_A_CPU0_SA_DQS_DN<7> DQS7_A_C||TDQS7_A_C @T6G_MB_LIB.T6G(SCH_1):M_A_CPU0_SA_DQS_DN(7)

SCONN288_DDR506112002KQ-SCONN288_DDR506112002KQ,SMA  I538  J1
   6    GND   VSS0 @T6G_MB_LIB.T6G(SCH_1):GND
   8    GND   VSS1 @T6G_MB_LIB.T6G(SCH_1):GND
  10    GND   VSS2 @T6G_MB_LIB.T6G(SCH_1):GND
  13    GND   VSS3 @T6G_MB_LIB.T6G(SCH_1):GND
  15    GND   VSS4 @T6G_MB_LIB.T6G(SCH_1):GND
  17    GND   VSS5 @T6G_MB_LIB.T6G(SCH_1):GND
  19    GND   VSS6 @T6G_MB_LIB.T6G(SCH_1):GND
  21    GND   VSS7 @T6G_MB_LIB.T6G(SCH_1):GND
  24    GND   VSS8 @T6G_MB_LIB.T6G(SCH_1):GND
  26    GND   VSS9 @T6G_MB_LIB.T6G(SCH_1):GND
  28    GND  VSS10 @T6G_MB_LIB.T6G(SCH_1):GND
  30    GND  VSS11 @T6G_MB_LIB.T6G(SCH_1):GND
  32    GND  VSS12 @T6G_MB_LIB.T6G(SCH_1):GND
  35    GND  VSS13 @T6G_MB_LIB.T6G(SCH_1):GND
  37    GND  VSS14 @T6G_MB_LIB.T6G(SCH_1):GND
  39    GND  VSS15 @T6G_MB_LIB.T6G(SCH_1):GND
  41    GND  VSS16 @T6G_MB_LIB.T6G(SCH_1):GND
  43    GND  VSS17 @T6G_MB_LIB.T6G(SCH_1):GND
  46    GND  VSS18 @T6G_MB_LIB.T6G(SCH_1):GND
  48    GND  VSS19 @T6G_MB_LIB.T6G(SCH_1):GND
  50    GND  VSS20 @T6G_MB_LIB.T6G(SCH_1):GND
  52    GND  VSS21 @T6G_MB_LIB.T6G(SCH_1):GND
  54    GND  VSS22 @T6G_MB_LIB.T6G(SCH_1):GND
  57    GND  VSS23 @T6G_MB_LIB.T6G(SCH_1):GND
  59    GND  VSS24 @T6G_MB_LIB.T6G(SCH_1):GND
  61    GND  VSS25 @T6G_MB_LIB.T6G(SCH_1):GND
  63    GND  VSS26 @T6G_MB_LIB.T6G(SCH_1):GND
  65    GND  VSS27 @T6G_MB_LIB.T6G(SCH_1):GND
  67    GND  VSS28 @T6G_MB_LIB.T6G(SCH_1):GND
  69    GND  VSS29 @T6G_MB_LIB.T6G(SCH_1):GND
  71    GND  VSS30 @T6G_MB_LIB.T6G(SCH_1):GND
  73    GND  VSS31 @T6G_MB_LIB.T6G(SCH_1):GND
  75    GND  VSS32 @T6G_MB_LIB.T6G(SCH_1):GND
  77    GND  VSS33 @T6G_MB_LIB.T6G(SCH_1):GND
  79    GND  VSS34 @T6G_MB_LIB.T6G(SCH_1):GND
  81    GND  VSS35 @T6G_MB_LIB.T6G(SCH_1):GND
  83    GND  VSS36 @T6G_MB_LIB.T6G(SCH_1):GND
  85    GND  VSS37 @T6G_MB_LIB.T6G(SCH_1):GND
  88    GND  VSS38 @T6G_MB_LIB.T6G(SCH_1):GND
  90    GND  VSS39 @T6G_MB_LIB.T6G(SCH_1):GND
  92    GND  VSS40 @T6G_MB_LIB.T6G(SCH_1):GND
  95    GND  VSS41 @T6G_MB_LIB.T6G(SCH_1):GND
  97    GND  VSS42 @T6G_MB_LIB.T6G(SCH_1):GND
  99    GND  VSS43 @T6G_MB_LIB.T6G(SCH_1):GND
 101    GND  VSS44 @T6G_MB_LIB.T6G(SCH_1):GND
 103    GND  VSS45 @T6G_MB_LIB.T6G(SCH_1):GND
 106    GND  VSS46 @T6G_MB_LIB.T6G(SCH_1):GND
 108    GND  VSS47 @T6G_MB_LIB.T6G(SCH_1):GND
 110    GND  VSS48 @T6G_MB_LIB.T6G(SCH_1):GND
 112    GND  VSS49 @T6G_MB_LIB.T6G(SCH_1):GND
 114    GND  VSS50 @T6G_MB_LIB.T6G(SCH_1):GND
 117    GND  VSS51 @T6G_MB_LIB.T6G(SCH_1):GND
 119    GND  VSS52 @T6G_MB_LIB.T6G(SCH_1):GND
 121    GND  VSS53 @T6G_MB_LIB.T6G(SCH_1):GND
 123    GND  VSS54 @T6G_MB_LIB.T6G(SCH_1):GND
 125    GND  VSS55 @T6G_MB_LIB.T6G(SCH_1):GND
 128    GND  VSS56 @T6G_MB_LIB.T6G(SCH_1):GND
 130    GND  VSS57 @T6G_MB_LIB.T6G(SCH_1):GND
 134    GND  VSS59 @T6G_MB_LIB.T6G(SCH_1):GND
 143    GND  VSS63 @T6G_MB_LIB.T6G(SCH_1):GND
 151    GND  VSS64 @T6G_MB_LIB.T6G(SCH_1):GND
 153    GND  VSS65 @T6G_MB_LIB.T6G(SCH_1):GND
 155    GND  VSS66 @T6G_MB_LIB.T6G(SCH_1):GND
 158    GND  VSS67 @T6G_MB_LIB.T6G(SCH_1):GND
 160    GND  VSS68 @T6G_MB_LIB.T6G(SCH_1):GND
 162    GND  VSS69 @T6G_MB_LIB.T6G(SCH_1):GND
 164    GND  VSS70 @T6G_MB_LIB.T6G(SCH_1):GND
 166    GND  VSS71 @T6G_MB_LIB.T6G(SCH_1):GND
 169    GND  VSS72 @T6G_MB_LIB.T6G(SCH_1):GND
 171    GND  VSS73 @T6G_MB_LIB.T6G(SCH_1):GND
 173    GND  VSS74 @T6G_MB_LIB.T6G(SCH_1):GND
 175    GND  VSS75 @T6G_MB_LIB.T6G(SCH_1):GND
 177    GND  VSS76 @T6G_MB_LIB.T6G(SCH_1):GND
 180    GND  VSS77 @T6G_MB_LIB.T6G(SCH_1):GND
 182    GND  VSS78 @T6G_MB_LIB.T6G(SCH_1):GND
 184    GND  VSS79 @T6G_MB_LIB.T6G(SCH_1):GND
 186    GND  VSS80 @T6G_MB_LIB.T6G(SCH_1):GND
 188    GND  VSS81 @T6G_MB_LIB.T6G(SCH_1):GND
 191    GND  VSS82 @T6G_MB_LIB.T6G(SCH_1):GND
 193    GND  VSS83 @T6G_MB_LIB.T6G(SCH_1):GND
 195    GND  VSS84 @T6G_MB_LIB.T6G(SCH_1):GND
 197    GND  VSS85 @T6G_MB_LIB.T6G(SCH_1):GND
 199    GND  VSS86 @T6G_MB_LIB.T6G(SCH_1):GND
 202    GND  VSS87 @T6G_MB_LIB.T6G(SCH_1):GND
 204    GND  VSS88 @T6G_MB_LIB.T6G(SCH_1):GND
 206    GND  VSS89 @T6G_MB_LIB.T6G(SCH_1):GND
 208    GND  VSS90 @T6G_MB_LIB.T6G(SCH_1):GND
 210    GND  VSS91 @T6G_MB_LIB.T6G(SCH_1):GND
 212    GND  VSS92 @T6G_MB_LIB.T6G(SCH_1):GND
 214    GND  VSS93 @T6G_MB_LIB.T6G(SCH_1):GND
 216    GND  VSS94 @T6G_MB_LIB.T6G(SCH_1):GND
 219    GND  VSS95 @T6G_MB_LIB.T6G(SCH_1):GND
 222    GND  VSS96 @T6G_MB_LIB.T6G(SCH_1):GND
 224    GND  VSS97 @T6G_MB_LIB.T6G(SCH_1):GND
 226    GND  VSS98 @T6G_MB_LIB.T6G(SCH_1):GND
 228    GND  VSS99 @T6G_MB_LIB.T6G(SCH_1):GND
 233    GND VSS101 @T6G_MB_LIB.T6G(SCH_1):GND
 237    GND VSS103 @T6G_MB_LIB.T6G(SCH_1):GND
 242    GND VSS105 @T6G_MB_LIB.T6G(SCH_1):GND
 244    GND VSS106 @T6G_MB_LIB.T6G(SCH_1):GND
 246    GND VSS107 @T6G_MB_LIB.T6G(SCH_1):GND
 248    GND VSS108 @T6G_MB_LIB.T6G(SCH_1):GND
 251    GND VSS109 @T6G_MB_LIB.T6G(SCH_1):GND
 253    GND VSS110 @T6G_MB_LIB.T6G(SCH_1):GND
 255    GND VSS111 @T6G_MB_LIB.T6G(SCH_1):GND
 257    GND VSS112 @T6G_MB_LIB.T6G(SCH_1):GND
 259    GND VSS113 @T6G_MB_LIB.T6G(SCH_1):GND
 262    GND VSS114 @T6G_MB_LIB.T6G(SCH_1):GND
 264    GND VSS115 @T6G_MB_LIB.T6G(SCH_1):GND
 266    GND VSS116 @T6G_MB_LIB.T6G(SCH_1):GND
 268    GND VSS117 @T6G_MB_LIB.T6G(SCH_1):GND
 270    GND VSS118 @T6G_MB_LIB.T6G(SCH_1):GND
 273    GND VSS119 @T6G_MB_LIB.T6G(SCH_1):GND
 275    GND VSS120 @T6G_MB_LIB.T6G(SCH_1):GND
 277    GND VSS121 @T6G_MB_LIB.T6G(SCH_1):GND
 279    GND VSS122 @T6G_MB_LIB.T6G(SCH_1):GND
 281    GND VSS123 @T6G_MB_LIB.T6G(SCH_1):GND
 284    GND VSS124 @T6G_MB_LIB.T6G(SCH_1):GND
 286    GND VSS125 @T6G_MB_LIB.T6G(SCH_1):GND
 288    GND VSS126 @T6G_MB_LIB.T6G(SCH_1):GND
   1 P12V_MEM_CPU0 VIN_BULK0 @T6G_MB_LIB.T6G(SCH_1):P12V_MEM_CPU0
 145 P12V_MEM_CPU0 VIN_BULK1 @T6G_MB_LIB.T6G(SCH_1):P12V_MEM_CPU0
 146 P12V_MEM_CPU0 VIN_BULK2 @T6G_MB_LIB.T6G(SCH_1):P12V_MEM_CPU0
 230    GND VSS100 @T6G_MB_LIB.T6G(SCH_1):GND
 235    GND VSS102 @T6G_MB_LIB.T6G(SCH_1):GND
 240    GND VSS104 @T6G_MB_LIB.T6G(SCH_1):GND
 132    GND  VSS58 @T6G_MB_LIB.T6G(SCH_1):GND
 136    GND  VSS60 @T6G_MB_LIB.T6G(SCH_1):GND
 139    GND  VSS61 @T6G_MB_LIB.T6G(SCH_1):GND
 141    GND  VSS62 @T6G_MB_LIB.T6G(SCH_1):GND
  G1    GND     G1 @T6G_MB_LIB.T6G(SCH_1):GND
  G2    GND     G2 @T6G_MB_LIB.T6G(SCH_1):GND
  G3    GND     G3 @T6G_MB_LIB.T6G(SCH_1):GND

Q_RES_0402LF-49.9,1%,1/16W,CHIP,CS04992FB07  I539  R1568
   1 I3C_SPD_DDRAF_CPU0_SCL      A @T6G_MB_LIB.T6G(SCH_1):I3C_SPD_DDRAF_CPU0_SCL
   2 I3C_SPD_DDRA_CPU0_SCL      B @T6G_MB_LIB.T6G(SCH_1):I3C_SPD_DDRA_CPU0_SCL

Q_RES_0402LF-10K,1%,1/16W,CHIP,CS31002FB08  I540  R8037
   1 P3V3_AUX      A @T6G_MB_LIB.T6G(SCH_1):P3V3_AUX
   2 PWRGD_CHAF_CPU0      B @T6G_MB_LIB.T6G(SCH_1):PWRGD_CHAF_CPU0

Q_RES_0402LF-0,5%,1/16W,CHIP,CS00002JB13  I544  R8080
   1 PWRGD_CHAF_CPU0      A @T6G_MB_LIB.T6G(SCH_1):PWRGD_CHAF_CPU0
   2 PWRGD_CHAF_CPU0_R1      B @T6G_MB_LIB.T6G(SCH_1):PWRGD_CHAF_CPU0_R1

Q_RES_0402LF-0,5%,1/16W,CHIP,CS00002JB13  I545  R8081
   1 PWRGD_CHAF_CPU0_R1      A @T6G_MB_LIB.T6G(SCH_1):PWRGD_CHAF_CPU0_R1
   2 PWRGD_CHAF_CPU0_R2      B @T6G_MB_LIB.T6G(SCH_1):PWRGD_CHAF_CPU0_R2

Q_RES_0402LF-10K,1%,1/16W,EMPTY,CS31002FB08  I547  R8082
   1 P3V3_AUX      A @T6G_MB_LIB.T6G(SCH_1):P3V3_AUX
   2 PWRGD_CHAF_CPU0_R1      B @T6G_MB_LIB.T6G(SCH_1):PWRGD_CHAF_CPU0_R1

SCHOTTKY_12-B0530WS7F,SMLF,EMPTY,BC000530Z41  I549  D8003
   1 PWRGD_CHAF_CPU0_R1      A @T6G_MB_LIB.T6G(SCH_1):PWRGD_CHAF_CPU0_R1
   2 P3V3_AUX      C @T6G_MB_LIB.T6G(SCH_1):P3V3_AUX

Q_RES_0402LF-10,1%,1/16W,CHIP,CS01002FB07  I554  R1674
   1 I3C_SPD_DDRAF_CPU0_SDA      A @T6G_MB_LIB.T6G(SCH_1):I3C_SPD_DDRAF_CPU0_SDA
   2 I3C_SPD_DDRA_CPU0_SDA      B @T6G_MB_LIB.T6G(SCH_1):I3C_SPD_DDRA_CPU0_SDA


DRAWING: @T6G_MB_LIB.T6G(SCH_1):PAGE86 

Q_RES_0402LF-15.4K,1%,1/16W,CHIP,CS31542FB02  I349  R761
   1 PD_CHB_CPU0_DIMM_SAA      A @T6G_MB_LIB.T6G(SCH_1):PD_CHB_CPU0_DIMM_SAA
   2    GND      B @T6G_MB_LIB.T6G(SCH_1):GND

SCONN288_DDR506112002KQ-SCONN288_DDR506112002KQ,SMA  I350  J15
   3 P3V3_AUX VIN_MGMT @T6G_MB_LIB.T6G(SCH_1):P3V3_AUX
   2     NC   RFU0     NC
 144     NC   RFU1     NC
 149     NC   RFU2     NC
 150     NC   RFU3     NC
 220     NC   RFU4     NC
 231     NC   RFU5     NC
 232     NC   RFU6     NC
 207 M_B_CPU0_RESET_N RESET_N @T6G_MB_LIB.T6G(SCH_1):M_B_CPU0_RESET_N
 147 PWRGD_CHB_CPU0_DIMM PWR_GOOD||FAIL_N @T6G_MB_LIB.T6G(SCH_1):PWRGD_CHB_CPU0_DIMM
 227 M_B_CPU0_SB_PAR  PAR_B @T6G_MB_LIB.T6G(SCH_1):M_B_CPU0_SB_PAR
  74 M_B_CPU0_SA_PAR  PAR_A @T6G_MB_LIB.T6G(SCH_1):M_B_CPU0_SA_PAR
  87 M_B_CPU0_SB_RSP<0> LBS||RSP_B_N @T6G_MB_LIB.T6G(SCH_1):M_B_CPU0_SB_RSP(0)
  86 M_B_CPU0_SA_RSP<0> LBD||RSP_A_N @T6G_MB_LIB.T6G(SCH_1):M_B_CPU0_SA_RSP(0)
   5 I3C_SPD_DDRB_CPU0_SDA   HSDA @T6G_MB_LIB.T6G(SCH_1):I3C_SPD_DDRB_CPU0_SDA
   4 I3C_SPD_DDRB_CPU0_SCL   HSCL @T6G_MB_LIB.T6G(SCH_1):I3C_SPD_DDRB_CPU0_SCL
 148 PD_CHB_CPU0_DIMM_SAA    HAS @T6G_MB_LIB.T6G(SCH_1):PD_CHB_CPU0_DIMM_SAA
 100 M_B_CPU0_SB_DQ<0>  DQ0_B @T6G_MB_LIB.T6G(SCH_1):M_B_CPU0_SB_DQ(0)
 102 M_B_CPU0_SB_DQ<1>  DQ1_B @T6G_MB_LIB.T6G(SCH_1):M_B_CPU0_SB_DQ(1)
 245 M_B_CPU0_SB_DQ<2>  DQ2_B @T6G_MB_LIB.T6G(SCH_1):M_B_CPU0_SB_DQ(2)
 247 M_B_CPU0_SB_DQ<3>  DQ3_B @T6G_MB_LIB.T6G(SCH_1):M_B_CPU0_SB_DQ(3)
 107 M_B_CPU0_SB_DQ<4>  DQ4_B @T6G_MB_LIB.T6G(SCH_1):M_B_CPU0_SB_DQ(4)
 109 M_B_CPU0_SB_DQ<5>  DQ5_B @T6G_MB_LIB.T6G(SCH_1):M_B_CPU0_SB_DQ(5)
 252 M_B_CPU0_SB_DQ<6>  DQ6_B @T6G_MB_LIB.T6G(SCH_1):M_B_CPU0_SB_DQ(6)
 254 M_B_CPU0_SB_DQ<7>  DQ7_B @T6G_MB_LIB.T6G(SCH_1):M_B_CPU0_SB_DQ(7)
 111 M_B_CPU0_SB_DQ<8>  DQ8_B @T6G_MB_LIB.T6G(SCH_1):M_B_CPU0_SB_DQ(8)
 113 M_B_CPU0_SB_DQ<9>  DQ9_B @T6G_MB_LIB.T6G(SCH_1):M_B_CPU0_SB_DQ(9)
 256 M_B_CPU0_SB_DQ<10> DQ10_B @T6G_MB_LIB.T6G(SCH_1):M_B_CPU0_SB_DQ(10)
 258 M_B_CPU0_SB_DQ<11> DQ11_B @T6G_MB_LIB.T6G(SCH_1):M_B_CPU0_SB_DQ(11)
 118 M_B_CPU0_SB_DQ<12> DQ12_B @T6G_MB_LIB.T6G(SCH_1):M_B_CPU0_SB_DQ(12)
 120 M_B_CPU0_SB_DQ<13> DQ13_B @T6G_MB_LIB.T6G(SCH_1):M_B_CPU0_SB_DQ(13)
 263 M_B_CPU0_SB_DQ<14> DQ14_B @T6G_MB_LIB.T6G(SCH_1):M_B_CPU0_SB_DQ(14)
 265 M_B_CPU0_SB_DQ<15> DQ15_B @T6G_MB_LIB.T6G(SCH_1):M_B_CPU0_SB_DQ(15)
 122 M_B_CPU0_SB_DQ<16> DQ16_B @T6G_MB_LIB.T6G(SCH_1):M_B_CPU0_SB_DQ(16)
 124 M_B_CPU0_SB_DQ<17> DQ17_B @T6G_MB_LIB.T6G(SCH_1):M_B_CPU0_SB_DQ(17)
 267 M_B_CPU0_SB_DQ<18> DQ18_B @T6G_MB_LIB.T6G(SCH_1):M_B_CPU0_SB_DQ(18)
 269 M_B_CPU0_SB_DQ<19> DQ19_B @T6G_MB_LIB.T6G(SCH_1):M_B_CPU0_SB_DQ(19)
 129 M_B_CPU0_SB_DQ<20> DQ20_B @T6G_MB_LIB.T6G(SCH_1):M_B_CPU0_SB_DQ(20)
 131 M_B_CPU0_SB_DQ<21> DQ21_B @T6G_MB_LIB.T6G(SCH_1):M_B_CPU0_SB_DQ(21)
 274 M_B_CPU0_SB_DQ<22> DQ22_B @T6G_MB_LIB.T6G(SCH_1):M_B_CPU0_SB_DQ(22)
 276 M_B_CPU0_SB_DQ<23> DQ23_B @T6G_MB_LIB.T6G(SCH_1):M_B_CPU0_SB_DQ(23)
 133 M_B_CPU0_SB_DQ<24> DQ24_B @T6G_MB_LIB.T6G(SCH_1):M_B_CPU0_SB_DQ(24)
 135 M_B_CPU0_SB_DQ<25> DQ25_B @T6G_MB_LIB.T6G(SCH_1):M_B_CPU0_SB_DQ(25)
 278 M_B_CPU0_SB_DQ<26> DQ26_B @T6G_MB_LIB.T6G(SCH_1):M_B_CPU0_SB_DQ(26)
 280 M_B_CPU0_SB_DQ<27> DQ27_B @T6G_MB_LIB.T6G(SCH_1):M_B_CPU0_SB_DQ(27)
 140 M_B_CPU0_SB_DQ<28> DQ28_B @T6G_MB_LIB.T6G(SCH_1):M_B_CPU0_SB_DQ(28)
 142 M_B_CPU0_SB_DQ<29> DQ29_B @T6G_MB_LIB.T6G(SCH_1):M_B_CPU0_SB_DQ(29)
 285 M_B_CPU0_SB_DQ<30> DQ30_B @T6G_MB_LIB.T6G(SCH_1):M_B_CPU0_SB_DQ(30)
 287 M_B_CPU0_SB_DQ<31> DQ31_B @T6G_MB_LIB.T6G(SCH_1):M_B_CPU0_SB_DQ(31)
   7 M_B_CPU0_SA_DQ<0>  DQ0_A @T6G_MB_LIB.T6G(SCH_1):M_B_CPU0_SA_DQ(0)
   9 M_B_CPU0_SA_DQ<1>  DQ1_A @T6G_MB_LIB.T6G(SCH_1):M_B_CPU0_SA_DQ(1)
 152 M_B_CPU0_SA_DQ<2>  DQ2_A @T6G_MB_LIB.T6G(SCH_1):M_B_CPU0_SA_DQ(2)
 154 M_B_CPU0_SA_DQ<3>  DQ3_A @T6G_MB_LIB.T6G(SCH_1):M_B_CPU0_SA_DQ(3)
  14 M_B_CPU0_SA_DQ<4>  DQ4_A @T6G_MB_LIB.T6G(SCH_1):M_B_CPU0_SA_DQ(4)
  16 M_B_CPU0_SA_DQ<5>  DQ5_A @T6G_MB_LIB.T6G(SCH_1):M_B_CPU0_SA_DQ(5)
 159 M_B_CPU0_SA_DQ<6>  DQ6_A @T6G_MB_LIB.T6G(SCH_1):M_B_CPU0_SA_DQ(6)
 161 M_B_CPU0_SA_DQ<7>  DQ7_A @T6G_MB_LIB.T6G(SCH_1):M_B_CPU0_SA_DQ(7)
  18 M_B_CPU0_SA_DQ<8>  DQ8_A @T6G_MB_LIB.T6G(SCH_1):M_B_CPU0_SA_DQ(8)
  20 M_B_CPU0_SA_DQ<9>  DQ9_A @T6G_MB_LIB.T6G(SCH_1):M_B_CPU0_SA_DQ(9)
 163 M_B_CPU0_SA_DQ<10> DQ10_A @T6G_MB_LIB.T6G(SCH_1):M_B_CPU0_SA_DQ(10)
 165 M_B_CPU0_SA_DQ<11> DQ11_A @T6G_MB_LIB.T6G(SCH_1):M_B_CPU0_SA_DQ(11)
  25 M_B_CPU0_SA_DQ<12> DQ12_A @T6G_MB_LIB.T6G(SCH_1):M_B_CPU0_SA_DQ(12)
  27 M_B_CPU0_SA_DQ<13> DQ13_A @T6G_MB_LIB.T6G(SCH_1):M_B_CPU0_SA_DQ(13)
 170 M_B_CPU0_SA_DQ<14> DQ14_A @T6G_MB_LIB.T6G(SCH_1):M_B_CPU0_SA_DQ(14)
 172 M_B_CPU0_SA_DQ<15> DQ15_A @T6G_MB_LIB.T6G(SCH_1):M_B_CPU0_SA_DQ(15)
  29 M_B_CPU0_SA_DQ<16> DQ16_A @T6G_MB_LIB.T6G(SCH_1):M_B_CPU0_SA_DQ(16)
  31 M_B_CPU0_SA_DQ<17> DQ17_A @T6G_MB_LIB.T6G(SCH_1):M_B_CPU0_SA_DQ(17)
 174 M_B_CPU0_SA_DQ<18> DQ18_A @T6G_MB_LIB.T6G(SCH_1):M_B_CPU0_SA_DQ(18)
 176 M_B_CPU0_SA_DQ<19> DQ19_A @T6G_MB_LIB.T6G(SCH_1):M_B_CPU0_SA_DQ(19)
  36 M_B_CPU0_SA_DQ<20> DQ20_A @T6G_MB_LIB.T6G(SCH_1):M_B_CPU0_SA_DQ(20)
  38 M_B_CPU0_SA_DQ<21> DQ21_A @T6G_MB_LIB.T6G(SCH_1):M_B_CPU0_SA_DQ(21)
 181 M_B_CPU0_SA_DQ<22> DQ22_A @T6G_MB_LIB.T6G(SCH_1):M_B_CPU0_SA_DQ(22)
 183 M_B_CPU0_SA_DQ<23> DQ23_A @T6G_MB_LIB.T6G(SCH_1):M_B_CPU0_SA_DQ(23)
  40 M_B_CPU0_SA_DQ<24> DQ24_A @T6G_MB_LIB.T6G(SCH_1):M_B_CPU0_SA_DQ(24)
  42 M_B_CPU0_SA_DQ<25> DQ25_A @T6G_MB_LIB.T6G(SCH_1):M_B_CPU0_SA_DQ(25)
 185 M_B_CPU0_SA_DQ<26> DQ26_A @T6G_MB_LIB.T6G(SCH_1):M_B_CPU0_SA_DQ(26)
 187 M_B_CPU0_SA_DQ<27> DQ27_A @T6G_MB_LIB.T6G(SCH_1):M_B_CPU0_SA_DQ(27)
  47 M_B_CPU0_SA_DQ<28> DQ28_A @T6G_MB_LIB.T6G(SCH_1):M_B_CPU0_SA_DQ(28)
  49 M_B_CPU0_SA_DQ<29> DQ29_A @T6G_MB_LIB.T6G(SCH_1):M_B_CPU0_SA_DQ(29)
 192 M_B_CPU0_SA_DQ<30> DQ30_A @T6G_MB_LIB.T6G(SCH_1):M_B_CPU0_SA_DQ(30)
 229 M_B_CPU0_SB_CS_N<1> CS1_B_N @T6G_MB_LIB.T6G(SCH_1):M_B_CPU0_SB_CS_N(1)
 209 M_B_CPU0_SA_CS_N<1> CS1_A_N @T6G_MB_LIB.T6G(SCH_1):M_B_CPU0_SA_CS_N(1)
  84 M_B_CPU0_SB_CS_N<0> CS0_B_N @T6G_MB_LIB.T6G(SCH_1):M_B_CPU0_SB_CS_N(0)
  64 M_B_CPU0_SA_CS_N<0> CS0_A_N @T6G_MB_LIB.T6G(SCH_1):M_B_CPU0_SA_CS_N(0)
 217 M_B_CPU0_CLK_DP<0>   CK_T @T6G_MB_LIB.T6G(SCH_1):M_B_CPU0_CLK_DP(0)
 218 M_B_CPU0_CLK_DN<0>   CK_C @T6G_MB_LIB.T6G(SCH_1):M_B_CPU0_CLK_DN(0)
  96 M_B_CPU0_SB_CB<0>  CB0_B @T6G_MB_LIB.T6G(SCH_1):M_B_CPU0_SB_CB(0)
  98 M_B_CPU0_SB_CB<1>  CB1_B @T6G_MB_LIB.T6G(SCH_1):M_B_CPU0_SB_CB(1)
 241 M_B_CPU0_SB_CB<2>  CB2_B @T6G_MB_LIB.T6G(SCH_1):M_B_CPU0_SB_CB(2)
 243 M_B_CPU0_SB_CB<3>  CB3_B @T6G_MB_LIB.T6G(SCH_1):M_B_CPU0_SB_CB(3)
  89 M_B_CPU0_SB_CB<4>  CB4_B @T6G_MB_LIB.T6G(SCH_1):M_B_CPU0_SB_CB(4)
  91 M_B_CPU0_SB_CB<5>  CB5_B @T6G_MB_LIB.T6G(SCH_1):M_B_CPU0_SB_CB(5)
 234 M_B_CPU0_SB_CB<6>  CB6_B @T6G_MB_LIB.T6G(SCH_1):M_B_CPU0_SB_CB(6)
  51 M_B_CPU0_SA_CB<0>  CB0_A @T6G_MB_LIB.T6G(SCH_1):M_B_CPU0_SA_CB(0)
 196 M_B_CPU0_SA_CB<2>  CB2_A @T6G_MB_LIB.T6G(SCH_1):M_B_CPU0_SA_CB(2)
 198 M_B_CPU0_SA_CB<3>  CB3_A @T6G_MB_LIB.T6G(SCH_1):M_B_CPU0_SA_CB(3)
  60 M_B_CPU0_SA_CB<5>  CB5_A @T6G_MB_LIB.T6G(SCH_1):M_B_CPU0_SA_CB(5)
 203 M_B_CPU0_SA_CB<6>  CB6_A @T6G_MB_LIB.T6G(SCH_1):M_B_CPU0_SA_CB(6)
  82 M_B_CPU0_SB_CA<6>  CA6_B @T6G_MB_LIB.T6G(SCH_1):M_B_CPU0_SB_CA(6)
  72 M_B_CPU0_SA_CA<6>  CA6_A @T6G_MB_LIB.T6G(SCH_1):M_B_CPU0_SA_CA(6)
 225 M_B_CPU0_SB_CA<5>  CA5_B @T6G_MB_LIB.T6G(SCH_1):M_B_CPU0_SB_CA(5)
 215 M_B_CPU0_SA_CA<5>  CA5_A @T6G_MB_LIB.T6G(SCH_1):M_B_CPU0_SA_CA(5)
  80 M_B_CPU0_SB_CA<4>  CA4_B @T6G_MB_LIB.T6G(SCH_1):M_B_CPU0_SB_CA(4)
  70 M_B_CPU0_SA_CA<4>  CA4_A @T6G_MB_LIB.T6G(SCH_1):M_B_CPU0_SA_CA(4)
 223 M_B_CPU0_SB_CA<3>  CA3_B @T6G_MB_LIB.T6G(SCH_1):M_B_CPU0_SB_CA(3)
 213 M_B_CPU0_SA_CA<3>  CA3_A @T6G_MB_LIB.T6G(SCH_1):M_B_CPU0_SA_CA(3)
  78 M_B_CPU0_SB_CA<2>  CA2_B @T6G_MB_LIB.T6G(SCH_1):M_B_CPU0_SB_CA(2)
  68 M_B_CPU0_SA_CA<2>  CA2_A @T6G_MB_LIB.T6G(SCH_1):M_B_CPU0_SA_CA(2)
 221 M_B_CPU0_SB_CA<1>  CA1_B @T6G_MB_LIB.T6G(SCH_1):M_B_CPU0_SB_CA(1)
 211 M_B_CPU0_SA_CA<1>  CA1_A @T6G_MB_LIB.T6G(SCH_1):M_B_CPU0_SA_CA(1)
  76 M_B_CPU0_SB_CA<0>  CA0_B @T6G_MB_LIB.T6G(SCH_1):M_B_CPU0_SB_CA(0)
  66 M_B_CPU0_SA_CA<0>  CA0_A @T6G_MB_LIB.T6G(SCH_1):M_B_CPU0_SA_CA(0)
  62 M_B_CPU0_ALERT_N ALERT_N @T6G_MB_LIB.T6G(SCH_1):M_B_CPU0_ALERT_N
 236 M_B_CPU0_SB_CB<7>  CB7_B @T6G_MB_LIB.T6G(SCH_1):M_B_CPU0_SB_CB(7)
  53 M_B_CPU0_SA_CB<1>  CB1_A @T6G_MB_LIB.T6G(SCH_1):M_B_CPU0_SA_CB(1)
  58 M_B_CPU0_SA_CB<4>  CB4_A @T6G_MB_LIB.T6G(SCH_1):M_B_CPU0_SA_CB(4)
 205 M_B_CPU0_SA_CB<7>  CB7_A @T6G_MB_LIB.T6G(SCH_1):M_B_CPU0_SA_CB(7)
 194 M_B_CPU0_SA_DQ<31> DQ31_A @T6G_MB_LIB.T6G(SCH_1):M_B_CPU0_SA_DQ(31)

SCONN288_DDR506112002KQ-SCONN288_DDR506112002KQ,SMA  I352  J15
   6    GND   VSS0 @T6G_MB_LIB.T6G(SCH_1):GND
   8    GND   VSS1 @T6G_MB_LIB.T6G(SCH_1):GND
  10    GND   VSS2 @T6G_MB_LIB.T6G(SCH_1):GND
  13    GND   VSS3 @T6G_MB_LIB.T6G(SCH_1):GND
  15    GND   VSS4 @T6G_MB_LIB.T6G(SCH_1):GND
  17    GND   VSS5 @T6G_MB_LIB.T6G(SCH_1):GND
  19    GND   VSS6 @T6G_MB_LIB.T6G(SCH_1):GND
  21    GND   VSS7 @T6G_MB_LIB.T6G(SCH_1):GND
  24    GND   VSS8 @T6G_MB_LIB.T6G(SCH_1):GND
  26    GND   VSS9 @T6G_MB_LIB.T6G(SCH_1):GND
  28    GND  VSS10 @T6G_MB_LIB.T6G(SCH_1):GND
  30    GND  VSS11 @T6G_MB_LIB.T6G(SCH_1):GND
  32    GND  VSS12 @T6G_MB_LIB.T6G(SCH_1):GND
  35    GND  VSS13 @T6G_MB_LIB.T6G(SCH_1):GND
  37    GND  VSS14 @T6G_MB_LIB.T6G(SCH_1):GND
  39    GND  VSS15 @T6G_MB_LIB.T6G(SCH_1):GND
  41    GND  VSS16 @T6G_MB_LIB.T6G(SCH_1):GND
  43    GND  VSS17 @T6G_MB_LIB.T6G(SCH_1):GND
  46    GND  VSS18 @T6G_MB_LIB.T6G(SCH_1):GND
  48    GND  VSS19 @T6G_MB_LIB.T6G(SCH_1):GND
  50    GND  VSS20 @T6G_MB_LIB.T6G(SCH_1):GND
  52    GND  VSS21 @T6G_MB_LIB.T6G(SCH_1):GND
  54    GND  VSS22 @T6G_MB_LIB.T6G(SCH_1):GND
  57    GND  VSS23 @T6G_MB_LIB.T6G(SCH_1):GND
  59    GND  VSS24 @T6G_MB_LIB.T6G(SCH_1):GND
  61    GND  VSS25 @T6G_MB_LIB.T6G(SCH_1):GND
  63    GND  VSS26 @T6G_MB_LIB.T6G(SCH_1):GND
  65    GND  VSS27 @T6G_MB_LIB.T6G(SCH_1):GND
  67    GND  VSS28 @T6G_MB_LIB.T6G(SCH_1):GND
  69    GND  VSS29 @T6G_MB_LIB.T6G(SCH_1):GND
  71    GND  VSS30 @T6G_MB_LIB.T6G(SCH_1):GND
  73    GND  VSS31 @T6G_MB_LIB.T6G(SCH_1):GND
  75    GND  VSS32 @T6G_MB_LIB.T6G(SCH_1):GND
  77    GND  VSS33 @T6G_MB_LIB.T6G(SCH_1):GND
  79    GND  VSS34 @T6G_MB_LIB.T6G(SCH_1):GND
  81    GND  VSS35 @T6G_MB_LIB.T6G(SCH_1):GND
  83    GND  VSS36 @T6G_MB_LIB.T6G(SCH_1):GND
  85    GND  VSS37 @T6G_MB_LIB.T6G(SCH_1):GND
  88    GND  VSS38 @T6G_MB_LIB.T6G(SCH_1):GND
  90    GND  VSS39 @T6G_MB_LIB.T6G(SCH_1):GND
  92    GND  VSS40 @T6G_MB_LIB.T6G(SCH_1):GND
  95    GND  VSS41 @T6G_MB_LIB.T6G(SCH_1):GND
  97    GND  VSS42 @T6G_MB_LIB.T6G(SCH_1):GND
  99    GND  VSS43 @T6G_MB_LIB.T6G(SCH_1):GND
 101    GND  VSS44 @T6G_MB_LIB.T6G(SCH_1):GND
 103    GND  VSS45 @T6G_MB_LIB.T6G(SCH_1):GND
 106    GND  VSS46 @T6G_MB_LIB.T6G(SCH_1):GND
 108    GND  VSS47 @T6G_MB_LIB.T6G(SCH_1):GND
 110    GND  VSS48 @T6G_MB_LIB.T6G(SCH_1):GND
 112    GND  VSS49 @T6G_MB_LIB.T6G(SCH_1):GND
 114    GND  VSS50 @T6G_MB_LIB.T6G(SCH_1):GND
 117    GND  VSS51 @T6G_MB_LIB.T6G(SCH_1):GND
 119    GND  VSS52 @T6G_MB_LIB.T6G(SCH_1):GND
 121    GND  VSS53 @T6G_MB_LIB.T6G(SCH_1):GND
 123    GND  VSS54 @T6G_MB_LIB.T6G(SCH_1):GND
 125    GND  VSS55 @T6G_MB_LIB.T6G(SCH_1):GND
 128    GND  VSS56 @T6G_MB_LIB.T6G(SCH_1):GND
 130    GND  VSS57 @T6G_MB_LIB.T6G(SCH_1):GND
 134    GND  VSS59 @T6G_MB_LIB.T6G(SCH_1):GND
 143    GND  VSS63 @T6G_MB_LIB.T6G(SCH_1):GND
 151    GND  VSS64 @T6G_MB_LIB.T6G(SCH_1):GND
 153    GND  VSS65 @T6G_MB_LIB.T6G(SCH_1):GND
 155    GND  VSS66 @T6G_MB_LIB.T6G(SCH_1):GND
 158    GND  VSS67 @T6G_MB_LIB.T6G(SCH_1):GND
 160    GND  VSS68 @T6G_MB_LIB.T6G(SCH_1):GND
 162    GND  VSS69 @T6G_MB_LIB.T6G(SCH_1):GND
 164    GND  VSS70 @T6G_MB_LIB.T6G(SCH_1):GND
 166    GND  VSS71 @T6G_MB_LIB.T6G(SCH_1):GND
 169    GND  VSS72 @T6G_MB_LIB.T6G(SCH_1):GND
 171    GND  VSS73 @T6G_MB_LIB.T6G(SCH_1):GND
 173    GND  VSS74 @T6G_MB_LIB.T6G(SCH_1):GND
 175    GND  VSS75 @T6G_MB_LIB.T6G(SCH_1):GND
 177    GND  VSS76 @T6G_MB_LIB.T6G(SCH_1):GND
 180    GND  VSS77 @T6G_MB_LIB.T6G(SCH_1):GND
 182    GND  VSS78 @T6G_MB_LIB.T6G(SCH_1):GND
 184    GND  VSS79 @T6G_MB_LIB.T6G(SCH_1):GND
 186    GND  VSS80 @T6G_MB_LIB.T6G(SCH_1):GND
 188    GND  VSS81 @T6G_MB_LIB.T6G(SCH_1):GND
 191    GND  VSS82 @T6G_MB_LIB.T6G(SCH_1):GND
 193    GND  VSS83 @T6G_MB_LIB.T6G(SCH_1):GND
 195    GND  VSS84 @T6G_MB_LIB.T6G(SCH_1):GND
 197    GND  VSS85 @T6G_MB_LIB.T6G(SCH_1):GND
 199    GND  VSS86 @T6G_MB_LIB.T6G(SCH_1):GND
 202    GND  VSS87 @T6G_MB_LIB.T6G(SCH_1):GND
 204    GND  VSS88 @T6G_MB_LIB.T6G(SCH_1):GND
 206    GND  VSS89 @T6G_MB_LIB.T6G(SCH_1):GND
 208    GND  VSS90 @T6G_MB_LIB.T6G(SCH_1):GND
 210    GND  VSS91 @T6G_MB_LIB.T6G(SCH_1):GND
 212    GND  VSS92 @T6G_MB_LIB.T6G(SCH_1):GND
 214    GND  VSS93 @T6G_MB_LIB.T6G(SCH_1):GND
 216    GND  VSS94 @T6G_MB_LIB.T6G(SCH_1):GND
 219    GND  VSS95 @T6G_MB_LIB.T6G(SCH_1):GND
 222    GND  VSS96 @T6G_MB_LIB.T6G(SCH_1):GND
 224    GND  VSS97 @T6G_MB_LIB.T6G(SCH_1):GND
 226    GND  VSS98 @T6G_MB_LIB.T6G(SCH_1):GND
 228    GND  VSS99 @T6G_MB_LIB.T6G(SCH_1):GND
 233    GND VSS101 @T6G_MB_LIB.T6G(SCH_1):GND
 237    GND VSS103 @T6G_MB_LIB.T6G(SCH_1):GND
 242    GND VSS105 @T6G_MB_LIB.T6G(SCH_1):GND
 244    GND VSS106 @T6G_MB_LIB.T6G(SCH_1):GND
 246    GND VSS107 @T6G_MB_LIB.T6G(SCH_1):GND
 248    GND VSS108 @T6G_MB_LIB.T6G(SCH_1):GND
 251    GND VSS109 @T6G_MB_LIB.T6G(SCH_1):GND
 253    GND VSS110 @T6G_MB_LIB.T6G(SCH_1):GND
 255    GND VSS111 @T6G_MB_LIB.T6G(SCH_1):GND
 257    GND VSS112 @T6G_MB_LIB.T6G(SCH_1):GND
 259    GND VSS113 @T6G_MB_LIB.T6G(SCH_1):GND
 262    GND VSS114 @T6G_MB_LIB.T6G(SCH_1):GND
 264    GND VSS115 @T6G_MB_LIB.T6G(SCH_1):GND
 266    GND VSS116 @T6G_MB_LIB.T6G(SCH_1):GND
 268    GND VSS117 @T6G_MB_LIB.T6G(SCH_1):GND
 270    GND VSS118 @T6G_MB_LIB.T6G(SCH_1):GND
 273    GND VSS119 @T6G_MB_LIB.T6G(SCH_1):GND
 275    GND VSS120 @T6G_MB_LIB.T6G(SCH_1):GND
 277    GND VSS121 @T6G_MB_LIB.T6G(SCH_1):GND
 279    GND VSS122 @T6G_MB_LIB.T6G(SCH_1):GND
 281    GND VSS123 @T6G_MB_LIB.T6G(SCH_1):GND
 284    GND VSS124 @T6G_MB_LIB.T6G(SCH_1):GND
 286    GND VSS125 @T6G_MB_LIB.T6G(SCH_1):GND
 288    GND VSS126 @T6G_MB_LIB.T6G(SCH_1):GND
   1 P12V_MEM_CPU0 VIN_BULK0 @T6G_MB_LIB.T6G(SCH_1):P12V_MEM_CPU0
 145 P12V_MEM_CPU0 VIN_BULK1 @T6G_MB_LIB.T6G(SCH_1):P12V_MEM_CPU0
 146 P12V_MEM_CPU0 VIN_BULK2 @T6G_MB_LIB.T6G(SCH_1):P12V_MEM_CPU0
 230    GND VSS100 @T6G_MB_LIB.T6G(SCH_1):GND
 235    GND VSS102 @T6G_MB_LIB.T6G(SCH_1):GND
 240    GND VSS104 @T6G_MB_LIB.T6G(SCH_1):GND
 132    GND  VSS58 @T6G_MB_LIB.T6G(SCH_1):GND
 136    GND  VSS60 @T6G_MB_LIB.T6G(SCH_1):GND
 139    GND  VSS61 @T6G_MB_LIB.T6G(SCH_1):GND
 141    GND  VSS62 @T6G_MB_LIB.T6G(SCH_1):GND
  G1    GND     G1 @T6G_MB_LIB.T6G(SCH_1):GND
  G2    GND     G2 @T6G_MB_LIB.T6G(SCH_1):GND
  G3    GND     G3 @T6G_MB_LIB.T6G(SCH_1):GND

Q_CAP_0402-0.1UF,25V,10%,X7R,CH4104K1B00  I362  C92
   1 P3V3_AUX      A @T6G_MB_LIB.T6G(SCH_1):P3V3_AUX
   2    GND      B @T6G_MB_LIB.T6G(SCH_1):GND

Q_RES_0402LF-1K,1%,1/16W,CHIP,CS21002FB06  I364  R292
   1 PWRGD_CHB_CPU0_DIMM      A @T6G_MB_LIB.T6G(SCH_1):PWRGD_CHB_CPU0_DIMM
   2 PWRGD_CHAF_CPU0      B @T6G_MB_LIB.T6G(SCH_1):PWRGD_CHAF_CPU0

Q_RES_0402LF-1K,1%,1/16W,EMPTY,CS21002FB06  I365  R90
   1   P3V3      A @T6G_MB_LIB.T6G(SCH_1):P3V3
   2 PWRGD_CHB_CPU0_DIMM      B @T6G_MB_LIB.T6G(SCH_1):PWRGD_CHB_CPU0_DIMM

SCONN288_DDR506112002KQ-SCONN288_DDR506112002KQ,SMA  I367  J15
  93 M_B_CPU0_SB_DQS_DP<9> DQS9_B_T||TDQS9_B_T||DBI4_B_N @T6G_MB_LIB.T6G(SCH_1):M_B_CPU0_SB_DQS_DP(9)
  94 M_B_CPU0_SB_DQS_DN<9> DQS9_B_C||TDQS9_B_C @T6G_MB_LIB.T6G(SCH_1):M_B_CPU0_SB_DQS_DN(9)
 201 M_B_CPU0_SA_DQS_DP<9> DQS9_A_T||TDQS9_A_T @T6G_MB_LIB.T6G(SCH_1):M_B_CPU0_SA_DQS_DP(9)
 200 M_B_CPU0_SA_DQS_DN<9> DQS9_A_C||TDQS9_A_C @T6G_MB_LIB.T6G(SCH_1):M_B_CPU0_SA_DQS_DN(9)
 190 M_B_CPU0_SA_DQS_DP<8> DQS8_A_T||TDQS8_A_T @T6G_MB_LIB.T6G(SCH_1):M_B_CPU0_SA_DQS_DP(8)
 189 M_B_CPU0_SA_DQS_DN<8> DQS8_A_C||TDQS8_A_C @T6G_MB_LIB.T6G(SCH_1):M_B_CPU0_SA_DQS_DN(8)
 271 M_B_CPU0_SB_DQS_DN<7> DQS7_B_C||TDQS7_B_C @T6G_MB_LIB.T6G(SCH_1):M_B_CPU0_SB_DQS_DN(7)
 179 M_B_CPU0_SA_DQS_DP<7> DQS7_A_T||TDQS7_A_T @T6G_MB_LIB.T6G(SCH_1):M_B_CPU0_SA_DQS_DP(7)
 261 M_B_CPU0_SB_DQS_DP<6> DQS6_B_T||TDQS6_B_T @T6G_MB_LIB.T6G(SCH_1):M_B_CPU0_SB_DQS_DP(6)
 260 M_B_CPU0_SB_DQS_DN<6> DQS6_B_C||TDQS6_B_C @T6G_MB_LIB.T6G(SCH_1):M_B_CPU0_SB_DQS_DN(6)
 167 M_B_CPU0_SA_DQS_DN<6> DQS6_A_C||TDQS6_A_C||DQS6_A_T||TDQS6_A_T @T6G_MB_LIB.T6G(SCH_1):M_B_CPU0_SA_DQS_DN(6)
 250 M_B_CPU0_SB_DQS_DP<5> DQS5_B_T||TDQS5_B_T @T6G_MB_LIB.T6G(SCH_1):M_B_CPU0_SB_DQS_DP(5)
 249 M_B_CPU0_SB_DQS_DN<5> DQS5_B_C||TDQS5_B_C @T6G_MB_LIB.T6G(SCH_1):M_B_CPU0_SB_DQS_DN(5)
 157 M_B_CPU0_SA_DQS_DP<5> DQS5_A_T||TDQS5_A_T @T6G_MB_LIB.T6G(SCH_1):M_B_CPU0_SA_DQS_DP(5)
 156 M_B_CPU0_SA_DQS_DN<5> DQS5_A_C||TDQS5_A_C||DQS5_A_T||TDQS5_A_T @T6G_MB_LIB.T6G(SCH_1):M_B_CPU0_SA_DQS_DN(5)
 239 M_B_CPU0_SB_DQS_DP<4> DQS4_B_T @T6G_MB_LIB.T6G(SCH_1):M_B_CPU0_SB_DQS_DP(4)
 238 M_B_CPU0_SB_DQS_DN<4> DQS4_B_C @T6G_MB_LIB.T6G(SCH_1):M_B_CPU0_SB_DQS_DN(4)
  55 M_B_CPU0_SA_DQS_DP<4> DQS4_A_T @T6G_MB_LIB.T6G(SCH_1):M_B_CPU0_SA_DQS_DP(4)
  56 M_B_CPU0_SA_DQS_DN<4> DQS4_A_C @T6G_MB_LIB.T6G(SCH_1):M_B_CPU0_SA_DQS_DN(4)
 137 M_B_CPU0_SB_DQS_DP<3> DQS3_B_T @T6G_MB_LIB.T6G(SCH_1):M_B_CPU0_SB_DQS_DP(3)
 138 M_B_CPU0_SB_DQS_DN<3> DQS3_B_C @T6G_MB_LIB.T6G(SCH_1):M_B_CPU0_SB_DQS_DN(3)
  44 M_B_CPU0_SA_DQS_DP<3> DQS3_A_T @T6G_MB_LIB.T6G(SCH_1):M_B_CPU0_SA_DQS_DP(3)
  45 M_B_CPU0_SA_DQS_DN<3> DQS3_A_C @T6G_MB_LIB.T6G(SCH_1):M_B_CPU0_SA_DQS_DN(3)
 126 M_B_CPU0_SB_DQS_DP<2> DQS2_B_T @T6G_MB_LIB.T6G(SCH_1):M_B_CPU0_SB_DQS_DP(2)
 127 M_B_CPU0_SB_DQS_DN<2> DQS2_B_C @T6G_MB_LIB.T6G(SCH_1):M_B_CPU0_SB_DQS_DN(2)
  33 M_B_CPU0_SA_DQS_DP<2> DQS2_A_T @T6G_MB_LIB.T6G(SCH_1):M_B_CPU0_SA_DQS_DP(2)
  34 M_B_CPU0_SA_DQS_DN<2> DQS2_A_C @T6G_MB_LIB.T6G(SCH_1):M_B_CPU0_SA_DQS_DN(2)
 115 M_B_CPU0_SB_DQS_DP<1> DQS1_B_T @T6G_MB_LIB.T6G(SCH_1):M_B_CPU0_SB_DQS_DP(1)
 116 M_B_CPU0_SB_DQS_DN<1> DQS1_B_C @T6G_MB_LIB.T6G(SCH_1):M_B_CPU0_SB_DQS_DN(1)
  22 M_B_CPU0_SA_DQS_DP<1> DQS1_A_T @T6G_MB_LIB.T6G(SCH_1):M_B_CPU0_SA_DQS_DP(1)
  23 M_B_CPU0_SA_DQS_DN<1> DQS1_A_C @T6G_MB_LIB.T6G(SCH_1):M_B_CPU0_SA_DQS_DN(1)
 104 M_B_CPU0_SB_DQS_DP<0> DQS0_B_T @T6G_MB_LIB.T6G(SCH_1):M_B_CPU0_SB_DQS_DP(0)
 105 M_B_CPU0_SB_DQS_DN<0> DQS0_B_C @T6G_MB_LIB.T6G(SCH_1):M_B_CPU0_SB_DQS_DN(0)
  11 M_B_CPU0_SA_DQS_DP<0> DQS0_A_T @T6G_MB_LIB.T6G(SCH_1):M_B_CPU0_SA_DQS_DP(0)
  12 M_B_CPU0_SA_DQS_DN<0> DQS0_A_C @T6G_MB_LIB.T6G(SCH_1):M_B_CPU0_SA_DQS_DN(0)
 272 M_B_CPU0_SB_DQS_DP<7> DQS7_B_T||TDQS7_B_T @T6G_MB_LIB.T6G(SCH_1):M_B_CPU0_SB_DQS_DP(7)
 282 M_B_CPU0_SB_DQS_DN<8> DQS8_B_C||TDQS8_B_C @T6G_MB_LIB.T6G(SCH_1):M_B_CPU0_SB_DQS_DN(8)
 283 M_B_CPU0_SB_DQS_DP<8> DQS8_B_T||TDQS8_B_T @T6G_MB_LIB.T6G(SCH_1):M_B_CPU0_SB_DQS_DP(8)
 168 M_B_CPU0_SA_DQS_DP<6> DQS6_A_T||TDQS6_A_T @T6G_MB_LIB.T6G(SCH_1):M_B_CPU0_SA_DQS_DP(6)
 178 M_B_CPU0_SA_DQS_DN<7> DQS7_A_C||TDQS7_A_C @T6G_MB_LIB.T6G(SCH_1):M_B_CPU0_SA_DQS_DN(7)

Q_CAP_C0805-10UF,25V,10%,X6S,CH6104KEA00  I369  C143
   1 P12V_MEM_CPU0      A @T6G_MB_LIB.T6G(SCH_1):P12V_MEM_CPU0
   2    GND      B @T6G_MB_LIB.T6G(SCH_1):GND

Q_CAP_C0805-10UF,25V,10%,X6S,CH6104KEA00  I370  C145
   1 P12V_MEM_CPU0      A @T6G_MB_LIB.T6G(SCH_1):P12V_MEM_CPU0
   2    GND      B @T6G_MB_LIB.T6G(SCH_1):GND

Q_RES_0402LF-49.9,1%,1/16W,CHIP,CS04992FB07  I372  R1569
   1 I3C_SPD_DDRAF_CPU0_SCL      A @T6G_MB_LIB.T6G(SCH_1):I3C_SPD_DDRAF_CPU0_SCL
   2 I3C_SPD_DDRB_CPU0_SCL      B @T6G_MB_LIB.T6G(SCH_1):I3C_SPD_DDRB_CPU0_SCL

Q_RES_0402LF-10,1%,1/16W,CHIP,CS01002FB07  I373  R1675
   1 I3C_SPD_DDRAF_CPU0_SDA      A @T6G_MB_LIB.T6G(SCH_1):I3C_SPD_DDRAF_CPU0_SDA
   2 I3C_SPD_DDRB_CPU0_SDA      B @T6G_MB_LIB.T6G(SCH_1):I3C_SPD_DDRB_CPU0_SDA


DRAWING: @T6G_MB_LIB.T6G(SCH_1):PAGE87 

Q_RES_0402LF-23.2K,1%,1/16W,CHIP,CS32322FB03  I349  R762
   1 PD_CHC_CPU0_DIMM_SAA      A @T6G_MB_LIB.T6G(SCH_1):PD_CHC_CPU0_DIMM_SAA
   2    GND      B @T6G_MB_LIB.T6G(SCH_1):GND

SCONN288_DDR506112002KQ-SCONN288_DDR506112002KQ,SMA  I350  J17
   3 P3V3_AUX VIN_MGMT @T6G_MB_LIB.T6G(SCH_1):P3V3_AUX
   2     NC   RFU0     NC
 144     NC   RFU1     NC
 149     NC   RFU2     NC
 150     NC   RFU3     NC
 220     NC   RFU4     NC
 231     NC   RFU5     NC
 232     NC   RFU6     NC
 207 M_C_CPU0_RESET_N RESET_N @T6G_MB_LIB.T6G(SCH_1):M_C_CPU0_RESET_N
 147 PWRGD_CHC_CPU0_DIMM PWR_GOOD||FAIL_N @T6G_MB_LIB.T6G(SCH_1):PWRGD_CHC_CPU0_DIMM
 227 M_C_CPU0_SB_PAR  PAR_B @T6G_MB_LIB.T6G(SCH_1):M_C_CPU0_SB_PAR
  74 M_C_CPU0_SA_PAR  PAR_A @T6G_MB_LIB.T6G(SCH_1):M_C_CPU0_SA_PAR
  87 M_C_CPU0_SB_RSP<0> LBS||RSP_B_N @T6G_MB_LIB.T6G(SCH_1):M_C_CPU0_SB_RSP(0)
  86 M_C_CPU0_SA_RSP<0> LBD||RSP_A_N @T6G_MB_LIB.T6G(SCH_1):M_C_CPU0_SA_RSP(0)
   5 I3C_SPD_DDRC_CPU0_SDA   HSDA @T6G_MB_LIB.T6G(SCH_1):I3C_SPD_DDRC_CPU0_SDA
   4 I3C_SPD_DDRC_CPU0_SCL   HSCL @T6G_MB_LIB.T6G(SCH_1):I3C_SPD_DDRC_CPU0_SCL
 148 PD_CHC_CPU0_DIMM_SAA    HAS @T6G_MB_LIB.T6G(SCH_1):PD_CHC_CPU0_DIMM_SAA
 100 M_C_CPU0_SB_DQ<0>  DQ0_B @T6G_MB_LIB.T6G(SCH_1):M_C_CPU0_SB_DQ(0)
 102 M_C_CPU0_SB_DQ<1>  DQ1_B @T6G_MB_LIB.T6G(SCH_1):M_C_CPU0_SB_DQ(1)
 245 M_C_CPU0_SB_DQ<2>  DQ2_B @T6G_MB_LIB.T6G(SCH_1):M_C_CPU0_SB_DQ(2)
 247 M_C_CPU0_SB_DQ<3>  DQ3_B @T6G_MB_LIB.T6G(SCH_1):M_C_CPU0_SB_DQ(3)
 107 M_C_CPU0_SB_DQ<4>  DQ4_B @T6G_MB_LIB.T6G(SCH_1):M_C_CPU0_SB_DQ(4)
 109 M_C_CPU0_SB_DQ<5>  DQ5_B @T6G_MB_LIB.T6G(SCH_1):M_C_CPU0_SB_DQ(5)
 252 M_C_CPU0_SB_DQ<6>  DQ6_B @T6G_MB_LIB.T6G(SCH_1):M_C_CPU0_SB_DQ(6)
 254 M_C_CPU0_SB_DQ<7>  DQ7_B @T6G_MB_LIB.T6G(SCH_1):M_C_CPU0_SB_DQ(7)
 111 M_C_CPU0_SB_DQ<8>  DQ8_B @T6G_MB_LIB.T6G(SCH_1):M_C_CPU0_SB_DQ(8)
 113 M_C_CPU0_SB_DQ<9>  DQ9_B @T6G_MB_LIB.T6G(SCH_1):M_C_CPU0_SB_DQ(9)
 256 M_C_CPU0_SB_DQ<10> DQ10_B @T6G_MB_LIB.T6G(SCH_1):M_C_CPU0_SB_DQ(10)
 258 M_C_CPU0_SB_DQ<11> DQ11_B @T6G_MB_LIB.T6G(SCH_1):M_C_CPU0_SB_DQ(11)
 118 M_C_CPU0_SB_DQ<12> DQ12_B @T6G_MB_LIB.T6G(SCH_1):M_C_CPU0_SB_DQ(12)
 120 M_C_CPU0_SB_DQ<13> DQ13_B @T6G_MB_LIB.T6G(SCH_1):M_C_CPU0_SB_DQ(13)
 263 M_C_CPU0_SB_DQ<14> DQ14_B @T6G_MB_LIB.T6G(SCH_1):M_C_CPU0_SB_DQ(14)
 265 M_C_CPU0_SB_DQ<15> DQ15_B @T6G_MB_LIB.T6G(SCH_1):M_C_CPU0_SB_DQ(15)
 122 M_C_CPU0_SB_DQ<16> DQ16_B @T6G_MB_LIB.T6G(SCH_1):M_C_CPU0_SB_DQ(16)
 124 M_C_CPU0_SB_DQ<17> DQ17_B @T6G_MB_LIB.T6G(SCH_1):M_C_CPU0_SB_DQ(17)
 267 M_C_CPU0_SB_DQ<18> DQ18_B @T6G_MB_LIB.T6G(SCH_1):M_C_CPU0_SB_DQ(18)
 269 M_C_CPU0_SB_DQ<19> DQ19_B @T6G_MB_LIB.T6G(SCH_1):M_C_CPU0_SB_DQ(19)
 129 M_C_CPU0_SB_DQ<20> DQ20_B @T6G_MB_LIB.T6G(SCH_1):M_C_CPU0_SB_DQ(20)
 131 M_C_CPU0_SB_DQ<21> DQ21_B @T6G_MB_LIB.T6G(SCH_1):M_C_CPU0_SB_DQ(21)
 274 M_C_CPU0_SB_DQ<22> DQ22_B @T6G_MB_LIB.T6G(SCH_1):M_C_CPU0_SB_DQ(22)
 276 M_C_CPU0_SB_DQ<23> DQ23_B @T6G_MB_LIB.T6G(SCH_1):M_C_CPU0_SB_DQ(23)
 133 M_C_CPU0_SB_DQ<24> DQ24_B @T6G_MB_LIB.T6G(SCH_1):M_C_CPU0_SB_DQ(24)
 135 M_C_CPU0_SB_DQ<25> DQ25_B @T6G_MB_LIB.T6G(SCH_1):M_C_CPU0_SB_DQ(25)
 278 M_C_CPU0_SB_DQ<26> DQ26_B @T6G_MB_LIB.T6G(SCH_1):M_C_CPU0_SB_DQ(26)
 280 M_C_CPU0_SB_DQ<27> DQ27_B @T6G_MB_LIB.T6G(SCH_1):M_C_CPU0_SB_DQ(27)
 140 M_C_CPU0_SB_DQ<28> DQ28_B @T6G_MB_LIB.T6G(SCH_1):M_C_CPU0_SB_DQ(28)
 142 M_C_CPU0_SB_DQ<29> DQ29_B @T6G_MB_LIB.T6G(SCH_1):M_C_CPU0_SB_DQ(29)
 285 M_C_CPU0_SB_DQ<30> DQ30_B @T6G_MB_LIB.T6G(SCH_1):M_C_CPU0_SB_DQ(30)
 287 M_C_CPU0_SB_DQ<31> DQ31_B @T6G_MB_LIB.T6G(SCH_1):M_C_CPU0_SB_DQ(31)
   7 M_C_CPU0_SA_DQ<0>  DQ0_A @T6G_MB_LIB.T6G(SCH_1):M_C_CPU0_SA_DQ(0)
   9 M_C_CPU0_SA_DQ<1>  DQ1_A @T6G_MB_LIB.T6G(SCH_1):M_C_CPU0_SA_DQ(1)
 152 M_C_CPU0_SA_DQ<2>  DQ2_A @T6G_MB_LIB.T6G(SCH_1):M_C_CPU0_SA_DQ(2)
 154 M_C_CPU0_SA_DQ<3>  DQ3_A @T6G_MB_LIB.T6G(SCH_1):M_C_CPU0_SA_DQ(3)
  14 M_C_CPU0_SA_DQ<4>  DQ4_A @T6G_MB_LIB.T6G(SCH_1):M_C_CPU0_SA_DQ(4)
  16 M_C_CPU0_SA_DQ<5>  DQ5_A @T6G_MB_LIB.T6G(SCH_1):M_C_CPU0_SA_DQ(5)
 159 M_C_CPU0_SA_DQ<6>  DQ6_A @T6G_MB_LIB.T6G(SCH_1):M_C_CPU0_SA_DQ(6)
 161 M_C_CPU0_SA_DQ<7>  DQ7_A @T6G_MB_LIB.T6G(SCH_1):M_C_CPU0_SA_DQ(7)
  18 M_C_CPU0_SA_DQ<8>  DQ8_A @T6G_MB_LIB.T6G(SCH_1):M_C_CPU0_SA_DQ(8)
  20 M_C_CPU0_SA_DQ<9>  DQ9_A @T6G_MB_LIB.T6G(SCH_1):M_C_CPU0_SA_DQ(9)
 163 M_C_CPU0_SA_DQ<10> DQ10_A @T6G_MB_LIB.T6G(SCH_1):M_C_CPU0_SA_DQ(10)
 165 M_C_CPU0_SA_DQ<11> DQ11_A @T6G_MB_LIB.T6G(SCH_1):M_C_CPU0_SA_DQ(11)
  25 M_C_CPU0_SA_DQ<12> DQ12_A @T6G_MB_LIB.T6G(SCH_1):M_C_CPU0_SA_DQ(12)
  27 M_C_CPU0_SA_DQ<13> DQ13_A @T6G_MB_LIB.T6G(SCH_1):M_C_CPU0_SA_DQ(13)
 170 M_C_CPU0_SA_DQ<14> DQ14_A @T6G_MB_LIB.T6G(SCH_1):M_C_CPU0_SA_DQ(14)
 172 M_C_CPU0_SA_DQ<15> DQ15_A @T6G_MB_LIB.T6G(SCH_1):M_C_CPU0_SA_DQ(15)
  29 M_C_CPU0_SA_DQ<16> DQ16_A @T6G_MB_LIB.T6G(SCH_1):M_C_CPU0_SA_DQ(16)
  31 M_C_CPU0_SA_DQ<17> DQ17_A @T6G_MB_LIB.T6G(SCH_1):M_C_CPU0_SA_DQ(17)
 174 M_C_CPU0_SA_DQ<18> DQ18_A @T6G_MB_LIB.T6G(SCH_1):M_C_CPU0_SA_DQ(18)
 176 M_C_CPU0_SA_DQ<19> DQ19_A @T6G_MB_LIB.T6G(SCH_1):M_C_CPU0_SA_DQ(19)
  36 M_C_CPU0_SA_DQ<20> DQ20_A @T6G_MB_LIB.T6G(SCH_1):M_C_CPU0_SA_DQ(20)
  38 M_C_CPU0_SA_DQ<21> DQ21_A @T6G_MB_LIB.T6G(SCH_1):M_C_CPU0_SA_DQ(21)
 181 M_C_CPU0_SA_DQ<22> DQ22_A @T6G_MB_LIB.T6G(SCH_1):M_C_CPU0_SA_DQ(22)
 183 M_C_CPU0_SA_DQ<23> DQ23_A @T6G_MB_LIB.T6G(SCH_1):M_C_CPU0_SA_DQ(23)
  40 M_C_CPU0_SA_DQ<24> DQ24_A @T6G_MB_LIB.T6G(SCH_1):M_C_CPU0_SA_DQ(24)
  42 M_C_CPU0_SA_DQ<25> DQ25_A @T6G_MB_LIB.T6G(SCH_1):M_C_CPU0_SA_DQ(25)
 185 M_C_CPU0_SA_DQ<26> DQ26_A @T6G_MB_LIB.T6G(SCH_1):M_C_CPU0_SA_DQ(26)
 187 M_C_CPU0_SA_DQ<27> DQ27_A @T6G_MB_LIB.T6G(SCH_1):M_C_CPU0_SA_DQ(27)
  47 M_C_CPU0_SA_DQ<28> DQ28_A @T6G_MB_LIB.T6G(SCH_1):M_C_CPU0_SA_DQ(28)
  49 M_C_CPU0_SA_DQ<29> DQ29_A @T6G_MB_LIB.T6G(SCH_1):M_C_CPU0_SA_DQ(29)
 192 M_C_CPU0_SA_DQ<30> DQ30_A @T6G_MB_LIB.T6G(SCH_1):M_C_CPU0_SA_DQ(30)
 229 M_C_CPU0_SB_CS_N<1> CS1_B_N @T6G_MB_LIB.T6G(SCH_1):M_C_CPU0_SB_CS_N(1)
 209 M_C_CPU0_SA_CS_N<1> CS1_A_N @T6G_MB_LIB.T6G(SCH_1):M_C_CPU0_SA_CS_N(1)
  84 M_C_CPU0_SB_CS_N<0> CS0_B_N @T6G_MB_LIB.T6G(SCH_1):M_C_CPU0_SB_CS_N(0)
  64 M_C_CPU0_SA_CS_N<0> CS0_A_N @T6G_MB_LIB.T6G(SCH_1):M_C_CPU0_SA_CS_N(0)
 217 M_C_CPU0_CLK_DP<0>   CK_T @T6G_MB_LIB.T6G(SCH_1):M_C_CPU0_CLK_DP(0)
 218 M_C_CPU0_CLK_DN<0>   CK_C @T6G_MB_LIB.T6G(SCH_1):M_C_CPU0_CLK_DN(0)
  96 M_C_CPU0_SB_CB<0>  CB0_B @T6G_MB_LIB.T6G(SCH_1):M_C_CPU0_SB_CB(0)
  98 M_C_CPU0_SB_CB<1>  CB1_B @T6G_MB_LIB.T6G(SCH_1):M_C_CPU0_SB_CB(1)
 241 M_C_CPU0_SB_CB<2>  CB2_B @T6G_MB_LIB.T6G(SCH_1):M_C_CPU0_SB_CB(2)
 243 M_C_CPU0_SB_CB<3>  CB3_B @T6G_MB_LIB.T6G(SCH_1):M_C_CPU0_SB_CB(3)
  89 M_C_CPU0_SB_CB<4>  CB4_B @T6G_MB_LIB.T6G(SCH_1):M_C_CPU0_SB_CB(4)
  91 M_C_CPU0_SB_CB<5>  CB5_B @T6G_MB_LIB.T6G(SCH_1):M_C_CPU0_SB_CB(5)
 234 M_C_CPU0_SB_CB<6>  CB6_B @T6G_MB_LIB.T6G(SCH_1):M_C_CPU0_SB_CB(6)
  51 M_C_CPU0_SA_CB<0>  CB0_A @T6G_MB_LIB.T6G(SCH_1):M_C_CPU0_SA_CB(0)
 196 M_C_CPU0_SA_CB<2>  CB2_A @T6G_MB_LIB.T6G(SCH_1):M_C_CPU0_SA_CB(2)
 198 M_C_CPU0_SA_CB<3>  CB3_A @T6G_MB_LIB.T6G(SCH_1):M_C_CPU0_SA_CB(3)
  60 M_C_CPU0_SA_CB<5>  CB5_A @T6G_MB_LIB.T6G(SCH_1):M_C_CPU0_SA_CB(5)
 203 M_C_CPU0_SA_CB<6>  CB6_A @T6G_MB_LIB.T6G(SCH_1):M_C_CPU0_SA_CB(6)
  82 M_C_CPU0_SB_CA<6>  CA6_B @T6G_MB_LIB.T6G(SCH_1):M_C_CPU0_SB_CA(6)
  72 M_C_CPU0_SA_CA<6>  CA6_A @T6G_MB_LIB.T6G(SCH_1):M_C_CPU0_SA_CA(6)
 225 M_C_CPU0_SB_CA<5>  CA5_B @T6G_MB_LIB.T6G(SCH_1):M_C_CPU0_SB_CA(5)
 215 M_C_CPU0_SA_CA<5>  CA5_A @T6G_MB_LIB.T6G(SCH_1):M_C_CPU0_SA_CA(5)
  80 M_C_CPU0_SB_CA<4>  CA4_B @T6G_MB_LIB.T6G(SCH_1):M_C_CPU0_SB_CA(4)
  70 M_C_CPU0_SA_CA<4>  CA4_A @T6G_MB_LIB.T6G(SCH_1):M_C_CPU0_SA_CA(4)
 223 M_C_CPU0_SB_CA<3>  CA3_B @T6G_MB_LIB.T6G(SCH_1):M_C_CPU0_SB_CA(3)
 213 M_C_CPU0_SA_CA<3>  CA3_A @T6G_MB_LIB.T6G(SCH_1):M_C_CPU0_SA_CA(3)
  78 M_C_CPU0_SB_CA<2>  CA2_B @T6G_MB_LIB.T6G(SCH_1):M_C_CPU0_SB_CA(2)
  68 M_C_CPU0_SA_CA<2>  CA2_A @T6G_MB_LIB.T6G(SCH_1):M_C_CPU0_SA_CA(2)
 221 M_C_CPU0_SB_CA<1>  CA1_B @T6G_MB_LIB.T6G(SCH_1):M_C_CPU0_SB_CA(1)
 211 M_C_CPU0_SA_CA<1>  CA1_A @T6G_MB_LIB.T6G(SCH_1):M_C_CPU0_SA_CA(1)
  76 M_C_CPU0_SB_CA<0>  CA0_B @T6G_MB_LIB.T6G(SCH_1):M_C_CPU0_SB_CA(0)
  66 M_C_CPU0_SA_CA<0>  CA0_A @T6G_MB_LIB.T6G(SCH_1):M_C_CPU0_SA_CA(0)
  62 M_C_CPU0_ALERT_N ALERT_N @T6G_MB_LIB.T6G(SCH_1):M_C_CPU0_ALERT_N
 236 M_C_CPU0_SB_CB<7>  CB7_B @T6G_MB_LIB.T6G(SCH_1):M_C_CPU0_SB_CB(7)
  53 M_C_CPU0_SA_CB<1>  CB1_A @T6G_MB_LIB.T6G(SCH_1):M_C_CPU0_SA_CB(1)
  58 M_C_CPU0_SA_CB<4>  CB4_A @T6G_MB_LIB.T6G(SCH_1):M_C_CPU0_SA_CB(4)
 205 M_C_CPU0_SA_CB<7>  CB7_A @T6G_MB_LIB.T6G(SCH_1):M_C_CPU0_SA_CB(7)
 194 M_C_CPU0_SA_DQ<31> DQ31_A @T6G_MB_LIB.T6G(SCH_1):M_C_CPU0_SA_DQ(31)

SCONN288_DDR506112002KQ-SCONN288_DDR506112002KQ,SMA  I352  J17
   6    GND   VSS0 @T6G_MB_LIB.T6G(SCH_1):GND
   8    GND   VSS1 @T6G_MB_LIB.T6G(SCH_1):GND
  10    GND   VSS2 @T6G_MB_LIB.T6G(SCH_1):GND
  13    GND   VSS3 @T6G_MB_LIB.T6G(SCH_1):GND
  15    GND   VSS4 @T6G_MB_LIB.T6G(SCH_1):GND
  17    GND   VSS5 @T6G_MB_LIB.T6G(SCH_1):GND
  19    GND   VSS6 @T6G_MB_LIB.T6G(SCH_1):GND
  21    GND   VSS7 @T6G_MB_LIB.T6G(SCH_1):GND
  24    GND   VSS8 @T6G_MB_LIB.T6G(SCH_1):GND
  26    GND   VSS9 @T6G_MB_LIB.T6G(SCH_1):GND
  28    GND  VSS10 @T6G_MB_LIB.T6G(SCH_1):GND
  30    GND  VSS11 @T6G_MB_LIB.T6G(SCH_1):GND
  32    GND  VSS12 @T6G_MB_LIB.T6G(SCH_1):GND
  35    GND  VSS13 @T6G_MB_LIB.T6G(SCH_1):GND
  37    GND  VSS14 @T6G_MB_LIB.T6G(SCH_1):GND
  39    GND  VSS15 @T6G_MB_LIB.T6G(SCH_1):GND
  41    GND  VSS16 @T6G_MB_LIB.T6G(SCH_1):GND
  43    GND  VSS17 @T6G_MB_LIB.T6G(SCH_1):GND
  46    GND  VSS18 @T6G_MB_LIB.T6G(SCH_1):GND
  48    GND  VSS19 @T6G_MB_LIB.T6G(SCH_1):GND
  50    GND  VSS20 @T6G_MB_LIB.T6G(SCH_1):GND
  52    GND  VSS21 @T6G_MB_LIB.T6G(SCH_1):GND
  54    GND  VSS22 @T6G_MB_LIB.T6G(SCH_1):GND
  57    GND  VSS23 @T6G_MB_LIB.T6G(SCH_1):GND
  59    GND  VSS24 @T6G_MB_LIB.T6G(SCH_1):GND
  61    GND  VSS25 @T6G_MB_LIB.T6G(SCH_1):GND
  63    GND  VSS26 @T6G_MB_LIB.T6G(SCH_1):GND
  65    GND  VSS27 @T6G_MB_LIB.T6G(SCH_1):GND
  67    GND  VSS28 @T6G_MB_LIB.T6G(SCH_1):GND
  69    GND  VSS29 @T6G_MB_LIB.T6G(SCH_1):GND
  71    GND  VSS30 @T6G_MB_LIB.T6G(SCH_1):GND
  73    GND  VSS31 @T6G_MB_LIB.T6G(SCH_1):GND
  75    GND  VSS32 @T6G_MB_LIB.T6G(SCH_1):GND
  77    GND  VSS33 @T6G_MB_LIB.T6G(SCH_1):GND
  79    GND  VSS34 @T6G_MB_LIB.T6G(SCH_1):GND
  81    GND  VSS35 @T6G_MB_LIB.T6G(SCH_1):GND
  83    GND  VSS36 @T6G_MB_LIB.T6G(SCH_1):GND
  85    GND  VSS37 @T6G_MB_LIB.T6G(SCH_1):GND
  88    GND  VSS38 @T6G_MB_LIB.T6G(SCH_1):GND
  90    GND  VSS39 @T6G_MB_LIB.T6G(SCH_1):GND
  92    GND  VSS40 @T6G_MB_LIB.T6G(SCH_1):GND
  95    GND  VSS41 @T6G_MB_LIB.T6G(SCH_1):GND
  97    GND  VSS42 @T6G_MB_LIB.T6G(SCH_1):GND
  99    GND  VSS43 @T6G_MB_LIB.T6G(SCH_1):GND
 101    GND  VSS44 @T6G_MB_LIB.T6G(SCH_1):GND
 103    GND  VSS45 @T6G_MB_LIB.T6G(SCH_1):GND
 106    GND  VSS46 @T6G_MB_LIB.T6G(SCH_1):GND
 108    GND  VSS47 @T6G_MB_LIB.T6G(SCH_1):GND
 110    GND  VSS48 @T6G_MB_LIB.T6G(SCH_1):GND
 112    GND  VSS49 @T6G_MB_LIB.T6G(SCH_1):GND
 114    GND  VSS50 @T6G_MB_LIB.T6G(SCH_1):GND
 117    GND  VSS51 @T6G_MB_LIB.T6G(SCH_1):GND
 119    GND  VSS52 @T6G_MB_LIB.T6G(SCH_1):GND
 121    GND  VSS53 @T6G_MB_LIB.T6G(SCH_1):GND
 123    GND  VSS54 @T6G_MB_LIB.T6G(SCH_1):GND
 125    GND  VSS55 @T6G_MB_LIB.T6G(SCH_1):GND
 128    GND  VSS56 @T6G_MB_LIB.T6G(SCH_1):GND
 130    GND  VSS57 @T6G_MB_LIB.T6G(SCH_1):GND
 134    GND  VSS59 @T6G_MB_LIB.T6G(SCH_1):GND
 143    GND  VSS63 @T6G_MB_LIB.T6G(SCH_1):GND
 151    GND  VSS64 @T6G_MB_LIB.T6G(SCH_1):GND
 153    GND  VSS65 @T6G_MB_LIB.T6G(SCH_1):GND
 155    GND  VSS66 @T6G_MB_LIB.T6G(SCH_1):GND
 158    GND  VSS67 @T6G_MB_LIB.T6G(SCH_1):GND
 160    GND  VSS68 @T6G_MB_LIB.T6G(SCH_1):GND
 162    GND  VSS69 @T6G_MB_LIB.T6G(SCH_1):GND
 164    GND  VSS70 @T6G_MB_LIB.T6G(SCH_1):GND
 166    GND  VSS71 @T6G_MB_LIB.T6G(SCH_1):GND
 169    GND  VSS72 @T6G_MB_LIB.T6G(SCH_1):GND
 171    GND  VSS73 @T6G_MB_LIB.T6G(SCH_1):GND
 173    GND  VSS74 @T6G_MB_LIB.T6G(SCH_1):GND
 175    GND  VSS75 @T6G_MB_LIB.T6G(SCH_1):GND
 177    GND  VSS76 @T6G_MB_LIB.T6G(SCH_1):GND
 180    GND  VSS77 @T6G_MB_LIB.T6G(SCH_1):GND
 182    GND  VSS78 @T6G_MB_LIB.T6G(SCH_1):GND
 184    GND  VSS79 @T6G_MB_LIB.T6G(SCH_1):GND
 186    GND  VSS80 @T6G_MB_LIB.T6G(SCH_1):GND
 188    GND  VSS81 @T6G_MB_LIB.T6G(SCH_1):GND
 191    GND  VSS82 @T6G_MB_LIB.T6G(SCH_1):GND
 193    GND  VSS83 @T6G_MB_LIB.T6G(SCH_1):GND
 195    GND  VSS84 @T6G_MB_LIB.T6G(SCH_1):GND
 197    GND  VSS85 @T6G_MB_LIB.T6G(SCH_1):GND
 199    GND  VSS86 @T6G_MB_LIB.T6G(SCH_1):GND
 202    GND  VSS87 @T6G_MB_LIB.T6G(SCH_1):GND
 204    GND  VSS88 @T6G_MB_LIB.T6G(SCH_1):GND
 206    GND  VSS89 @T6G_MB_LIB.T6G(SCH_1):GND
 208    GND  VSS90 @T6G_MB_LIB.T6G(SCH_1):GND
 210    GND  VSS91 @T6G_MB_LIB.T6G(SCH_1):GND
 212    GND  VSS92 @T6G_MB_LIB.T6G(SCH_1):GND
 214    GND  VSS93 @T6G_MB_LIB.T6G(SCH_1):GND
 216    GND  VSS94 @T6G_MB_LIB.T6G(SCH_1):GND
 219    GND  VSS95 @T6G_MB_LIB.T6G(SCH_1):GND
 222    GND  VSS96 @T6G_MB_LIB.T6G(SCH_1):GND
 224    GND  VSS97 @T6G_MB_LIB.T6G(SCH_1):GND
 226    GND  VSS98 @T6G_MB_LIB.T6G(SCH_1):GND
 228    GND  VSS99 @T6G_MB_LIB.T6G(SCH_1):GND
 233    GND VSS101 @T6G_MB_LIB.T6G(SCH_1):GND
 237    GND VSS103 @T6G_MB_LIB.T6G(SCH_1):GND
 242    GND VSS105 @T6G_MB_LIB.T6G(SCH_1):GND
 244    GND VSS106 @T6G_MB_LIB.T6G(SCH_1):GND
 246    GND VSS107 @T6G_MB_LIB.T6G(SCH_1):GND
 248    GND VSS108 @T6G_MB_LIB.T6G(SCH_1):GND
 251    GND VSS109 @T6G_MB_LIB.T6G(SCH_1):GND
 253    GND VSS110 @T6G_MB_LIB.T6G(SCH_1):GND
 255    GND VSS111 @T6G_MB_LIB.T6G(SCH_1):GND
 257    GND VSS112 @T6G_MB_LIB.T6G(SCH_1):GND
 259    GND VSS113 @T6G_MB_LIB.T6G(SCH_1):GND
 262    GND VSS114 @T6G_MB_LIB.T6G(SCH_1):GND
 264    GND VSS115 @T6G_MB_LIB.T6G(SCH_1):GND
 266    GND VSS116 @T6G_MB_LIB.T6G(SCH_1):GND
 268    GND VSS117 @T6G_MB_LIB.T6G(SCH_1):GND
 270    GND VSS118 @T6G_MB_LIB.T6G(SCH_1):GND
 273    GND VSS119 @T6G_MB_LIB.T6G(SCH_1):GND
 275    GND VSS120 @T6G_MB_LIB.T6G(SCH_1):GND
 277    GND VSS121 @T6G_MB_LIB.T6G(SCH_1):GND
 279    GND VSS122 @T6G_MB_LIB.T6G(SCH_1):GND
 281    GND VSS123 @T6G_MB_LIB.T6G(SCH_1):GND
 284    GND VSS124 @T6G_MB_LIB.T6G(SCH_1):GND
 286    GND VSS125 @T6G_MB_LIB.T6G(SCH_1):GND
 288    GND VSS126 @T6G_MB_LIB.T6G(SCH_1):GND
   1 P12V_MEM_CPU0 VIN_BULK0 @T6G_MB_LIB.T6G(SCH_1):P12V_MEM_CPU0
 145 P12V_MEM_CPU0 VIN_BULK1 @T6G_MB_LIB.T6G(SCH_1):P12V_MEM_CPU0
 146 P12V_MEM_CPU0 VIN_BULK2 @T6G_MB_LIB.T6G(SCH_1):P12V_MEM_CPU0
 230    GND VSS100 @T6G_MB_LIB.T6G(SCH_1):GND
 235    GND VSS102 @T6G_MB_LIB.T6G(SCH_1):GND
 240    GND VSS104 @T6G_MB_LIB.T6G(SCH_1):GND
 132    GND  VSS58 @T6G_MB_LIB.T6G(SCH_1):GND
 136    GND  VSS60 @T6G_MB_LIB.T6G(SCH_1):GND
 139    GND  VSS61 @T6G_MB_LIB.T6G(SCH_1):GND
 141    GND  VSS62 @T6G_MB_LIB.T6G(SCH_1):GND
  G1    GND     G1 @T6G_MB_LIB.T6G(SCH_1):GND
  G2    GND     G2 @T6G_MB_LIB.T6G(SCH_1):GND
  G3    GND     G3 @T6G_MB_LIB.T6G(SCH_1):GND

Q_CAP_0402-0.1UF,25V,10%,X7R,CH4104K1B00  I362  C96
   1 P3V3_AUX      A @T6G_MB_LIB.T6G(SCH_1):P3V3_AUX
   2    GND      B @T6G_MB_LIB.T6G(SCH_1):GND

Q_RES_0402LF-1K,1%,1/16W,CHIP,CS21002FB06  I364  R293
   1 PWRGD_CHC_CPU0_DIMM      A @T6G_MB_LIB.T6G(SCH_1):PWRGD_CHC_CPU0_DIMM
   2 PWRGD_CHAF_CPU0      B @T6G_MB_LIB.T6G(SCH_1):PWRGD_CHAF_CPU0

Q_RES_0402LF-1K,1%,1/16W,EMPTY,CS21002FB06  I365  R91
   1   P3V3      A @T6G_MB_LIB.T6G(SCH_1):P3V3
   2 PWRGD_CHC_CPU0_DIMM      B @T6G_MB_LIB.T6G(SCH_1):PWRGD_CHC_CPU0_DIMM

SCONN288_DDR506112002KQ-SCONN288_DDR506112002KQ,SMA  I411  J17
  93 M_C_CPU0_SB_DQS_DP<9> DQS9_B_T||TDQS9_B_T||DBI4_B_N @T6G_MB_LIB.T6G(SCH_1):M_C_CPU0_SB_DQS_DP(9)
  94 M_C_CPU0_SB_DQS_DN<9> DQS9_B_C||TDQS9_B_C @T6G_MB_LIB.T6G(SCH_1):M_C_CPU0_SB_DQS_DN(9)
 201 M_C_CPU0_SA_DQS_DP<9> DQS9_A_T||TDQS9_A_T @T6G_MB_LIB.T6G(SCH_1):M_C_CPU0_SA_DQS_DP(9)
 200 M_C_CPU0_SA_DQS_DN<9> DQS9_A_C||TDQS9_A_C @T6G_MB_LIB.T6G(SCH_1):M_C_CPU0_SA_DQS_DN(9)
 190 M_C_CPU0_SA_DQS_DP<8> DQS8_A_T||TDQS8_A_T @T6G_MB_LIB.T6G(SCH_1):M_C_CPU0_SA_DQS_DP(8)
 189 M_C_CPU0_SA_DQS_DN<8> DQS8_A_C||TDQS8_A_C @T6G_MB_LIB.T6G(SCH_1):M_C_CPU0_SA_DQS_DN(8)
 271 M_C_CPU0_SB_DQS_DN<7> DQS7_B_C||TDQS7_B_C @T6G_MB_LIB.T6G(SCH_1):M_C_CPU0_SB_DQS_DN(7)
 179 M_C_CPU0_SA_DQS_DP<7> DQS7_A_T||TDQS7_A_T @T6G_MB_LIB.T6G(SCH_1):M_C_CPU0_SA_DQS_DP(7)
 261 M_C_CPU0_SB_DQS_DP<6> DQS6_B_T||TDQS6_B_T @T6G_MB_LIB.T6G(SCH_1):M_C_CPU0_SB_DQS_DP(6)
 260 M_C_CPU0_SB_DQS_DN<6> DQS6_B_C||TDQS6_B_C @T6G_MB_LIB.T6G(SCH_1):M_C_CPU0_SB_DQS_DN(6)
 167 M_C_CPU0_SA_DQS_DN<6> DQS6_A_C||TDQS6_A_C||DQS6_A_T||TDQS6_A_T @T6G_MB_LIB.T6G(SCH_1):M_C_CPU0_SA_DQS_DN(6)
 250 M_C_CPU0_SB_DQS_DP<5> DQS5_B_T||TDQS5_B_T @T6G_MB_LIB.T6G(SCH_1):M_C_CPU0_SB_DQS_DP(5)
 249 M_C_CPU0_SB_DQS_DN<5> DQS5_B_C||TDQS5_B_C @T6G_MB_LIB.T6G(SCH_1):M_C_CPU0_SB_DQS_DN(5)
 157 M_C_CPU0_SA_DQS_DP<5> DQS5_A_T||TDQS5_A_T @T6G_MB_LIB.T6G(SCH_1):M_C_CPU0_SA_DQS_DP(5)
 156 M_C_CPU0_SA_DQS_DN<5> DQS5_A_C||TDQS5_A_C||DQS5_A_T||TDQS5_A_T @T6G_MB_LIB.T6G(SCH_1):M_C_CPU0_SA_DQS_DN(5)
 239 M_C_CPU0_SB_DQS_DP<4> DQS4_B_T @T6G_MB_LIB.T6G(SCH_1):M_C_CPU0_SB_DQS_DP(4)
 238 M_C_CPU0_SB_DQS_DN<4> DQS4_B_C @T6G_MB_LIB.T6G(SCH_1):M_C_CPU0_SB_DQS_DN(4)
  55 M_C_CPU0_SA_DQS_DP<4> DQS4_A_T @T6G_MB_LIB.T6G(SCH_1):M_C_CPU0_SA_DQS_DP(4)
  56 M_C_CPU0_SA_DQS_DN<4> DQS4_A_C @T6G_MB_LIB.T6G(SCH_1):M_C_CPU0_SA_DQS_DN(4)
 137 M_C_CPU0_SB_DQS_DP<3> DQS3_B_T @T6G_MB_LIB.T6G(SCH_1):M_C_CPU0_SB_DQS_DP(3)
 138 M_C_CPU0_SB_DQS_DN<3> DQS3_B_C @T6G_MB_LIB.T6G(SCH_1):M_C_CPU0_SB_DQS_DN(3)
  44 M_C_CPU0_SA_DQS_DP<3> DQS3_A_T @T6G_MB_LIB.T6G(SCH_1):M_C_CPU0_SA_DQS_DP(3)
  45 M_C_CPU0_SA_DQS_DN<3> DQS3_A_C @T6G_MB_LIB.T6G(SCH_1):M_C_CPU0_SA_DQS_DN(3)
 126 M_C_CPU0_SB_DQS_DP<2> DQS2_B_T @T6G_MB_LIB.T6G(SCH_1):M_C_CPU0_SB_DQS_DP(2)
 127 M_C_CPU0_SB_DQS_DN<2> DQS2_B_C @T6G_MB_LIB.T6G(SCH_1):M_C_CPU0_SB_DQS_DN(2)
  33 M_C_CPU0_SA_DQS_DP<2> DQS2_A_T @T6G_MB_LIB.T6G(SCH_1):M_C_CPU0_SA_DQS_DP(2)
  34 M_C_CPU0_SA_DQS_DN<2> DQS2_A_C @T6G_MB_LIB.T6G(SCH_1):M_C_CPU0_SA_DQS_DN(2)
 115 M_C_CPU0_SB_DQS_DP<1> DQS1_B_T @T6G_MB_LIB.T6G(SCH_1):M_C_CPU0_SB_DQS_DP(1)
 116 M_C_CPU0_SB_DQS_DN<1> DQS1_B_C @T6G_MB_LIB.T6G(SCH_1):M_C_CPU0_SB_DQS_DN(1)
  22 M_C_CPU0_SA_DQS_DP<1> DQS1_A_T @T6G_MB_LIB.T6G(SCH_1):M_C_CPU0_SA_DQS_DP(1)
  23 M_C_CPU0_SA_DQS_DN<1> DQS1_A_C @T6G_MB_LIB.T6G(SCH_1):M_C_CPU0_SA_DQS_DN(1)
 104 M_C_CPU0_SB_DQS_DP<0> DQS0_B_T @T6G_MB_LIB.T6G(SCH_1):M_C_CPU0_SB_DQS_DP(0)
 105 M_C_CPU0_SB_DQS_DN<0> DQS0_B_C @T6G_MB_LIB.T6G(SCH_1):M_C_CPU0_SB_DQS_DN(0)
  11 M_C_CPU0_SA_DQS_DP<0> DQS0_A_T @T6G_MB_LIB.T6G(SCH_1):M_C_CPU0_SA_DQS_DP(0)
  12 M_C_CPU0_SA_DQS_DN<0> DQS0_A_C @T6G_MB_LIB.T6G(SCH_1):M_C_CPU0_SA_DQS_DN(0)
 272 M_C_CPU0_SB_DQS_DP<7> DQS7_B_T||TDQS7_B_T @T6G_MB_LIB.T6G(SCH_1):M_C_CPU0_SB_DQS_DP(7)
 282 M_C_CPU0_SB_DQS_DN<8> DQS8_B_C||TDQS8_B_C @T6G_MB_LIB.T6G(SCH_1):M_C_CPU0_SB_DQS_DN(8)
 283 M_C_CPU0_SB_DQS_DP<8> DQS8_B_T||TDQS8_B_T @T6G_MB_LIB.T6G(SCH_1):M_C_CPU0_SB_DQS_DP(8)
 168 M_C_CPU0_SA_DQS_DP<6> DQS6_A_T||TDQS6_A_T @T6G_MB_LIB.T6G(SCH_1):M_C_CPU0_SA_DQS_DP(6)
 178 M_C_CPU0_SA_DQS_DN<7> DQS7_A_C||TDQS7_A_C @T6G_MB_LIB.T6G(SCH_1):M_C_CPU0_SA_DQS_DN(7)

Q_CAP_C0805-10UF,25V,10%,X6S,CH6104KEA00  I413  C146
   1 P12V_MEM_CPU0      A @T6G_MB_LIB.T6G(SCH_1):P12V_MEM_CPU0
   2    GND      B @T6G_MB_LIB.T6G(SCH_1):GND

Q_CAP_C0805-10UF,25V,10%,X6S,CH6104KEA00  I414  C147
   1 P12V_MEM_CPU0      A @T6G_MB_LIB.T6G(SCH_1):P12V_MEM_CPU0
   2    GND      B @T6G_MB_LIB.T6G(SCH_1):GND

Q_RES_0402LF-49.9,1%,1/16W,CHIP,CS04992FB07  I417  R1570
   1 I3C_SPD_DDRAF_CPU0_SCL      A @T6G_MB_LIB.T6G(SCH_1):I3C_SPD_DDRAF_CPU0_SCL
   2 I3C_SPD_DDRC_CPU0_SCL      B @T6G_MB_LIB.T6G(SCH_1):I3C_SPD_DDRC_CPU0_SCL

Q_RES_0402LF-10,1%,1/16W,CHIP,CS01002FB07  I418  R1677
   1 I3C_SPD_DDRAF_CPU0_SDA      A @T6G_MB_LIB.T6G(SCH_1):I3C_SPD_DDRAF_CPU0_SDA
   2 I3C_SPD_DDRC_CPU0_SDA      B @T6G_MB_LIB.T6G(SCH_1):I3C_SPD_DDRC_CPU0_SDA


DRAWING: @T6G_MB_LIB.T6G(SCH_1):PAGE88 

Q_RES_0402LF-35.7K,1%,1/16W,CHIP,CS33572FB01  I349  R763
   1 PD_CHD_CPU0_DIMM_SAA      A @T6G_MB_LIB.T6G(SCH_1):PD_CHD_CPU0_DIMM_SAA
   2    GND      B @T6G_MB_LIB.T6G(SCH_1):GND

SCONN288_DDR506112002KQ-SCONN288_DDR506112002KQ,SMA  I350  J19
   3 P3V3_AUX VIN_MGMT @T6G_MB_LIB.T6G(SCH_1):P3V3_AUX
   2     NC   RFU0     NC
 144     NC   RFU1     NC
 149     NC   RFU2     NC
 150     NC   RFU3     NC
 220     NC   RFU4     NC
 231     NC   RFU5     NC
 232     NC   RFU6     NC
 207 M_D_CPU0_RESET_N RESET_N @T6G_MB_LIB.T6G(SCH_1):M_D_CPU0_RESET_N
 147 PWRGD_CHD_CPU0_DIMM PWR_GOOD||FAIL_N @T6G_MB_LIB.T6G(SCH_1):PWRGD_CHD_CPU0_DIMM
 227 M_D_CPU0_SB_PAR  PAR_B @T6G_MB_LIB.T6G(SCH_1):M_D_CPU0_SB_PAR
  74 M_D_CPU0_SA_PAR  PAR_A @T6G_MB_LIB.T6G(SCH_1):M_D_CPU0_SA_PAR
  87 M_D_CPU0_SB_RSP<0> LBS||RSP_B_N @T6G_MB_LIB.T6G(SCH_1):M_D_CPU0_SB_RSP(0)
  86 M_D_CPU0_SA_RSP<0> LBD||RSP_A_N @T6G_MB_LIB.T6G(SCH_1):M_D_CPU0_SA_RSP(0)
   5 I3C_SPD_DDRD_CPU0_SDA   HSDA @T6G_MB_LIB.T6G(SCH_1):I3C_SPD_DDRD_CPU0_SDA
   4 I3C_SPD_DDRD_CPU0_SCL   HSCL @T6G_MB_LIB.T6G(SCH_1):I3C_SPD_DDRD_CPU0_SCL
 148 PD_CHD_CPU0_DIMM_SAA    HAS @T6G_MB_LIB.T6G(SCH_1):PD_CHD_CPU0_DIMM_SAA
 100 M_D_CPU0_SB_DQ<0>  DQ0_B @T6G_MB_LIB.T6G(SCH_1):M_D_CPU0_SB_DQ(0)
 102 M_D_CPU0_SB_DQ<1>  DQ1_B @T6G_MB_LIB.T6G(SCH_1):M_D_CPU0_SB_DQ(1)
 245 M_D_CPU0_SB_DQ<2>  DQ2_B @T6G_MB_LIB.T6G(SCH_1):M_D_CPU0_SB_DQ(2)
 247 M_D_CPU0_SB_DQ<3>  DQ3_B @T6G_MB_LIB.T6G(SCH_1):M_D_CPU0_SB_DQ(3)
 107 M_D_CPU0_SB_DQ<4>  DQ4_B @T6G_MB_LIB.T6G(SCH_1):M_D_CPU0_SB_DQ(4)
 109 M_D_CPU0_SB_DQ<5>  DQ5_B @T6G_MB_LIB.T6G(SCH_1):M_D_CPU0_SB_DQ(5)
 252 M_D_CPU0_SB_DQ<6>  DQ6_B @T6G_MB_LIB.T6G(SCH_1):M_D_CPU0_SB_DQ(6)
 254 M_D_CPU0_SB_DQ<7>  DQ7_B @T6G_MB_LIB.T6G(SCH_1):M_D_CPU0_SB_DQ(7)
 111 M_D_CPU0_SB_DQ<8>  DQ8_B @T6G_MB_LIB.T6G(SCH_1):M_D_CPU0_SB_DQ(8)
 113 M_D_CPU0_SB_DQ<9>  DQ9_B @T6G_MB_LIB.T6G(SCH_1):M_D_CPU0_SB_DQ(9)
 256 M_D_CPU0_SB_DQ<10> DQ10_B @T6G_MB_LIB.T6G(SCH_1):M_D_CPU0_SB_DQ(10)
 258 M_D_CPU0_SB_DQ<11> DQ11_B @T6G_MB_LIB.T6G(SCH_1):M_D_CPU0_SB_DQ(11)
 118 M_D_CPU0_SB_DQ<12> DQ12_B @T6G_MB_LIB.T6G(SCH_1):M_D_CPU0_SB_DQ(12)
 120 M_D_CPU0_SB_DQ<13> DQ13_B @T6G_MB_LIB.T6G(SCH_1):M_D_CPU0_SB_DQ(13)
 263 M_D_CPU0_SB_DQ<14> DQ14_B @T6G_MB_LIB.T6G(SCH_1):M_D_CPU0_SB_DQ(14)
 265 M_D_CPU0_SB_DQ<15> DQ15_B @T6G_MB_LIB.T6G(SCH_1):M_D_CPU0_SB_DQ(15)
 122 M_D_CPU0_SB_DQ<16> DQ16_B @T6G_MB_LIB.T6G(SCH_1):M_D_CPU0_SB_DQ(16)
 124 M_D_CPU0_SB_DQ<17> DQ17_B @T6G_MB_LIB.T6G(SCH_1):M_D_CPU0_SB_DQ(17)
 267 M_D_CPU0_SB_DQ<18> DQ18_B @T6G_MB_LIB.T6G(SCH_1):M_D_CPU0_SB_DQ(18)
 269 M_D_CPU0_SB_DQ<19> DQ19_B @T6G_MB_LIB.T6G(SCH_1):M_D_CPU0_SB_DQ(19)
 129 M_D_CPU0_SB_DQ<20> DQ20_B @T6G_MB_LIB.T6G(SCH_1):M_D_CPU0_SB_DQ(20)
 131 M_D_CPU0_SB_DQ<21> DQ21_B @T6G_MB_LIB.T6G(SCH_1):M_D_CPU0_SB_DQ(21)
 274 M_D_CPU0_SB_DQ<22> DQ22_B @T6G_MB_LIB.T6G(SCH_1):M_D_CPU0_SB_DQ(22)
 276 M_D_CPU0_SB_DQ<23> DQ23_B @T6G_MB_LIB.T6G(SCH_1):M_D_CPU0_SB_DQ(23)
 133 M_D_CPU0_SB_DQ<24> DQ24_B @T6G_MB_LIB.T6G(SCH_1):M_D_CPU0_SB_DQ(24)
 135 M_D_CPU0_SB_DQ<25> DQ25_B @T6G_MB_LIB.T6G(SCH_1):M_D_CPU0_SB_DQ(25)
 278 M_D_CPU0_SB_DQ<26> DQ26_B @T6G_MB_LIB.T6G(SCH_1):M_D_CPU0_SB_DQ(26)
 280 M_D_CPU0_SB_DQ<27> DQ27_B @T6G_MB_LIB.T6G(SCH_1):M_D_CPU0_SB_DQ(27)
 140 M_D_CPU0_SB_DQ<28> DQ28_B @T6G_MB_LIB.T6G(SCH_1):M_D_CPU0_SB_DQ(28)
 142 M_D_CPU0_SB_DQ<29> DQ29_B @T6G_MB_LIB.T6G(SCH_1):M_D_CPU0_SB_DQ(29)
 285 M_D_CPU0_SB_DQ<30> DQ30_B @T6G_MB_LIB.T6G(SCH_1):M_D_CPU0_SB_DQ(30)
 287 M_D_CPU0_SB_DQ<31> DQ31_B @T6G_MB_LIB.T6G(SCH_1):M_D_CPU0_SB_DQ(31)
   7 M_D_CPU0_SA_DQ<0>  DQ0_A @T6G_MB_LIB.T6G(SCH_1):M_D_CPU0_SA_DQ(0)
   9 M_D_CPU0_SA_DQ<1>  DQ1_A @T6G_MB_LIB.T6G(SCH_1):M_D_CPU0_SA_DQ(1)
 152 M_D_CPU0_SA_DQ<2>  DQ2_A @T6G_MB_LIB.T6G(SCH_1):M_D_CPU0_SA_DQ(2)
 154 M_D_CPU0_SA_DQ<3>  DQ3_A @T6G_MB_LIB.T6G(SCH_1):M_D_CPU0_SA_DQ(3)
  14 M_D_CPU0_SA_DQ<4>  DQ4_A @T6G_MB_LIB.T6G(SCH_1):M_D_CPU0_SA_DQ(4)
  16 M_D_CPU0_SA_DQ<5>  DQ5_A @T6G_MB_LIB.T6G(SCH_1):M_D_CPU0_SA_DQ(5)
 159 M_D_CPU0_SA_DQ<6>  DQ6_A @T6G_MB_LIB.T6G(SCH_1):M_D_CPU0_SA_DQ(6)
 161 M_D_CPU0_SA_DQ<7>  DQ7_A @T6G_MB_LIB.T6G(SCH_1):M_D_CPU0_SA_DQ(7)
  18 M_D_CPU0_SA_DQ<8>  DQ8_A @T6G_MB_LIB.T6G(SCH_1):M_D_CPU0_SA_DQ(8)
  20 M_D_CPU0_SA_DQ<9>  DQ9_A @T6G_MB_LIB.T6G(SCH_1):M_D_CPU0_SA_DQ(9)
 163 M_D_CPU0_SA_DQ<10> DQ10_A @T6G_MB_LIB.T6G(SCH_1):M_D_CPU0_SA_DQ(10)
 165 M_D_CPU0_SA_DQ<11> DQ11_A @T6G_MB_LIB.T6G(SCH_1):M_D_CPU0_SA_DQ(11)
  25 M_D_CPU0_SA_DQ<12> DQ12_A @T6G_MB_LIB.T6G(SCH_1):M_D_CPU0_SA_DQ(12)
  27 M_D_CPU0_SA_DQ<13> DQ13_A @T6G_MB_LIB.T6G(SCH_1):M_D_CPU0_SA_DQ(13)
 170 M_D_CPU0_SA_DQ<14> DQ14_A @T6G_MB_LIB.T6G(SCH_1):M_D_CPU0_SA_DQ(14)
 172 M_D_CPU0_SA_DQ<15> DQ15_A @T6G_MB_LIB.T6G(SCH_1):M_D_CPU0_SA_DQ(15)
  29 M_D_CPU0_SA_DQ<16> DQ16_A @T6G_MB_LIB.T6G(SCH_1):M_D_CPU0_SA_DQ(16)
  31 M_D_CPU0_SA_DQ<17> DQ17_A @T6G_MB_LIB.T6G(SCH_1):M_D_CPU0_SA_DQ(17)
 174 M_D_CPU0_SA_DQ<18> DQ18_A @T6G_MB_LIB.T6G(SCH_1):M_D_CPU0_SA_DQ(18)
 176 M_D_CPU0_SA_DQ<19> DQ19_A @T6G_MB_LIB.T6G(SCH_1):M_D_CPU0_SA_DQ(19)
  36 M_D_CPU0_SA_DQ<20> DQ20_A @T6G_MB_LIB.T6G(SCH_1):M_D_CPU0_SA_DQ(20)
  38 M_D_CPU0_SA_DQ<21> DQ21_A @T6G_MB_LIB.T6G(SCH_1):M_D_CPU0_SA_DQ(21)
 181 M_D_CPU0_SA_DQ<22> DQ22_A @T6G_MB_LIB.T6G(SCH_1):M_D_CPU0_SA_DQ(22)
 183 M_D_CPU0_SA_DQ<23> DQ23_A @T6G_MB_LIB.T6G(SCH_1):M_D_CPU0_SA_DQ(23)
  40 M_D_CPU0_SA_DQ<24> DQ24_A @T6G_MB_LIB.T6G(SCH_1):M_D_CPU0_SA_DQ(24)
  42 M_D_CPU0_SA_DQ<25> DQ25_A @T6G_MB_LIB.T6G(SCH_1):M_D_CPU0_SA_DQ(25)
 185 M_D_CPU0_SA_DQ<26> DQ26_A @T6G_MB_LIB.T6G(SCH_1):M_D_CPU0_SA_DQ(26)
 187 M_D_CPU0_SA_DQ<27> DQ27_A @T6G_MB_LIB.T6G(SCH_1):M_D_CPU0_SA_DQ(27)
  47 M_D_CPU0_SA_DQ<28> DQ28_A @T6G_MB_LIB.T6G(SCH_1):M_D_CPU0_SA_DQ(28)
  49 M_D_CPU0_SA_DQ<29> DQ29_A @T6G_MB_LIB.T6G(SCH_1):M_D_CPU0_SA_DQ(29)
 192 M_D_CPU0_SA_DQ<30> DQ30_A @T6G_MB_LIB.T6G(SCH_1):M_D_CPU0_SA_DQ(30)
 229 M_D_CPU0_SB_CS_N<1> CS1_B_N @T6G_MB_LIB.T6G(SCH_1):M_D_CPU0_SB_CS_N(1)
 209 M_D_CPU0_SA_CS_N<1> CS1_A_N @T6G_MB_LIB.T6G(SCH_1):M_D_CPU0_SA_CS_N(1)
  84 M_D_CPU0_SB_CS_N<0> CS0_B_N @T6G_MB_LIB.T6G(SCH_1):M_D_CPU0_SB_CS_N(0)
  64 M_D_CPU0_SA_CS_N<0> CS0_A_N @T6G_MB_LIB.T6G(SCH_1):M_D_CPU0_SA_CS_N(0)
 217 M_D_CPU0_CLK_DP<0>   CK_T @T6G_MB_LIB.T6G(SCH_1):M_D_CPU0_CLK_DP(0)
 218 M_D_CPU0_CLK_DN<0>   CK_C @T6G_MB_LIB.T6G(SCH_1):M_D_CPU0_CLK_DN(0)
  96 M_D_CPU0_SB_CB<0>  CB0_B @T6G_MB_LIB.T6G(SCH_1):M_D_CPU0_SB_CB(0)
  98 M_D_CPU0_SB_CB<1>  CB1_B @T6G_MB_LIB.T6G(SCH_1):M_D_CPU0_SB_CB(1)
 241 M_D_CPU0_SB_CB<2>  CB2_B @T6G_MB_LIB.T6G(SCH_1):M_D_CPU0_SB_CB(2)
 243 M_D_CPU0_SB_CB<3>  CB3_B @T6G_MB_LIB.T6G(SCH_1):M_D_CPU0_SB_CB(3)
  89 M_D_CPU0_SB_CB<4>  CB4_B @T6G_MB_LIB.T6G(SCH_1):M_D_CPU0_SB_CB(4)
  91 M_D_CPU0_SB_CB<5>  CB5_B @T6G_MB_LIB.T6G(SCH_1):M_D_CPU0_SB_CB(5)
 234 M_D_CPU0_SB_CB<6>  CB6_B @T6G_MB_LIB.T6G(SCH_1):M_D_CPU0_SB_CB(6)
  51 M_D_CPU0_SA_CB<0>  CB0_A @T6G_MB_LIB.T6G(SCH_1):M_D_CPU0_SA_CB(0)
 196 M_D_CPU0_SA_CB<2>  CB2_A @T6G_MB_LIB.T6G(SCH_1):M_D_CPU0_SA_CB(2)
 198 M_D_CPU0_SA_CB<3>  CB3_A @T6G_MB_LIB.T6G(SCH_1):M_D_CPU0_SA_CB(3)
  60 M_D_CPU0_SA_CB<5>  CB5_A @T6G_MB_LIB.T6G(SCH_1):M_D_CPU0_SA_CB(5)
 203 M_D_CPU0_SA_CB<6>  CB6_A @T6G_MB_LIB.T6G(SCH_1):M_D_CPU0_SA_CB(6)
  82 M_D_CPU0_SB_CA<6>  CA6_B @T6G_MB_LIB.T6G(SCH_1):M_D_CPU0_SB_CA(6)
  72 M_D_CPU0_SA_CA<6>  CA6_A @T6G_MB_LIB.T6G(SCH_1):M_D_CPU0_SA_CA(6)
 225 M_D_CPU0_SB_CA<5>  CA5_B @T6G_MB_LIB.T6G(SCH_1):M_D_CPU0_SB_CA(5)
 215 M_D_CPU0_SA_CA<5>  CA5_A @T6G_MB_LIB.T6G(SCH_1):M_D_CPU0_SA_CA(5)
  80 M_D_CPU0_SB_CA<4>  CA4_B @T6G_MB_LIB.T6G(SCH_1):M_D_CPU0_SB_CA(4)
  70 M_D_CPU0_SA_CA<4>  CA4_A @T6G_MB_LIB.T6G(SCH_1):M_D_CPU0_SA_CA(4)
 223 M_D_CPU0_SB_CA<3>  CA3_B @T6G_MB_LIB.T6G(SCH_1):M_D_CPU0_SB_CA(3)
 213 M_D_CPU0_SA_CA<3>  CA3_A @T6G_MB_LIB.T6G(SCH_1):M_D_CPU0_SA_CA(3)
  78 M_D_CPU0_SB_CA<2>  CA2_B @T6G_MB_LIB.T6G(SCH_1):M_D_CPU0_SB_CA(2)
  68 M_D_CPU0_SA_CA<2>  CA2_A @T6G_MB_LIB.T6G(SCH_1):M_D_CPU0_SA_CA(2)
 221 M_D_CPU0_SB_CA<1>  CA1_B @T6G_MB_LIB.T6G(SCH_1):M_D_CPU0_SB_CA(1)
 211 M_D_CPU0_SA_CA<1>  CA1_A @T6G_MB_LIB.T6G(SCH_1):M_D_CPU0_SA_CA(1)
  76 M_D_CPU0_SB_CA<0>  CA0_B @T6G_MB_LIB.T6G(SCH_1):M_D_CPU0_SB_CA(0)
  66 M_D_CPU0_SA_CA<0>  CA0_A @T6G_MB_LIB.T6G(SCH_1):M_D_CPU0_SA_CA(0)
  62 M_D_CPU0_ALERT_N ALERT_N @T6G_MB_LIB.T6G(SCH_1):M_D_CPU0_ALERT_N
 236 M_D_CPU0_SB_CB<7>  CB7_B @T6G_MB_LIB.T6G(SCH_1):M_D_CPU0_SB_CB(7)
  53 M_D_CPU0_SA_CB<1>  CB1_A @T6G_MB_LIB.T6G(SCH_1):M_D_CPU0_SA_CB(1)
  58 M_D_CPU0_SA_CB<4>  CB4_A @T6G_MB_LIB.T6G(SCH_1):M_D_CPU0_SA_CB(4)
 205 M_D_CPU0_SA_CB<7>  CB7_A @T6G_MB_LIB.T6G(SCH_1):M_D_CPU0_SA_CB(7)
 194 M_D_CPU0_SA_DQ<31> DQ31_A @T6G_MB_LIB.T6G(SCH_1):M_D_CPU0_SA_DQ(31)

SCONN288_DDR506112002KQ-SCONN288_DDR506112002KQ,SMA  I352  J19
   6    GND   VSS0 @T6G_MB_LIB.T6G(SCH_1):GND
   8    GND   VSS1 @T6G_MB_LIB.T6G(SCH_1):GND
  10    GND   VSS2 @T6G_MB_LIB.T6G(SCH_1):GND
  13    GND   VSS3 @T6G_MB_LIB.T6G(SCH_1):GND
  15    GND   VSS4 @T6G_MB_LIB.T6G(SCH_1):GND
  17    GND   VSS5 @T6G_MB_LIB.T6G(SCH_1):GND
  19    GND   VSS6 @T6G_MB_LIB.T6G(SCH_1):GND
  21    GND   VSS7 @T6G_MB_LIB.T6G(SCH_1):GND
  24    GND   VSS8 @T6G_MB_LIB.T6G(SCH_1):GND
  26    GND   VSS9 @T6G_MB_LIB.T6G(SCH_1):GND
  28    GND  VSS10 @T6G_MB_LIB.T6G(SCH_1):GND
  30    GND  VSS11 @T6G_MB_LIB.T6G(SCH_1):GND
  32    GND  VSS12 @T6G_MB_LIB.T6G(SCH_1):GND
  35    GND  VSS13 @T6G_MB_LIB.T6G(SCH_1):GND
  37    GND  VSS14 @T6G_MB_LIB.T6G(SCH_1):GND
  39    GND  VSS15 @T6G_MB_LIB.T6G(SCH_1):GND
  41    GND  VSS16 @T6G_MB_LIB.T6G(SCH_1):GND
  43    GND  VSS17 @T6G_MB_LIB.T6G(SCH_1):GND
  46    GND  VSS18 @T6G_MB_LIB.T6G(SCH_1):GND
  48    GND  VSS19 @T6G_MB_LIB.T6G(SCH_1):GND
  50    GND  VSS20 @T6G_MB_LIB.T6G(SCH_1):GND
  52    GND  VSS21 @T6G_MB_LIB.T6G(SCH_1):GND
  54    GND  VSS22 @T6G_MB_LIB.T6G(SCH_1):GND
  57    GND  VSS23 @T6G_MB_LIB.T6G(SCH_1):GND
  59    GND  VSS24 @T6G_MB_LIB.T6G(SCH_1):GND
  61    GND  VSS25 @T6G_MB_LIB.T6G(SCH_1):GND
  63    GND  VSS26 @T6G_MB_LIB.T6G(SCH_1):GND
  65    GND  VSS27 @T6G_MB_LIB.T6G(SCH_1):GND
  67    GND  VSS28 @T6G_MB_LIB.T6G(SCH_1):GND
  69    GND  VSS29 @T6G_MB_LIB.T6G(SCH_1):GND
  71    GND  VSS30 @T6G_MB_LIB.T6G(SCH_1):GND
  73    GND  VSS31 @T6G_MB_LIB.T6G(SCH_1):GND
  75    GND  VSS32 @T6G_MB_LIB.T6G(SCH_1):GND
  77    GND  VSS33 @T6G_MB_LIB.T6G(SCH_1):GND
  79    GND  VSS34 @T6G_MB_LIB.T6G(SCH_1):GND
  81    GND  VSS35 @T6G_MB_LIB.T6G(SCH_1):GND
  83    GND  VSS36 @T6G_MB_LIB.T6G(SCH_1):GND
  85    GND  VSS37 @T6G_MB_LIB.T6G(SCH_1):GND
  88    GND  VSS38 @T6G_MB_LIB.T6G(SCH_1):GND
  90    GND  VSS39 @T6G_MB_LIB.T6G(SCH_1):GND
  92    GND  VSS40 @T6G_MB_LIB.T6G(SCH_1):GND
  95    GND  VSS41 @T6G_MB_LIB.T6G(SCH_1):GND
  97    GND  VSS42 @T6G_MB_LIB.T6G(SCH_1):GND
  99    GND  VSS43 @T6G_MB_LIB.T6G(SCH_1):GND
 101    GND  VSS44 @T6G_MB_LIB.T6G(SCH_1):GND
 103    GND  VSS45 @T6G_MB_LIB.T6G(SCH_1):GND
 106    GND  VSS46 @T6G_MB_LIB.T6G(SCH_1):GND
 108    GND  VSS47 @T6G_MB_LIB.T6G(SCH_1):GND
 110    GND  VSS48 @T6G_MB_LIB.T6G(SCH_1):GND
 112    GND  VSS49 @T6G_MB_LIB.T6G(SCH_1):GND
 114    GND  VSS50 @T6G_MB_LIB.T6G(SCH_1):GND
 117    GND  VSS51 @T6G_MB_LIB.T6G(SCH_1):GND
 119    GND  VSS52 @T6G_MB_LIB.T6G(SCH_1):GND
 121    GND  VSS53 @T6G_MB_LIB.T6G(SCH_1):GND
 123    GND  VSS54 @T6G_MB_LIB.T6G(SCH_1):GND
 125    GND  VSS55 @T6G_MB_LIB.T6G(SCH_1):GND
 128    GND  VSS56 @T6G_MB_LIB.T6G(SCH_1):GND
 130    GND  VSS57 @T6G_MB_LIB.T6G(SCH_1):GND
 134    GND  VSS59 @T6G_MB_LIB.T6G(SCH_1):GND
 143    GND  VSS63 @T6G_MB_LIB.T6G(SCH_1):GND
 151    GND  VSS64 @T6G_MB_LIB.T6G(SCH_1):GND
 153    GND  VSS65 @T6G_MB_LIB.T6G(SCH_1):GND
 155    GND  VSS66 @T6G_MB_LIB.T6G(SCH_1):GND
 158    GND  VSS67 @T6G_MB_LIB.T6G(SCH_1):GND
 160    GND  VSS68 @T6G_MB_LIB.T6G(SCH_1):GND
 162    GND  VSS69 @T6G_MB_LIB.T6G(SCH_1):GND
 164    GND  VSS70 @T6G_MB_LIB.T6G(SCH_1):GND
 166    GND  VSS71 @T6G_MB_LIB.T6G(SCH_1):GND
 169    GND  VSS72 @T6G_MB_LIB.T6G(SCH_1):GND
 171    GND  VSS73 @T6G_MB_LIB.T6G(SCH_1):GND
 173    GND  VSS74 @T6G_MB_LIB.T6G(SCH_1):GND
 175    GND  VSS75 @T6G_MB_LIB.T6G(SCH_1):GND
 177    GND  VSS76 @T6G_MB_LIB.T6G(SCH_1):GND
 180    GND  VSS77 @T6G_MB_LIB.T6G(SCH_1):GND
 182    GND  VSS78 @T6G_MB_LIB.T6G(SCH_1):GND
 184    GND  VSS79 @T6G_MB_LIB.T6G(SCH_1):GND
 186    GND  VSS80 @T6G_MB_LIB.T6G(SCH_1):GND
 188    GND  VSS81 @T6G_MB_LIB.T6G(SCH_1):GND
 191    GND  VSS82 @T6G_MB_LIB.T6G(SCH_1):GND
 193    GND  VSS83 @T6G_MB_LIB.T6G(SCH_1):GND
 195    GND  VSS84 @T6G_MB_LIB.T6G(SCH_1):GND
 197    GND  VSS85 @T6G_MB_LIB.T6G(SCH_1):GND
 199    GND  VSS86 @T6G_MB_LIB.T6G(SCH_1):GND
 202    GND  VSS87 @T6G_MB_LIB.T6G(SCH_1):GND
 204    GND  VSS88 @T6G_MB_LIB.T6G(SCH_1):GND
 206    GND  VSS89 @T6G_MB_LIB.T6G(SCH_1):GND
 208    GND  VSS90 @T6G_MB_LIB.T6G(SCH_1):GND
 210    GND  VSS91 @T6G_MB_LIB.T6G(SCH_1):GND
 212    GND  VSS92 @T6G_MB_LIB.T6G(SCH_1):GND
 214    GND  VSS93 @T6G_MB_LIB.T6G(SCH_1):GND
 216    GND  VSS94 @T6G_MB_LIB.T6G(SCH_1):GND
 219    GND  VSS95 @T6G_MB_LIB.T6G(SCH_1):GND
 222    GND  VSS96 @T6G_MB_LIB.T6G(SCH_1):GND
 224    GND  VSS97 @T6G_MB_LIB.T6G(SCH_1):GND
 226    GND  VSS98 @T6G_MB_LIB.T6G(SCH_1):GND
 228    GND  VSS99 @T6G_MB_LIB.T6G(SCH_1):GND
 233    GND VSS101 @T6G_MB_LIB.T6G(SCH_1):GND
 237    GND VSS103 @T6G_MB_LIB.T6G(SCH_1):GND
 242    GND VSS105 @T6G_MB_LIB.T6G(SCH_1):GND
 244    GND VSS106 @T6G_MB_LIB.T6G(SCH_1):GND
 246    GND VSS107 @T6G_MB_LIB.T6G(SCH_1):GND
 248    GND VSS108 @T6G_MB_LIB.T6G(SCH_1):GND
 251    GND VSS109 @T6G_MB_LIB.T6G(SCH_1):GND
 253    GND VSS110 @T6G_MB_LIB.T6G(SCH_1):GND
 255    GND VSS111 @T6G_MB_LIB.T6G(SCH_1):GND
 257    GND VSS112 @T6G_MB_LIB.T6G(SCH_1):GND
 259    GND VSS113 @T6G_MB_LIB.T6G(SCH_1):GND
 262    GND VSS114 @T6G_MB_LIB.T6G(SCH_1):GND
 264    GND VSS115 @T6G_MB_LIB.T6G(SCH_1):GND
 266    GND VSS116 @T6G_MB_LIB.T6G(SCH_1):GND
 268    GND VSS117 @T6G_MB_LIB.T6G(SCH_1):GND
 270    GND VSS118 @T6G_MB_LIB.T6G(SCH_1):GND
 273    GND VSS119 @T6G_MB_LIB.T6G(SCH_1):GND
 275    GND VSS120 @T6G_MB_LIB.T6G(SCH_1):GND
 277    GND VSS121 @T6G_MB_LIB.T6G(SCH_1):GND
 279    GND VSS122 @T6G_MB_LIB.T6G(SCH_1):GND
 281    GND VSS123 @T6G_MB_LIB.T6G(SCH_1):GND
 284    GND VSS124 @T6G_MB_LIB.T6G(SCH_1):GND
 286    GND VSS125 @T6G_MB_LIB.T6G(SCH_1):GND
 288    GND VSS126 @T6G_MB_LIB.T6G(SCH_1):GND
   1 P12V_MEM_CPU0 VIN_BULK0 @T6G_MB_LIB.T6G(SCH_1):P12V_MEM_CPU0
 145 P12V_MEM_CPU0 VIN_BULK1 @T6G_MB_LIB.T6G(SCH_1):P12V_MEM_CPU0
 146 P12V_MEM_CPU0 VIN_BULK2 @T6G_MB_LIB.T6G(SCH_1):P12V_MEM_CPU0
 230    GND VSS100 @T6G_MB_LIB.T6G(SCH_1):GND
 235    GND VSS102 @T6G_MB_LIB.T6G(SCH_1):GND
 240    GND VSS104 @T6G_MB_LIB.T6G(SCH_1):GND
 132    GND  VSS58 @T6G_MB_LIB.T6G(SCH_1):GND
 136    GND  VSS60 @T6G_MB_LIB.T6G(SCH_1):GND
 139    GND  VSS61 @T6G_MB_LIB.T6G(SCH_1):GND
 141    GND  VSS62 @T6G_MB_LIB.T6G(SCH_1):GND
  G1    GND     G1 @T6G_MB_LIB.T6G(SCH_1):GND
  G2    GND     G2 @T6G_MB_LIB.T6G(SCH_1):GND
  G3    GND     G3 @T6G_MB_LIB.T6G(SCH_1):GND

Q_CAP_0402-0.1UF,25V,10%,X7R,CH4104K1B00  I362  C100
   1 P3V3_AUX      A @T6G_MB_LIB.T6G(SCH_1):P3V3_AUX
   2    GND      B @T6G_MB_LIB.T6G(SCH_1):GND

Q_RES_0402LF-1K,1%,1/16W,EMPTY,CS21002FB06  I367  R92
   1   P3V3      A @T6G_MB_LIB.T6G(SCH_1):P3V3
   2 PWRGD_CHD_CPU0_DIMM      B @T6G_MB_LIB.T6G(SCH_1):PWRGD_CHD_CPU0_DIMM

Q_RES_0402LF-1K,1%,1/16W,CHIP,CS21002FB06  I369  R294
   1 PWRGD_CHD_CPU0_DIMM      A @T6G_MB_LIB.T6G(SCH_1):PWRGD_CHD_CPU0_DIMM
   2 PWRGD_CHAF_CPU0      B @T6G_MB_LIB.T6G(SCH_1):PWRGD_CHAF_CPU0

SCONN288_DDR506112002KQ-SCONN288_DDR506112002KQ,SMA  I415  J19
  93 M_D_CPU0_SB_DQS_DP<9> DQS9_B_T||TDQS9_B_T||DBI4_B_N @T6G_MB_LIB.T6G(SCH_1):M_D_CPU0_SB_DQS_DP(9)
  94 M_D_CPU0_SB_DQS_DN<9> DQS9_B_C||TDQS9_B_C @T6G_MB_LIB.T6G(SCH_1):M_D_CPU0_SB_DQS_DN(9)
 201 M_D_CPU0_SA_DQS_DP<9> DQS9_A_T||TDQS9_A_T @T6G_MB_LIB.T6G(SCH_1):M_D_CPU0_SA_DQS_DP(9)
 200 M_D_CPU0_SA_DQS_DN<9> DQS9_A_C||TDQS9_A_C @T6G_MB_LIB.T6G(SCH_1):M_D_CPU0_SA_DQS_DN(9)
 190 M_D_CPU0_SA_DQS_DP<8> DQS8_A_T||TDQS8_A_T @T6G_MB_LIB.T6G(SCH_1):M_D_CPU0_SA_DQS_DP(8)
 189 M_D_CPU0_SA_DQS_DN<8> DQS8_A_C||TDQS8_A_C @T6G_MB_LIB.T6G(SCH_1):M_D_CPU0_SA_DQS_DN(8)
 271 M_D_CPU0_SB_DQS_DN<7> DQS7_B_C||TDQS7_B_C @T6G_MB_LIB.T6G(SCH_1):M_D_CPU0_SB_DQS_DN(7)
 179 M_D_CPU0_SA_DQS_DP<7> DQS7_A_T||TDQS7_A_T @T6G_MB_LIB.T6G(SCH_1):M_D_CPU0_SA_DQS_DP(7)
 261 M_D_CPU0_SB_DQS_DP<6> DQS6_B_T||TDQS6_B_T @T6G_MB_LIB.T6G(SCH_1):M_D_CPU0_SB_DQS_DP(6)
 260 M_D_CPU0_SB_DQS_DN<6> DQS6_B_C||TDQS6_B_C @T6G_MB_LIB.T6G(SCH_1):M_D_CPU0_SB_DQS_DN(6)
 167 M_D_CPU0_SA_DQS_DN<6> DQS6_A_C||TDQS6_A_C||DQS6_A_T||TDQS6_A_T @T6G_MB_LIB.T6G(SCH_1):M_D_CPU0_SA_DQS_DN(6)
 250 M_D_CPU0_SB_DQS_DP<5> DQS5_B_T||TDQS5_B_T @T6G_MB_LIB.T6G(SCH_1):M_D_CPU0_SB_DQS_DP(5)
 249 M_D_CPU0_SB_DQS_DN<5> DQS5_B_C||TDQS5_B_C @T6G_MB_LIB.T6G(SCH_1):M_D_CPU0_SB_DQS_DN(5)
 157 M_D_CPU0_SA_DQS_DP<5> DQS5_A_T||TDQS5_A_T @T6G_MB_LIB.T6G(SCH_1):M_D_CPU0_SA_DQS_DP(5)
 156 M_D_CPU0_SA_DQS_DN<5> DQS5_A_C||TDQS5_A_C||DQS5_A_T||TDQS5_A_T @T6G_MB_LIB.T6G(SCH_1):M_D_CPU0_SA_DQS_DN(5)
 239 M_D_CPU0_SB_DQS_DP<4> DQS4_B_T @T6G_MB_LIB.T6G(SCH_1):M_D_CPU0_SB_DQS_DP(4)
 238 M_D_CPU0_SB_DQS_DN<4> DQS4_B_C @T6G_MB_LIB.T6G(SCH_1):M_D_CPU0_SB_DQS_DN(4)
  55 M_D_CPU0_SA_DQS_DP<4> DQS4_A_T @T6G_MB_LIB.T6G(SCH_1):M_D_CPU0_SA_DQS_DP(4)
  56 M_D_CPU0_SA_DQS_DN<4> DQS4_A_C @T6G_MB_LIB.T6G(SCH_1):M_D_CPU0_SA_DQS_DN(4)
 137 M_D_CPU0_SB_DQS_DP<3> DQS3_B_T @T6G_MB_LIB.T6G(SCH_1):M_D_CPU0_SB_DQS_DP(3)
 138 M_D_CPU0_SB_DQS_DN<3> DQS3_B_C @T6G_MB_LIB.T6G(SCH_1):M_D_CPU0_SB_DQS_DN(3)
  44 M_D_CPU0_SA_DQS_DP<3> DQS3_A_T @T6G_MB_LIB.T6G(SCH_1):M_D_CPU0_SA_DQS_DP(3)
  45 M_D_CPU0_SA_DQS_DN<3> DQS3_A_C @T6G_MB_LIB.T6G(SCH_1):M_D_CPU0_SA_DQS_DN(3)
 126 M_D_CPU0_SB_DQS_DP<2> DQS2_B_T @T6G_MB_LIB.T6G(SCH_1):M_D_CPU0_SB_DQS_DP(2)
 127 M_D_CPU0_SB_DQS_DN<2> DQS2_B_C @T6G_MB_LIB.T6G(SCH_1):M_D_CPU0_SB_DQS_DN(2)
  33 M_D_CPU0_SA_DQS_DP<2> DQS2_A_T @T6G_MB_LIB.T6G(SCH_1):M_D_CPU0_SA_DQS_DP(2)
  34 M_D_CPU0_SA_DQS_DN<2> DQS2_A_C @T6G_MB_LIB.T6G(SCH_1):M_D_CPU0_SA_DQS_DN(2)
 115 M_D_CPU0_SB_DQS_DP<1> DQS1_B_T @T6G_MB_LIB.T6G(SCH_1):M_D_CPU0_SB_DQS_DP(1)
 116 M_D_CPU0_SB_DQS_DN<1> DQS1_B_C @T6G_MB_LIB.T6G(SCH_1):M_D_CPU0_SB_DQS_DN(1)
  22 M_D_CPU0_SA_DQS_DP<1> DQS1_A_T @T6G_MB_LIB.T6G(SCH_1):M_D_CPU0_SA_DQS_DP(1)
  23 M_D_CPU0_SA_DQS_DN<1> DQS1_A_C @T6G_MB_LIB.T6G(SCH_1):M_D_CPU0_SA_DQS_DN(1)
 104 M_D_CPU0_SB_DQS_DP<0> DQS0_B_T @T6G_MB_LIB.T6G(SCH_1):M_D_CPU0_SB_DQS_DP(0)
 105 M_D_CPU0_SB_DQS_DN<0> DQS0_B_C @T6G_MB_LIB.T6G(SCH_1):M_D_CPU0_SB_DQS_DN(0)
  11 M_D_CPU0_SA_DQS_DP<0> DQS0_A_T @T6G_MB_LIB.T6G(SCH_1):M_D_CPU0_SA_DQS_DP(0)
  12 M_D_CPU0_SA_DQS_DN<0> DQS0_A_C @T6G_MB_LIB.T6G(SCH_1):M_D_CPU0_SA_DQS_DN(0)
 272 M_D_CPU0_SB_DQS_DP<7> DQS7_B_T||TDQS7_B_T @T6G_MB_LIB.T6G(SCH_1):M_D_CPU0_SB_DQS_DP(7)
 282 M_D_CPU0_SB_DQS_DN<8> DQS8_B_C||TDQS8_B_C @T6G_MB_LIB.T6G(SCH_1):M_D_CPU0_SB_DQS_DN(8)
 283 M_D_CPU0_SB_DQS_DP<8> DQS8_B_T||TDQS8_B_T @T6G_MB_LIB.T6G(SCH_1):M_D_CPU0_SB_DQS_DP(8)
 168 M_D_CPU0_SA_DQS_DP<6> DQS6_A_T||TDQS6_A_T @T6G_MB_LIB.T6G(SCH_1):M_D_CPU0_SA_DQS_DP(6)
 178 M_D_CPU0_SA_DQS_DN<7> DQS7_A_C||TDQS7_A_C @T6G_MB_LIB.T6G(SCH_1):M_D_CPU0_SA_DQS_DN(7)

Q_CAP_C0805-10UF,25V,10%,X6S,CH6104KEA00  I417  C149
   1 P12V_MEM_CPU0      A @T6G_MB_LIB.T6G(SCH_1):P12V_MEM_CPU0
   2    GND      B @T6G_MB_LIB.T6G(SCH_1):GND

Q_CAP_C0805-10UF,25V,10%,X6S,CH6104KEA00  I418  C150
   1 P12V_MEM_CPU0      A @T6G_MB_LIB.T6G(SCH_1):P12V_MEM_CPU0
   2    GND      B @T6G_MB_LIB.T6G(SCH_1):GND

Q_RES_0402LF-49.9,1%,1/16W,CHIP,CS04992FB07  I421  R1
   1 I3C_SPD_DDRAF_CPU0_SCL      A @T6G_MB_LIB.T6G(SCH_1):I3C_SPD_DDRAF_CPU0_SCL
   2 I3C_SPD_DDRD_CPU0_SCL      B @T6G_MB_LIB.T6G(SCH_1):I3C_SPD_DDRD_CPU0_SCL

Q_RES_0402LF-10,1%,1/16W,CHIP,CS01002FB07  I422  R1676
   1 I3C_SPD_DDRAF_CPU0_SDA      A @T6G_MB_LIB.T6G(SCH_1):I3C_SPD_DDRAF_CPU0_SDA
   2 I3C_SPD_DDRD_CPU0_SDA      B @T6G_MB_LIB.T6G(SCH_1):I3C_SPD_DDRD_CPU0_SDA


DRAWING: @T6G_MB_LIB.T6G(SCH_1):PAGE89 

Q_RES_0402LF-54.9K,1%,1/16W,CHIP,CS35492FB03  I331  R5
   1 PD_CHE_CPU0_DIMM_SAA      A @T6G_MB_LIB.T6G(SCH_1):PD_CHE_CPU0_DIMM_SAA
   2    GND      B @T6G_MB_LIB.T6G(SCH_1):GND

SCONN288_DDR506112002KQ-SCONN288_DDR506112002KQ,SMA  I348  J21
   3 P3V3_AUX VIN_MGMT @T6G_MB_LIB.T6G(SCH_1):P3V3_AUX
   2     NC   RFU0     NC
 144     NC   RFU1     NC
 149     NC   RFU2     NC
 150     NC   RFU3     NC
 220     NC   RFU4     NC
 231     NC   RFU5     NC
 232     NC   RFU6     NC
 207 M_E_CPU0_RESET_N RESET_N @T6G_MB_LIB.T6G(SCH_1):M_E_CPU0_RESET_N
 147 PWRGD_CHE_CPU0_DIMM PWR_GOOD||FAIL_N @T6G_MB_LIB.T6G(SCH_1):PWRGD_CHE_CPU0_DIMM
 227 M_E_CPU0_SB_PAR  PAR_B @T6G_MB_LIB.T6G(SCH_1):M_E_CPU0_SB_PAR
  74 M_E_CPU0_SA_PAR  PAR_A @T6G_MB_LIB.T6G(SCH_1):M_E_CPU0_SA_PAR
  87 M_E_CPU0_SB_RSP<0> LBS||RSP_B_N @T6G_MB_LIB.T6G(SCH_1):M_E_CPU0_SB_RSP(0)
  86 M_E_CPU0_SA_RSP<0> LBD||RSP_A_N @T6G_MB_LIB.T6G(SCH_1):M_E_CPU0_SA_RSP(0)
   5 I3C_SPD_DDRE_CPU0_SDA   HSDA @T6G_MB_LIB.T6G(SCH_1):I3C_SPD_DDRE_CPU0_SDA
   4 I3C_SPD_DDRE_CPU0_SCL   HSCL @T6G_MB_LIB.T6G(SCH_1):I3C_SPD_DDRE_CPU0_SCL
 148 PD_CHE_CPU0_DIMM_SAA    HAS @T6G_MB_LIB.T6G(SCH_1):PD_CHE_CPU0_DIMM_SAA
 100 M_E_CPU0_SB_DQ<0>  DQ0_B @T6G_MB_LIB.T6G(SCH_1):M_E_CPU0_SB_DQ(0)
 102 M_E_CPU0_SB_DQ<1>  DQ1_B @T6G_MB_LIB.T6G(SCH_1):M_E_CPU0_SB_DQ(1)
 245 M_E_CPU0_SB_DQ<2>  DQ2_B @T6G_MB_LIB.T6G(SCH_1):M_E_CPU0_SB_DQ(2)
 247 M_E_CPU0_SB_DQ<3>  DQ3_B @T6G_MB_LIB.T6G(SCH_1):M_E_CPU0_SB_DQ(3)
 107 M_E_CPU0_SB_DQ<4>  DQ4_B @T6G_MB_LIB.T6G(SCH_1):M_E_CPU0_SB_DQ(4)
 109 M_E_CPU0_SB_DQ<5>  DQ5_B @T6G_MB_LIB.T6G(SCH_1):M_E_CPU0_SB_DQ(5)
 252 M_E_CPU0_SB_DQ<6>  DQ6_B @T6G_MB_LIB.T6G(SCH_1):M_E_CPU0_SB_DQ(6)
 254 M_E_CPU0_SB_DQ<7>  DQ7_B @T6G_MB_LIB.T6G(SCH_1):M_E_CPU0_SB_DQ(7)
 111 M_E_CPU0_SB_DQ<8>  DQ8_B @T6G_MB_LIB.T6G(SCH_1):M_E_CPU0_SB_DQ(8)
 113 M_E_CPU0_SB_DQ<9>  DQ9_B @T6G_MB_LIB.T6G(SCH_1):M_E_CPU0_SB_DQ(9)
 256 M_E_CPU0_SB_DQ<10> DQ10_B @T6G_MB_LIB.T6G(SCH_1):M_E_CPU0_SB_DQ(10)
 258 M_E_CPU0_SB_DQ<11> DQ11_B @T6G_MB_LIB.T6G(SCH_1):M_E_CPU0_SB_DQ(11)
 118 M_E_CPU0_SB_DQ<12> DQ12_B @T6G_MB_LIB.T6G(SCH_1):M_E_CPU0_SB_DQ(12)
 120 M_E_CPU0_SB_DQ<13> DQ13_B @T6G_MB_LIB.T6G(SCH_1):M_E_CPU0_SB_DQ(13)
 263 M_E_CPU0_SB_DQ<14> DQ14_B @T6G_MB_LIB.T6G(SCH_1):M_E_CPU0_SB_DQ(14)
 265 M_E_CPU0_SB_DQ<15> DQ15_B @T6G_MB_LIB.T6G(SCH_1):M_E_CPU0_SB_DQ(15)
 122 M_E_CPU0_SB_DQ<16> DQ16_B @T6G_MB_LIB.T6G(SCH_1):M_E_CPU0_SB_DQ(16)
 124 M_E_CPU0_SB_DQ<17> DQ17_B @T6G_MB_LIB.T6G(SCH_1):M_E_CPU0_SB_DQ(17)
 267 M_E_CPU0_SB_DQ<18> DQ18_B @T6G_MB_LIB.T6G(SCH_1):M_E_CPU0_SB_DQ(18)
 269 M_E_CPU0_SB_DQ<19> DQ19_B @T6G_MB_LIB.T6G(SCH_1):M_E_CPU0_SB_DQ(19)
 129 M_E_CPU0_SB_DQ<20> DQ20_B @T6G_MB_LIB.T6G(SCH_1):M_E_CPU0_SB_DQ(20)
 131 M_E_CPU0_SB_DQ<21> DQ21_B @T6G_MB_LIB.T6G(SCH_1):M_E_CPU0_SB_DQ(21)
 274 M_E_CPU0_SB_DQ<22> DQ22_B @T6G_MB_LIB.T6G(SCH_1):M_E_CPU0_SB_DQ(22)
 276 M_E_CPU0_SB_DQ<23> DQ23_B @T6G_MB_LIB.T6G(SCH_1):M_E_CPU0_SB_DQ(23)
 133 M_E_CPU0_SB_DQ<24> DQ24_B @T6G_MB_LIB.T6G(SCH_1):M_E_CPU0_SB_DQ(24)
 135 M_E_CPU0_SB_DQ<25> DQ25_B @T6G_MB_LIB.T6G(SCH_1):M_E_CPU0_SB_DQ(25)
 278 M_E_CPU0_SB_DQ<26> DQ26_B @T6G_MB_LIB.T6G(SCH_1):M_E_CPU0_SB_DQ(26)
 280 M_E_CPU0_SB_DQ<27> DQ27_B @T6G_MB_LIB.T6G(SCH_1):M_E_CPU0_SB_DQ(27)
 140 M_E_CPU0_SB_DQ<28> DQ28_B @T6G_MB_LIB.T6G(SCH_1):M_E_CPU0_SB_DQ(28)
 142 M_E_CPU0_SB_DQ<29> DQ29_B @T6G_MB_LIB.T6G(SCH_1):M_E_CPU0_SB_DQ(29)
 285 M_E_CPU0_SB_DQ<30> DQ30_B @T6G_MB_LIB.T6G(SCH_1):M_E_CPU0_SB_DQ(30)
 287 M_E_CPU0_SB_DQ<31> DQ31_B @T6G_MB_LIB.T6G(SCH_1):M_E_CPU0_SB_DQ(31)
   7 M_E_CPU0_SA_DQ<0>  DQ0_A @T6G_MB_LIB.T6G(SCH_1):M_E_CPU0_SA_DQ(0)
   9 M_E_CPU0_SA_DQ<1>  DQ1_A @T6G_MB_LIB.T6G(SCH_1):M_E_CPU0_SA_DQ(1)
 152 M_E_CPU0_SA_DQ<2>  DQ2_A @T6G_MB_LIB.T6G(SCH_1):M_E_CPU0_SA_DQ(2)
 154 M_E_CPU0_SA_DQ<3>  DQ3_A @T6G_MB_LIB.T6G(SCH_1):M_E_CPU0_SA_DQ(3)
  14 M_E_CPU0_SA_DQ<4>  DQ4_A @T6G_MB_LIB.T6G(SCH_1):M_E_CPU0_SA_DQ(4)
  16 M_E_CPU0_SA_DQ<5>  DQ5_A @T6G_MB_LIB.T6G(SCH_1):M_E_CPU0_SA_DQ(5)
 159 M_E_CPU0_SA_DQ<6>  DQ6_A @T6G_MB_LIB.T6G(SCH_1):M_E_CPU0_SA_DQ(6)
 161 M_E_CPU0_SA_DQ<7>  DQ7_A @T6G_MB_LIB.T6G(SCH_1):M_E_CPU0_SA_DQ(7)
  18 M_E_CPU0_SA_DQ<8>  DQ8_A @T6G_MB_LIB.T6G(SCH_1):M_E_CPU0_SA_DQ(8)
  20 M_E_CPU0_SA_DQ<9>  DQ9_A @T6G_MB_LIB.T6G(SCH_1):M_E_CPU0_SA_DQ(9)
 163 M_E_CPU0_SA_DQ<10> DQ10_A @T6G_MB_LIB.T6G(SCH_1):M_E_CPU0_SA_DQ(10)
 165 M_E_CPU0_SA_DQ<11> DQ11_A @T6G_MB_LIB.T6G(SCH_1):M_E_CPU0_SA_DQ(11)
  25 M_E_CPU0_SA_DQ<12> DQ12_A @T6G_MB_LIB.T6G(SCH_1):M_E_CPU0_SA_DQ(12)
  27 M_E_CPU0_SA_DQ<13> DQ13_A @T6G_MB_LIB.T6G(SCH_1):M_E_CPU0_SA_DQ(13)
 170 M_E_CPU0_SA_DQ<14> DQ14_A @T6G_MB_LIB.T6G(SCH_1):M_E_CPU0_SA_DQ(14)
 172 M_E_CPU0_SA_DQ<15> DQ15_A @T6G_MB_LIB.T6G(SCH_1):M_E_CPU0_SA_DQ(15)
  29 M_E_CPU0_SA_DQ<16> DQ16_A @T6G_MB_LIB.T6G(SCH_1):M_E_CPU0_SA_DQ(16)
  31 M_E_CPU0_SA_DQ<17> DQ17_A @T6G_MB_LIB.T6G(SCH_1):M_E_CPU0_SA_DQ(17)
 174 M_E_CPU0_SA_DQ<18> DQ18_A @T6G_MB_LIB.T6G(SCH_1):M_E_CPU0_SA_DQ(18)
 176 M_E_CPU0_SA_DQ<19> DQ19_A @T6G_MB_LIB.T6G(SCH_1):M_E_CPU0_SA_DQ(19)
  36 M_E_CPU0_SA_DQ<20> DQ20_A @T6G_MB_LIB.T6G(SCH_1):M_E_CPU0_SA_DQ(20)
  38 M_E_CPU0_SA_DQ<21> DQ21_A @T6G_MB_LIB.T6G(SCH_1):M_E_CPU0_SA_DQ(21)
 181 M_E_CPU0_SA_DQ<22> DQ22_A @T6G_MB_LIB.T6G(SCH_1):M_E_CPU0_SA_DQ(22)
 183 M_E_CPU0_SA_DQ<23> DQ23_A @T6G_MB_LIB.T6G(SCH_1):M_E_CPU0_SA_DQ(23)
  40 M_E_CPU0_SA_DQ<24> DQ24_A @T6G_MB_LIB.T6G(SCH_1):M_E_CPU0_SA_DQ(24)
  42 M_E_CPU0_SA_DQ<25> DQ25_A @T6G_MB_LIB.T6G(SCH_1):M_E_CPU0_SA_DQ(25)
 185 M_E_CPU0_SA_DQ<26> DQ26_A @T6G_MB_LIB.T6G(SCH_1):M_E_CPU0_SA_DQ(26)
 187 M_E_CPU0_SA_DQ<27> DQ27_A @T6G_MB_LIB.T6G(SCH_1):M_E_CPU0_SA_DQ(27)
  47 M_E_CPU0_SA_DQ<28> DQ28_A @T6G_MB_LIB.T6G(SCH_1):M_E_CPU0_SA_DQ(28)
  49 M_E_CPU0_SA_DQ<29> DQ29_A @T6G_MB_LIB.T6G(SCH_1):M_E_CPU0_SA_DQ(29)
 192 M_E_CPU0_SA_DQ<30> DQ30_A @T6G_MB_LIB.T6G(SCH_1):M_E_CPU0_SA_DQ(30)
 229 M_E_CPU0_SB_CS_N<1> CS1_B_N @T6G_MB_LIB.T6G(SCH_1):M_E_CPU0_SB_CS_N(1)
 209 M_E_CPU0_SA_CS_N<1> CS1_A_N @T6G_MB_LIB.T6G(SCH_1):M_E_CPU0_SA_CS_N(1)
  84 M_E_CPU0_SB_CS_N<0> CS0_B_N @T6G_MB_LIB.T6G(SCH_1):M_E_CPU0_SB_CS_N(0)
  64 M_E_CPU0_SA_CS_N<0> CS0_A_N @T6G_MB_LIB.T6G(SCH_1):M_E_CPU0_SA_CS_N(0)
 217 M_E_CPU0_CLK_DP<0>   CK_T @T6G_MB_LIB.T6G(SCH_1):M_E_CPU0_CLK_DP(0)
 218 M_E_CPU0_CLK_DN<0>   CK_C @T6G_MB_LIB.T6G(SCH_1):M_E_CPU0_CLK_DN(0)
  96 M_E_CPU0_SB_CB<0>  CB0_B @T6G_MB_LIB.T6G(SCH_1):M_E_CPU0_SB_CB(0)
  98 M_E_CPU0_SB_CB<1>  CB1_B @T6G_MB_LIB.T6G(SCH_1):M_E_CPU0_SB_CB(1)
 241 M_E_CPU0_SB_CB<2>  CB2_B @T6G_MB_LIB.T6G(SCH_1):M_E_CPU0_SB_CB(2)
 243 M_E_CPU0_SB_CB<3>  CB3_B @T6G_MB_LIB.T6G(SCH_1):M_E_CPU0_SB_CB(3)
  89 M_E_CPU0_SB_CB<4>  CB4_B @T6G_MB_LIB.T6G(SCH_1):M_E_CPU0_SB_CB(4)
  91 M_E_CPU0_SB_CB<5>  CB5_B @T6G_MB_LIB.T6G(SCH_1):M_E_CPU0_SB_CB(5)
 234 M_E_CPU0_SB_CB<6>  CB6_B @T6G_MB_LIB.T6G(SCH_1):M_E_CPU0_SB_CB(6)
  51 M_E_CPU0_SA_CB<0>  CB0_A @T6G_MB_LIB.T6G(SCH_1):M_E_CPU0_SA_CB(0)
 196 M_E_CPU0_SA_CB<2>  CB2_A @T6G_MB_LIB.T6G(SCH_1):M_E_CPU0_SA_CB(2)
 198 M_E_CPU0_SA_CB<3>  CB3_A @T6G_MB_LIB.T6G(SCH_1):M_E_CPU0_SA_CB(3)
  60 M_E_CPU0_SA_CB<5>  CB5_A @T6G_MB_LIB.T6G(SCH_1):M_E_CPU0_SA_CB(5)
 203 M_E_CPU0_SA_CB<6>  CB6_A @T6G_MB_LIB.T6G(SCH_1):M_E_CPU0_SA_CB(6)
  82 M_E_CPU0_SB_CA<6>  CA6_B @T6G_MB_LIB.T6G(SCH_1):M_E_CPU0_SB_CA(6)
  72 M_E_CPU0_SA_CA<6>  CA6_A @T6G_MB_LIB.T6G(SCH_1):M_E_CPU0_SA_CA(6)
 225 M_E_CPU0_SB_CA<5>  CA5_B @T6G_MB_LIB.T6G(SCH_1):M_E_CPU0_SB_CA(5)
 215 M_E_CPU0_SA_CA<5>  CA5_A @T6G_MB_LIB.T6G(SCH_1):M_E_CPU0_SA_CA(5)
  80 M_E_CPU0_SB_CA<4>  CA4_B @T6G_MB_LIB.T6G(SCH_1):M_E_CPU0_SB_CA(4)
  70 M_E_CPU0_SA_CA<4>  CA4_A @T6G_MB_LIB.T6G(SCH_1):M_E_CPU0_SA_CA(4)
 223 M_E_CPU0_SB_CA<3>  CA3_B @T6G_MB_LIB.T6G(SCH_1):M_E_CPU0_SB_CA(3)
 213 M_E_CPU0_SA_CA<3>  CA3_A @T6G_MB_LIB.T6G(SCH_1):M_E_CPU0_SA_CA(3)
  78 M_E_CPU0_SB_CA<2>  CA2_B @T6G_MB_LIB.T6G(SCH_1):M_E_CPU0_SB_CA(2)
  68 M_E_CPU0_SA_CA<2>  CA2_A @T6G_MB_LIB.T6G(SCH_1):M_E_CPU0_SA_CA(2)
 221 M_E_CPU0_SB_CA<1>  CA1_B @T6G_MB_LIB.T6G(SCH_1):M_E_CPU0_SB_CA(1)
 211 M_E_CPU0_SA_CA<1>  CA1_A @T6G_MB_LIB.T6G(SCH_1):M_E_CPU0_SA_CA(1)
  76 M_E_CPU0_SB_CA<0>  CA0_B @T6G_MB_LIB.T6G(SCH_1):M_E_CPU0_SB_CA(0)
  66 M_E_CPU0_SA_CA<0>  CA0_A @T6G_MB_LIB.T6G(SCH_1):M_E_CPU0_SA_CA(0)
  62 M_E_CPU0_ALERT_N ALERT_N @T6G_MB_LIB.T6G(SCH_1):M_E_CPU0_ALERT_N
 236 M_E_CPU0_SB_CB<7>  CB7_B @T6G_MB_LIB.T6G(SCH_1):M_E_CPU0_SB_CB(7)
  53 M_E_CPU0_SA_CB<1>  CB1_A @T6G_MB_LIB.T6G(SCH_1):M_E_CPU0_SA_CB(1)
  58 M_E_CPU0_SA_CB<4>  CB4_A @T6G_MB_LIB.T6G(SCH_1):M_E_CPU0_SA_CB(4)
 205 M_E_CPU0_SA_CB<7>  CB7_A @T6G_MB_LIB.T6G(SCH_1):M_E_CPU0_SA_CB(7)
 194 M_E_CPU0_SA_DQ<31> DQ31_A @T6G_MB_LIB.T6G(SCH_1):M_E_CPU0_SA_DQ(31)

SCONN288_DDR506112002KQ-SCONN288_DDR506112002KQ,SMA  I350  J21
   6    GND   VSS0 @T6G_MB_LIB.T6G(SCH_1):GND
   8    GND   VSS1 @T6G_MB_LIB.T6G(SCH_1):GND
  10    GND   VSS2 @T6G_MB_LIB.T6G(SCH_1):GND
  13    GND   VSS3 @T6G_MB_LIB.T6G(SCH_1):GND
  15    GND   VSS4 @T6G_MB_LIB.T6G(SCH_1):GND
  17    GND   VSS5 @T6G_MB_LIB.T6G(SCH_1):GND
  19    GND   VSS6 @T6G_MB_LIB.T6G(SCH_1):GND
  21    GND   VSS7 @T6G_MB_LIB.T6G(SCH_1):GND
  24    GND   VSS8 @T6G_MB_LIB.T6G(SCH_1):GND
  26    GND   VSS9 @T6G_MB_LIB.T6G(SCH_1):GND
  28    GND  VSS10 @T6G_MB_LIB.T6G(SCH_1):GND
  30    GND  VSS11 @T6G_MB_LIB.T6G(SCH_1):GND
  32    GND  VSS12 @T6G_MB_LIB.T6G(SCH_1):GND
  35    GND  VSS13 @T6G_MB_LIB.T6G(SCH_1):GND
  37    GND  VSS14 @T6G_MB_LIB.T6G(SCH_1):GND
  39    GND  VSS15 @T6G_MB_LIB.T6G(SCH_1):GND
  41    GND  VSS16 @T6G_MB_LIB.T6G(SCH_1):GND
  43    GND  VSS17 @T6G_MB_LIB.T6G(SCH_1):GND
  46    GND  VSS18 @T6G_MB_LIB.T6G(SCH_1):GND
  48    GND  VSS19 @T6G_MB_LIB.T6G(SCH_1):GND
  50    GND  VSS20 @T6G_MB_LIB.T6G(SCH_1):GND
  52    GND  VSS21 @T6G_MB_LIB.T6G(SCH_1):GND
  54    GND  VSS22 @T6G_MB_LIB.T6G(SCH_1):GND
  57    GND  VSS23 @T6G_MB_LIB.T6G(SCH_1):GND
  59    GND  VSS24 @T6G_MB_LIB.T6G(SCH_1):GND
  61    GND  VSS25 @T6G_MB_LIB.T6G(SCH_1):GND
  63    GND  VSS26 @T6G_MB_LIB.T6G(SCH_1):GND
  65    GND  VSS27 @T6G_MB_LIB.T6G(SCH_1):GND
  67    GND  VSS28 @T6G_MB_LIB.T6G(SCH_1):GND
  69    GND  VSS29 @T6G_MB_LIB.T6G(SCH_1):GND
  71    GND  VSS30 @T6G_MB_LIB.T6G(SCH_1):GND
  73    GND  VSS31 @T6G_MB_LIB.T6G(SCH_1):GND
  75    GND  VSS32 @T6G_MB_LIB.T6G(SCH_1):GND
  77    GND  VSS33 @T6G_MB_LIB.T6G(SCH_1):GND
  79    GND  VSS34 @T6G_MB_LIB.T6G(SCH_1):GND
  81    GND  VSS35 @T6G_MB_LIB.T6G(SCH_1):GND
  83    GND  VSS36 @T6G_MB_LIB.T6G(SCH_1):GND
  85    GND  VSS37 @T6G_MB_LIB.T6G(SCH_1):GND
  88    GND  VSS38 @T6G_MB_LIB.T6G(SCH_1):GND
  90    GND  VSS39 @T6G_MB_LIB.T6G(SCH_1):GND
  92    GND  VSS40 @T6G_MB_LIB.T6G(SCH_1):GND
  95    GND  VSS41 @T6G_MB_LIB.T6G(SCH_1):GND
  97    GND  VSS42 @T6G_MB_LIB.T6G(SCH_1):GND
  99    GND  VSS43 @T6G_MB_LIB.T6G(SCH_1):GND
 101    GND  VSS44 @T6G_MB_LIB.T6G(SCH_1):GND
 103    GND  VSS45 @T6G_MB_LIB.T6G(SCH_1):GND
 106    GND  VSS46 @T6G_MB_LIB.T6G(SCH_1):GND
 108    GND  VSS47 @T6G_MB_LIB.T6G(SCH_1):GND
 110    GND  VSS48 @T6G_MB_LIB.T6G(SCH_1):GND
 112    GND  VSS49 @T6G_MB_LIB.T6G(SCH_1):GND
 114    GND  VSS50 @T6G_MB_LIB.T6G(SCH_1):GND
 117    GND  VSS51 @T6G_MB_LIB.T6G(SCH_1):GND
 119    GND  VSS52 @T6G_MB_LIB.T6G(SCH_1):GND
 121    GND  VSS53 @T6G_MB_LIB.T6G(SCH_1):GND
 123    GND  VSS54 @T6G_MB_LIB.T6G(SCH_1):GND
 125    GND  VSS55 @T6G_MB_LIB.T6G(SCH_1):GND
 128    GND  VSS56 @T6G_MB_LIB.T6G(SCH_1):GND
 130    GND  VSS57 @T6G_MB_LIB.T6G(SCH_1):GND
 134    GND  VSS59 @T6G_MB_LIB.T6G(SCH_1):GND
 143    GND  VSS63 @T6G_MB_LIB.T6G(SCH_1):GND
 151    GND  VSS64 @T6G_MB_LIB.T6G(SCH_1):GND
 153    GND  VSS65 @T6G_MB_LIB.T6G(SCH_1):GND
 155    GND  VSS66 @T6G_MB_LIB.T6G(SCH_1):GND
 158    GND  VSS67 @T6G_MB_LIB.T6G(SCH_1):GND
 160    GND  VSS68 @T6G_MB_LIB.T6G(SCH_1):GND
 162    GND  VSS69 @T6G_MB_LIB.T6G(SCH_1):GND
 164    GND  VSS70 @T6G_MB_LIB.T6G(SCH_1):GND
 166    GND  VSS71 @T6G_MB_LIB.T6G(SCH_1):GND
 169    GND  VSS72 @T6G_MB_LIB.T6G(SCH_1):GND
 171    GND  VSS73 @T6G_MB_LIB.T6G(SCH_1):GND
 173    GND  VSS74 @T6G_MB_LIB.T6G(SCH_1):GND
 175    GND  VSS75 @T6G_MB_LIB.T6G(SCH_1):GND
 177    GND  VSS76 @T6G_MB_LIB.T6G(SCH_1):GND
 180    GND  VSS77 @T6G_MB_LIB.T6G(SCH_1):GND
 182    GND  VSS78 @T6G_MB_LIB.T6G(SCH_1):GND
 184    GND  VSS79 @T6G_MB_LIB.T6G(SCH_1):GND
 186    GND  VSS80 @T6G_MB_LIB.T6G(SCH_1):GND
 188    GND  VSS81 @T6G_MB_LIB.T6G(SCH_1):GND
 191    GND  VSS82 @T6G_MB_LIB.T6G(SCH_1):GND
 193    GND  VSS83 @T6G_MB_LIB.T6G(SCH_1):GND
 195    GND  VSS84 @T6G_MB_LIB.T6G(SCH_1):GND
 197    GND  VSS85 @T6G_MB_LIB.T6G(SCH_1):GND
 199    GND  VSS86 @T6G_MB_LIB.T6G(SCH_1):GND
 202    GND  VSS87 @T6G_MB_LIB.T6G(SCH_1):GND
 204    GND  VSS88 @T6G_MB_LIB.T6G(SCH_1):GND
 206    GND  VSS89 @T6G_MB_LIB.T6G(SCH_1):GND
 208    GND  VSS90 @T6G_MB_LIB.T6G(SCH_1):GND
 210    GND  VSS91 @T6G_MB_LIB.T6G(SCH_1):GND
 212    GND  VSS92 @T6G_MB_LIB.T6G(SCH_1):GND
 214    GND  VSS93 @T6G_MB_LIB.T6G(SCH_1):GND
 216    GND  VSS94 @T6G_MB_LIB.T6G(SCH_1):GND
 219    GND  VSS95 @T6G_MB_LIB.T6G(SCH_1):GND
 222    GND  VSS96 @T6G_MB_LIB.T6G(SCH_1):GND
 224    GND  VSS97 @T6G_MB_LIB.T6G(SCH_1):GND
 226    GND  VSS98 @T6G_MB_LIB.T6G(SCH_1):GND
 228    GND  VSS99 @T6G_MB_LIB.T6G(SCH_1):GND
 233    GND VSS101 @T6G_MB_LIB.T6G(SCH_1):GND
 237    GND VSS103 @T6G_MB_LIB.T6G(SCH_1):GND
 242    GND VSS105 @T6G_MB_LIB.T6G(SCH_1):GND
 244    GND VSS106 @T6G_MB_LIB.T6G(SCH_1):GND
 246    GND VSS107 @T6G_MB_LIB.T6G(SCH_1):GND
 248    GND VSS108 @T6G_MB_LIB.T6G(SCH_1):GND
 251    GND VSS109 @T6G_MB_LIB.T6G(SCH_1):GND
 253    GND VSS110 @T6G_MB_LIB.T6G(SCH_1):GND
 255    GND VSS111 @T6G_MB_LIB.T6G(SCH_1):GND
 257    GND VSS112 @T6G_MB_LIB.T6G(SCH_1):GND
 259    GND VSS113 @T6G_MB_LIB.T6G(SCH_1):GND
 262    GND VSS114 @T6G_MB_LIB.T6G(SCH_1):GND
 264    GND VSS115 @T6G_MB_LIB.T6G(SCH_1):GND
 266    GND VSS116 @T6G_MB_LIB.T6G(SCH_1):GND
 268    GND VSS117 @T6G_MB_LIB.T6G(SCH_1):GND
 270    GND VSS118 @T6G_MB_LIB.T6G(SCH_1):GND
 273    GND VSS119 @T6G_MB_LIB.T6G(SCH_1):GND
 275    GND VSS120 @T6G_MB_LIB.T6G(SCH_1):GND
 277    GND VSS121 @T6G_MB_LIB.T6G(SCH_1):GND
 279    GND VSS122 @T6G_MB_LIB.T6G(SCH_1):GND
 281    GND VSS123 @T6G_MB_LIB.T6G(SCH_1):GND
 284    GND VSS124 @T6G_MB_LIB.T6G(SCH_1):GND
 286    GND VSS125 @T6G_MB_LIB.T6G(SCH_1):GND
 288    GND VSS126 @T6G_MB_LIB.T6G(SCH_1):GND
   1 P12V_MEM_CPU0 VIN_BULK0 @T6G_MB_LIB.T6G(SCH_1):P12V_MEM_CPU0
 145 P12V_MEM_CPU0 VIN_BULK1 @T6G_MB_LIB.T6G(SCH_1):P12V_MEM_CPU0
 146 P12V_MEM_CPU0 VIN_BULK2 @T6G_MB_LIB.T6G(SCH_1):P12V_MEM_CPU0
 230    GND VSS100 @T6G_MB_LIB.T6G(SCH_1):GND
 235    GND VSS102 @T6G_MB_LIB.T6G(SCH_1):GND
 240    GND VSS104 @T6G_MB_LIB.T6G(SCH_1):GND
 132    GND  VSS58 @T6G_MB_LIB.T6G(SCH_1):GND
 136    GND  VSS60 @T6G_MB_LIB.T6G(SCH_1):GND
 139    GND  VSS61 @T6G_MB_LIB.T6G(SCH_1):GND
 141    GND  VSS62 @T6G_MB_LIB.T6G(SCH_1):GND
  G1    GND     G1 @T6G_MB_LIB.T6G(SCH_1):GND
  G2    GND     G2 @T6G_MB_LIB.T6G(SCH_1):GND
  G3    GND     G3 @T6G_MB_LIB.T6G(SCH_1):GND

Q_CAP_0402-0.1UF,25V,10%,X7R,CH4104K1B00  I360  C104
   1 P3V3_AUX      A @T6G_MB_LIB.T6G(SCH_1):P3V3_AUX
   2    GND      B @T6G_MB_LIB.T6G(SCH_1):GND

Q_RES_0402LF-1K,1%,1/16W,CHIP,CS21002FB06  I362  R295
   1 PWRGD_CHE_CPU0_DIMM      A @T6G_MB_LIB.T6G(SCH_1):PWRGD_CHE_CPU0_DIMM
   2 PWRGD_CHAF_CPU0      B @T6G_MB_LIB.T6G(SCH_1):PWRGD_CHAF_CPU0

Q_RES_0402LF-1K,1%,1/16W,EMPTY,CS21002FB06  I364  R93
   1   P3V3      A @T6G_MB_LIB.T6G(SCH_1):P3V3
   2 PWRGD_CHE_CPU0_DIMM      B @T6G_MB_LIB.T6G(SCH_1):PWRGD_CHE_CPU0_DIMM

SCONN288_DDR506112002KQ-SCONN288_DDR506112002KQ,SMA  I410  J21
  93 M_E_CPU0_SB_DQS_DP<9> DQS9_B_T||TDQS9_B_T||DBI4_B_N @T6G_MB_LIB.T6G(SCH_1):M_E_CPU0_SB_DQS_DP(9)
  94 M_E_CPU0_SB_DQS_DN<9> DQS9_B_C||TDQS9_B_C @T6G_MB_LIB.T6G(SCH_1):M_E_CPU0_SB_DQS_DN(9)
 201 M_E_CPU0_SA_DQS_DP<9> DQS9_A_T||TDQS9_A_T @T6G_MB_LIB.T6G(SCH_1):M_E_CPU0_SA_DQS_DP(9)
 200 M_E_CPU0_SA_DQS_DN<9> DQS9_A_C||TDQS9_A_C @T6G_MB_LIB.T6G(SCH_1):M_E_CPU0_SA_DQS_DN(9)
 190 M_E_CPU0_SA_DQS_DP<8> DQS8_A_T||TDQS8_A_T @T6G_MB_LIB.T6G(SCH_1):M_E_CPU0_SA_DQS_DP(8)
 189 M_E_CPU0_SA_DQS_DN<8> DQS8_A_C||TDQS8_A_C @T6G_MB_LIB.T6G(SCH_1):M_E_CPU0_SA_DQS_DN(8)
 271 M_E_CPU0_SB_DQS_DN<7> DQS7_B_C||TDQS7_B_C @T6G_MB_LIB.T6G(SCH_1):M_E_CPU0_SB_DQS_DN(7)
 179 M_E_CPU0_SA_DQS_DP<7> DQS7_A_T||TDQS7_A_T @T6G_MB_LIB.T6G(SCH_1):M_E_CPU0_SA_DQS_DP(7)
 261 M_E_CPU0_SB_DQS_DP<6> DQS6_B_T||TDQS6_B_T @T6G_MB_LIB.T6G(SCH_1):M_E_CPU0_SB_DQS_DP(6)
 260 M_E_CPU0_SB_DQS_DN<6> DQS6_B_C||TDQS6_B_C @T6G_MB_LIB.T6G(SCH_1):M_E_CPU0_SB_DQS_DN(6)
 167 M_E_CPU0_SA_DQS_DN<6> DQS6_A_C||TDQS6_A_C||DQS6_A_T||TDQS6_A_T @T6G_MB_LIB.T6G(SCH_1):M_E_CPU0_SA_DQS_DN(6)
 250 M_E_CPU0_SB_DQS_DP<5> DQS5_B_T||TDQS5_B_T @T6G_MB_LIB.T6G(SCH_1):M_E_CPU0_SB_DQS_DP(5)
 249 M_E_CPU0_SB_DQS_DN<5> DQS5_B_C||TDQS5_B_C @T6G_MB_LIB.T6G(SCH_1):M_E_CPU0_SB_DQS_DN(5)
 157 M_E_CPU0_SA_DQS_DP<5> DQS5_A_T||TDQS5_A_T @T6G_MB_LIB.T6G(SCH_1):M_E_CPU0_SA_DQS_DP(5)
 156 M_E_CPU0_SA_DQS_DN<5> DQS5_A_C||TDQS5_A_C||DQS5_A_T||TDQS5_A_T @T6G_MB_LIB.T6G(SCH_1):M_E_CPU0_SA_DQS_DN(5)
 239 M_E_CPU0_SB_DQS_DP<4> DQS4_B_T @T6G_MB_LIB.T6G(SCH_1):M_E_CPU0_SB_DQS_DP(4)
 238 M_E_CPU0_SB_DQS_DN<4> DQS4_B_C @T6G_MB_LIB.T6G(SCH_1):M_E_CPU0_SB_DQS_DN(4)
  55 M_E_CPU0_SA_DQS_DP<4> DQS4_A_T @T6G_MB_LIB.T6G(SCH_1):M_E_CPU0_SA_DQS_DP(4)
  56 M_E_CPU0_SA_DQS_DN<4> DQS4_A_C @T6G_MB_LIB.T6G(SCH_1):M_E_CPU0_SA_DQS_DN(4)
 137 M_E_CPU0_SB_DQS_DP<3> DQS3_B_T @T6G_MB_LIB.T6G(SCH_1):M_E_CPU0_SB_DQS_DP(3)
 138 M_E_CPU0_SB_DQS_DN<3> DQS3_B_C @T6G_MB_LIB.T6G(SCH_1):M_E_CPU0_SB_DQS_DN(3)
  44 M_E_CPU0_SA_DQS_DP<3> DQS3_A_T @T6G_MB_LIB.T6G(SCH_1):M_E_CPU0_SA_DQS_DP(3)
  45 M_E_CPU0_SA_DQS_DN<3> DQS3_A_C @T6G_MB_LIB.T6G(SCH_1):M_E_CPU0_SA_DQS_DN(3)
 126 M_E_CPU0_SB_DQS_DP<2> DQS2_B_T @T6G_MB_LIB.T6G(SCH_1):M_E_CPU0_SB_DQS_DP(2)
 127 M_E_CPU0_SB_DQS_DN<2> DQS2_B_C @T6G_MB_LIB.T6G(SCH_1):M_E_CPU0_SB_DQS_DN(2)
  33 M_E_CPU0_SA_DQS_DP<2> DQS2_A_T @T6G_MB_LIB.T6G(SCH_1):M_E_CPU0_SA_DQS_DP(2)
  34 M_E_CPU0_SA_DQS_DN<2> DQS2_A_C @T6G_MB_LIB.T6G(SCH_1):M_E_CPU0_SA_DQS_DN(2)
 115 M_E_CPU0_SB_DQS_DP<1> DQS1_B_T @T6G_MB_LIB.T6G(SCH_1):M_E_CPU0_SB_DQS_DP(1)
 116 M_E_CPU0_SB_DQS_DN<1> DQS1_B_C @T6G_MB_LIB.T6G(SCH_1):M_E_CPU0_SB_DQS_DN(1)
  22 M_E_CPU0_SA_DQS_DP<1> DQS1_A_T @T6G_MB_LIB.T6G(SCH_1):M_E_CPU0_SA_DQS_DP(1)
  23 M_E_CPU0_SA_DQS_DN<1> DQS1_A_C @T6G_MB_LIB.T6G(SCH_1):M_E_CPU0_SA_DQS_DN(1)
 104 M_E_CPU0_SB_DQS_DP<0> DQS0_B_T @T6G_MB_LIB.T6G(SCH_1):M_E_CPU0_SB_DQS_DP(0)
 105 M_E_CPU0_SB_DQS_DN<0> DQS0_B_C @T6G_MB_LIB.T6G(SCH_1):M_E_CPU0_SB_DQS_DN(0)
  11 M_E_CPU0_SA_DQS_DP<0> DQS0_A_T @T6G_MB_LIB.T6G(SCH_1):M_E_CPU0_SA_DQS_DP(0)
  12 M_E_CPU0_SA_DQS_DN<0> DQS0_A_C @T6G_MB_LIB.T6G(SCH_1):M_E_CPU0_SA_DQS_DN(0)
 272 M_E_CPU0_SB_DQS_DP<7> DQS7_B_T||TDQS7_B_T @T6G_MB_LIB.T6G(SCH_1):M_E_CPU0_SB_DQS_DP(7)
 282 M_E_CPU0_SB_DQS_DN<8> DQS8_B_C||TDQS8_B_C @T6G_MB_LIB.T6G(SCH_1):M_E_CPU0_SB_DQS_DN(8)
 283 M_E_CPU0_SB_DQS_DP<8> DQS8_B_T||TDQS8_B_T @T6G_MB_LIB.T6G(SCH_1):M_E_CPU0_SB_DQS_DP(8)
 168 M_E_CPU0_SA_DQS_DP<6> DQS6_A_T||TDQS6_A_T @T6G_MB_LIB.T6G(SCH_1):M_E_CPU0_SA_DQS_DP(6)
 178 M_E_CPU0_SA_DQS_DN<7> DQS7_A_C||TDQS7_A_C @T6G_MB_LIB.T6G(SCH_1):M_E_CPU0_SA_DQS_DN(7)

Q_CAP_C0805-10UF,25V,10%,X6S,CH6104KEA00  I412  C151
   1 P12V_MEM_CPU0      A @T6G_MB_LIB.T6G(SCH_1):P12V_MEM_CPU0
   2    GND      B @T6G_MB_LIB.T6G(SCH_1):GND

Q_CAP_C0805-10UF,25V,10%,X6S,CH6104KEA00  I413  C153
   1 P12V_MEM_CPU0      A @T6G_MB_LIB.T6G(SCH_1):P12V_MEM_CPU0
   2    GND      B @T6G_MB_LIB.T6G(SCH_1):GND

Q_RES_0402LF-49.9,1%,1/16W,CHIP,CS04992FB07  I416  R1572
   1 I3C_SPD_DDRAF_CPU0_SCL      A @T6G_MB_LIB.T6G(SCH_1):I3C_SPD_DDRAF_CPU0_SCL
   2 I3C_SPD_DDRE_CPU0_SCL      B @T6G_MB_LIB.T6G(SCH_1):I3C_SPD_DDRE_CPU0_SCL

Q_RES_0402LF-10,1%,1/16W,CHIP,CS01002FB07  I418  R1678
   1 I3C_SPD_DDRAF_CPU0_SDA      A @T6G_MB_LIB.T6G(SCH_1):I3C_SPD_DDRAF_CPU0_SDA
   2 I3C_SPD_DDRE_CPU0_SDA      B @T6G_MB_LIB.T6G(SCH_1):I3C_SPD_DDRE_CPU0_SDA


DRAWING: @T6G_MB_LIB.T6G(SCH_1):PAGE90 

Q_RES_0402LF-84.5K,1%,1/16W,CHIP,CS38452FB05  I349  R764
   1 PD_CHF_CPU0_DIMM_SAA      A @T6G_MB_LIB.T6G(SCH_1):PD_CHF_CPU0_DIMM_SAA
   2    GND      B @T6G_MB_LIB.T6G(SCH_1):GND

SCONN288_DDR506112002KQ-SCONN288_DDR506112002KQ,SMA  I350  J23
   3 P3V3_AUX VIN_MGMT @T6G_MB_LIB.T6G(SCH_1):P3V3_AUX
   2     NC   RFU0     NC
 144     NC   RFU1     NC
 149     NC   RFU2     NC
 150     NC   RFU3     NC
 220     NC   RFU4     NC
 231     NC   RFU5     NC
 232     NC   RFU6     NC
 207 M_F_CPU0_RESET_N RESET_N @T6G_MB_LIB.T6G(SCH_1):M_F_CPU0_RESET_N
 147 PWRGD_CHF_CPU0_DIMM PWR_GOOD||FAIL_N @T6G_MB_LIB.T6G(SCH_1):PWRGD_CHF_CPU0_DIMM
 227 M_F_CPU0_SB_PAR  PAR_B @T6G_MB_LIB.T6G(SCH_1):M_F_CPU0_SB_PAR
  74 M_F_CPU0_SA_PAR  PAR_A @T6G_MB_LIB.T6G(SCH_1):M_F_CPU0_SA_PAR
  87 M_F_CPU0_SB_RSP<0> LBS||RSP_B_N @T6G_MB_LIB.T6G(SCH_1):M_F_CPU0_SB_RSP(0)
  86 M_F_CPU0_SA_RSP<0> LBD||RSP_A_N @T6G_MB_LIB.T6G(SCH_1):M_F_CPU0_SA_RSP(0)
   5 I3C_SPD_DDRF_CPU0_SDA   HSDA @T6G_MB_LIB.T6G(SCH_1):I3C_SPD_DDRF_CPU0_SDA
   4 I3C_SPD_DDRF_CPU0_SCL   HSCL @T6G_MB_LIB.T6G(SCH_1):I3C_SPD_DDRF_CPU0_SCL
 148 PD_CHF_CPU0_DIMM_SAA    HAS @T6G_MB_LIB.T6G(SCH_1):PD_CHF_CPU0_DIMM_SAA
 100 M_F_CPU0_SB_DQ<0>  DQ0_B @T6G_MB_LIB.T6G(SCH_1):M_F_CPU0_SB_DQ(0)
 102 M_F_CPU0_SB_DQ<1>  DQ1_B @T6G_MB_LIB.T6G(SCH_1):M_F_CPU0_SB_DQ(1)
 245 M_F_CPU0_SB_DQ<2>  DQ2_B @T6G_MB_LIB.T6G(SCH_1):M_F_CPU0_SB_DQ(2)
 247 M_F_CPU0_SB_DQ<3>  DQ3_B @T6G_MB_LIB.T6G(SCH_1):M_F_CPU0_SB_DQ(3)
 107 M_F_CPU0_SB_DQ<4>  DQ4_B @T6G_MB_LIB.T6G(SCH_1):M_F_CPU0_SB_DQ(4)
 109 M_F_CPU0_SB_DQ<5>  DQ5_B @T6G_MB_LIB.T6G(SCH_1):M_F_CPU0_SB_DQ(5)
 252 M_F_CPU0_SB_DQ<6>  DQ6_B @T6G_MB_LIB.T6G(SCH_1):M_F_CPU0_SB_DQ(6)
 254 M_F_CPU0_SB_DQ<7>  DQ7_B @T6G_MB_LIB.T6G(SCH_1):M_F_CPU0_SB_DQ(7)
 111 M_F_CPU0_SB_DQ<8>  DQ8_B @T6G_MB_LIB.T6G(SCH_1):M_F_CPU0_SB_DQ(8)
 113 M_F_CPU0_SB_DQ<9>  DQ9_B @T6G_MB_LIB.T6G(SCH_1):M_F_CPU0_SB_DQ(9)
 256 M_F_CPU0_SB_DQ<10> DQ10_B @T6G_MB_LIB.T6G(SCH_1):M_F_CPU0_SB_DQ(10)
 258 M_F_CPU0_SB_DQ<11> DQ11_B @T6G_MB_LIB.T6G(SCH_1):M_F_CPU0_SB_DQ(11)
 118 M_F_CPU0_SB_DQ<12> DQ12_B @T6G_MB_LIB.T6G(SCH_1):M_F_CPU0_SB_DQ(12)
 120 M_F_CPU0_SB_DQ<13> DQ13_B @T6G_MB_LIB.T6G(SCH_1):M_F_CPU0_SB_DQ(13)
 263 M_F_CPU0_SB_DQ<14> DQ14_B @T6G_MB_LIB.T6G(SCH_1):M_F_CPU0_SB_DQ(14)
 265 M_F_CPU0_SB_DQ<15> DQ15_B @T6G_MB_LIB.T6G(SCH_1):M_F_CPU0_SB_DQ(15)
 122 M_F_CPU0_SB_DQ<16> DQ16_B @T6G_MB_LIB.T6G(SCH_1):M_F_CPU0_SB_DQ(16)
 124 M_F_CPU0_SB_DQ<17> DQ17_B @T6G_MB_LIB.T6G(SCH_1):M_F_CPU0_SB_DQ(17)
 267 M_F_CPU0_SB_DQ<18> DQ18_B @T6G_MB_LIB.T6G(SCH_1):M_F_CPU0_SB_DQ(18)
 269 M_F_CPU0_SB_DQ<19> DQ19_B @T6G_MB_LIB.T6G(SCH_1):M_F_CPU0_SB_DQ(19)
 129 M_F_CPU0_SB_DQ<20> DQ20_B @T6G_MB_LIB.T6G(SCH_1):M_F_CPU0_SB_DQ(20)
 131 M_F_CPU0_SB_DQ<21> DQ21_B @T6G_MB_LIB.T6G(SCH_1):M_F_CPU0_SB_DQ(21)
 274 M_F_CPU0_SB_DQ<22> DQ22_B @T6G_MB_LIB.T6G(SCH_1):M_F_CPU0_SB_DQ(22)
 276 M_F_CPU0_SB_DQ<23> DQ23_B @T6G_MB_LIB.T6G(SCH_1):M_F_CPU0_SB_DQ(23)
 133 M_F_CPU0_SB_DQ<24> DQ24_B @T6G_MB_LIB.T6G(SCH_1):M_F_CPU0_SB_DQ(24)
 135 M_F_CPU0_SB_DQ<25> DQ25_B @T6G_MB_LIB.T6G(SCH_1):M_F_CPU0_SB_DQ(25)
 278 M_F_CPU0_SB_DQ<26> DQ26_B @T6G_MB_LIB.T6G(SCH_1):M_F_CPU0_SB_DQ(26)
 280 M_F_CPU0_SB_DQ<27> DQ27_B @T6G_MB_LIB.T6G(SCH_1):M_F_CPU0_SB_DQ(27)
 140 M_F_CPU0_SB_DQ<28> DQ28_B @T6G_MB_LIB.T6G(SCH_1):M_F_CPU0_SB_DQ(28)
 142 M_F_CPU0_SB_DQ<29> DQ29_B @T6G_MB_LIB.T6G(SCH_1):M_F_CPU0_SB_DQ(29)
 285 M_F_CPU0_SB_DQ<30> DQ30_B @T6G_MB_LIB.T6G(SCH_1):M_F_CPU0_SB_DQ(30)
 287 M_F_CPU0_SB_DQ<31> DQ31_B @T6G_MB_LIB.T6G(SCH_1):M_F_CPU0_SB_DQ(31)
   7 M_F_CPU0_SA_DQ<0>  DQ0_A @T6G_MB_LIB.T6G(SCH_1):M_F_CPU0_SA_DQ(0)
   9 M_F_CPU0_SA_DQ<1>  DQ1_A @T6G_MB_LIB.T6G(SCH_1):M_F_CPU0_SA_DQ(1)
 152 M_F_CPU0_SA_DQ<2>  DQ2_A @T6G_MB_LIB.T6G(SCH_1):M_F_CPU0_SA_DQ(2)
 154 M_F_CPU0_SA_DQ<3>  DQ3_A @T6G_MB_LIB.T6G(SCH_1):M_F_CPU0_SA_DQ(3)
  14 M_F_CPU0_SA_DQ<4>  DQ4_A @T6G_MB_LIB.T6G(SCH_1):M_F_CPU0_SA_DQ(4)
  16 M_F_CPU0_SA_DQ<5>  DQ5_A @T6G_MB_LIB.T6G(SCH_1):M_F_CPU0_SA_DQ(5)
 159 M_F_CPU0_SA_DQ<6>  DQ6_A @T6G_MB_LIB.T6G(SCH_1):M_F_CPU0_SA_DQ(6)
 161 M_F_CPU0_SA_DQ<7>  DQ7_A @T6G_MB_LIB.T6G(SCH_1):M_F_CPU0_SA_DQ(7)
  18 M_F_CPU0_SA_DQ<8>  DQ8_A @T6G_MB_LIB.T6G(SCH_1):M_F_CPU0_SA_DQ(8)
  20 M_F_CPU0_SA_DQ<9>  DQ9_A @T6G_MB_LIB.T6G(SCH_1):M_F_CPU0_SA_DQ(9)
 163 M_F_CPU0_SA_DQ<10> DQ10_A @T6G_MB_LIB.T6G(SCH_1):M_F_CPU0_SA_DQ(10)
 165 M_F_CPU0_SA_DQ<11> DQ11_A @T6G_MB_LIB.T6G(SCH_1):M_F_CPU0_SA_DQ(11)
  25 M_F_CPU0_SA_DQ<12> DQ12_A @T6G_MB_LIB.T6G(SCH_1):M_F_CPU0_SA_DQ(12)
  27 M_F_CPU0_SA_DQ<13> DQ13_A @T6G_MB_LIB.T6G(SCH_1):M_F_CPU0_SA_DQ(13)
 170 M_F_CPU0_SA_DQ<14> DQ14_A @T6G_MB_LIB.T6G(SCH_1):M_F_CPU0_SA_DQ(14)
 172 M_F_CPU0_SA_DQ<15> DQ15_A @T6G_MB_LIB.T6G(SCH_1):M_F_CPU0_SA_DQ(15)
  29 M_F_CPU0_SA_DQ<16> DQ16_A @T6G_MB_LIB.T6G(SCH_1):M_F_CPU0_SA_DQ(16)
  31 M_F_CPU0_SA_DQ<17> DQ17_A @T6G_MB_LIB.T6G(SCH_1):M_F_CPU0_SA_DQ(17)
 174 M_F_CPU0_SA_DQ<18> DQ18_A @T6G_MB_LIB.T6G(SCH_1):M_F_CPU0_SA_DQ(18)
 176 M_F_CPU0_SA_DQ<19> DQ19_A @T6G_MB_LIB.T6G(SCH_1):M_F_CPU0_SA_DQ(19)
  36 M_F_CPU0_SA_DQ<20> DQ20_A @T6G_MB_LIB.T6G(SCH_1):M_F_CPU0_SA_DQ(20)
  38 M_F_CPU0_SA_DQ<21> DQ21_A @T6G_MB_LIB.T6G(SCH_1):M_F_CPU0_SA_DQ(21)
 181 M_F_CPU0_SA_DQ<22> DQ22_A @T6G_MB_LIB.T6G(SCH_1):M_F_CPU0_SA_DQ(22)
 183 M_F_CPU0_SA_DQ<23> DQ23_A @T6G_MB_LIB.T6G(SCH_1):M_F_CPU0_SA_DQ(23)
  40 M_F_CPU0_SA_DQ<24> DQ24_A @T6G_MB_LIB.T6G(SCH_1):M_F_CPU0_SA_DQ(24)
  42 M_F_CPU0_SA_DQ<25> DQ25_A @T6G_MB_LIB.T6G(SCH_1):M_F_CPU0_SA_DQ(25)
 185 M_F_CPU0_SA_DQ<26> DQ26_A @T6G_MB_LIB.T6G(SCH_1):M_F_CPU0_SA_DQ(26)
 187 M_F_CPU0_SA_DQ<27> DQ27_A @T6G_MB_LIB.T6G(SCH_1):M_F_CPU0_SA_DQ(27)
  47 M_F_CPU0_SA_DQ<28> DQ28_A @T6G_MB_LIB.T6G(SCH_1):M_F_CPU0_SA_DQ(28)
  49 M_F_CPU0_SA_DQ<29> DQ29_A @T6G_MB_LIB.T6G(SCH_1):M_F_CPU0_SA_DQ(29)
 192 M_F_CPU0_SA_DQ<30> DQ30_A @T6G_MB_LIB.T6G(SCH_1):M_F_CPU0_SA_DQ(30)
 229 M_F_CPU0_SB_CS_N<1> CS1_B_N @T6G_MB_LIB.T6G(SCH_1):M_F_CPU0_SB_CS_N(1)
 209 M_F_CPU0_SA_CS_N<1> CS1_A_N @T6G_MB_LIB.T6G(SCH_1):M_F_CPU0_SA_CS_N(1)
  84 M_F_CPU0_SB_CS_N<0> CS0_B_N @T6G_MB_LIB.T6G(SCH_1):M_F_CPU0_SB_CS_N(0)
  64 M_F_CPU0_SA_CS_N<0> CS0_A_N @T6G_MB_LIB.T6G(SCH_1):M_F_CPU0_SA_CS_N(0)
 217 M_F_CPU0_CLK_DP<0>   CK_T @T6G_MB_LIB.T6G(SCH_1):M_F_CPU0_CLK_DP(0)
 218 M_F_CPU0_CLK_DN<0>   CK_C @T6G_MB_LIB.T6G(SCH_1):M_F_CPU0_CLK_DN(0)
  96 M_F_CPU0_SB_CB<0>  CB0_B @T6G_MB_LIB.T6G(SCH_1):M_F_CPU0_SB_CB(0)
  98 M_F_CPU0_SB_CB<1>  CB1_B @T6G_MB_LIB.T6G(SCH_1):M_F_CPU0_SB_CB(1)
 241 M_F_CPU0_SB_CB<2>  CB2_B @T6G_MB_LIB.T6G(SCH_1):M_F_CPU0_SB_CB(2)
 243 M_F_CPU0_SB_CB<3>  CB3_B @T6G_MB_LIB.T6G(SCH_1):M_F_CPU0_SB_CB(3)
  89 M_F_CPU0_SB_CB<4>  CB4_B @T6G_MB_LIB.T6G(SCH_1):M_F_CPU0_SB_CB(4)
  91 M_F_CPU0_SB_CB<5>  CB5_B @T6G_MB_LIB.T6G(SCH_1):M_F_CPU0_SB_CB(5)
 234 M_F_CPU0_SB_CB<6>  CB6_B @T6G_MB_LIB.T6G(SCH_1):M_F_CPU0_SB_CB(6)
  51 M_F_CPU0_SA_CB<0>  CB0_A @T6G_MB_LIB.T6G(SCH_1):M_F_CPU0_SA_CB(0)
 196 M_F_CPU0_SA_CB<2>  CB2_A @T6G_MB_LIB.T6G(SCH_1):M_F_CPU0_SA_CB(2)
 198 M_F_CPU0_SA_CB<3>  CB3_A @T6G_MB_LIB.T6G(SCH_1):M_F_CPU0_SA_CB(3)
  60 M_F_CPU0_SA_CB<5>  CB5_A @T6G_MB_LIB.T6G(SCH_1):M_F_CPU0_SA_CB(5)
 203 M_F_CPU0_SA_CB<6>  CB6_A @T6G_MB_LIB.T6G(SCH_1):M_F_CPU0_SA_CB(6)
  82 M_F_CPU0_SB_CA<6>  CA6_B @T6G_MB_LIB.T6G(SCH_1):M_F_CPU0_SB_CA(6)
  72 M_F_CPU0_SA_CA<6>  CA6_A @T6G_MB_LIB.T6G(SCH_1):M_F_CPU0_SA_CA(6)
 225 M_F_CPU0_SB_CA<5>  CA5_B @T6G_MB_LIB.T6G(SCH_1):M_F_CPU0_SB_CA(5)
 215 M_F_CPU0_SA_CA<5>  CA5_A @T6G_MB_LIB.T6G(SCH_1):M_F_CPU0_SA_CA(5)
  80 M_F_CPU0_SB_CA<4>  CA4_B @T6G_MB_LIB.T6G(SCH_1):M_F_CPU0_SB_CA(4)
  70 M_F_CPU0_SA_CA<4>  CA4_A @T6G_MB_LIB.T6G(SCH_1):M_F_CPU0_SA_CA(4)
 223 M_F_CPU0_SB_CA<3>  CA3_B @T6G_MB_LIB.T6G(SCH_1):M_F_CPU0_SB_CA(3)
 213 M_F_CPU0_SA_CA<3>  CA3_A @T6G_MB_LIB.T6G(SCH_1):M_F_CPU0_SA_CA(3)
  78 M_F_CPU0_SB_CA<2>  CA2_B @T6G_MB_LIB.T6G(SCH_1):M_F_CPU0_SB_CA(2)
  68 M_F_CPU0_SA_CA<2>  CA2_A @T6G_MB_LIB.T6G(SCH_1):M_F_CPU0_SA_CA(2)
 221 M_F_CPU0_SB_CA<1>  CA1_B @T6G_MB_LIB.T6G(SCH_1):M_F_CPU0_SB_CA(1)
 211 M_F_CPU0_SA_CA<1>  CA1_A @T6G_MB_LIB.T6G(SCH_1):M_F_CPU0_SA_CA(1)
  76 M_F_CPU0_SB_CA<0>  CA0_B @T6G_MB_LIB.T6G(SCH_1):M_F_CPU0_SB_CA(0)
  66 M_F_CPU0_SA_CA<0>  CA0_A @T6G_MB_LIB.T6G(SCH_1):M_F_CPU0_SA_CA(0)
  62 M_F_CPU0_ALERT_N ALERT_N @T6G_MB_LIB.T6G(SCH_1):M_F_CPU0_ALERT_N
 236 M_F_CPU0_SB_CB<7>  CB7_B @T6G_MB_LIB.T6G(SCH_1):M_F_CPU0_SB_CB(7)
  53 M_F_CPU0_SA_CB<1>  CB1_A @T6G_MB_LIB.T6G(SCH_1):M_F_CPU0_SA_CB(1)
  58 M_F_CPU0_SA_CB<4>  CB4_A @T6G_MB_LIB.T6G(SCH_1):M_F_CPU0_SA_CB(4)
 205 M_F_CPU0_SA_CB<7>  CB7_A @T6G_MB_LIB.T6G(SCH_1):M_F_CPU0_SA_CB(7)
 194 M_F_CPU0_SA_DQ<31> DQ31_A @T6G_MB_LIB.T6G(SCH_1):M_F_CPU0_SA_DQ(31)

SCONN288_DDR506112002KQ-SCONN288_DDR506112002KQ,SMA  I352  J23
   6    GND   VSS0 @T6G_MB_LIB.T6G(SCH_1):GND
   8    GND   VSS1 @T6G_MB_LIB.T6G(SCH_1):GND
  10    GND   VSS2 @T6G_MB_LIB.T6G(SCH_1):GND
  13    GND   VSS3 @T6G_MB_LIB.T6G(SCH_1):GND
  15    GND   VSS4 @T6G_MB_LIB.T6G(SCH_1):GND
  17    GND   VSS5 @T6G_MB_LIB.T6G(SCH_1):GND
  19    GND   VSS6 @T6G_MB_LIB.T6G(SCH_1):GND
  21    GND   VSS7 @T6G_MB_LIB.T6G(SCH_1):GND
  24    GND   VSS8 @T6G_MB_LIB.T6G(SCH_1):GND
  26    GND   VSS9 @T6G_MB_LIB.T6G(SCH_1):GND
  28    GND  VSS10 @T6G_MB_LIB.T6G(SCH_1):GND
  30    GND  VSS11 @T6G_MB_LIB.T6G(SCH_1):GND
  32    GND  VSS12 @T6G_MB_LIB.T6G(SCH_1):GND
  35    GND  VSS13 @T6G_MB_LIB.T6G(SCH_1):GND
  37    GND  VSS14 @T6G_MB_LIB.T6G(SCH_1):GND
  39    GND  VSS15 @T6G_MB_LIB.T6G(SCH_1):GND
  41    GND  VSS16 @T6G_MB_LIB.T6G(SCH_1):GND
  43    GND  VSS17 @T6G_MB_LIB.T6G(SCH_1):GND
  46    GND  VSS18 @T6G_MB_LIB.T6G(SCH_1):GND
  48    GND  VSS19 @T6G_MB_LIB.T6G(SCH_1):GND
  50    GND  VSS20 @T6G_MB_LIB.T6G(SCH_1):GND
  52    GND  VSS21 @T6G_MB_LIB.T6G(SCH_1):GND
  54    GND  VSS22 @T6G_MB_LIB.T6G(SCH_1):GND
  57    GND  VSS23 @T6G_MB_LIB.T6G(SCH_1):GND
  59    GND  VSS24 @T6G_MB_LIB.T6G(SCH_1):GND
  61    GND  VSS25 @T6G_MB_LIB.T6G(SCH_1):GND
  63    GND  VSS26 @T6G_MB_LIB.T6G(SCH_1):GND
  65    GND  VSS27 @T6G_MB_LIB.T6G(SCH_1):GND
  67    GND  VSS28 @T6G_MB_LIB.T6G(SCH_1):GND
  69    GND  VSS29 @T6G_MB_LIB.T6G(SCH_1):GND
  71    GND  VSS30 @T6G_MB_LIB.T6G(SCH_1):GND
  73    GND  VSS31 @T6G_MB_LIB.T6G(SCH_1):GND
  75    GND  VSS32 @T6G_MB_LIB.T6G(SCH_1):GND
  77    GND  VSS33 @T6G_MB_LIB.T6G(SCH_1):GND
  79    GND  VSS34 @T6G_MB_LIB.T6G(SCH_1):GND
  81    GND  VSS35 @T6G_MB_LIB.T6G(SCH_1):GND
  83    GND  VSS36 @T6G_MB_LIB.T6G(SCH_1):GND
  85    GND  VSS37 @T6G_MB_LIB.T6G(SCH_1):GND
  88    GND  VSS38 @T6G_MB_LIB.T6G(SCH_1):GND
  90    GND  VSS39 @T6G_MB_LIB.T6G(SCH_1):GND
  92    GND  VSS40 @T6G_MB_LIB.T6G(SCH_1):GND
  95    GND  VSS41 @T6G_MB_LIB.T6G(SCH_1):GND
  97    GND  VSS42 @T6G_MB_LIB.T6G(SCH_1):GND
  99    GND  VSS43 @T6G_MB_LIB.T6G(SCH_1):GND
 101    GND  VSS44 @T6G_MB_LIB.T6G(SCH_1):GND
 103    GND  VSS45 @T6G_MB_LIB.T6G(SCH_1):GND
 106    GND  VSS46 @T6G_MB_LIB.T6G(SCH_1):GND
 108    GND  VSS47 @T6G_MB_LIB.T6G(SCH_1):GND
 110    GND  VSS48 @T6G_MB_LIB.T6G(SCH_1):GND
 112    GND  VSS49 @T6G_MB_LIB.T6G(SCH_1):GND
 114    GND  VSS50 @T6G_MB_LIB.T6G(SCH_1):GND
 117    GND  VSS51 @T6G_MB_LIB.T6G(SCH_1):GND
 119    GND  VSS52 @T6G_MB_LIB.T6G(SCH_1):GND
 121    GND  VSS53 @T6G_MB_LIB.T6G(SCH_1):GND
 123    GND  VSS54 @T6G_MB_LIB.T6G(SCH_1):GND
 125    GND  VSS55 @T6G_MB_LIB.T6G(SCH_1):GND
 128    GND  VSS56 @T6G_MB_LIB.T6G(SCH_1):GND
 130    GND  VSS57 @T6G_MB_LIB.T6G(SCH_1):GND
 134    GND  VSS59 @T6G_MB_LIB.T6G(SCH_1):GND
 143    GND  VSS63 @T6G_MB_LIB.T6G(SCH_1):GND
 151    GND  VSS64 @T6G_MB_LIB.T6G(SCH_1):GND
 153    GND  VSS65 @T6G_MB_LIB.T6G(SCH_1):GND
 155    GND  VSS66 @T6G_MB_LIB.T6G(SCH_1):GND
 158    GND  VSS67 @T6G_MB_LIB.T6G(SCH_1):GND
 160    GND  VSS68 @T6G_MB_LIB.T6G(SCH_1):GND
 162    GND  VSS69 @T6G_MB_LIB.T6G(SCH_1):GND
 164    GND  VSS70 @T6G_MB_LIB.T6G(SCH_1):GND
 166    GND  VSS71 @T6G_MB_LIB.T6G(SCH_1):GND
 169    GND  VSS72 @T6G_MB_LIB.T6G(SCH_1):GND
 171    GND  VSS73 @T6G_MB_LIB.T6G(SCH_1):GND
 173    GND  VSS74 @T6G_MB_LIB.T6G(SCH_1):GND
 175    GND  VSS75 @T6G_MB_LIB.T6G(SCH_1):GND
 177    GND  VSS76 @T6G_MB_LIB.T6G(SCH_1):GND
 180    GND  VSS77 @T6G_MB_LIB.T6G(SCH_1):GND
 182    GND  VSS78 @T6G_MB_LIB.T6G(SCH_1):GND
 184    GND  VSS79 @T6G_MB_LIB.T6G(SCH_1):GND
 186    GND  VSS80 @T6G_MB_LIB.T6G(SCH_1):GND
 188    GND  VSS81 @T6G_MB_LIB.T6G(SCH_1):GND
 191    GND  VSS82 @T6G_MB_LIB.T6G(SCH_1):GND
 193    GND  VSS83 @T6G_MB_LIB.T6G(SCH_1):GND
 195    GND  VSS84 @T6G_MB_LIB.T6G(SCH_1):GND
 197    GND  VSS85 @T6G_MB_LIB.T6G(SCH_1):GND
 199    GND  VSS86 @T6G_MB_LIB.T6G(SCH_1):GND
 202    GND  VSS87 @T6G_MB_LIB.T6G(SCH_1):GND
 204    GND  VSS88 @T6G_MB_LIB.T6G(SCH_1):GND
 206    GND  VSS89 @T6G_MB_LIB.T6G(SCH_1):GND
 208    GND  VSS90 @T6G_MB_LIB.T6G(SCH_1):GND
 210    GND  VSS91 @T6G_MB_LIB.T6G(SCH_1):GND
 212    GND  VSS92 @T6G_MB_LIB.T6G(SCH_1):GND
 214    GND  VSS93 @T6G_MB_LIB.T6G(SCH_1):GND
 216    GND  VSS94 @T6G_MB_LIB.T6G(SCH_1):GND
 219    GND  VSS95 @T6G_MB_LIB.T6G(SCH_1):GND
 222    GND  VSS96 @T6G_MB_LIB.T6G(SCH_1):GND
 224    GND  VSS97 @T6G_MB_LIB.T6G(SCH_1):GND
 226    GND  VSS98 @T6G_MB_LIB.T6G(SCH_1):GND
 228    GND  VSS99 @T6G_MB_LIB.T6G(SCH_1):GND
 233    GND VSS101 @T6G_MB_LIB.T6G(SCH_1):GND
 237    GND VSS103 @T6G_MB_LIB.T6G(SCH_1):GND
 242    GND VSS105 @T6G_MB_LIB.T6G(SCH_1):GND
 244    GND VSS106 @T6G_MB_LIB.T6G(SCH_1):GND
 246    GND VSS107 @T6G_MB_LIB.T6G(SCH_1):GND
 248    GND VSS108 @T6G_MB_LIB.T6G(SCH_1):GND
 251    GND VSS109 @T6G_MB_LIB.T6G(SCH_1):GND
 253    GND VSS110 @T6G_MB_LIB.T6G(SCH_1):GND
 255    GND VSS111 @T6G_MB_LIB.T6G(SCH_1):GND
 257    GND VSS112 @T6G_MB_LIB.T6G(SCH_1):GND
 259    GND VSS113 @T6G_MB_LIB.T6G(SCH_1):GND
 262    GND VSS114 @T6G_MB_LIB.T6G(SCH_1):GND
 264    GND VSS115 @T6G_MB_LIB.T6G(SCH_1):GND
 266    GND VSS116 @T6G_MB_LIB.T6G(SCH_1):GND
 268    GND VSS117 @T6G_MB_LIB.T6G(SCH_1):GND
 270    GND VSS118 @T6G_MB_LIB.T6G(SCH_1):GND
 273    GND VSS119 @T6G_MB_LIB.T6G(SCH_1):GND
 275    GND VSS120 @T6G_MB_LIB.T6G(SCH_1):GND
 277    GND VSS121 @T6G_MB_LIB.T6G(SCH_1):GND
 279    GND VSS122 @T6G_MB_LIB.T6G(SCH_1):GND
 281    GND VSS123 @T6G_MB_LIB.T6G(SCH_1):GND
 284    GND VSS124 @T6G_MB_LIB.T6G(SCH_1):GND
 286    GND VSS125 @T6G_MB_LIB.T6G(SCH_1):GND
 288    GND VSS126 @T6G_MB_LIB.T6G(SCH_1):GND
   1 P12V_MEM_CPU0 VIN_BULK0 @T6G_MB_LIB.T6G(SCH_1):P12V_MEM_CPU0
 145 P12V_MEM_CPU0 VIN_BULK1 @T6G_MB_LIB.T6G(SCH_1):P12V_MEM_CPU0
 146 P12V_MEM_CPU0 VIN_BULK2 @T6G_MB_LIB.T6G(SCH_1):P12V_MEM_CPU0
 230    GND VSS100 @T6G_MB_LIB.T6G(SCH_1):GND
 235    GND VSS102 @T6G_MB_LIB.T6G(SCH_1):GND
 240    GND VSS104 @T6G_MB_LIB.T6G(SCH_1):GND
 132    GND  VSS58 @T6G_MB_LIB.T6G(SCH_1):GND
 136    GND  VSS60 @T6G_MB_LIB.T6G(SCH_1):GND
 139    GND  VSS61 @T6G_MB_LIB.T6G(SCH_1):GND
 141    GND  VSS62 @T6G_MB_LIB.T6G(SCH_1):GND
  G1    GND     G1 @T6G_MB_LIB.T6G(SCH_1):GND
  G2    GND     G2 @T6G_MB_LIB.T6G(SCH_1):GND
  G3    GND     G3 @T6G_MB_LIB.T6G(SCH_1):GND

Q_CAP_0402-0.1UF,25V,10%,X7R,CH4104K1B00  I361  C108
   1 P3V3_AUX      A @T6G_MB_LIB.T6G(SCH_1):P3V3_AUX
   2    GND      B @T6G_MB_LIB.T6G(SCH_1):GND

Q_RES_0402LF-1K,1%,1/16W,CHIP,CS21002FB06  I364  R296
   1 PWRGD_CHF_CPU0_DIMM      A @T6G_MB_LIB.T6G(SCH_1):PWRGD_CHF_CPU0_DIMM
   2 PWRGD_CHAF_CPU0      B @T6G_MB_LIB.T6G(SCH_1):PWRGD_CHAF_CPU0

Q_RES_0402LF-1K,1%,1/16W,EMPTY,CS21002FB06  I365  R94
   1   P3V3      A @T6G_MB_LIB.T6G(SCH_1):P3V3
   2 PWRGD_CHF_CPU0_DIMM      B @T6G_MB_LIB.T6G(SCH_1):PWRGD_CHF_CPU0_DIMM

SCONN288_DDR506112002KQ-SCONN288_DDR506112002KQ,SMA  I412  J23
  93 M_F_CPU0_SB_DQS_DP<9> DQS9_B_T||TDQS9_B_T||DBI4_B_N @T6G_MB_LIB.T6G(SCH_1):M_F_CPU0_SB_DQS_DP(9)
  94 M_F_CPU0_SB_DQS_DN<9> DQS9_B_C||TDQS9_B_C @T6G_MB_LIB.T6G(SCH_1):M_F_CPU0_SB_DQS_DN(9)
 201 M_F_CPU0_SA_DQS_DP<9> DQS9_A_T||TDQS9_A_T @T6G_MB_LIB.T6G(SCH_1):M_F_CPU0_SA_DQS_DP(9)
 200 M_F_CPU0_SA_DQS_DN<9> DQS9_A_C||TDQS9_A_C @T6G_MB_LIB.T6G(SCH_1):M_F_CPU0_SA_DQS_DN(9)
 190 M_F_CPU0_SA_DQS_DP<8> DQS8_A_T||TDQS8_A_T @T6G_MB_LIB.T6G(SCH_1):M_F_CPU0_SA_DQS_DP(8)
 189 M_F_CPU0_SA_DQS_DN<8> DQS8_A_C||TDQS8_A_C @T6G_MB_LIB.T6G(SCH_1):M_F_CPU0_SA_DQS_DN(8)
 271 M_F_CPU0_SB_DQS_DN<7> DQS7_B_C||TDQS7_B_C @T6G_MB_LIB.T6G(SCH_1):M_F_CPU0_SB_DQS_DN(7)
 179 M_F_CPU0_SA_DQS_DP<7> DQS7_A_T||TDQS7_A_T @T6G_MB_LIB.T6G(SCH_1):M_F_CPU0_SA_DQS_DP(7)
 261 M_F_CPU0_SB_DQS_DP<6> DQS6_B_T||TDQS6_B_T @T6G_MB_LIB.T6G(SCH_1):M_F_CPU0_SB_DQS_DP(6)
 260 M_F_CPU0_SB_DQS_DN<6> DQS6_B_C||TDQS6_B_C @T6G_MB_LIB.T6G(SCH_1):M_F_CPU0_SB_DQS_DN(6)
 167 M_F_CPU0_SA_DQS_DN<6> DQS6_A_C||TDQS6_A_C||DQS6_A_T||TDQS6_A_T @T6G_MB_LIB.T6G(SCH_1):M_F_CPU0_SA_DQS_DN(6)
 250 M_F_CPU0_SB_DQS_DP<5> DQS5_B_T||TDQS5_B_T @T6G_MB_LIB.T6G(SCH_1):M_F_CPU0_SB_DQS_DP(5)
 249 M_F_CPU0_SB_DQS_DN<5> DQS5_B_C||TDQS5_B_C @T6G_MB_LIB.T6G(SCH_1):M_F_CPU0_SB_DQS_DN(5)
 157 M_F_CPU0_SA_DQS_DP<5> DQS5_A_T||TDQS5_A_T @T6G_MB_LIB.T6G(SCH_1):M_F_CPU0_SA_DQS_DP(5)
 156 M_F_CPU0_SA_DQS_DN<5> DQS5_A_C||TDQS5_A_C||DQS5_A_T||TDQS5_A_T @T6G_MB_LIB.T6G(SCH_1):M_F_CPU0_SA_DQS_DN(5)
 239 M_F_CPU0_SB_DQS_DP<4> DQS4_B_T @T6G_MB_LIB.T6G(SCH_1):M_F_CPU0_SB_DQS_DP(4)
 238 M_F_CPU0_SB_DQS_DN<4> DQS4_B_C @T6G_MB_LIB.T6G(SCH_1):M_F_CPU0_SB_DQS_DN(4)
  55 M_F_CPU0_SA_DQS_DP<4> DQS4_A_T @T6G_MB_LIB.T6G(SCH_1):M_F_CPU0_SA_DQS_DP(4)
  56 M_F_CPU0_SA_DQS_DN<4> DQS4_A_C @T6G_MB_LIB.T6G(SCH_1):M_F_CPU0_SA_DQS_DN(4)
 137 M_F_CPU0_SB_DQS_DP<3> DQS3_B_T @T6G_MB_LIB.T6G(SCH_1):M_F_CPU0_SB_DQS_DP(3)
 138 M_F_CPU0_SB_DQS_DN<3> DQS3_B_C @T6G_MB_LIB.T6G(SCH_1):M_F_CPU0_SB_DQS_DN(3)
  44 M_F_CPU0_SA_DQS_DP<3> DQS3_A_T @T6G_MB_LIB.T6G(SCH_1):M_F_CPU0_SA_DQS_DP(3)
  45 M_F_CPU0_SA_DQS_DN<3> DQS3_A_C @T6G_MB_LIB.T6G(SCH_1):M_F_CPU0_SA_DQS_DN(3)
 126 M_F_CPU0_SB_DQS_DP<2> DQS2_B_T @T6G_MB_LIB.T6G(SCH_1):M_F_CPU0_SB_DQS_DP(2)
 127 M_F_CPU0_SB_DQS_DN<2> DQS2_B_C @T6G_MB_LIB.T6G(SCH_1):M_F_CPU0_SB_DQS_DN(2)
  33 M_F_CPU0_SA_DQS_DP<2> DQS2_A_T @T6G_MB_LIB.T6G(SCH_1):M_F_CPU0_SA_DQS_DP(2)
  34 M_F_CPU0_SA_DQS_DN<2> DQS2_A_C @T6G_MB_LIB.T6G(SCH_1):M_F_CPU0_SA_DQS_DN(2)
 115 M_F_CPU0_SB_DQS_DP<1> DQS1_B_T @T6G_MB_LIB.T6G(SCH_1):M_F_CPU0_SB_DQS_DP(1)
 116 M_F_CPU0_SB_DQS_DN<1> DQS1_B_C @T6G_MB_LIB.T6G(SCH_1):M_F_CPU0_SB_DQS_DN(1)
  22 M_F_CPU0_SA_DQS_DP<1> DQS1_A_T @T6G_MB_LIB.T6G(SCH_1):M_F_CPU0_SA_DQS_DP(1)
  23 M_F_CPU0_SA_DQS_DN<1> DQS1_A_C @T6G_MB_LIB.T6G(SCH_1):M_F_CPU0_SA_DQS_DN(1)
 104 M_F_CPU0_SB_DQS_DP<0> DQS0_B_T @T6G_MB_LIB.T6G(SCH_1):M_F_CPU0_SB_DQS_DP(0)
 105 M_F_CPU0_SB_DQS_DN<0> DQS0_B_C @T6G_MB_LIB.T6G(SCH_1):M_F_CPU0_SB_DQS_DN(0)
  11 M_F_CPU0_SA_DQS_DP<0> DQS0_A_T @T6G_MB_LIB.T6G(SCH_1):M_F_CPU0_SA_DQS_DP(0)
  12 M_F_CPU0_SA_DQS_DN<0> DQS0_A_C @T6G_MB_LIB.T6G(SCH_1):M_F_CPU0_SA_DQS_DN(0)
 272 M_F_CPU0_SB_DQS_DP<7> DQS7_B_T||TDQS7_B_T @T6G_MB_LIB.T6G(SCH_1):M_F_CPU0_SB_DQS_DP(7)
 282 M_F_CPU0_SB_DQS_DN<8> DQS8_B_C||TDQS8_B_C @T6G_MB_LIB.T6G(SCH_1):M_F_CPU0_SB_DQS_DN(8)
 283 M_F_CPU0_SB_DQS_DP<8> DQS8_B_T||TDQS8_B_T @T6G_MB_LIB.T6G(SCH_1):M_F_CPU0_SB_DQS_DP(8)
 168 M_F_CPU0_SA_DQS_DP<6> DQS6_A_T||TDQS6_A_T @T6G_MB_LIB.T6G(SCH_1):M_F_CPU0_SA_DQS_DP(6)
 178 M_F_CPU0_SA_DQS_DN<7> DQS7_A_C||TDQS7_A_C @T6G_MB_LIB.T6G(SCH_1):M_F_CPU0_SA_DQS_DN(7)

Q_CAP_C0805-10UF,25V,10%,X6S,CH6104KEA00  I414  C154
   1 P12V_MEM_CPU0      A @T6G_MB_LIB.T6G(SCH_1):P12V_MEM_CPU0
   2    GND      B @T6G_MB_LIB.T6G(SCH_1):GND

Q_CAP_C0805-10UF,25V,10%,X6S,CH6104KEA00  I415  C155
   1 P12V_MEM_CPU0      A @T6G_MB_LIB.T6G(SCH_1):P12V_MEM_CPU0
   2    GND      B @T6G_MB_LIB.T6G(SCH_1):GND

Q_RES_0402LF-49.9,1%,1/16W,CHIP,CS04992FB07  I418  R1573
   1 I3C_SPD_DDRAF_CPU0_SCL      A @T6G_MB_LIB.T6G(SCH_1):I3C_SPD_DDRAF_CPU0_SCL
   2 I3C_SPD_DDRF_CPU0_SCL      B @T6G_MB_LIB.T6G(SCH_1):I3C_SPD_DDRF_CPU0_SCL

Q_RES_0402LF-10,1%,1/16W,CHIP,CS01002FB07  I419  R1679
   1 I3C_SPD_DDRAF_CPU0_SDA      A @T6G_MB_LIB.T6G(SCH_1):I3C_SPD_DDRAF_CPU0_SDA
   2 I3C_SPD_DDRF_CPU0_SDA      B @T6G_MB_LIB.T6G(SCH_1):I3C_SPD_DDRF_CPU0_SDA


DRAWING: @T6G_MB_LIB.T6G(SCH_1):PAGE91 

SCONN288_DDR506112002KQ-SCONN288_DDR506112002KQ,SMA  I22  J16
   3 P3V3_AUX VIN_MGMT @T6G_MB_LIB.T6G(SCH_1):P3V3_AUX
   2     NC   RFU0     NC
 144     NC   RFU1     NC
 149     NC   RFU2     NC
 150     NC   RFU3     NC
 220     NC   RFU4     NC
 231     NC   RFU5     NC
 232     NC   RFU6     NC
 207 M_G_CPU0_RESET_N RESET_N @T6G_MB_LIB.T6G(SCH_1):M_G_CPU0_RESET_N
 147 PWRGD_CHG_CPU0_DIMM0 PWR_GOOD||FAIL_N @T6G_MB_LIB.T6G(SCH_1):PWRGD_CHG_CPU0_DIMM0
 227 M_G_CPU0_SB_PAR  PAR_B @T6G_MB_LIB.T6G(SCH_1):M_G_CPU0_SB_PAR
  74 M_G_CPU0_SA_PAR  PAR_A @T6G_MB_LIB.T6G(SCH_1):M_G_CPU0_SA_PAR
  87 M_G_CPU0_SB_RSP<0> LBS||RSP_B_N @T6G_MB_LIB.T6G(SCH_1):M_G_CPU0_SB_RSP(0)
  86 M_G_CPU0_SA_RSP<0> LBD||RSP_A_N @T6G_MB_LIB.T6G(SCH_1):M_G_CPU0_SA_RSP(0)
   5 I3C_SPD_DDRG_CPU0_SDA   HSDA @T6G_MB_LIB.T6G(SCH_1):I3C_SPD_DDRG_CPU0_SDA
   4 I3C_SPD_DDRG_CPU0_SCL   HSCL @T6G_MB_LIB.T6G(SCH_1):I3C_SPD_DDRG_CPU0_SCL
 148 PD_CHG_CPU0_DIMM0_SAA    HAS @T6G_MB_LIB.T6G(SCH_1):PD_CHG_CPU0_DIMM0_SAA
 100 M_G_CPU0_SB_DQ<0>  DQ0_B @T6G_MB_LIB.T6G(SCH_1):M_G_CPU0_SB_DQ(0)
 102 M_G_CPU0_SB_DQ<1>  DQ1_B @T6G_MB_LIB.T6G(SCH_1):M_G_CPU0_SB_DQ(1)
 245 M_G_CPU0_SB_DQ<2>  DQ2_B @T6G_MB_LIB.T6G(SCH_1):M_G_CPU0_SB_DQ(2)
 247 M_G_CPU0_SB_DQ<3>  DQ3_B @T6G_MB_LIB.T6G(SCH_1):M_G_CPU0_SB_DQ(3)
 107 M_G_CPU0_SB_DQ<4>  DQ4_B @T6G_MB_LIB.T6G(SCH_1):M_G_CPU0_SB_DQ(4)
 109 M_G_CPU0_SB_DQ<5>  DQ5_B @T6G_MB_LIB.T6G(SCH_1):M_G_CPU0_SB_DQ(5)
 252 M_G_CPU0_SB_DQ<6>  DQ6_B @T6G_MB_LIB.T6G(SCH_1):M_G_CPU0_SB_DQ(6)
 254 M_G_CPU0_SB_DQ<7>  DQ7_B @T6G_MB_LIB.T6G(SCH_1):M_G_CPU0_SB_DQ(7)
 111 M_G_CPU0_SB_DQ<8>  DQ8_B @T6G_MB_LIB.T6G(SCH_1):M_G_CPU0_SB_DQ(8)
 113 M_G_CPU0_SB_DQ<9>  DQ9_B @T6G_MB_LIB.T6G(SCH_1):M_G_CPU0_SB_DQ(9)
 256 M_G_CPU0_SB_DQ<10> DQ10_B @T6G_MB_LIB.T6G(SCH_1):M_G_CPU0_SB_DQ(10)
 258 M_G_CPU0_SB_DQ<11> DQ11_B @T6G_MB_LIB.T6G(SCH_1):M_G_CPU0_SB_DQ(11)
 118 M_G_CPU0_SB_DQ<12> DQ12_B @T6G_MB_LIB.T6G(SCH_1):M_G_CPU0_SB_DQ(12)
 120 M_G_CPU0_SB_DQ<13> DQ13_B @T6G_MB_LIB.T6G(SCH_1):M_G_CPU0_SB_DQ(13)
 263 M_G_CPU0_SB_DQ<14> DQ14_B @T6G_MB_LIB.T6G(SCH_1):M_G_CPU0_SB_DQ(14)
 265 M_G_CPU0_SB_DQ<15> DQ15_B @T6G_MB_LIB.T6G(SCH_1):M_G_CPU0_SB_DQ(15)
 122 M_G_CPU0_SB_DQ<16> DQ16_B @T6G_MB_LIB.T6G(SCH_1):M_G_CPU0_SB_DQ(16)
 124 M_G_CPU0_SB_DQ<17> DQ17_B @T6G_MB_LIB.T6G(SCH_1):M_G_CPU0_SB_DQ(17)
 267 M_G_CPU0_SB_DQ<18> DQ18_B @T6G_MB_LIB.T6G(SCH_1):M_G_CPU0_SB_DQ(18)
 269 M_G_CPU0_SB_DQ<19> DQ19_B @T6G_MB_LIB.T6G(SCH_1):M_G_CPU0_SB_DQ(19)
 129 M_G_CPU0_SB_DQ<20> DQ20_B @T6G_MB_LIB.T6G(SCH_1):M_G_CPU0_SB_DQ(20)
 131 M_G_CPU0_SB_DQ<21> DQ21_B @T6G_MB_LIB.T6G(SCH_1):M_G_CPU0_SB_DQ(21)
 274 M_G_CPU0_SB_DQ<22> DQ22_B @T6G_MB_LIB.T6G(SCH_1):M_G_CPU0_SB_DQ(22)
 276 M_G_CPU0_SB_DQ<23> DQ23_B @T6G_MB_LIB.T6G(SCH_1):M_G_CPU0_SB_DQ(23)
 133 M_G_CPU0_SB_DQ<24> DQ24_B @T6G_MB_LIB.T6G(SCH_1):M_G_CPU0_SB_DQ(24)
 135 M_G_CPU0_SB_DQ<25> DQ25_B @T6G_MB_LIB.T6G(SCH_1):M_G_CPU0_SB_DQ(25)
 278 M_G_CPU0_SB_DQ<26> DQ26_B @T6G_MB_LIB.T6G(SCH_1):M_G_CPU0_SB_DQ(26)
 280 M_G_CPU0_SB_DQ<27> DQ27_B @T6G_MB_LIB.T6G(SCH_1):M_G_CPU0_SB_DQ(27)
 140 M_G_CPU0_SB_DQ<28> DQ28_B @T6G_MB_LIB.T6G(SCH_1):M_G_CPU0_SB_DQ(28)
 142 M_G_CPU0_SB_DQ<29> DQ29_B @T6G_MB_LIB.T6G(SCH_1):M_G_CPU0_SB_DQ(29)
 285 M_G_CPU0_SB_DQ<30> DQ30_B @T6G_MB_LIB.T6G(SCH_1):M_G_CPU0_SB_DQ(30)
 287 M_G_CPU0_SB_DQ<31> DQ31_B @T6G_MB_LIB.T6G(SCH_1):M_G_CPU0_SB_DQ(31)
   7 M_G_CPU0_SA_DQ<0>  DQ0_A @T6G_MB_LIB.T6G(SCH_1):M_G_CPU0_SA_DQ(0)
   9 M_G_CPU0_SA_DQ<1>  DQ1_A @T6G_MB_LIB.T6G(SCH_1):M_G_CPU0_SA_DQ(1)
 152 M_G_CPU0_SA_DQ<2>  DQ2_A @T6G_MB_LIB.T6G(SCH_1):M_G_CPU0_SA_DQ(2)
 154 M_G_CPU0_SA_DQ<3>  DQ3_A @T6G_MB_LIB.T6G(SCH_1):M_G_CPU0_SA_DQ(3)
  14 M_G_CPU0_SA_DQ<4>  DQ4_A @T6G_MB_LIB.T6G(SCH_1):M_G_CPU0_SA_DQ(4)
  16 M_G_CPU0_SA_DQ<5>  DQ5_A @T6G_MB_LIB.T6G(SCH_1):M_G_CPU0_SA_DQ(5)
 159 M_G_CPU0_SA_DQ<6>  DQ6_A @T6G_MB_LIB.T6G(SCH_1):M_G_CPU0_SA_DQ(6)
 161 M_G_CPU0_SA_DQ<7>  DQ7_A @T6G_MB_LIB.T6G(SCH_1):M_G_CPU0_SA_DQ(7)
  18 M_G_CPU0_SA_DQ<8>  DQ8_A @T6G_MB_LIB.T6G(SCH_1):M_G_CPU0_SA_DQ(8)
  20 M_G_CPU0_SA_DQ<9>  DQ9_A @T6G_MB_LIB.T6G(SCH_1):M_G_CPU0_SA_DQ(9)
 163 M_G_CPU0_SA_DQ<10> DQ10_A @T6G_MB_LIB.T6G(SCH_1):M_G_CPU0_SA_DQ(10)
 165 M_G_CPU0_SA_DQ<11> DQ11_A @T6G_MB_LIB.T6G(SCH_1):M_G_CPU0_SA_DQ(11)
  25 M_G_CPU0_SA_DQ<12> DQ12_A @T6G_MB_LIB.T6G(SCH_1):M_G_CPU0_SA_DQ(12)
  27 M_G_CPU0_SA_DQ<13> DQ13_A @T6G_MB_LIB.T6G(SCH_1):M_G_CPU0_SA_DQ(13)
 170 M_G_CPU0_SA_DQ<14> DQ14_A @T6G_MB_LIB.T6G(SCH_1):M_G_CPU0_SA_DQ(14)
 172 M_G_CPU0_SA_DQ<15> DQ15_A @T6G_MB_LIB.T6G(SCH_1):M_G_CPU0_SA_DQ(15)
  29 M_G_CPU0_SA_DQ<16> DQ16_A @T6G_MB_LIB.T6G(SCH_1):M_G_CPU0_SA_DQ(16)
  31 M_G_CPU0_SA_DQ<17> DQ17_A @T6G_MB_LIB.T6G(SCH_1):M_G_CPU0_SA_DQ(17)
 174 M_G_CPU0_SA_DQ<18> DQ18_A @T6G_MB_LIB.T6G(SCH_1):M_G_CPU0_SA_DQ(18)
 176 M_G_CPU0_SA_DQ<19> DQ19_A @T6G_MB_LIB.T6G(SCH_1):M_G_CPU0_SA_DQ(19)
  36 M_G_CPU0_SA_DQ<20> DQ20_A @T6G_MB_LIB.T6G(SCH_1):M_G_CPU0_SA_DQ(20)
  38 M_G_CPU0_SA_DQ<21> DQ21_A @T6G_MB_LIB.T6G(SCH_1):M_G_CPU0_SA_DQ(21)
 181 M_G_CPU0_SA_DQ<22> DQ22_A @T6G_MB_LIB.T6G(SCH_1):M_G_CPU0_SA_DQ(22)
 183 M_G_CPU0_SA_DQ<23> DQ23_A @T6G_MB_LIB.T6G(SCH_1):M_G_CPU0_SA_DQ(23)
  40 M_G_CPU0_SA_DQ<24> DQ24_A @T6G_MB_LIB.T6G(SCH_1):M_G_CPU0_SA_DQ(24)
  42 M_G_CPU0_SA_DQ<25> DQ25_A @T6G_MB_LIB.T6G(SCH_1):M_G_CPU0_SA_DQ(25)
 185 M_G_CPU0_SA_DQ<26> DQ26_A @T6G_MB_LIB.T6G(SCH_1):M_G_CPU0_SA_DQ(26)
 187 M_G_CPU0_SA_DQ<27> DQ27_A @T6G_MB_LIB.T6G(SCH_1):M_G_CPU0_SA_DQ(27)
  47 M_G_CPU0_SA_DQ<28> DQ28_A @T6G_MB_LIB.T6G(SCH_1):M_G_CPU0_SA_DQ(28)
  49 M_G_CPU0_SA_DQ<29> DQ29_A @T6G_MB_LIB.T6G(SCH_1):M_G_CPU0_SA_DQ(29)
 192 M_G_CPU0_SA_DQ<30> DQ30_A @T6G_MB_LIB.T6G(SCH_1):M_G_CPU0_SA_DQ(30)
 229 M_G_CPU0_SB_CS_N<1> CS1_B_N @T6G_MB_LIB.T6G(SCH_1):M_G_CPU0_SB_CS_N(1)
 209 M_G_CPU0_SA_CS_N<1> CS1_A_N @T6G_MB_LIB.T6G(SCH_1):M_G_CPU0_SA_CS_N(1)
  84 M_G_CPU0_SB_CS_N<0> CS0_B_N @T6G_MB_LIB.T6G(SCH_1):M_G_CPU0_SB_CS_N(0)
  64 M_G_CPU0_SA_CS_N<0> CS0_A_N @T6G_MB_LIB.T6G(SCH_1):M_G_CPU0_SA_CS_N(0)
 217 M_G_CPU0_CLK_DP<0>   CK_T @T6G_MB_LIB.T6G(SCH_1):M_G_CPU0_CLK_DP(0)
 218 M_G_CPU0_CLK_DN<0>   CK_C @T6G_MB_LIB.T6G(SCH_1):M_G_CPU0_CLK_DN(0)
  96 M_G_CPU0_SB_CB<0>  CB0_B @T6G_MB_LIB.T6G(SCH_1):M_G_CPU0_SB_CB(0)
  98 M_G_CPU0_SB_CB<1>  CB1_B @T6G_MB_LIB.T6G(SCH_1):M_G_CPU0_SB_CB(1)
 241 M_G_CPU0_SB_CB<2>  CB2_B @T6G_MB_LIB.T6G(SCH_1):M_G_CPU0_SB_CB(2)
 243 M_G_CPU0_SB_CB<3>  CB3_B @T6G_MB_LIB.T6G(SCH_1):M_G_CPU0_SB_CB(3)
  89 M_G_CPU0_SB_CB<4>  CB4_B @T6G_MB_LIB.T6G(SCH_1):M_G_CPU0_SB_CB(4)
  91 M_G_CPU0_SB_CB<5>  CB5_B @T6G_MB_LIB.T6G(SCH_1):M_G_CPU0_SB_CB(5)
 234 M_G_CPU0_SB_CB<6>  CB6_B @T6G_MB_LIB.T6G(SCH_1):M_G_CPU0_SB_CB(6)
  51 M_G_CPU0_SA_CB<0>  CB0_A @T6G_MB_LIB.T6G(SCH_1):M_G_CPU0_SA_CB(0)
 196 M_G_CPU0_SA_CB<2>  CB2_A @T6G_MB_LIB.T6G(SCH_1):M_G_CPU0_SA_CB(2)
 198 M_G_CPU0_SA_CB<3>  CB3_A @T6G_MB_LIB.T6G(SCH_1):M_G_CPU0_SA_CB(3)
  60 M_G_CPU0_SA_CB<5>  CB5_A @T6G_MB_LIB.T6G(SCH_1):M_G_CPU0_SA_CB(5)
 203 M_G_CPU0_SA_CB<6>  CB6_A @T6G_MB_LIB.T6G(SCH_1):M_G_CPU0_SA_CB(6)
  82 M_G_CPU0_SB_CA<6>  CA6_B @T6G_MB_LIB.T6G(SCH_1):M_G_CPU0_SB_CA(6)
  72 M_G_CPU0_SA_CA<6>  CA6_A @T6G_MB_LIB.T6G(SCH_1):M_G_CPU0_SA_CA(6)
 225 M_G_CPU0_SB_CA<5>  CA5_B @T6G_MB_LIB.T6G(SCH_1):M_G_CPU0_SB_CA(5)
 215 M_G_CPU0_SA_CA<5>  CA5_A @T6G_MB_LIB.T6G(SCH_1):M_G_CPU0_SA_CA(5)
  80 M_G_CPU0_SB_CA<4>  CA4_B @T6G_MB_LIB.T6G(SCH_1):M_G_CPU0_SB_CA(4)
  70 M_G_CPU0_SA_CA<4>  CA4_A @T6G_MB_LIB.T6G(SCH_1):M_G_CPU0_SA_CA(4)
 223 M_G_CPU0_SB_CA<3>  CA3_B @T6G_MB_LIB.T6G(SCH_1):M_G_CPU0_SB_CA(3)
 213 M_G_CPU0_SA_CA<3>  CA3_A @T6G_MB_LIB.T6G(SCH_1):M_G_CPU0_SA_CA(3)
  78 M_G_CPU0_SB_CA<2>  CA2_B @T6G_MB_LIB.T6G(SCH_1):M_G_CPU0_SB_CA(2)
  68 M_G_CPU0_SA_CA<2>  CA2_A @T6G_MB_LIB.T6G(SCH_1):M_G_CPU0_SA_CA(2)
 221 M_G_CPU0_SB_CA<1>  CA1_B @T6G_MB_LIB.T6G(SCH_1):M_G_CPU0_SB_CA(1)
 211 M_G_CPU0_SA_CA<1>  CA1_A @T6G_MB_LIB.T6G(SCH_1):M_G_CPU0_SA_CA(1)
  76 M_G_CPU0_SB_CA<0>  CA0_B @T6G_MB_LIB.T6G(SCH_1):M_G_CPU0_SB_CA(0)
  66 M_G_CPU0_SA_CA<0>  CA0_A @T6G_MB_LIB.T6G(SCH_1):M_G_CPU0_SA_CA(0)
  62 M_G_CPU0_ALERT_N ALERT_N @T6G_MB_LIB.T6G(SCH_1):M_G_CPU0_ALERT_N
 236 M_G_CPU0_SB_CB<7>  CB7_B @T6G_MB_LIB.T6G(SCH_1):M_G_CPU0_SB_CB(7)
  53 M_G_CPU0_SA_CB<1>  CB1_A @T6G_MB_LIB.T6G(SCH_1):M_G_CPU0_SA_CB(1)
  58 M_G_CPU0_SA_CB<4>  CB4_A @T6G_MB_LIB.T6G(SCH_1):M_G_CPU0_SA_CB(4)
 205 M_G_CPU0_SA_CB<7>  CB7_A @T6G_MB_LIB.T6G(SCH_1):M_G_CPU0_SA_CB(7)
 194 M_G_CPU0_SA_DQ<31> DQ31_A @T6G_MB_LIB.T6G(SCH_1):M_G_CPU0_SA_DQ(31)

Q_RES_0402LF-10K,1%,1/16W,CHIP,CS31002FB08  I129  R35
   1 PD_CHG_CPU0_DIMM0_SAA      A @T6G_MB_LIB.T6G(SCH_1):PD_CHG_CPU0_DIMM0_SAA
   2    GND      B @T6G_MB_LIB.T6G(SCH_1):GND

SCONN288_DDR506112002KQ-SCONN288_DDR506112002KQ,SMA  I177  J16
   6    GND   VSS0 @T6G_MB_LIB.T6G(SCH_1):GND
   8    GND   VSS1 @T6G_MB_LIB.T6G(SCH_1):GND
  10    GND   VSS2 @T6G_MB_LIB.T6G(SCH_1):GND
  13    GND   VSS3 @T6G_MB_LIB.T6G(SCH_1):GND
  15    GND   VSS4 @T6G_MB_LIB.T6G(SCH_1):GND
  17    GND   VSS5 @T6G_MB_LIB.T6G(SCH_1):GND
  19    GND   VSS6 @T6G_MB_LIB.T6G(SCH_1):GND
  21    GND   VSS7 @T6G_MB_LIB.T6G(SCH_1):GND
  24    GND   VSS8 @T6G_MB_LIB.T6G(SCH_1):GND
  26    GND   VSS9 @T6G_MB_LIB.T6G(SCH_1):GND
  28    GND  VSS10 @T6G_MB_LIB.T6G(SCH_1):GND
  30    GND  VSS11 @T6G_MB_LIB.T6G(SCH_1):GND
  32    GND  VSS12 @T6G_MB_LIB.T6G(SCH_1):GND
  35    GND  VSS13 @T6G_MB_LIB.T6G(SCH_1):GND
  37    GND  VSS14 @T6G_MB_LIB.T6G(SCH_1):GND
  39    GND  VSS15 @T6G_MB_LIB.T6G(SCH_1):GND
  41    GND  VSS16 @T6G_MB_LIB.T6G(SCH_1):GND
  43    GND  VSS17 @T6G_MB_LIB.T6G(SCH_1):GND
  46    GND  VSS18 @T6G_MB_LIB.T6G(SCH_1):GND
  48    GND  VSS19 @T6G_MB_LIB.T6G(SCH_1):GND
  50    GND  VSS20 @T6G_MB_LIB.T6G(SCH_1):GND
  52    GND  VSS21 @T6G_MB_LIB.T6G(SCH_1):GND
  54    GND  VSS22 @T6G_MB_LIB.T6G(SCH_1):GND
  57    GND  VSS23 @T6G_MB_LIB.T6G(SCH_1):GND
  59    GND  VSS24 @T6G_MB_LIB.T6G(SCH_1):GND
  61    GND  VSS25 @T6G_MB_LIB.T6G(SCH_1):GND
  63    GND  VSS26 @T6G_MB_LIB.T6G(SCH_1):GND
  65    GND  VSS27 @T6G_MB_LIB.T6G(SCH_1):GND
  67    GND  VSS28 @T6G_MB_LIB.T6G(SCH_1):GND
  69    GND  VSS29 @T6G_MB_LIB.T6G(SCH_1):GND
  71    GND  VSS30 @T6G_MB_LIB.T6G(SCH_1):GND
  73    GND  VSS31 @T6G_MB_LIB.T6G(SCH_1):GND
  75    GND  VSS32 @T6G_MB_LIB.T6G(SCH_1):GND
  77    GND  VSS33 @T6G_MB_LIB.T6G(SCH_1):GND
  79    GND  VSS34 @T6G_MB_LIB.T6G(SCH_1):GND
  81    GND  VSS35 @T6G_MB_LIB.T6G(SCH_1):GND
  83    GND  VSS36 @T6G_MB_LIB.T6G(SCH_1):GND
  85    GND  VSS37 @T6G_MB_LIB.T6G(SCH_1):GND
  88    GND  VSS38 @T6G_MB_LIB.T6G(SCH_1):GND
  90    GND  VSS39 @T6G_MB_LIB.T6G(SCH_1):GND
  92    GND  VSS40 @T6G_MB_LIB.T6G(SCH_1):GND
  95    GND  VSS41 @T6G_MB_LIB.T6G(SCH_1):GND
  97    GND  VSS42 @T6G_MB_LIB.T6G(SCH_1):GND
  99    GND  VSS43 @T6G_MB_LIB.T6G(SCH_1):GND
 101    GND  VSS44 @T6G_MB_LIB.T6G(SCH_1):GND
 103    GND  VSS45 @T6G_MB_LIB.T6G(SCH_1):GND
 106    GND  VSS46 @T6G_MB_LIB.T6G(SCH_1):GND
 108    GND  VSS47 @T6G_MB_LIB.T6G(SCH_1):GND
 110    GND  VSS48 @T6G_MB_LIB.T6G(SCH_1):GND
 112    GND  VSS49 @T6G_MB_LIB.T6G(SCH_1):GND
 114    GND  VSS50 @T6G_MB_LIB.T6G(SCH_1):GND
 117    GND  VSS51 @T6G_MB_LIB.T6G(SCH_1):GND
 119    GND  VSS52 @T6G_MB_LIB.T6G(SCH_1):GND
 121    GND  VSS53 @T6G_MB_LIB.T6G(SCH_1):GND
 123    GND  VSS54 @T6G_MB_LIB.T6G(SCH_1):GND
 125    GND  VSS55 @T6G_MB_LIB.T6G(SCH_1):GND
 128    GND  VSS56 @T6G_MB_LIB.T6G(SCH_1):GND
 130    GND  VSS57 @T6G_MB_LIB.T6G(SCH_1):GND
 134    GND  VSS59 @T6G_MB_LIB.T6G(SCH_1):GND
 143    GND  VSS63 @T6G_MB_LIB.T6G(SCH_1):GND
 151    GND  VSS64 @T6G_MB_LIB.T6G(SCH_1):GND
 153    GND  VSS65 @T6G_MB_LIB.T6G(SCH_1):GND
 155    GND  VSS66 @T6G_MB_LIB.T6G(SCH_1):GND
 158    GND  VSS67 @T6G_MB_LIB.T6G(SCH_1):GND
 160    GND  VSS68 @T6G_MB_LIB.T6G(SCH_1):GND
 162    GND  VSS69 @T6G_MB_LIB.T6G(SCH_1):GND
 164    GND  VSS70 @T6G_MB_LIB.T6G(SCH_1):GND
 166    GND  VSS71 @T6G_MB_LIB.T6G(SCH_1):GND
 169    GND  VSS72 @T6G_MB_LIB.T6G(SCH_1):GND
 171    GND  VSS73 @T6G_MB_LIB.T6G(SCH_1):GND
 173    GND  VSS74 @T6G_MB_LIB.T6G(SCH_1):GND
 175    GND  VSS75 @T6G_MB_LIB.T6G(SCH_1):GND
 177    GND  VSS76 @T6G_MB_LIB.T6G(SCH_1):GND
 180    GND  VSS77 @T6G_MB_LIB.T6G(SCH_1):GND
 182    GND  VSS78 @T6G_MB_LIB.T6G(SCH_1):GND
 184    GND  VSS79 @T6G_MB_LIB.T6G(SCH_1):GND
 186    GND  VSS80 @T6G_MB_LIB.T6G(SCH_1):GND
 188    GND  VSS81 @T6G_MB_LIB.T6G(SCH_1):GND
 191    GND  VSS82 @T6G_MB_LIB.T6G(SCH_1):GND
 193    GND  VSS83 @T6G_MB_LIB.T6G(SCH_1):GND
 195    GND  VSS84 @T6G_MB_LIB.T6G(SCH_1):GND
 197    GND  VSS85 @T6G_MB_LIB.T6G(SCH_1):GND
 199    GND  VSS86 @T6G_MB_LIB.T6G(SCH_1):GND
 202    GND  VSS87 @T6G_MB_LIB.T6G(SCH_1):GND
 204    GND  VSS88 @T6G_MB_LIB.T6G(SCH_1):GND
 206    GND  VSS89 @T6G_MB_LIB.T6G(SCH_1):GND
 208    GND  VSS90 @T6G_MB_LIB.T6G(SCH_1):GND
 210    GND  VSS91 @T6G_MB_LIB.T6G(SCH_1):GND
 212    GND  VSS92 @T6G_MB_LIB.T6G(SCH_1):GND
 214    GND  VSS93 @T6G_MB_LIB.T6G(SCH_1):GND
 216    GND  VSS94 @T6G_MB_LIB.T6G(SCH_1):GND
 219    GND  VSS95 @T6G_MB_LIB.T6G(SCH_1):GND
 222    GND  VSS96 @T6G_MB_LIB.T6G(SCH_1):GND
 224    GND  VSS97 @T6G_MB_LIB.T6G(SCH_1):GND
 226    GND  VSS98 @T6G_MB_LIB.T6G(SCH_1):GND
 228    GND  VSS99 @T6G_MB_LIB.T6G(SCH_1):GND
 233    GND VSS101 @T6G_MB_LIB.T6G(SCH_1):GND
 237    GND VSS103 @T6G_MB_LIB.T6G(SCH_1):GND
 242    GND VSS105 @T6G_MB_LIB.T6G(SCH_1):GND
 244    GND VSS106 @T6G_MB_LIB.T6G(SCH_1):GND
 246    GND VSS107 @T6G_MB_LIB.T6G(SCH_1):GND
 248    GND VSS108 @T6G_MB_LIB.T6G(SCH_1):GND
 251    GND VSS109 @T6G_MB_LIB.T6G(SCH_1):GND
 253    GND VSS110 @T6G_MB_LIB.T6G(SCH_1):GND
 255    GND VSS111 @T6G_MB_LIB.T6G(SCH_1):GND
 257    GND VSS112 @T6G_MB_LIB.T6G(SCH_1):GND
 259    GND VSS113 @T6G_MB_LIB.T6G(SCH_1):GND
 262    GND VSS114 @T6G_MB_LIB.T6G(SCH_1):GND
 264    GND VSS115 @T6G_MB_LIB.T6G(SCH_1):GND
 266    GND VSS116 @T6G_MB_LIB.T6G(SCH_1):GND
 268    GND VSS117 @T6G_MB_LIB.T6G(SCH_1):GND
 270    GND VSS118 @T6G_MB_LIB.T6G(SCH_1):GND
 273    GND VSS119 @T6G_MB_LIB.T6G(SCH_1):GND
 275    GND VSS120 @T6G_MB_LIB.T6G(SCH_1):GND
 277    GND VSS121 @T6G_MB_LIB.T6G(SCH_1):GND
 279    GND VSS122 @T6G_MB_LIB.T6G(SCH_1):GND
 281    GND VSS123 @T6G_MB_LIB.T6G(SCH_1):GND
 284    GND VSS124 @T6G_MB_LIB.T6G(SCH_1):GND
 286    GND VSS125 @T6G_MB_LIB.T6G(SCH_1):GND
 288    GND VSS126 @T6G_MB_LIB.T6G(SCH_1):GND
   1 P12V_MEM_CPU0 VIN_BULK0 @T6G_MB_LIB.T6G(SCH_1):P12V_MEM_CPU0
 145 P12V_MEM_CPU0 VIN_BULK1 @T6G_MB_LIB.T6G(SCH_1):P12V_MEM_CPU0
 146 P12V_MEM_CPU0 VIN_BULK2 @T6G_MB_LIB.T6G(SCH_1):P12V_MEM_CPU0
 230    GND VSS100 @T6G_MB_LIB.T6G(SCH_1):GND
 235    GND VSS102 @T6G_MB_LIB.T6G(SCH_1):GND
 240    GND VSS104 @T6G_MB_LIB.T6G(SCH_1):GND
 132    GND  VSS58 @T6G_MB_LIB.T6G(SCH_1):GND
 136    GND  VSS60 @T6G_MB_LIB.T6G(SCH_1):GND
 139    GND  VSS61 @T6G_MB_LIB.T6G(SCH_1):GND
 141    GND  VSS62 @T6G_MB_LIB.T6G(SCH_1):GND
  G1    GND     G1 @T6G_MB_LIB.T6G(SCH_1):GND
  G2    GND     G2 @T6G_MB_LIB.T6G(SCH_1):GND
  G3    GND     G3 @T6G_MB_LIB.T6G(SCH_1):GND

Q_CAP_0402-0.1UF,25V,10%,X7R,CH4104K1B00  I183  C112
   1 P3V3_AUX      A @T6G_MB_LIB.T6G(SCH_1):P3V3_AUX
   2    GND      B @T6G_MB_LIB.T6G(SCH_1):GND

Q_RES_0402LF-1K,1%,1/16W,CHIP,CS21002FB06  I186  R297
   1 PWRGD_CHG_CPU0_DIMM0      A @T6G_MB_LIB.T6G(SCH_1):PWRGD_CHG_CPU0_DIMM0
   2 PWRGD_CHGL_CPU0      B @T6G_MB_LIB.T6G(SCH_1):PWRGD_CHGL_CPU0

Q_RES_0402LF-1K,1%,1/16W,EMPTY,CS21002FB06  I187  R96
   1   P3V3      A @T6G_MB_LIB.T6G(SCH_1):P3V3
   2 PWRGD_CHG_CPU0_DIMM0      B @T6G_MB_LIB.T6G(SCH_1):PWRGD_CHG_CPU0_DIMM0

Q_RES_0402LF-1K,1%,1/16W,EMPTY,CS21002FB06  I190  R95
   1   P3V3      A @T6G_MB_LIB.T6G(SCH_1):P3V3
   2 PWRGD_CHGL_CPU0      B @T6G_MB_LIB.T6G(SCH_1):PWRGD_CHGL_CPU0

SCONN288_DDR506112002KQ-SCONN288_DDR506112002KQ,SMA  I236  J16
  93 M_G_CPU0_SB_DQS_DP<9> DQS9_B_T||TDQS9_B_T||DBI4_B_N @T6G_MB_LIB.T6G(SCH_1):M_G_CPU0_SB_DQS_DP(9)
  94 M_G_CPU0_SB_DQS_DN<9> DQS9_B_C||TDQS9_B_C @T6G_MB_LIB.T6G(SCH_1):M_G_CPU0_SB_DQS_DN(9)
 201 M_G_CPU0_SA_DQS_DP<9> DQS9_A_T||TDQS9_A_T @T6G_MB_LIB.T6G(SCH_1):M_G_CPU0_SA_DQS_DP(9)
 200 M_G_CPU0_SA_DQS_DN<9> DQS9_A_C||TDQS9_A_C @T6G_MB_LIB.T6G(SCH_1):M_G_CPU0_SA_DQS_DN(9)
 190 M_G_CPU0_SA_DQS_DP<8> DQS8_A_T||TDQS8_A_T @T6G_MB_LIB.T6G(SCH_1):M_G_CPU0_SA_DQS_DP(8)
 189 M_G_CPU0_SA_DQS_DN<8> DQS8_A_C||TDQS8_A_C @T6G_MB_LIB.T6G(SCH_1):M_G_CPU0_SA_DQS_DN(8)
 271 M_G_CPU0_SB_DQS_DN<7> DQS7_B_C||TDQS7_B_C @T6G_MB_LIB.T6G(SCH_1):M_G_CPU0_SB_DQS_DN(7)
 179 M_G_CPU0_SA_DQS_DP<7> DQS7_A_T||TDQS7_A_T @T6G_MB_LIB.T6G(SCH_1):M_G_CPU0_SA_DQS_DP(7)
 261 M_G_CPU0_SB_DQS_DP<6> DQS6_B_T||TDQS6_B_T @T6G_MB_LIB.T6G(SCH_1):M_G_CPU0_SB_DQS_DP(6)
 260 M_G_CPU0_SB_DQS_DN<6> DQS6_B_C||TDQS6_B_C @T6G_MB_LIB.T6G(SCH_1):M_G_CPU0_SB_DQS_DN(6)
 167 M_G_CPU0_SA_DQS_DN<6> DQS6_A_C||TDQS6_A_C||DQS6_A_T||TDQS6_A_T @T6G_MB_LIB.T6G(SCH_1):M_G_CPU0_SA_DQS_DN(6)
 250 M_G_CPU0_SB_DQS_DP<5> DQS5_B_T||TDQS5_B_T @T6G_MB_LIB.T6G(SCH_1):M_G_CPU0_SB_DQS_DP(5)
 249 M_G_CPU0_SB_DQS_DN<5> DQS5_B_C||TDQS5_B_C @T6G_MB_LIB.T6G(SCH_1):M_G_CPU0_SB_DQS_DN(5)
 157 M_G_CPU0_SA_DQS_DP<5> DQS5_A_T||TDQS5_A_T @T6G_MB_LIB.T6G(SCH_1):M_G_CPU0_SA_DQS_DP(5)
 156 M_G_CPU0_SA_DQS_DN<5> DQS5_A_C||TDQS5_A_C||DQS5_A_T||TDQS5_A_T @T6G_MB_LIB.T6G(SCH_1):M_G_CPU0_SA_DQS_DN(5)
 239 M_G_CPU0_SB_DQS_DP<4> DQS4_B_T @T6G_MB_LIB.T6G(SCH_1):M_G_CPU0_SB_DQS_DP(4)
 238 M_G_CPU0_SB_DQS_DN<4> DQS4_B_C @T6G_MB_LIB.T6G(SCH_1):M_G_CPU0_SB_DQS_DN(4)
  55 M_G_CPU0_SA_DQS_DP<4> DQS4_A_T @T6G_MB_LIB.T6G(SCH_1):M_G_CPU0_SA_DQS_DP(4)
  56 M_G_CPU0_SA_DQS_DN<4> DQS4_A_C @T6G_MB_LIB.T6G(SCH_1):M_G_CPU0_SA_DQS_DN(4)
 137 M_G_CPU0_SB_DQS_DP<3> DQS3_B_T @T6G_MB_LIB.T6G(SCH_1):M_G_CPU0_SB_DQS_DP(3)
 138 M_G_CPU0_SB_DQS_DN<3> DQS3_B_C @T6G_MB_LIB.T6G(SCH_1):M_G_CPU0_SB_DQS_DN(3)
  44 M_G_CPU0_SA_DQS_DP<3> DQS3_A_T @T6G_MB_LIB.T6G(SCH_1):M_G_CPU0_SA_DQS_DP(3)
  45 M_G_CPU0_SA_DQS_DN<3> DQS3_A_C @T6G_MB_LIB.T6G(SCH_1):M_G_CPU0_SA_DQS_DN(3)
 126 M_G_CPU0_SB_DQS_DP<2> DQS2_B_T @T6G_MB_LIB.T6G(SCH_1):M_G_CPU0_SB_DQS_DP(2)
 127 M_G_CPU0_SB_DQS_DN<2> DQS2_B_C @T6G_MB_LIB.T6G(SCH_1):M_G_CPU0_SB_DQS_DN(2)
  33 M_G_CPU0_SA_DQS_DP<2> DQS2_A_T @T6G_MB_LIB.T6G(SCH_1):M_G_CPU0_SA_DQS_DP(2)
  34 M_G_CPU0_SA_DQS_DN<2> DQS2_A_C @T6G_MB_LIB.T6G(SCH_1):M_G_CPU0_SA_DQS_DN(2)
 115 M_G_CPU0_SB_DQS_DP<1> DQS1_B_T @T6G_MB_LIB.T6G(SCH_1):M_G_CPU0_SB_DQS_DP(1)
 116 M_G_CPU0_SB_DQS_DN<1> DQS1_B_C @T6G_MB_LIB.T6G(SCH_1):M_G_CPU0_SB_DQS_DN(1)
  22 M_G_CPU0_SA_DQS_DP<1> DQS1_A_T @T6G_MB_LIB.T6G(SCH_1):M_G_CPU0_SA_DQS_DP(1)
  23 M_G_CPU0_SA_DQS_DN<1> DQS1_A_C @T6G_MB_LIB.T6G(SCH_1):M_G_CPU0_SA_DQS_DN(1)
 104 M_G_CPU0_SB_DQS_DP<0> DQS0_B_T @T6G_MB_LIB.T6G(SCH_1):M_G_CPU0_SB_DQS_DP(0)
 105 M_G_CPU0_SB_DQS_DN<0> DQS0_B_C @T6G_MB_LIB.T6G(SCH_1):M_G_CPU0_SB_DQS_DN(0)
  11 M_G_CPU0_SA_DQS_DP<0> DQS0_A_T @T6G_MB_LIB.T6G(SCH_1):M_G_CPU0_SA_DQS_DP(0)
  12 M_G_CPU0_SA_DQS_DN<0> DQS0_A_C @T6G_MB_LIB.T6G(SCH_1):M_G_CPU0_SA_DQS_DN(0)
 272 M_G_CPU0_SB_DQS_DP<7> DQS7_B_T||TDQS7_B_T @T6G_MB_LIB.T6G(SCH_1):M_G_CPU0_SB_DQS_DP(7)
 282 M_G_CPU0_SB_DQS_DN<8> DQS8_B_C||TDQS8_B_C @T6G_MB_LIB.T6G(SCH_1):M_G_CPU0_SB_DQS_DN(8)
 283 M_G_CPU0_SB_DQS_DP<8> DQS8_B_T||TDQS8_B_T @T6G_MB_LIB.T6G(SCH_1):M_G_CPU0_SB_DQS_DP(8)
 168 M_G_CPU0_SA_DQS_DP<6> DQS6_A_T||TDQS6_A_T @T6G_MB_LIB.T6G(SCH_1):M_G_CPU0_SA_DQS_DP(6)
 178 M_G_CPU0_SA_DQS_DN<7> DQS7_A_C||TDQS7_A_C @T6G_MB_LIB.T6G(SCH_1):M_G_CPU0_SA_DQS_DN(7)

Q_CAP_C0805-10UF,25V,10%,X6S,CH6104KEA00  I238  C157
   1 P12V_MEM_CPU0      A @T6G_MB_LIB.T6G(SCH_1):P12V_MEM_CPU0
   2    GND      B @T6G_MB_LIB.T6G(SCH_1):GND

Q_CAP_C0805-10UF,25V,10%,X6S,CH6104KEA00  I239  C158
   1 P12V_MEM_CPU0      A @T6G_MB_LIB.T6G(SCH_1):P12V_MEM_CPU0
   2    GND      B @T6G_MB_LIB.T6G(SCH_1):GND

Q_RES_0402LF-49.9,1%,1/16W,CHIP,CS04992FB07  I242  R1574
   1 I3C_SPD_DDRGL_CPU0_SCL      A @T6G_MB_LIB.T6G(SCH_1):I3C_SPD_DDRGL_CPU0_SCL
   2 I3C_SPD_DDRG_CPU0_SCL      B @T6G_MB_LIB.T6G(SCH_1):I3C_SPD_DDRG_CPU0_SCL

Q_RES_0402LF-10K,1%,1/16W,CHIP,CS31002FB08  I243  R8038
   1 P3V3_AUX      A @T6G_MB_LIB.T6G(SCH_1):P3V3_AUX
   2 PWRGD_CHGL_CPU0      B @T6G_MB_LIB.T6G(SCH_1):PWRGD_CHGL_CPU0

Q_RES_0402LF-0,5%,1/16W,CHIP,CS00002JB13  I248  R8083
   1 PWRGD_CHGL_CPU0      A @T6G_MB_LIB.T6G(SCH_1):PWRGD_CHGL_CPU0
   2 PWRGD_CHGL_CPU0_R1      B @T6G_MB_LIB.T6G(SCH_1):PWRGD_CHGL_CPU0_R1

Q_RES_0402LF-10K,1%,1/16W,EMPTY,CS31002FB08  I249  R8085
   1 P3V3_AUX      A @T6G_MB_LIB.T6G(SCH_1):P3V3_AUX
   2 PWRGD_CHGL_CPU0_R1      B @T6G_MB_LIB.T6G(SCH_1):PWRGD_CHGL_CPU0_R1

Q_RES_0402LF-0,5%,1/16W,CHIP,CS00002JB13  I250  R8084
   1 PWRGD_CHGL_CPU0_R1      A @T6G_MB_LIB.T6G(SCH_1):PWRGD_CHGL_CPU0_R1
   2 PWRGD_CHGL_CPU0_R2      B @T6G_MB_LIB.T6G(SCH_1):PWRGD_CHGL_CPU0_R2

SCHOTTKY_12-B0530WS7F,SMLF,EMPTY,BC000530Z41  I251  D8004
   1 PWRGD_CHGL_CPU0_R1      A @T6G_MB_LIB.T6G(SCH_1):PWRGD_CHGL_CPU0_R1
   2 P3V3_AUX      C @T6G_MB_LIB.T6G(SCH_1):P3V3_AUX

Q_RES_0402LF-10,1%,1/16W,CHIP,CS01002FB07  I254  R1680
   1 I3C_SPD_DDRGL_CPU0_SDA      A @T6G_MB_LIB.T6G(SCH_1):I3C_SPD_DDRGL_CPU0_SDA
   2 I3C_SPD_DDRG_CPU0_SDA      B @T6G_MB_LIB.T6G(SCH_1):I3C_SPD_DDRG_CPU0_SDA


DRAWING: @T6G_MB_LIB.T6G(SCH_1):PAGE92 

SCONN288_DDR506112002KQ-SCONN288_DDR506112002KQ,SMA  I22  J69
   3 P3V3_AUX VIN_MGMT @T6G_MB_LIB.T6G(SCH_1):P3V3_AUX
   2     NC   RFU0     NC
 144     NC   RFU1     NC
 149     NC   RFU2     NC
 150     NC   RFU3     NC
 220     NC   RFU4     NC
 231     NC   RFU5     NC
 232     NC   RFU6     NC
 207 M_H_CPU0_RESET_N RESET_N @T6G_MB_LIB.T6G(SCH_1):M_H_CPU0_RESET_N
 147 PWRGD_CHH_CPU0_DIMM PWR_GOOD||FAIL_N @T6G_MB_LIB.T6G(SCH_1):PWRGD_CHH_CPU0_DIMM
 227 M_H_CPU0_SB_PAR  PAR_B @T6G_MB_LIB.T6G(SCH_1):M_H_CPU0_SB_PAR
  74 M_H_CPU0_SA_PAR  PAR_A @T6G_MB_LIB.T6G(SCH_1):M_H_CPU0_SA_PAR
  87 M_H_CPU0_SB_RSP<0> LBS||RSP_B_N @T6G_MB_LIB.T6G(SCH_1):M_H_CPU0_SB_RSP(0)
  86 M_H_CPU0_SA_RSP<0> LBD||RSP_A_N @T6G_MB_LIB.T6G(SCH_1):M_H_CPU0_SA_RSP(0)
   5 I3C_SPD_DDRH_CPU0_SDA   HSDA @T6G_MB_LIB.T6G(SCH_1):I3C_SPD_DDRH_CPU0_SDA
   4 I3C_SPD_DDRH_CPU0_SCL   HSCL @T6G_MB_LIB.T6G(SCH_1):I3C_SPD_DDRH_CPU0_SCL
 148 PD_CHH_CPU0_DIMM_SAA    HAS @T6G_MB_LIB.T6G(SCH_1):PD_CHH_CPU0_DIMM_SAA
 100 M_H_CPU0_SB_DQ<0>  DQ0_B @T6G_MB_LIB.T6G(SCH_1):M_H_CPU0_SB_DQ(0)
 102 M_H_CPU0_SB_DQ<1>  DQ1_B @T6G_MB_LIB.T6G(SCH_1):M_H_CPU0_SB_DQ(1)
 245 M_H_CPU0_SB_DQ<2>  DQ2_B @T6G_MB_LIB.T6G(SCH_1):M_H_CPU0_SB_DQ(2)
 247 M_H_CPU0_SB_DQ<3>  DQ3_B @T6G_MB_LIB.T6G(SCH_1):M_H_CPU0_SB_DQ(3)
 107 M_H_CPU0_SB_DQ<4>  DQ4_B @T6G_MB_LIB.T6G(SCH_1):M_H_CPU0_SB_DQ(4)
 109 M_H_CPU0_SB_DQ<5>  DQ5_B @T6G_MB_LIB.T6G(SCH_1):M_H_CPU0_SB_DQ(5)
 252 M_H_CPU0_SB_DQ<6>  DQ6_B @T6G_MB_LIB.T6G(SCH_1):M_H_CPU0_SB_DQ(6)
 254 M_H_CPU0_SB_DQ<7>  DQ7_B @T6G_MB_LIB.T6G(SCH_1):M_H_CPU0_SB_DQ(7)
 111 M_H_CPU0_SB_DQ<8>  DQ8_B @T6G_MB_LIB.T6G(SCH_1):M_H_CPU0_SB_DQ(8)
 113 M_H_CPU0_SB_DQ<9>  DQ9_B @T6G_MB_LIB.T6G(SCH_1):M_H_CPU0_SB_DQ(9)
 256 M_H_CPU0_SB_DQ<10> DQ10_B @T6G_MB_LIB.T6G(SCH_1):M_H_CPU0_SB_DQ(10)
 258 M_H_CPU0_SB_DQ<11> DQ11_B @T6G_MB_LIB.T6G(SCH_1):M_H_CPU0_SB_DQ(11)
 118 M_H_CPU0_SB_DQ<12> DQ12_B @T6G_MB_LIB.T6G(SCH_1):M_H_CPU0_SB_DQ(12)
 120 M_H_CPU0_SB_DQ<13> DQ13_B @T6G_MB_LIB.T6G(SCH_1):M_H_CPU0_SB_DQ(13)
 263 M_H_CPU0_SB_DQ<14> DQ14_B @T6G_MB_LIB.T6G(SCH_1):M_H_CPU0_SB_DQ(14)
 265 M_H_CPU0_SB_DQ<15> DQ15_B @T6G_MB_LIB.T6G(SCH_1):M_H_CPU0_SB_DQ(15)
 122 M_H_CPU0_SB_DQ<16> DQ16_B @T6G_MB_LIB.T6G(SCH_1):M_H_CPU0_SB_DQ(16)
 124 M_H_CPU0_SB_DQ<17> DQ17_B @T6G_MB_LIB.T6G(SCH_1):M_H_CPU0_SB_DQ(17)
 267 M_H_CPU0_SB_DQ<18> DQ18_B @T6G_MB_LIB.T6G(SCH_1):M_H_CPU0_SB_DQ(18)
 269 M_H_CPU0_SB_DQ<19> DQ19_B @T6G_MB_LIB.T6G(SCH_1):M_H_CPU0_SB_DQ(19)
 129 M_H_CPU0_SB_DQ<20> DQ20_B @T6G_MB_LIB.T6G(SCH_1):M_H_CPU0_SB_DQ(20)
 131 M_H_CPU0_SB_DQ<21> DQ21_B @T6G_MB_LIB.T6G(SCH_1):M_H_CPU0_SB_DQ(21)
 274 M_H_CPU0_SB_DQ<22> DQ22_B @T6G_MB_LIB.T6G(SCH_1):M_H_CPU0_SB_DQ(22)
 276 M_H_CPU0_SB_DQ<23> DQ23_B @T6G_MB_LIB.T6G(SCH_1):M_H_CPU0_SB_DQ(23)
 133 M_H_CPU0_SB_DQ<24> DQ24_B @T6G_MB_LIB.T6G(SCH_1):M_H_CPU0_SB_DQ(24)
 135 M_H_CPU0_SB_DQ<25> DQ25_B @T6G_MB_LIB.T6G(SCH_1):M_H_CPU0_SB_DQ(25)
 278 M_H_CPU0_SB_DQ<26> DQ26_B @T6G_MB_LIB.T6G(SCH_1):M_H_CPU0_SB_DQ(26)
 280 M_H_CPU0_SB_DQ<27> DQ27_B @T6G_MB_LIB.T6G(SCH_1):M_H_CPU0_SB_DQ(27)
 140 M_H_CPU0_SB_DQ<28> DQ28_B @T6G_MB_LIB.T6G(SCH_1):M_H_CPU0_SB_DQ(28)
 142 M_H_CPU0_SB_DQ<29> DQ29_B @T6G_MB_LIB.T6G(SCH_1):M_H_CPU0_SB_DQ(29)
 285 M_H_CPU0_SB_DQ<30> DQ30_B @T6G_MB_LIB.T6G(SCH_1):M_H_CPU0_SB_DQ(30)
 287 M_H_CPU0_SB_DQ<31> DQ31_B @T6G_MB_LIB.T6G(SCH_1):M_H_CPU0_SB_DQ(31)
   7 M_H_CPU0_SA_DQ<0>  DQ0_A @T6G_MB_LIB.T6G(SCH_1):M_H_CPU0_SA_DQ(0)
   9 M_H_CPU0_SA_DQ<1>  DQ1_A @T6G_MB_LIB.T6G(SCH_1):M_H_CPU0_SA_DQ(1)
 152 M_H_CPU0_SA_DQ<2>  DQ2_A @T6G_MB_LIB.T6G(SCH_1):M_H_CPU0_SA_DQ(2)
 154 M_H_CPU0_SA_DQ<3>  DQ3_A @T6G_MB_LIB.T6G(SCH_1):M_H_CPU0_SA_DQ(3)
  14 M_H_CPU0_SA_DQ<4>  DQ4_A @T6G_MB_LIB.T6G(SCH_1):M_H_CPU0_SA_DQ(4)
  16 M_H_CPU0_SA_DQ<5>  DQ5_A @T6G_MB_LIB.T6G(SCH_1):M_H_CPU0_SA_DQ(5)
 159 M_H_CPU0_SA_DQ<6>  DQ6_A @T6G_MB_LIB.T6G(SCH_1):M_H_CPU0_SA_DQ(6)
 161 M_H_CPU0_SA_DQ<7>  DQ7_A @T6G_MB_LIB.T6G(SCH_1):M_H_CPU0_SA_DQ(7)
  18 M_H_CPU0_SA_DQ<8>  DQ8_A @T6G_MB_LIB.T6G(SCH_1):M_H_CPU0_SA_DQ(8)
  20 M_H_CPU0_SA_DQ<9>  DQ9_A @T6G_MB_LIB.T6G(SCH_1):M_H_CPU0_SA_DQ(9)
 163 M_H_CPU0_SA_DQ<10> DQ10_A @T6G_MB_LIB.T6G(SCH_1):M_H_CPU0_SA_DQ(10)
 165 M_H_CPU0_SA_DQ<11> DQ11_A @T6G_MB_LIB.T6G(SCH_1):M_H_CPU0_SA_DQ(11)
  25 M_H_CPU0_SA_DQ<12> DQ12_A @T6G_MB_LIB.T6G(SCH_1):M_H_CPU0_SA_DQ(12)
  27 M_H_CPU0_SA_DQ<13> DQ13_A @T6G_MB_LIB.T6G(SCH_1):M_H_CPU0_SA_DQ(13)
 170 M_H_CPU0_SA_DQ<14> DQ14_A @T6G_MB_LIB.T6G(SCH_1):M_H_CPU0_SA_DQ(14)
 172 M_H_CPU0_SA_DQ<15> DQ15_A @T6G_MB_LIB.T6G(SCH_1):M_H_CPU0_SA_DQ(15)
  29 M_H_CPU0_SA_DQ<16> DQ16_A @T6G_MB_LIB.T6G(SCH_1):M_H_CPU0_SA_DQ(16)
  31 M_H_CPU0_SA_DQ<17> DQ17_A @T6G_MB_LIB.T6G(SCH_1):M_H_CPU0_SA_DQ(17)
 174 M_H_CPU0_SA_DQ<18> DQ18_A @T6G_MB_LIB.T6G(SCH_1):M_H_CPU0_SA_DQ(18)
 176 M_H_CPU0_SA_DQ<19> DQ19_A @T6G_MB_LIB.T6G(SCH_1):M_H_CPU0_SA_DQ(19)
  36 M_H_CPU0_SA_DQ<20> DQ20_A @T6G_MB_LIB.T6G(SCH_1):M_H_CPU0_SA_DQ(20)
  38 M_H_CPU0_SA_DQ<21> DQ21_A @T6G_MB_LIB.T6G(SCH_1):M_H_CPU0_SA_DQ(21)
 181 M_H_CPU0_SA_DQ<22> DQ22_A @T6G_MB_LIB.T6G(SCH_1):M_H_CPU0_SA_DQ(22)
 183 M_H_CPU0_SA_DQ<23> DQ23_A @T6G_MB_LIB.T6G(SCH_1):M_H_CPU0_SA_DQ(23)
  40 M_H_CPU0_SA_DQ<24> DQ24_A @T6G_MB_LIB.T6G(SCH_1):M_H_CPU0_SA_DQ(24)
  42 M_H_CPU0_SA_DQ<25> DQ25_A @T6G_MB_LIB.T6G(SCH_1):M_H_CPU0_SA_DQ(25)
 185 M_H_CPU0_SA_DQ<26> DQ26_A @T6G_MB_LIB.T6G(SCH_1):M_H_CPU0_SA_DQ(26)
 187 M_H_CPU0_SA_DQ<27> DQ27_A @T6G_MB_LIB.T6G(SCH_1):M_H_CPU0_SA_DQ(27)
  47 M_H_CPU0_SA_DQ<28> DQ28_A @T6G_MB_LIB.T6G(SCH_1):M_H_CPU0_SA_DQ(28)
  49 M_H_CPU0_SA_DQ<29> DQ29_A @T6G_MB_LIB.T6G(SCH_1):M_H_CPU0_SA_DQ(29)
 192 M_H_CPU0_SA_DQ<30> DQ30_A @T6G_MB_LIB.T6G(SCH_1):M_H_CPU0_SA_DQ(30)
 229 M_H_CPU0_SB_CS_N<1> CS1_B_N @T6G_MB_LIB.T6G(SCH_1):M_H_CPU0_SB_CS_N(1)
 209 M_H_CPU0_SA_CS_N<1> CS1_A_N @T6G_MB_LIB.T6G(SCH_1):M_H_CPU0_SA_CS_N(1)
  84 M_H_CPU0_SB_CS_N<0> CS0_B_N @T6G_MB_LIB.T6G(SCH_1):M_H_CPU0_SB_CS_N(0)
  64 M_H_CPU0_SA_CS_N<0> CS0_A_N @T6G_MB_LIB.T6G(SCH_1):M_H_CPU0_SA_CS_N(0)
 217 M_H_CPU0_CLK_DP<0>   CK_T @T6G_MB_LIB.T6G(SCH_1):M_H_CPU0_CLK_DP(0)
 218 M_H_CPU0_CLK_DN<0>   CK_C @T6G_MB_LIB.T6G(SCH_1):M_H_CPU0_CLK_DN(0)
  96 M_H_CPU0_SB_CB<0>  CB0_B @T6G_MB_LIB.T6G(SCH_1):M_H_CPU0_SB_CB(0)
  98 M_H_CPU0_SB_CB<1>  CB1_B @T6G_MB_LIB.T6G(SCH_1):M_H_CPU0_SB_CB(1)
 241 M_H_CPU0_SB_CB<2>  CB2_B @T6G_MB_LIB.T6G(SCH_1):M_H_CPU0_SB_CB(2)
 243 M_H_CPU0_SB_CB<3>  CB3_B @T6G_MB_LIB.T6G(SCH_1):M_H_CPU0_SB_CB(3)
  89 M_H_CPU0_SB_CB<4>  CB4_B @T6G_MB_LIB.T6G(SCH_1):M_H_CPU0_SB_CB(4)
  91 M_H_CPU0_SB_CB<5>  CB5_B @T6G_MB_LIB.T6G(SCH_1):M_H_CPU0_SB_CB(5)
 234 M_H_CPU0_SB_CB<6>  CB6_B @T6G_MB_LIB.T6G(SCH_1):M_H_CPU0_SB_CB(6)
  51 M_H_CPU0_SA_CB<0>  CB0_A @T6G_MB_LIB.T6G(SCH_1):M_H_CPU0_SA_CB(0)
 196 M_H_CPU0_SA_CB<2>  CB2_A @T6G_MB_LIB.T6G(SCH_1):M_H_CPU0_SA_CB(2)
 198 M_H_CPU0_SA_CB<3>  CB3_A @T6G_MB_LIB.T6G(SCH_1):M_H_CPU0_SA_CB(3)
  60 M_H_CPU0_SA_CB<5>  CB5_A @T6G_MB_LIB.T6G(SCH_1):M_H_CPU0_SA_CB(5)
 203 M_H_CPU0_SA_CB<6>  CB6_A @T6G_MB_LIB.T6G(SCH_1):M_H_CPU0_SA_CB(6)
  82 M_H_CPU0_SB_CA<6>  CA6_B @T6G_MB_LIB.T6G(SCH_1):M_H_CPU0_SB_CA(6)
  72 M_H_CPU0_SA_CA<6>  CA6_A @T6G_MB_LIB.T6G(SCH_1):M_H_CPU0_SA_CA(6)
 225 M_H_CPU0_SB_CA<5>  CA5_B @T6G_MB_LIB.T6G(SCH_1):M_H_CPU0_SB_CA(5)
 215 M_H_CPU0_SA_CA<5>  CA5_A @T6G_MB_LIB.T6G(SCH_1):M_H_CPU0_SA_CA(5)
  80 M_H_CPU0_SB_CA<4>  CA4_B @T6G_MB_LIB.T6G(SCH_1):M_H_CPU0_SB_CA(4)
  70 M_H_CPU0_SA_CA<4>  CA4_A @T6G_MB_LIB.T6G(SCH_1):M_H_CPU0_SA_CA(4)
 223 M_H_CPU0_SB_CA<3>  CA3_B @T6G_MB_LIB.T6G(SCH_1):M_H_CPU0_SB_CA(3)
 213 M_H_CPU0_SA_CA<3>  CA3_A @T6G_MB_LIB.T6G(SCH_1):M_H_CPU0_SA_CA(3)
  78 M_H_CPU0_SB_CA<2>  CA2_B @T6G_MB_LIB.T6G(SCH_1):M_H_CPU0_SB_CA(2)
  68 M_H_CPU0_SA_CA<2>  CA2_A @T6G_MB_LIB.T6G(SCH_1):M_H_CPU0_SA_CA(2)
 221 M_H_CPU0_SB_CA<1>  CA1_B @T6G_MB_LIB.T6G(SCH_1):M_H_CPU0_SB_CA(1)
 211 M_H_CPU0_SA_CA<1>  CA1_A @T6G_MB_LIB.T6G(SCH_1):M_H_CPU0_SA_CA(1)
  76 M_H_CPU0_SB_CA<0>  CA0_B @T6G_MB_LIB.T6G(SCH_1):M_H_CPU0_SB_CA(0)
  66 M_H_CPU0_SA_CA<0>  CA0_A @T6G_MB_LIB.T6G(SCH_1):M_H_CPU0_SA_CA(0)
  62 M_H_CPU0_ALERT_N ALERT_N @T6G_MB_LIB.T6G(SCH_1):M_H_CPU0_ALERT_N
 236 M_H_CPU0_SB_CB<7>  CB7_B @T6G_MB_LIB.T6G(SCH_1):M_H_CPU0_SB_CB(7)
  53 M_H_CPU0_SA_CB<1>  CB1_A @T6G_MB_LIB.T6G(SCH_1):M_H_CPU0_SA_CB(1)
  58 M_H_CPU0_SA_CB<4>  CB4_A @T6G_MB_LIB.T6G(SCH_1):M_H_CPU0_SA_CB(4)
 205 M_H_CPU0_SA_CB<7>  CB7_A @T6G_MB_LIB.T6G(SCH_1):M_H_CPU0_SA_CB(7)
 194 M_H_CPU0_SA_DQ<31> DQ31_A @T6G_MB_LIB.T6G(SCH_1):M_H_CPU0_SA_DQ(31)

Q_RES_0402LF-15.4K,1%,1/16W,CHIP,CS31542FB02  I129  R765
   1 PD_CHH_CPU0_DIMM_SAA      A @T6G_MB_LIB.T6G(SCH_1):PD_CHH_CPU0_DIMM_SAA
   2    GND      B @T6G_MB_LIB.T6G(SCH_1):GND

SCONN288_DDR506112002KQ-SCONN288_DDR506112002KQ,SMA  I177  J69
   6    GND   VSS0 @T6G_MB_LIB.T6G(SCH_1):GND
   8    GND   VSS1 @T6G_MB_LIB.T6G(SCH_1):GND
  10    GND   VSS2 @T6G_MB_LIB.T6G(SCH_1):GND
  13    GND   VSS3 @T6G_MB_LIB.T6G(SCH_1):GND
  15    GND   VSS4 @T6G_MB_LIB.T6G(SCH_1):GND
  17    GND   VSS5 @T6G_MB_LIB.T6G(SCH_1):GND
  19    GND   VSS6 @T6G_MB_LIB.T6G(SCH_1):GND
  21    GND   VSS7 @T6G_MB_LIB.T6G(SCH_1):GND
  24    GND   VSS8 @T6G_MB_LIB.T6G(SCH_1):GND
  26    GND   VSS9 @T6G_MB_LIB.T6G(SCH_1):GND
  28    GND  VSS10 @T6G_MB_LIB.T6G(SCH_1):GND
  30    GND  VSS11 @T6G_MB_LIB.T6G(SCH_1):GND
  32    GND  VSS12 @T6G_MB_LIB.T6G(SCH_1):GND
  35    GND  VSS13 @T6G_MB_LIB.T6G(SCH_1):GND
  37    GND  VSS14 @T6G_MB_LIB.T6G(SCH_1):GND
  39    GND  VSS15 @T6G_MB_LIB.T6G(SCH_1):GND
  41    GND  VSS16 @T6G_MB_LIB.T6G(SCH_1):GND
  43    GND  VSS17 @T6G_MB_LIB.T6G(SCH_1):GND
  46    GND  VSS18 @T6G_MB_LIB.T6G(SCH_1):GND
  48    GND  VSS19 @T6G_MB_LIB.T6G(SCH_1):GND
  50    GND  VSS20 @T6G_MB_LIB.T6G(SCH_1):GND
  52    GND  VSS21 @T6G_MB_LIB.T6G(SCH_1):GND
  54    GND  VSS22 @T6G_MB_LIB.T6G(SCH_1):GND
  57    GND  VSS23 @T6G_MB_LIB.T6G(SCH_1):GND
  59    GND  VSS24 @T6G_MB_LIB.T6G(SCH_1):GND
  61    GND  VSS25 @T6G_MB_LIB.T6G(SCH_1):GND
  63    GND  VSS26 @T6G_MB_LIB.T6G(SCH_1):GND
  65    GND  VSS27 @T6G_MB_LIB.T6G(SCH_1):GND
  67    GND  VSS28 @T6G_MB_LIB.T6G(SCH_1):GND
  69    GND  VSS29 @T6G_MB_LIB.T6G(SCH_1):GND
  71    GND  VSS30 @T6G_MB_LIB.T6G(SCH_1):GND
  73    GND  VSS31 @T6G_MB_LIB.T6G(SCH_1):GND
  75    GND  VSS32 @T6G_MB_LIB.T6G(SCH_1):GND
  77    GND  VSS33 @T6G_MB_LIB.T6G(SCH_1):GND
  79    GND  VSS34 @T6G_MB_LIB.T6G(SCH_1):GND
  81    GND  VSS35 @T6G_MB_LIB.T6G(SCH_1):GND
  83    GND  VSS36 @T6G_MB_LIB.T6G(SCH_1):GND
  85    GND  VSS37 @T6G_MB_LIB.T6G(SCH_1):GND
  88    GND  VSS38 @T6G_MB_LIB.T6G(SCH_1):GND
  90    GND  VSS39 @T6G_MB_LIB.T6G(SCH_1):GND
  92    GND  VSS40 @T6G_MB_LIB.T6G(SCH_1):GND
  95    GND  VSS41 @T6G_MB_LIB.T6G(SCH_1):GND
  97    GND  VSS42 @T6G_MB_LIB.T6G(SCH_1):GND
  99    GND  VSS43 @T6G_MB_LIB.T6G(SCH_1):GND
 101    GND  VSS44 @T6G_MB_LIB.T6G(SCH_1):GND
 103    GND  VSS45 @T6G_MB_LIB.T6G(SCH_1):GND
 106    GND  VSS46 @T6G_MB_LIB.T6G(SCH_1):GND
 108    GND  VSS47 @T6G_MB_LIB.T6G(SCH_1):GND
 110    GND  VSS48 @T6G_MB_LIB.T6G(SCH_1):GND
 112    GND  VSS49 @T6G_MB_LIB.T6G(SCH_1):GND
 114    GND  VSS50 @T6G_MB_LIB.T6G(SCH_1):GND
 117    GND  VSS51 @T6G_MB_LIB.T6G(SCH_1):GND
 119    GND  VSS52 @T6G_MB_LIB.T6G(SCH_1):GND
 121    GND  VSS53 @T6G_MB_LIB.T6G(SCH_1):GND
 123    GND  VSS54 @T6G_MB_LIB.T6G(SCH_1):GND
 125    GND  VSS55 @T6G_MB_LIB.T6G(SCH_1):GND
 128    GND  VSS56 @T6G_MB_LIB.T6G(SCH_1):GND
 130    GND  VSS57 @T6G_MB_LIB.T6G(SCH_1):GND
 134    GND  VSS59 @T6G_MB_LIB.T6G(SCH_1):GND
 143    GND  VSS63 @T6G_MB_LIB.T6G(SCH_1):GND
 151    GND  VSS64 @T6G_MB_LIB.T6G(SCH_1):GND
 153    GND  VSS65 @T6G_MB_LIB.T6G(SCH_1):GND
 155    GND  VSS66 @T6G_MB_LIB.T6G(SCH_1):GND
 158    GND  VSS67 @T6G_MB_LIB.T6G(SCH_1):GND
 160    GND  VSS68 @T6G_MB_LIB.T6G(SCH_1):GND
 162    GND  VSS69 @T6G_MB_LIB.T6G(SCH_1):GND
 164    GND  VSS70 @T6G_MB_LIB.T6G(SCH_1):GND
 166    GND  VSS71 @T6G_MB_LIB.T6G(SCH_1):GND
 169    GND  VSS72 @T6G_MB_LIB.T6G(SCH_1):GND
 171    GND  VSS73 @T6G_MB_LIB.T6G(SCH_1):GND
 173    GND  VSS74 @T6G_MB_LIB.T6G(SCH_1):GND
 175    GND  VSS75 @T6G_MB_LIB.T6G(SCH_1):GND
 177    GND  VSS76 @T6G_MB_LIB.T6G(SCH_1):GND
 180    GND  VSS77 @T6G_MB_LIB.T6G(SCH_1):GND
 182    GND  VSS78 @T6G_MB_LIB.T6G(SCH_1):GND
 184    GND  VSS79 @T6G_MB_LIB.T6G(SCH_1):GND
 186    GND  VSS80 @T6G_MB_LIB.T6G(SCH_1):GND
 188    GND  VSS81 @T6G_MB_LIB.T6G(SCH_1):GND
 191    GND  VSS82 @T6G_MB_LIB.T6G(SCH_1):GND
 193    GND  VSS83 @T6G_MB_LIB.T6G(SCH_1):GND
 195    GND  VSS84 @T6G_MB_LIB.T6G(SCH_1):GND
 197    GND  VSS85 @T6G_MB_LIB.T6G(SCH_1):GND
 199    GND  VSS86 @T6G_MB_LIB.T6G(SCH_1):GND
 202    GND  VSS87 @T6G_MB_LIB.T6G(SCH_1):GND
 204    GND  VSS88 @T6G_MB_LIB.T6G(SCH_1):GND
 206    GND  VSS89 @T6G_MB_LIB.T6G(SCH_1):GND
 208    GND  VSS90 @T6G_MB_LIB.T6G(SCH_1):GND
 210    GND  VSS91 @T6G_MB_LIB.T6G(SCH_1):GND
 212    GND  VSS92 @T6G_MB_LIB.T6G(SCH_1):GND
 214    GND  VSS93 @T6G_MB_LIB.T6G(SCH_1):GND
 216    GND  VSS94 @T6G_MB_LIB.T6G(SCH_1):GND
 219    GND  VSS95 @T6G_MB_LIB.T6G(SCH_1):GND
 222    GND  VSS96 @T6G_MB_LIB.T6G(SCH_1):GND
 224    GND  VSS97 @T6G_MB_LIB.T6G(SCH_1):GND
 226    GND  VSS98 @T6G_MB_LIB.T6G(SCH_1):GND
 228    GND  VSS99 @T6G_MB_LIB.T6G(SCH_1):GND
 233    GND VSS101 @T6G_MB_LIB.T6G(SCH_1):GND
 237    GND VSS103 @T6G_MB_LIB.T6G(SCH_1):GND
 242    GND VSS105 @T6G_MB_LIB.T6G(SCH_1):GND
 244    GND VSS106 @T6G_MB_LIB.T6G(SCH_1):GND
 246    GND VSS107 @T6G_MB_LIB.T6G(SCH_1):GND
 248    GND VSS108 @T6G_MB_LIB.T6G(SCH_1):GND
 251    GND VSS109 @T6G_MB_LIB.T6G(SCH_1):GND
 253    GND VSS110 @T6G_MB_LIB.T6G(SCH_1):GND
 255    GND VSS111 @T6G_MB_LIB.T6G(SCH_1):GND
 257    GND VSS112 @T6G_MB_LIB.T6G(SCH_1):GND
 259    GND VSS113 @T6G_MB_LIB.T6G(SCH_1):GND
 262    GND VSS114 @T6G_MB_LIB.T6G(SCH_1):GND
 264    GND VSS115 @T6G_MB_LIB.T6G(SCH_1):GND
 266    GND VSS116 @T6G_MB_LIB.T6G(SCH_1):GND
 268    GND VSS117 @T6G_MB_LIB.T6G(SCH_1):GND
 270    GND VSS118 @T6G_MB_LIB.T6G(SCH_1):GND
 273    GND VSS119 @T6G_MB_LIB.T6G(SCH_1):GND
 275    GND VSS120 @T6G_MB_LIB.T6G(SCH_1):GND
 277    GND VSS121 @T6G_MB_LIB.T6G(SCH_1):GND
 279    GND VSS122 @T6G_MB_LIB.T6G(SCH_1):GND
 281    GND VSS123 @T6G_MB_LIB.T6G(SCH_1):GND
 284    GND VSS124 @T6G_MB_LIB.T6G(SCH_1):GND
 286    GND VSS125 @T6G_MB_LIB.T6G(SCH_1):GND
 288    GND VSS126 @T6G_MB_LIB.T6G(SCH_1):GND
   1 P12V_MEM_CPU0 VIN_BULK0 @T6G_MB_LIB.T6G(SCH_1):P12V_MEM_CPU0
 145 P12V_MEM_CPU0 VIN_BULK1 @T6G_MB_LIB.T6G(SCH_1):P12V_MEM_CPU0
 146 P12V_MEM_CPU0 VIN_BULK2 @T6G_MB_LIB.T6G(SCH_1):P12V_MEM_CPU0
 230    GND VSS100 @T6G_MB_LIB.T6G(SCH_1):GND
 235    GND VSS102 @T6G_MB_LIB.T6G(SCH_1):GND
 240    GND VSS104 @T6G_MB_LIB.T6G(SCH_1):GND
 132    GND  VSS58 @T6G_MB_LIB.T6G(SCH_1):GND
 136    GND  VSS60 @T6G_MB_LIB.T6G(SCH_1):GND
 139    GND  VSS61 @T6G_MB_LIB.T6G(SCH_1):GND
 141    GND  VSS62 @T6G_MB_LIB.T6G(SCH_1):GND
  G1    GND     G1 @T6G_MB_LIB.T6G(SCH_1):GND
  G2    GND     G2 @T6G_MB_LIB.T6G(SCH_1):GND
  G3    GND     G3 @T6G_MB_LIB.T6G(SCH_1):GND

Q_CAP_0402-0.1UF,25V,10%,X7R,CH4104K1B00  I186  C116
   1 P3V3_AUX      A @T6G_MB_LIB.T6G(SCH_1):P3V3_AUX
   2    GND      B @T6G_MB_LIB.T6G(SCH_1):GND

Q_RES_0402LF-1K,1%,1/16W,CHIP,CS21002FB06  I189  R298
   1 PWRGD_CHH_CPU0_DIMM      A @T6G_MB_LIB.T6G(SCH_1):PWRGD_CHH_CPU0_DIMM
   2 PWRGD_CHGL_CPU0      B @T6G_MB_LIB.T6G(SCH_1):PWRGD_CHGL_CPU0

Q_RES_0402LF-1K,1%,1/16W,EMPTY,CS21002FB06  I191  R97
   1   P3V3      A @T6G_MB_LIB.T6G(SCH_1):P3V3
   2 PWRGD_CHH_CPU0_DIMM      B @T6G_MB_LIB.T6G(SCH_1):PWRGD_CHH_CPU0_DIMM

SCONN288_DDR506112002KQ-SCONN288_DDR506112002KQ,SMA  I237  J69
  93 M_H_CPU0_SB_DQS_DP<9> DQS9_B_T||TDQS9_B_T||DBI4_B_N @T6G_MB_LIB.T6G(SCH_1):M_H_CPU0_SB_DQS_DP(9)
  94 M_H_CPU0_SB_DQS_DN<9> DQS9_B_C||TDQS9_B_C @T6G_MB_LIB.T6G(SCH_1):M_H_CPU0_SB_DQS_DN(9)
 201 M_H_CPU0_SA_DQS_DP<9> DQS9_A_T||TDQS9_A_T @T6G_MB_LIB.T6G(SCH_1):M_H_CPU0_SA_DQS_DP(9)
 200 M_H_CPU0_SA_DQS_DN<9> DQS9_A_C||TDQS9_A_C @T6G_MB_LIB.T6G(SCH_1):M_H_CPU0_SA_DQS_DN(9)
 190 M_H_CPU0_SA_DQS_DP<8> DQS8_A_T||TDQS8_A_T @T6G_MB_LIB.T6G(SCH_1):M_H_CPU0_SA_DQS_DP(8)
 189 M_H_CPU0_SA_DQS_DN<8> DQS8_A_C||TDQS8_A_C @T6G_MB_LIB.T6G(SCH_1):M_H_CPU0_SA_DQS_DN(8)
 271 M_H_CPU0_SB_DQS_DN<7> DQS7_B_C||TDQS7_B_C @T6G_MB_LIB.T6G(SCH_1):M_H_CPU0_SB_DQS_DN(7)
 179 M_H_CPU0_SA_DQS_DP<7> DQS7_A_T||TDQS7_A_T @T6G_MB_LIB.T6G(SCH_1):M_H_CPU0_SA_DQS_DP(7)
 261 M_H_CPU0_SB_DQS_DP<6> DQS6_B_T||TDQS6_B_T @T6G_MB_LIB.T6G(SCH_1):M_H_CPU0_SB_DQS_DP(6)
 260 M_H_CPU0_SB_DQS_DN<6> DQS6_B_C||TDQS6_B_C @T6G_MB_LIB.T6G(SCH_1):M_H_CPU0_SB_DQS_DN(6)
 167 M_H_CPU0_SA_DQS_DN<6> DQS6_A_C||TDQS6_A_C||DQS6_A_T||TDQS6_A_T @T6G_MB_LIB.T6G(SCH_1):M_H_CPU0_SA_DQS_DN(6)
 250 M_H_CPU0_SB_DQS_DP<5> DQS5_B_T||TDQS5_B_T @T6G_MB_LIB.T6G(SCH_1):M_H_CPU0_SB_DQS_DP(5)
 249 M_H_CPU0_SB_DQS_DN<5> DQS5_B_C||TDQS5_B_C @T6G_MB_LIB.T6G(SCH_1):M_H_CPU0_SB_DQS_DN(5)
 157 M_H_CPU0_SA_DQS_DP<5> DQS5_A_T||TDQS5_A_T @T6G_MB_LIB.T6G(SCH_1):M_H_CPU0_SA_DQS_DP(5)
 156 M_H_CPU0_SA_DQS_DN<5> DQS5_A_C||TDQS5_A_C||DQS5_A_T||TDQS5_A_T @T6G_MB_LIB.T6G(SCH_1):M_H_CPU0_SA_DQS_DN(5)
 239 M_H_CPU0_SB_DQS_DP<4> DQS4_B_T @T6G_MB_LIB.T6G(SCH_1):M_H_CPU0_SB_DQS_DP(4)
 238 M_H_CPU0_SB_DQS_DN<4> DQS4_B_C @T6G_MB_LIB.T6G(SCH_1):M_H_CPU0_SB_DQS_DN(4)
  55 M_H_CPU0_SA_DQS_DP<4> DQS4_A_T @T6G_MB_LIB.T6G(SCH_1):M_H_CPU0_SA_DQS_DP(4)
  56 M_H_CPU0_SA_DQS_DN<4> DQS4_A_C @T6G_MB_LIB.T6G(SCH_1):M_H_CPU0_SA_DQS_DN(4)
 137 M_H_CPU0_SB_DQS_DP<3> DQS3_B_T @T6G_MB_LIB.T6G(SCH_1):M_H_CPU0_SB_DQS_DP(3)
 138 M_H_CPU0_SB_DQS_DN<3> DQS3_B_C @T6G_MB_LIB.T6G(SCH_1):M_H_CPU0_SB_DQS_DN(3)
  44 M_H_CPU0_SA_DQS_DP<3> DQS3_A_T @T6G_MB_LIB.T6G(SCH_1):M_H_CPU0_SA_DQS_DP(3)
  45 M_H_CPU0_SA_DQS_DN<3> DQS3_A_C @T6G_MB_LIB.T6G(SCH_1):M_H_CPU0_SA_DQS_DN(3)
 126 M_H_CPU0_SB_DQS_DP<2> DQS2_B_T @T6G_MB_LIB.T6G(SCH_1):M_H_CPU0_SB_DQS_DP(2)
 127 M_H_CPU0_SB_DQS_DN<2> DQS2_B_C @T6G_MB_LIB.T6G(SCH_1):M_H_CPU0_SB_DQS_DN(2)
  33 M_H_CPU0_SA_DQS_DP<2> DQS2_A_T @T6G_MB_LIB.T6G(SCH_1):M_H_CPU0_SA_DQS_DP(2)
  34 M_H_CPU0_SA_DQS_DN<2> DQS2_A_C @T6G_MB_LIB.T6G(SCH_1):M_H_CPU0_SA_DQS_DN(2)
 115 M_H_CPU0_SB_DQS_DP<1> DQS1_B_T @T6G_MB_LIB.T6G(SCH_1):M_H_CPU0_SB_DQS_DP(1)
 116 M_H_CPU0_SB_DQS_DN<1> DQS1_B_C @T6G_MB_LIB.T6G(SCH_1):M_H_CPU0_SB_DQS_DN(1)
  22 M_H_CPU0_SA_DQS_DP<1> DQS1_A_T @T6G_MB_LIB.T6G(SCH_1):M_H_CPU0_SA_DQS_DP(1)
  23 M_H_CPU0_SA_DQS_DN<1> DQS1_A_C @T6G_MB_LIB.T6G(SCH_1):M_H_CPU0_SA_DQS_DN(1)
 104 M_H_CPU0_SB_DQS_DP<0> DQS0_B_T @T6G_MB_LIB.T6G(SCH_1):M_H_CPU0_SB_DQS_DP(0)
 105 M_H_CPU0_SB_DQS_DN<0> DQS0_B_C @T6G_MB_LIB.T6G(SCH_1):M_H_CPU0_SB_DQS_DN(0)
  11 M_H_CPU0_SA_DQS_DP<0> DQS0_A_T @T6G_MB_LIB.T6G(SCH_1):M_H_CPU0_SA_DQS_DP(0)
  12 M_H_CPU0_SA_DQS_DN<0> DQS0_A_C @T6G_MB_LIB.T6G(SCH_1):M_H_CPU0_SA_DQS_DN(0)
 272 M_H_CPU0_SB_DQS_DP<7> DQS7_B_T||TDQS7_B_T @T6G_MB_LIB.T6G(SCH_1):M_H_CPU0_SB_DQS_DP(7)
 282 M_H_CPU0_SB_DQS_DN<8> DQS8_B_C||TDQS8_B_C @T6G_MB_LIB.T6G(SCH_1):M_H_CPU0_SB_DQS_DN(8)
 283 M_H_CPU0_SB_DQS_DP<8> DQS8_B_T||TDQS8_B_T @T6G_MB_LIB.T6G(SCH_1):M_H_CPU0_SB_DQS_DP(8)
 168 M_H_CPU0_SA_DQS_DP<6> DQS6_A_T||TDQS6_A_T @T6G_MB_LIB.T6G(SCH_1):M_H_CPU0_SA_DQS_DP(6)
 178 M_H_CPU0_SA_DQS_DN<7> DQS7_A_C||TDQS7_A_C @T6G_MB_LIB.T6G(SCH_1):M_H_CPU0_SA_DQS_DN(7)

Q_CAP_C0805-10UF,25V,10%,X6S,CH6104KEA00  I239  C159
   1 P12V_MEM_CPU0      A @T6G_MB_LIB.T6G(SCH_1):P12V_MEM_CPU0
   2    GND      B @T6G_MB_LIB.T6G(SCH_1):GND

Q_CAP_C0805-10UF,25V,10%,X6S,CH6104KEA00  I240  C161
   1 P12V_MEM_CPU0      A @T6G_MB_LIB.T6G(SCH_1):P12V_MEM_CPU0
   2    GND      B @T6G_MB_LIB.T6G(SCH_1):GND

Q_RES_0402LF-49.9,1%,1/16W,CHIP,CS04992FB07  I243  R1575
   1 I3C_SPD_DDRGL_CPU0_SCL      A @T6G_MB_LIB.T6G(SCH_1):I3C_SPD_DDRGL_CPU0_SCL
   2 I3C_SPD_DDRH_CPU0_SCL      B @T6G_MB_LIB.T6G(SCH_1):I3C_SPD_DDRH_CPU0_SCL

Q_RES_0402LF-10,1%,1/16W,CHIP,CS01002FB07  I244  R1681
   1 I3C_SPD_DDRGL_CPU0_SDA      A @T6G_MB_LIB.T6G(SCH_1):I3C_SPD_DDRGL_CPU0_SDA
   2 I3C_SPD_DDRH_CPU0_SDA      B @T6G_MB_LIB.T6G(SCH_1):I3C_SPD_DDRH_CPU0_SDA


DRAWING: @T6G_MB_LIB.T6G(SCH_1):PAGE93 

SCONN288_DDR506112002KQ-SCONN288_DDR506112002KQ,SMA  I22  J18
   3 P3V3_AUX VIN_MGMT @T6G_MB_LIB.T6G(SCH_1):P3V3_AUX
   2     NC   RFU0     NC
 144     NC   RFU1     NC
 149     NC   RFU2     NC
 150     NC   RFU3     NC
 220     NC   RFU4     NC
 231     NC   RFU5     NC
 232     NC   RFU6     NC
 207 M_I_CPU0_RESET_N RESET_N @T6G_MB_LIB.T6G(SCH_1):M_I_CPU0_RESET_N
 147 PWRGD_CHI_CPU0_DIMM PWR_GOOD||FAIL_N @T6G_MB_LIB.T6G(SCH_1):PWRGD_CHI_CPU0_DIMM
 227 M_I_CPU0_SB_PAR  PAR_B @T6G_MB_LIB.T6G(SCH_1):M_I_CPU0_SB_PAR
  74 M_I_CPU0_SA_PAR  PAR_A @T6G_MB_LIB.T6G(SCH_1):M_I_CPU0_SA_PAR
  87 M_I_CPU0_SB_RSP<0> LBS||RSP_B_N @T6G_MB_LIB.T6G(SCH_1):M_I_CPU0_SB_RSP(0)
  86 M_I_CPU0_SA_RSP<0> LBD||RSP_A_N @T6G_MB_LIB.T6G(SCH_1):M_I_CPU0_SA_RSP(0)
   5 I3C_SPD_DDRI_CPU0_SDA   HSDA @T6G_MB_LIB.T6G(SCH_1):I3C_SPD_DDRI_CPU0_SDA
   4 I3C_SPD_DDRI_CPU0_SCL   HSCL @T6G_MB_LIB.T6G(SCH_1):I3C_SPD_DDRI_CPU0_SCL
 148 PD_CHI_CPU0_DIMM_SAA    HAS @T6G_MB_LIB.T6G(SCH_1):PD_CHI_CPU0_DIMM_SAA
 100 M_I_CPU0_SB_DQ<0>  DQ0_B @T6G_MB_LIB.T6G(SCH_1):M_I_CPU0_SB_DQ(0)
 102 M_I_CPU0_SB_DQ<1>  DQ1_B @T6G_MB_LIB.T6G(SCH_1):M_I_CPU0_SB_DQ(1)
 245 M_I_CPU0_SB_DQ<2>  DQ2_B @T6G_MB_LIB.T6G(SCH_1):M_I_CPU0_SB_DQ(2)
 247 M_I_CPU0_SB_DQ<3>  DQ3_B @T6G_MB_LIB.T6G(SCH_1):M_I_CPU0_SB_DQ(3)
 107 M_I_CPU0_SB_DQ<4>  DQ4_B @T6G_MB_LIB.T6G(SCH_1):M_I_CPU0_SB_DQ(4)
 109 M_I_CPU0_SB_DQ<5>  DQ5_B @T6G_MB_LIB.T6G(SCH_1):M_I_CPU0_SB_DQ(5)
 252 M_I_CPU0_SB_DQ<6>  DQ6_B @T6G_MB_LIB.T6G(SCH_1):M_I_CPU0_SB_DQ(6)
 254 M_I_CPU0_SB_DQ<7>  DQ7_B @T6G_MB_LIB.T6G(SCH_1):M_I_CPU0_SB_DQ(7)
 111 M_I_CPU0_SB_DQ<8>  DQ8_B @T6G_MB_LIB.T6G(SCH_1):M_I_CPU0_SB_DQ(8)
 113 M_I_CPU0_SB_DQ<9>  DQ9_B @T6G_MB_LIB.T6G(SCH_1):M_I_CPU0_SB_DQ(9)
 256 M_I_CPU0_SB_DQ<10> DQ10_B @T6G_MB_LIB.T6G(SCH_1):M_I_CPU0_SB_DQ(10)
 258 M_I_CPU0_SB_DQ<11> DQ11_B @T6G_MB_LIB.T6G(SCH_1):M_I_CPU0_SB_DQ(11)
 118 M_I_CPU0_SB_DQ<12> DQ12_B @T6G_MB_LIB.T6G(SCH_1):M_I_CPU0_SB_DQ(12)
 120 M_I_CPU0_SB_DQ<13> DQ13_B @T6G_MB_LIB.T6G(SCH_1):M_I_CPU0_SB_DQ(13)
 263 M_I_CPU0_SB_DQ<14> DQ14_B @T6G_MB_LIB.T6G(SCH_1):M_I_CPU0_SB_DQ(14)
 265 M_I_CPU0_SB_DQ<15> DQ15_B @T6G_MB_LIB.T6G(SCH_1):M_I_CPU0_SB_DQ(15)
 122 M_I_CPU0_SB_DQ<16> DQ16_B @T6G_MB_LIB.T6G(SCH_1):M_I_CPU0_SB_DQ(16)
 124 M_I_CPU0_SB_DQ<17> DQ17_B @T6G_MB_LIB.T6G(SCH_1):M_I_CPU0_SB_DQ(17)
 267 M_I_CPU0_SB_DQ<18> DQ18_B @T6G_MB_LIB.T6G(SCH_1):M_I_CPU0_SB_DQ(18)
 269 M_I_CPU0_SB_DQ<19> DQ19_B @T6G_MB_LIB.T6G(SCH_1):M_I_CPU0_SB_DQ(19)
 129 M_I_CPU0_SB_DQ<20> DQ20_B @T6G_MB_LIB.T6G(SCH_1):M_I_CPU0_SB_DQ(20)
 131 M_I_CPU0_SB_DQ<21> DQ21_B @T6G_MB_LIB.T6G(SCH_1):M_I_CPU0_SB_DQ(21)
 274 M_I_CPU0_SB_DQ<22> DQ22_B @T6G_MB_LIB.T6G(SCH_1):M_I_CPU0_SB_DQ(22)
 276 M_I_CPU0_SB_DQ<23> DQ23_B @T6G_MB_LIB.T6G(SCH_1):M_I_CPU0_SB_DQ(23)
 133 M_I_CPU0_SB_DQ<24> DQ24_B @T6G_MB_LIB.T6G(SCH_1):M_I_CPU0_SB_DQ(24)
 135 M_I_CPU0_SB_DQ<25> DQ25_B @T6G_MB_LIB.T6G(SCH_1):M_I_CPU0_SB_DQ(25)
 278 M_I_CPU0_SB_DQ<26> DQ26_B @T6G_MB_LIB.T6G(SCH_1):M_I_CPU0_SB_DQ(26)
 280 M_I_CPU0_SB_DQ<27> DQ27_B @T6G_MB_LIB.T6G(SCH_1):M_I_CPU0_SB_DQ(27)
 140 M_I_CPU0_SB_DQ<28> DQ28_B @T6G_MB_LIB.T6G(SCH_1):M_I_CPU0_SB_DQ(28)
 142 M_I_CPU0_SB_DQ<29> DQ29_B @T6G_MB_LIB.T6G(SCH_1):M_I_CPU0_SB_DQ(29)
 285 M_I_CPU0_SB_DQ<30> DQ30_B @T6G_MB_LIB.T6G(SCH_1):M_I_CPU0_SB_DQ(30)
 287 M_I_CPU0_SB_DQ<31> DQ31_B @T6G_MB_LIB.T6G(SCH_1):M_I_CPU0_SB_DQ(31)
   7 M_I_CPU0_SA_DQ<0>  DQ0_A @T6G_MB_LIB.T6G(SCH_1):M_I_CPU0_SA_DQ(0)
   9 M_I_CPU0_SA_DQ<1>  DQ1_A @T6G_MB_LIB.T6G(SCH_1):M_I_CPU0_SA_DQ(1)
 152 M_I_CPU0_SA_DQ<2>  DQ2_A @T6G_MB_LIB.T6G(SCH_1):M_I_CPU0_SA_DQ(2)
 154 M_I_CPU0_SA_DQ<3>  DQ3_A @T6G_MB_LIB.T6G(SCH_1):M_I_CPU0_SA_DQ(3)
  14 M_I_CPU0_SA_DQ<4>  DQ4_A @T6G_MB_LIB.T6G(SCH_1):M_I_CPU0_SA_DQ(4)
  16 M_I_CPU0_SA_DQ<5>  DQ5_A @T6G_MB_LIB.T6G(SCH_1):M_I_CPU0_SA_DQ(5)
 159 M_I_CPU0_SA_DQ<6>  DQ6_A @T6G_MB_LIB.T6G(SCH_1):M_I_CPU0_SA_DQ(6)
 161 M_I_CPU0_SA_DQ<7>  DQ7_A @T6G_MB_LIB.T6G(SCH_1):M_I_CPU0_SA_DQ(7)
  18 M_I_CPU0_SA_DQ<8>  DQ8_A @T6G_MB_LIB.T6G(SCH_1):M_I_CPU0_SA_DQ(8)
  20 M_I_CPU0_SA_DQ<9>  DQ9_A @T6G_MB_LIB.T6G(SCH_1):M_I_CPU0_SA_DQ(9)
 163 M_I_CPU0_SA_DQ<10> DQ10_A @T6G_MB_LIB.T6G(SCH_1):M_I_CPU0_SA_DQ(10)
 165 M_I_CPU0_SA_DQ<11> DQ11_A @T6G_MB_LIB.T6G(SCH_1):M_I_CPU0_SA_DQ(11)
  25 M_I_CPU0_SA_DQ<12> DQ12_A @T6G_MB_LIB.T6G(SCH_1):M_I_CPU0_SA_DQ(12)
  27 M_I_CPU0_SA_DQ<13> DQ13_A @T6G_MB_LIB.T6G(SCH_1):M_I_CPU0_SA_DQ(13)
 170 M_I_CPU0_SA_DQ<14> DQ14_A @T6G_MB_LIB.T6G(SCH_1):M_I_CPU0_SA_DQ(14)
 172 M_I_CPU0_SA_DQ<15> DQ15_A @T6G_MB_LIB.T6G(SCH_1):M_I_CPU0_SA_DQ(15)
  29 M_I_CPU0_SA_DQ<16> DQ16_A @T6G_MB_LIB.T6G(SCH_1):M_I_CPU0_SA_DQ(16)
  31 M_I_CPU0_SA_DQ<17> DQ17_A @T6G_MB_LIB.T6G(SCH_1):M_I_CPU0_SA_DQ(17)
 174 M_I_CPU0_SA_DQ<18> DQ18_A @T6G_MB_LIB.T6G(SCH_1):M_I_CPU0_SA_DQ(18)
 176 M_I_CPU0_SA_DQ<19> DQ19_A @T6G_MB_LIB.T6G(SCH_1):M_I_CPU0_SA_DQ(19)
  36 M_I_CPU0_SA_DQ<20> DQ20_A @T6G_MB_LIB.T6G(SCH_1):M_I_CPU0_SA_DQ(20)
  38 M_I_CPU0_SA_DQ<21> DQ21_A @T6G_MB_LIB.T6G(SCH_1):M_I_CPU0_SA_DQ(21)
 181 M_I_CPU0_SA_DQ<22> DQ22_A @T6G_MB_LIB.T6G(SCH_1):M_I_CPU0_SA_DQ(22)
 183 M_I_CPU0_SA_DQ<23> DQ23_A @T6G_MB_LIB.T6G(SCH_1):M_I_CPU0_SA_DQ(23)
  40 M_I_CPU0_SA_DQ<24> DQ24_A @T6G_MB_LIB.T6G(SCH_1):M_I_CPU0_SA_DQ(24)
  42 M_I_CPU0_SA_DQ<25> DQ25_A @T6G_MB_LIB.T6G(SCH_1):M_I_CPU0_SA_DQ(25)
 185 M_I_CPU0_SA_DQ<26> DQ26_A @T6G_MB_LIB.T6G(SCH_1):M_I_CPU0_SA_DQ(26)
 187 M_I_CPU0_SA_DQ<27> DQ27_A @T6G_MB_LIB.T6G(SCH_1):M_I_CPU0_SA_DQ(27)
  47 M_I_CPU0_SA_DQ<28> DQ28_A @T6G_MB_LIB.T6G(SCH_1):M_I_CPU0_SA_DQ(28)
  49 M_I_CPU0_SA_DQ<29> DQ29_A @T6G_MB_LIB.T6G(SCH_1):M_I_CPU0_SA_DQ(29)
 192 M_I_CPU0_SA_DQ<30> DQ30_A @T6G_MB_LIB.T6G(SCH_1):M_I_CPU0_SA_DQ(30)
 229 M_I_CPU0_SB_CS_N<1> CS1_B_N @T6G_MB_LIB.T6G(SCH_1):M_I_CPU0_SB_CS_N(1)
 209 M_I_CPU0_SA_CS_N<1> CS1_A_N @T6G_MB_LIB.T6G(SCH_1):M_I_CPU0_SA_CS_N(1)
  84 M_I_CPU0_SB_CS_N<0> CS0_B_N @T6G_MB_LIB.T6G(SCH_1):M_I_CPU0_SB_CS_N(0)
  64 M_I_CPU0_SA_CS_N<0> CS0_A_N @T6G_MB_LIB.T6G(SCH_1):M_I_CPU0_SA_CS_N(0)
 217 M_I_CPU0_CLK_DP<0>   CK_T @T6G_MB_LIB.T6G(SCH_1):M_I_CPU0_CLK_DP(0)
 218 M_I_CPU0_CLK_DN<0>   CK_C @T6G_MB_LIB.T6G(SCH_1):M_I_CPU0_CLK_DN(0)
  96 M_I_CPU0_SB_CB<0>  CB0_B @T6G_MB_LIB.T6G(SCH_1):M_I_CPU0_SB_CB(0)
  98 M_I_CPU0_SB_CB<1>  CB1_B @T6G_MB_LIB.T6G(SCH_1):M_I_CPU0_SB_CB(1)
 241 M_I_CPU0_SB_CB<2>  CB2_B @T6G_MB_LIB.T6G(SCH_1):M_I_CPU0_SB_CB(2)
 243 M_I_CPU0_SB_CB<3>  CB3_B @T6G_MB_LIB.T6G(SCH_1):M_I_CPU0_SB_CB(3)
  89 M_I_CPU0_SB_CB<4>  CB4_B @T6G_MB_LIB.T6G(SCH_1):M_I_CPU0_SB_CB(4)
  91 M_I_CPU0_SB_CB<5>  CB5_B @T6G_MB_LIB.T6G(SCH_1):M_I_CPU0_SB_CB(5)
 234 M_I_CPU0_SB_CB<6>  CB6_B @T6G_MB_LIB.T6G(SCH_1):M_I_CPU0_SB_CB(6)
  51 M_I_CPU0_SA_CB<0>  CB0_A @T6G_MB_LIB.T6G(SCH_1):M_I_CPU0_SA_CB(0)
 196 M_I_CPU0_SA_CB<2>  CB2_A @T6G_MB_LIB.T6G(SCH_1):M_I_CPU0_SA_CB(2)
 198 M_I_CPU0_SA_CB<3>  CB3_A @T6G_MB_LIB.T6G(SCH_1):M_I_CPU0_SA_CB(3)
  60 M_I_CPU0_SA_CB<5>  CB5_A @T6G_MB_LIB.T6G(SCH_1):M_I_CPU0_SA_CB(5)
 203 M_I_CPU0_SA_CB<6>  CB6_A @T6G_MB_LIB.T6G(SCH_1):M_I_CPU0_SA_CB(6)
  82 M_I_CPU0_SB_CA<6>  CA6_B @T6G_MB_LIB.T6G(SCH_1):M_I_CPU0_SB_CA(6)
  72 M_I_CPU0_SA_CA<6>  CA6_A @T6G_MB_LIB.T6G(SCH_1):M_I_CPU0_SA_CA(6)
 225 M_I_CPU0_SB_CA<5>  CA5_B @T6G_MB_LIB.T6G(SCH_1):M_I_CPU0_SB_CA(5)
 215 M_I_CPU0_SA_CA<5>  CA5_A @T6G_MB_LIB.T6G(SCH_1):M_I_CPU0_SA_CA(5)
  80 M_I_CPU0_SB_CA<4>  CA4_B @T6G_MB_LIB.T6G(SCH_1):M_I_CPU0_SB_CA(4)
  70 M_I_CPU0_SA_CA<4>  CA4_A @T6G_MB_LIB.T6G(SCH_1):M_I_CPU0_SA_CA(4)
 223 M_I_CPU0_SB_CA<3>  CA3_B @T6G_MB_LIB.T6G(SCH_1):M_I_CPU0_SB_CA(3)
 213 M_I_CPU0_SA_CA<3>  CA3_A @T6G_MB_LIB.T6G(SCH_1):M_I_CPU0_SA_CA(3)
  78 M_I_CPU0_SB_CA<2>  CA2_B @T6G_MB_LIB.T6G(SCH_1):M_I_CPU0_SB_CA(2)
  68 M_I_CPU0_SA_CA<2>  CA2_A @T6G_MB_LIB.T6G(SCH_1):M_I_CPU0_SA_CA(2)
 221 M_I_CPU0_SB_CA<1>  CA1_B @T6G_MB_LIB.T6G(SCH_1):M_I_CPU0_SB_CA(1)
 211 M_I_CPU0_SA_CA<1>  CA1_A @T6G_MB_LIB.T6G(SCH_1):M_I_CPU0_SA_CA(1)
  76 M_I_CPU0_SB_CA<0>  CA0_B @T6G_MB_LIB.T6G(SCH_1):M_I_CPU0_SB_CA(0)
  66 M_I_CPU0_SA_CA<0>  CA0_A @T6G_MB_LIB.T6G(SCH_1):M_I_CPU0_SA_CA(0)
  62 M_I_CPU0_ALERT_N ALERT_N @T6G_MB_LIB.T6G(SCH_1):M_I_CPU0_ALERT_N
 236 M_I_CPU0_SB_CB<7>  CB7_B @T6G_MB_LIB.T6G(SCH_1):M_I_CPU0_SB_CB(7)
  53 M_I_CPU0_SA_CB<1>  CB1_A @T6G_MB_LIB.T6G(SCH_1):M_I_CPU0_SA_CB(1)
  58 M_I_CPU0_SA_CB<4>  CB4_A @T6G_MB_LIB.T6G(SCH_1):M_I_CPU0_SA_CB(4)
 205 M_I_CPU0_SA_CB<7>  CB7_A @T6G_MB_LIB.T6G(SCH_1):M_I_CPU0_SA_CB(7)
 194 M_I_CPU0_SA_DQ<31> DQ31_A @T6G_MB_LIB.T6G(SCH_1):M_I_CPU0_SA_DQ(31)

Q_RES_0402LF-23.2K,1%,1/16W,CHIP,CS32322FB03  I128  R766
   1 PD_CHI_CPU0_DIMM_SAA      A @T6G_MB_LIB.T6G(SCH_1):PD_CHI_CPU0_DIMM_SAA
   2    GND      B @T6G_MB_LIB.T6G(SCH_1):GND

SCONN288_DDR506112002KQ-SCONN288_DDR506112002KQ,SMA  I143  J18
   6    GND   VSS0 @T6G_MB_LIB.T6G(SCH_1):GND
   8    GND   VSS1 @T6G_MB_LIB.T6G(SCH_1):GND
  10    GND   VSS2 @T6G_MB_LIB.T6G(SCH_1):GND
  13    GND   VSS3 @T6G_MB_LIB.T6G(SCH_1):GND
  15    GND   VSS4 @T6G_MB_LIB.T6G(SCH_1):GND
  17    GND   VSS5 @T6G_MB_LIB.T6G(SCH_1):GND
  19    GND   VSS6 @T6G_MB_LIB.T6G(SCH_1):GND
  21    GND   VSS7 @T6G_MB_LIB.T6G(SCH_1):GND
  24    GND   VSS8 @T6G_MB_LIB.T6G(SCH_1):GND
  26    GND   VSS9 @T6G_MB_LIB.T6G(SCH_1):GND
  28    GND  VSS10 @T6G_MB_LIB.T6G(SCH_1):GND
  30    GND  VSS11 @T6G_MB_LIB.T6G(SCH_1):GND
  32    GND  VSS12 @T6G_MB_LIB.T6G(SCH_1):GND
  35    GND  VSS13 @T6G_MB_LIB.T6G(SCH_1):GND
  37    GND  VSS14 @T6G_MB_LIB.T6G(SCH_1):GND
  39    GND  VSS15 @T6G_MB_LIB.T6G(SCH_1):GND
  41    GND  VSS16 @T6G_MB_LIB.T6G(SCH_1):GND
  43    GND  VSS17 @T6G_MB_LIB.T6G(SCH_1):GND
  46    GND  VSS18 @T6G_MB_LIB.T6G(SCH_1):GND
  48    GND  VSS19 @T6G_MB_LIB.T6G(SCH_1):GND
  50    GND  VSS20 @T6G_MB_LIB.T6G(SCH_1):GND
  52    GND  VSS21 @T6G_MB_LIB.T6G(SCH_1):GND
  54    GND  VSS22 @T6G_MB_LIB.T6G(SCH_1):GND
  57    GND  VSS23 @T6G_MB_LIB.T6G(SCH_1):GND
  59    GND  VSS24 @T6G_MB_LIB.T6G(SCH_1):GND
  61    GND  VSS25 @T6G_MB_LIB.T6G(SCH_1):GND
  63    GND  VSS26 @T6G_MB_LIB.T6G(SCH_1):GND
  65    GND  VSS27 @T6G_MB_LIB.T6G(SCH_1):GND
  67    GND  VSS28 @T6G_MB_LIB.T6G(SCH_1):GND
  69    GND  VSS29 @T6G_MB_LIB.T6G(SCH_1):GND
  71    GND  VSS30 @T6G_MB_LIB.T6G(SCH_1):GND
  73    GND  VSS31 @T6G_MB_LIB.T6G(SCH_1):GND
  75    GND  VSS32 @T6G_MB_LIB.T6G(SCH_1):GND
  77    GND  VSS33 @T6G_MB_LIB.T6G(SCH_1):GND
  79    GND  VSS34 @T6G_MB_LIB.T6G(SCH_1):GND
  81    GND  VSS35 @T6G_MB_LIB.T6G(SCH_1):GND
  83    GND  VSS36 @T6G_MB_LIB.T6G(SCH_1):GND
  85    GND  VSS37 @T6G_MB_LIB.T6G(SCH_1):GND
  88    GND  VSS38 @T6G_MB_LIB.T6G(SCH_1):GND
  90    GND  VSS39 @T6G_MB_LIB.T6G(SCH_1):GND
  92    GND  VSS40 @T6G_MB_LIB.T6G(SCH_1):GND
  95    GND  VSS41 @T6G_MB_LIB.T6G(SCH_1):GND
  97    GND  VSS42 @T6G_MB_LIB.T6G(SCH_1):GND
  99    GND  VSS43 @T6G_MB_LIB.T6G(SCH_1):GND
 101    GND  VSS44 @T6G_MB_LIB.T6G(SCH_1):GND
 103    GND  VSS45 @T6G_MB_LIB.T6G(SCH_1):GND
 106    GND  VSS46 @T6G_MB_LIB.T6G(SCH_1):GND
 108    GND  VSS47 @T6G_MB_LIB.T6G(SCH_1):GND
 110    GND  VSS48 @T6G_MB_LIB.T6G(SCH_1):GND
 112    GND  VSS49 @T6G_MB_LIB.T6G(SCH_1):GND
 114    GND  VSS50 @T6G_MB_LIB.T6G(SCH_1):GND
 117    GND  VSS51 @T6G_MB_LIB.T6G(SCH_1):GND
 119    GND  VSS52 @T6G_MB_LIB.T6G(SCH_1):GND
 121    GND  VSS53 @T6G_MB_LIB.T6G(SCH_1):GND
 123    GND  VSS54 @T6G_MB_LIB.T6G(SCH_1):GND
 125    GND  VSS55 @T6G_MB_LIB.T6G(SCH_1):GND
 128    GND  VSS56 @T6G_MB_LIB.T6G(SCH_1):GND
 130    GND  VSS57 @T6G_MB_LIB.T6G(SCH_1):GND
 134    GND  VSS59 @T6G_MB_LIB.T6G(SCH_1):GND
 143    GND  VSS63 @T6G_MB_LIB.T6G(SCH_1):GND
 151    GND  VSS64 @T6G_MB_LIB.T6G(SCH_1):GND
 153    GND  VSS65 @T6G_MB_LIB.T6G(SCH_1):GND
 155    GND  VSS66 @T6G_MB_LIB.T6G(SCH_1):GND
 158    GND  VSS67 @T6G_MB_LIB.T6G(SCH_1):GND
 160    GND  VSS68 @T6G_MB_LIB.T6G(SCH_1):GND
 162    GND  VSS69 @T6G_MB_LIB.T6G(SCH_1):GND
 164    GND  VSS70 @T6G_MB_LIB.T6G(SCH_1):GND
 166    GND  VSS71 @T6G_MB_LIB.T6G(SCH_1):GND
 169    GND  VSS72 @T6G_MB_LIB.T6G(SCH_1):GND
 171    GND  VSS73 @T6G_MB_LIB.T6G(SCH_1):GND
 173    GND  VSS74 @T6G_MB_LIB.T6G(SCH_1):GND
 175    GND  VSS75 @T6G_MB_LIB.T6G(SCH_1):GND
 177    GND  VSS76 @T6G_MB_LIB.T6G(SCH_1):GND
 180    GND  VSS77 @T6G_MB_LIB.T6G(SCH_1):GND
 182    GND  VSS78 @T6G_MB_LIB.T6G(SCH_1):GND
 184    GND  VSS79 @T6G_MB_LIB.T6G(SCH_1):GND
 186    GND  VSS80 @T6G_MB_LIB.T6G(SCH_1):GND
 188    GND  VSS81 @T6G_MB_LIB.T6G(SCH_1):GND
 191    GND  VSS82 @T6G_MB_LIB.T6G(SCH_1):GND
 193    GND  VSS83 @T6G_MB_LIB.T6G(SCH_1):GND
 195    GND  VSS84 @T6G_MB_LIB.T6G(SCH_1):GND
 197    GND  VSS85 @T6G_MB_LIB.T6G(SCH_1):GND
 199    GND  VSS86 @T6G_MB_LIB.T6G(SCH_1):GND
 202    GND  VSS87 @T6G_MB_LIB.T6G(SCH_1):GND
 204    GND  VSS88 @T6G_MB_LIB.T6G(SCH_1):GND
 206    GND  VSS89 @T6G_MB_LIB.T6G(SCH_1):GND
 208    GND  VSS90 @T6G_MB_LIB.T6G(SCH_1):GND
 210    GND  VSS91 @T6G_MB_LIB.T6G(SCH_1):GND
 212    GND  VSS92 @T6G_MB_LIB.T6G(SCH_1):GND
 214    GND  VSS93 @T6G_MB_LIB.T6G(SCH_1):GND
 216    GND  VSS94 @T6G_MB_LIB.T6G(SCH_1):GND
 219    GND  VSS95 @T6G_MB_LIB.T6G(SCH_1):GND
 222    GND  VSS96 @T6G_MB_LIB.T6G(SCH_1):GND
 224    GND  VSS97 @T6G_MB_LIB.T6G(SCH_1):GND
 226    GND  VSS98 @T6G_MB_LIB.T6G(SCH_1):GND
 228    GND  VSS99 @T6G_MB_LIB.T6G(SCH_1):GND
 233    GND VSS101 @T6G_MB_LIB.T6G(SCH_1):GND
 237    GND VSS103 @T6G_MB_LIB.T6G(SCH_1):GND
 242    GND VSS105 @T6G_MB_LIB.T6G(SCH_1):GND
 244    GND VSS106 @T6G_MB_LIB.T6G(SCH_1):GND
 246    GND VSS107 @T6G_MB_LIB.T6G(SCH_1):GND
 248    GND VSS108 @T6G_MB_LIB.T6G(SCH_1):GND
 251    GND VSS109 @T6G_MB_LIB.T6G(SCH_1):GND
 253    GND VSS110 @T6G_MB_LIB.T6G(SCH_1):GND
 255    GND VSS111 @T6G_MB_LIB.T6G(SCH_1):GND
 257    GND VSS112 @T6G_MB_LIB.T6G(SCH_1):GND
 259    GND VSS113 @T6G_MB_LIB.T6G(SCH_1):GND
 262    GND VSS114 @T6G_MB_LIB.T6G(SCH_1):GND
 264    GND VSS115 @T6G_MB_LIB.T6G(SCH_1):GND
 266    GND VSS116 @T6G_MB_LIB.T6G(SCH_1):GND
 268    GND VSS117 @T6G_MB_LIB.T6G(SCH_1):GND
 270    GND VSS118 @T6G_MB_LIB.T6G(SCH_1):GND
 273    GND VSS119 @T6G_MB_LIB.T6G(SCH_1):GND
 275    GND VSS120 @T6G_MB_LIB.T6G(SCH_1):GND
 277    GND VSS121 @T6G_MB_LIB.T6G(SCH_1):GND
 279    GND VSS122 @T6G_MB_LIB.T6G(SCH_1):GND
 281    GND VSS123 @T6G_MB_LIB.T6G(SCH_1):GND
 284    GND VSS124 @T6G_MB_LIB.T6G(SCH_1):GND
 286    GND VSS125 @T6G_MB_LIB.T6G(SCH_1):GND
 288    GND VSS126 @T6G_MB_LIB.T6G(SCH_1):GND
   1 P12V_MEM_CPU0 VIN_BULK0 @T6G_MB_LIB.T6G(SCH_1):P12V_MEM_CPU0
 145 P12V_MEM_CPU0 VIN_BULK1 @T6G_MB_LIB.T6G(SCH_1):P12V_MEM_CPU0
 146 P12V_MEM_CPU0 VIN_BULK2 @T6G_MB_LIB.T6G(SCH_1):P12V_MEM_CPU0
 230    GND VSS100 @T6G_MB_LIB.T6G(SCH_1):GND
 235    GND VSS102 @T6G_MB_LIB.T6G(SCH_1):GND
 240    GND VSS104 @T6G_MB_LIB.T6G(SCH_1):GND
 132    GND  VSS58 @T6G_MB_LIB.T6G(SCH_1):GND
 136    GND  VSS60 @T6G_MB_LIB.T6G(SCH_1):GND
 139    GND  VSS61 @T6G_MB_LIB.T6G(SCH_1):GND
 141    GND  VSS62 @T6G_MB_LIB.T6G(SCH_1):GND
  G1    GND     G1 @T6G_MB_LIB.T6G(SCH_1):GND
  G2    GND     G2 @T6G_MB_LIB.T6G(SCH_1):GND
  G3    GND     G3 @T6G_MB_LIB.T6G(SCH_1):GND

Q_CAP_0402-0.1UF,25V,10%,X7R,CH4104K1B00  I185  C120
   1 P3V3_AUX      A @T6G_MB_LIB.T6G(SCH_1):P3V3_AUX
   2    GND      B @T6G_MB_LIB.T6G(SCH_1):GND

Q_RES_0402LF-1K,1%,1/16W,CHIP,CS21002FB06  I188  R299
   1 PWRGD_CHI_CPU0_DIMM      A @T6G_MB_LIB.T6G(SCH_1):PWRGD_CHI_CPU0_DIMM
   2 PWRGD_CHGL_CPU0      B @T6G_MB_LIB.T6G(SCH_1):PWRGD_CHGL_CPU0

Q_RES_0402LF-1K,1%,1/16W,EMPTY,CS21002FB06  I189  R98
   1   P3V3      A @T6G_MB_LIB.T6G(SCH_1):P3V3
   2 PWRGD_CHI_CPU0_DIMM      B @T6G_MB_LIB.T6G(SCH_1):PWRGD_CHI_CPU0_DIMM

SCONN288_DDR506112002KQ-SCONN288_DDR506112002KQ,SMA  I236  J18
  93 M_I_CPU0_SB_DQS_DP<9> DQS9_B_T||TDQS9_B_T||DBI4_B_N @T6G_MB_LIB.T6G(SCH_1):M_I_CPU0_SB_DQS_DP(9)
  94 M_I_CPU0_SB_DQS_DN<9> DQS9_B_C||TDQS9_B_C @T6G_MB_LIB.T6G(SCH_1):M_I_CPU0_SB_DQS_DN(9)
 201 M_I_CPU0_SA_DQS_DP<9> DQS9_A_T||TDQS9_A_T @T6G_MB_LIB.T6G(SCH_1):M_I_CPU0_SA_DQS_DP(9)
 200 M_I_CPU0_SA_DQS_DN<9> DQS9_A_C||TDQS9_A_C @T6G_MB_LIB.T6G(SCH_1):M_I_CPU0_SA_DQS_DN(9)
 190 M_I_CPU0_SA_DQS_DP<8> DQS8_A_T||TDQS8_A_T @T6G_MB_LIB.T6G(SCH_1):M_I_CPU0_SA_DQS_DP(8)
 189 M_I_CPU0_SA_DQS_DN<8> DQS8_A_C||TDQS8_A_C @T6G_MB_LIB.T6G(SCH_1):M_I_CPU0_SA_DQS_DN(8)
 271 M_I_CPU0_SB_DQS_DN<7> DQS7_B_C||TDQS7_B_C @T6G_MB_LIB.T6G(SCH_1):M_I_CPU0_SB_DQS_DN(7)
 179 M_I_CPU0_SA_DQS_DP<7> DQS7_A_T||TDQS7_A_T @T6G_MB_LIB.T6G(SCH_1):M_I_CPU0_SA_DQS_DP(7)
 261 M_I_CPU0_SB_DQS_DP<6> DQS6_B_T||TDQS6_B_T @T6G_MB_LIB.T6G(SCH_1):M_I_CPU0_SB_DQS_DP(6)
 260 M_I_CPU0_SB_DQS_DN<6> DQS6_B_C||TDQS6_B_C @T6G_MB_LIB.T6G(SCH_1):M_I_CPU0_SB_DQS_DN(6)
 167 M_I_CPU0_SA_DQS_DN<6> DQS6_A_C||TDQS6_A_C||DQS6_A_T||TDQS6_A_T @T6G_MB_LIB.T6G(SCH_1):M_I_CPU0_SA_DQS_DN(6)
 250 M_I_CPU0_SB_DQS_DP<5> DQS5_B_T||TDQS5_B_T @T6G_MB_LIB.T6G(SCH_1):M_I_CPU0_SB_DQS_DP(5)
 249 M_I_CPU0_SB_DQS_DN<5> DQS5_B_C||TDQS5_B_C @T6G_MB_LIB.T6G(SCH_1):M_I_CPU0_SB_DQS_DN(5)
 157 M_I_CPU0_SA_DQS_DP<5> DQS5_A_T||TDQS5_A_T @T6G_MB_LIB.T6G(SCH_1):M_I_CPU0_SA_DQS_DP(5)
 156 M_I_CPU0_SA_DQS_DN<5> DQS5_A_C||TDQS5_A_C||DQS5_A_T||TDQS5_A_T @T6G_MB_LIB.T6G(SCH_1):M_I_CPU0_SA_DQS_DN(5)
 239 M_I_CPU0_SB_DQS_DP<4> DQS4_B_T @T6G_MB_LIB.T6G(SCH_1):M_I_CPU0_SB_DQS_DP(4)
 238 M_I_CPU0_SB_DQS_DN<4> DQS4_B_C @T6G_MB_LIB.T6G(SCH_1):M_I_CPU0_SB_DQS_DN(4)
  55 M_I_CPU0_SA_DQS_DP<4> DQS4_A_T @T6G_MB_LIB.T6G(SCH_1):M_I_CPU0_SA_DQS_DP(4)
  56 M_I_CPU0_SA_DQS_DN<4> DQS4_A_C @T6G_MB_LIB.T6G(SCH_1):M_I_CPU0_SA_DQS_DN(4)
 137 M_I_CPU0_SB_DQS_DP<3> DQS3_B_T @T6G_MB_LIB.T6G(SCH_1):M_I_CPU0_SB_DQS_DP(3)
 138 M_I_CPU0_SB_DQS_DN<3> DQS3_B_C @T6G_MB_LIB.T6G(SCH_1):M_I_CPU0_SB_DQS_DN(3)
  44 M_I_CPU0_SA_DQS_DP<3> DQS3_A_T @T6G_MB_LIB.T6G(SCH_1):M_I_CPU0_SA_DQS_DP(3)
  45 M_I_CPU0_SA_DQS_DN<3> DQS3_A_C @T6G_MB_LIB.T6G(SCH_1):M_I_CPU0_SA_DQS_DN(3)
 126 M_I_CPU0_SB_DQS_DP<2> DQS2_B_T @T6G_MB_LIB.T6G(SCH_1):M_I_CPU0_SB_DQS_DP(2)
 127 M_I_CPU0_SB_DQS_DN<2> DQS2_B_C @T6G_MB_LIB.T6G(SCH_1):M_I_CPU0_SB_DQS_DN(2)
  33 M_I_CPU0_SA_DQS_DP<2> DQS2_A_T @T6G_MB_LIB.T6G(SCH_1):M_I_CPU0_SA_DQS_DP(2)
  34 M_I_CPU0_SA_DQS_DN<2> DQS2_A_C @T6G_MB_LIB.T6G(SCH_1):M_I_CPU0_SA_DQS_DN(2)
 115 M_I_CPU0_SB_DQS_DP<1> DQS1_B_T @T6G_MB_LIB.T6G(SCH_1):M_I_CPU0_SB_DQS_DP(1)
 116 M_I_CPU0_SB_DQS_DN<1> DQS1_B_C @T6G_MB_LIB.T6G(SCH_1):M_I_CPU0_SB_DQS_DN(1)
  22 M_I_CPU0_SA_DQS_DP<1> DQS1_A_T @T6G_MB_LIB.T6G(SCH_1):M_I_CPU0_SA_DQS_DP(1)
  23 M_I_CPU0_SA_DQS_DN<1> DQS1_A_C @T6G_MB_LIB.T6G(SCH_1):M_I_CPU0_SA_DQS_DN(1)
 104 M_I_CPU0_SB_DQS_DP<0> DQS0_B_T @T6G_MB_LIB.T6G(SCH_1):M_I_CPU0_SB_DQS_DP(0)
 105 M_I_CPU0_SB_DQS_DN<0> DQS0_B_C @T6G_MB_LIB.T6G(SCH_1):M_I_CPU0_SB_DQS_DN(0)
  11 M_I_CPU0_SA_DQS_DP<0> DQS0_A_T @T6G_MB_LIB.T6G(SCH_1):M_I_CPU0_SA_DQS_DP(0)
  12 M_I_CPU0_SA_DQS_DN<0> DQS0_A_C @T6G_MB_LIB.T6G(SCH_1):M_I_CPU0_SA_DQS_DN(0)
 272 M_I_CPU0_SB_DQS_DP<7> DQS7_B_T||TDQS7_B_T @T6G_MB_LIB.T6G(SCH_1):M_I_CPU0_SB_DQS_DP(7)
 282 M_I_CPU0_SB_DQS_DN<8> DQS8_B_C||TDQS8_B_C @T6G_MB_LIB.T6G(SCH_1):M_I_CPU0_SB_DQS_DN(8)
 283 M_I_CPU0_SB_DQS_DP<8> DQS8_B_T||TDQS8_B_T @T6G_MB_LIB.T6G(SCH_1):M_I_CPU0_SB_DQS_DP(8)
 168 M_I_CPU0_SA_DQS_DP<6> DQS6_A_T||TDQS6_A_T @T6G_MB_LIB.T6G(SCH_1):M_I_CPU0_SA_DQS_DP(6)
 178 M_I_CPU0_SA_DQS_DN<7> DQS7_A_C||TDQS7_A_C @T6G_MB_LIB.T6G(SCH_1):M_I_CPU0_SA_DQS_DN(7)

Q_CAP_C0805-10UF,25V,10%,X6S,CH6104KEA00  I238  C162
   1 P12V_MEM_CPU0      A @T6G_MB_LIB.T6G(SCH_1):P12V_MEM_CPU0
   2    GND      B @T6G_MB_LIB.T6G(SCH_1):GND

Q_CAP_C0805-10UF,25V,10%,X6S,CH6104KEA00  I239  C163
   1 P12V_MEM_CPU0      A @T6G_MB_LIB.T6G(SCH_1):P12V_MEM_CPU0
   2    GND      B @T6G_MB_LIB.T6G(SCH_1):GND

Q_RES_0402LF-49.9,1%,1/16W,CHIP,CS04992FB07  I242  R1576
   1 I3C_SPD_DDRGL_CPU0_SCL      A @T6G_MB_LIB.T6G(SCH_1):I3C_SPD_DDRGL_CPU0_SCL
   2 I3C_SPD_DDRI_CPU0_SCL      B @T6G_MB_LIB.T6G(SCH_1):I3C_SPD_DDRI_CPU0_SCL

Q_RES_0402LF-10,1%,1/16W,CHIP,CS01002FB07  I243  R1683
   1 I3C_SPD_DDRGL_CPU0_SDA      A @T6G_MB_LIB.T6G(SCH_1):I3C_SPD_DDRGL_CPU0_SDA
   2 I3C_SPD_DDRI_CPU0_SDA      B @T6G_MB_LIB.T6G(SCH_1):I3C_SPD_DDRI_CPU0_SDA


DRAWING: @T6G_MB_LIB.T6G(SCH_1):PAGE94 

SCONN288_DDR506112002KQ-SCONN288_DDR506112002KQ,SMA  I22  J68
   3 P3V3_AUX VIN_MGMT @T6G_MB_LIB.T6G(SCH_1):P3V3_AUX
   2     NC   RFU0     NC
 144     NC   RFU1     NC
 149     NC   RFU2     NC
 150     NC   RFU3     NC
 220     NC   RFU4     NC
 231     NC   RFU5     NC
 232     NC   RFU6     NC
 207 M_J_CPU0_RESET_N RESET_N @T6G_MB_LIB.T6G(SCH_1):M_J_CPU0_RESET_N
 147 PWRGD_CHJ_CPU0_DIMM PWR_GOOD||FAIL_N @T6G_MB_LIB.T6G(SCH_1):PWRGD_CHJ_CPU0_DIMM
 227 M_J_CPU0_SB_PAR  PAR_B @T6G_MB_LIB.T6G(SCH_1):M_J_CPU0_SB_PAR
  74 M_J_CPU0_SA_PAR  PAR_A @T6G_MB_LIB.T6G(SCH_1):M_J_CPU0_SA_PAR
  87 M_J_CPU0_SB_RSP<0> LBS||RSP_B_N @T6G_MB_LIB.T6G(SCH_1):M_J_CPU0_SB_RSP(0)
  86 M_J_CPU0_SA_RSP<0> LBD||RSP_A_N @T6G_MB_LIB.T6G(SCH_1):M_J_CPU0_SA_RSP(0)
   5 I3C_SPD_DDRJ_CPU0_SDA   HSDA @T6G_MB_LIB.T6G(SCH_1):I3C_SPD_DDRJ_CPU0_SDA
   4 I3C_SPD_DDRJ_CPU0_SCL   HSCL @T6G_MB_LIB.T6G(SCH_1):I3C_SPD_DDRJ_CPU0_SCL
 148 PD_CHJ_CPU0_DIMM_SAA    HAS @T6G_MB_LIB.T6G(SCH_1):PD_CHJ_CPU0_DIMM_SAA
 100 M_J_CPU0_SB_DQ<0>  DQ0_B @T6G_MB_LIB.T6G(SCH_1):M_J_CPU0_SB_DQ(0)
 102 M_J_CPU0_SB_DQ<1>  DQ1_B @T6G_MB_LIB.T6G(SCH_1):M_J_CPU0_SB_DQ(1)
 245 M_J_CPU0_SB_DQ<2>  DQ2_B @T6G_MB_LIB.T6G(SCH_1):M_J_CPU0_SB_DQ(2)
 247 M_J_CPU0_SB_DQ<3>  DQ3_B @T6G_MB_LIB.T6G(SCH_1):M_J_CPU0_SB_DQ(3)
 107 M_J_CPU0_SB_DQ<4>  DQ4_B @T6G_MB_LIB.T6G(SCH_1):M_J_CPU0_SB_DQ(4)
 109 M_J_CPU0_SB_DQ<5>  DQ5_B @T6G_MB_LIB.T6G(SCH_1):M_J_CPU0_SB_DQ(5)
 252 M_J_CPU0_SB_DQ<6>  DQ6_B @T6G_MB_LIB.T6G(SCH_1):M_J_CPU0_SB_DQ(6)
 254 M_J_CPU0_SB_DQ<7>  DQ7_B @T6G_MB_LIB.T6G(SCH_1):M_J_CPU0_SB_DQ(7)
 111 M_J_CPU0_SB_DQ<8>  DQ8_B @T6G_MB_LIB.T6G(SCH_1):M_J_CPU0_SB_DQ(8)
 113 M_J_CPU0_SB_DQ<9>  DQ9_B @T6G_MB_LIB.T6G(SCH_1):M_J_CPU0_SB_DQ(9)
 256 M_J_CPU0_SB_DQ<10> DQ10_B @T6G_MB_LIB.T6G(SCH_1):M_J_CPU0_SB_DQ(10)
 258 M_J_CPU0_SB_DQ<11> DQ11_B @T6G_MB_LIB.T6G(SCH_1):M_J_CPU0_SB_DQ(11)
 118 M_J_CPU0_SB_DQ<12> DQ12_B @T6G_MB_LIB.T6G(SCH_1):M_J_CPU0_SB_DQ(12)
 120 M_J_CPU0_SB_DQ<13> DQ13_B @T6G_MB_LIB.T6G(SCH_1):M_J_CPU0_SB_DQ(13)
 263 M_J_CPU0_SB_DQ<14> DQ14_B @T6G_MB_LIB.T6G(SCH_1):M_J_CPU0_SB_DQ(14)
 265 M_J_CPU0_SB_DQ<15> DQ15_B @T6G_MB_LIB.T6G(SCH_1):M_J_CPU0_SB_DQ(15)
 122 M_J_CPU0_SB_DQ<16> DQ16_B @T6G_MB_LIB.T6G(SCH_1):M_J_CPU0_SB_DQ(16)
 124 M_J_CPU0_SB_DQ<17> DQ17_B @T6G_MB_LIB.T6G(SCH_1):M_J_CPU0_SB_DQ(17)
 267 M_J_CPU0_SB_DQ<18> DQ18_B @T6G_MB_LIB.T6G(SCH_1):M_J_CPU0_SB_DQ(18)
 269 M_J_CPU0_SB_DQ<19> DQ19_B @T6G_MB_LIB.T6G(SCH_1):M_J_CPU0_SB_DQ(19)
 129 M_J_CPU0_SB_DQ<20> DQ20_B @T6G_MB_LIB.T6G(SCH_1):M_J_CPU0_SB_DQ(20)
 131 M_J_CPU0_SB_DQ<21> DQ21_B @T6G_MB_LIB.T6G(SCH_1):M_J_CPU0_SB_DQ(21)
 274 M_J_CPU0_SB_DQ<22> DQ22_B @T6G_MB_LIB.T6G(SCH_1):M_J_CPU0_SB_DQ(22)
 276 M_J_CPU0_SB_DQ<23> DQ23_B @T6G_MB_LIB.T6G(SCH_1):M_J_CPU0_SB_DQ(23)
 133 M_J_CPU0_SB_DQ<24> DQ24_B @T6G_MB_LIB.T6G(SCH_1):M_J_CPU0_SB_DQ(24)
 135 M_J_CPU0_SB_DQ<25> DQ25_B @T6G_MB_LIB.T6G(SCH_1):M_J_CPU0_SB_DQ(25)
 278 M_J_CPU0_SB_DQ<26> DQ26_B @T6G_MB_LIB.T6G(SCH_1):M_J_CPU0_SB_DQ(26)
 280 M_J_CPU0_SB_DQ<27> DQ27_B @T6G_MB_LIB.T6G(SCH_1):M_J_CPU0_SB_DQ(27)
 140 M_J_CPU0_SB_DQ<28> DQ28_B @T6G_MB_LIB.T6G(SCH_1):M_J_CPU0_SB_DQ(28)
 142 M_J_CPU0_SB_DQ<29> DQ29_B @T6G_MB_LIB.T6G(SCH_1):M_J_CPU0_SB_DQ(29)
 285 M_J_CPU0_SB_DQ<30> DQ30_B @T6G_MB_LIB.T6G(SCH_1):M_J_CPU0_SB_DQ(30)
 287 M_J_CPU0_SB_DQ<31> DQ31_B @T6G_MB_LIB.T6G(SCH_1):M_J_CPU0_SB_DQ(31)
   7 M_J_CPU0_SA_DQ<0>  DQ0_A @T6G_MB_LIB.T6G(SCH_1):M_J_CPU0_SA_DQ(0)
   9 M_J_CPU0_SA_DQ<1>  DQ1_A @T6G_MB_LIB.T6G(SCH_1):M_J_CPU0_SA_DQ(1)
 152 M_J_CPU0_SA_DQ<2>  DQ2_A @T6G_MB_LIB.T6G(SCH_1):M_J_CPU0_SA_DQ(2)
 154 M_J_CPU0_SA_DQ<3>  DQ3_A @T6G_MB_LIB.T6G(SCH_1):M_J_CPU0_SA_DQ(3)
  14 M_J_CPU0_SA_DQ<4>  DQ4_A @T6G_MB_LIB.T6G(SCH_1):M_J_CPU0_SA_DQ(4)
  16 M_J_CPU0_SA_DQ<5>  DQ5_A @T6G_MB_LIB.T6G(SCH_1):M_J_CPU0_SA_DQ(5)
 159 M_J_CPU0_SA_DQ<6>  DQ6_A @T6G_MB_LIB.T6G(SCH_1):M_J_CPU0_SA_DQ(6)
 161 M_J_CPU0_SA_DQ<7>  DQ7_A @T6G_MB_LIB.T6G(SCH_1):M_J_CPU0_SA_DQ(7)
  18 M_J_CPU0_SA_DQ<8>  DQ8_A @T6G_MB_LIB.T6G(SCH_1):M_J_CPU0_SA_DQ(8)
  20 M_J_CPU0_SA_DQ<9>  DQ9_A @T6G_MB_LIB.T6G(SCH_1):M_J_CPU0_SA_DQ(9)
 163 M_J_CPU0_SA_DQ<10> DQ10_A @T6G_MB_LIB.T6G(SCH_1):M_J_CPU0_SA_DQ(10)
 165 M_J_CPU0_SA_DQ<11> DQ11_A @T6G_MB_LIB.T6G(SCH_1):M_J_CPU0_SA_DQ(11)
  25 M_J_CPU0_SA_DQ<12> DQ12_A @T6G_MB_LIB.T6G(SCH_1):M_J_CPU0_SA_DQ(12)
  27 M_J_CPU0_SA_DQ<13> DQ13_A @T6G_MB_LIB.T6G(SCH_1):M_J_CPU0_SA_DQ(13)
 170 M_J_CPU0_SA_DQ<14> DQ14_A @T6G_MB_LIB.T6G(SCH_1):M_J_CPU0_SA_DQ(14)
 172 M_J_CPU0_SA_DQ<15> DQ15_A @T6G_MB_LIB.T6G(SCH_1):M_J_CPU0_SA_DQ(15)
  29 M_J_CPU0_SA_DQ<16> DQ16_A @T6G_MB_LIB.T6G(SCH_1):M_J_CPU0_SA_DQ(16)
  31 M_J_CPU0_SA_DQ<17> DQ17_A @T6G_MB_LIB.T6G(SCH_1):M_J_CPU0_SA_DQ(17)
 174 M_J_CPU0_SA_DQ<18> DQ18_A @T6G_MB_LIB.T6G(SCH_1):M_J_CPU0_SA_DQ(18)
 176 M_J_CPU0_SA_DQ<19> DQ19_A @T6G_MB_LIB.T6G(SCH_1):M_J_CPU0_SA_DQ(19)
  36 M_J_CPU0_SA_DQ<20> DQ20_A @T6G_MB_LIB.T6G(SCH_1):M_J_CPU0_SA_DQ(20)
  38 M_J_CPU0_SA_DQ<21> DQ21_A @T6G_MB_LIB.T6G(SCH_1):M_J_CPU0_SA_DQ(21)
 181 M_J_CPU0_SA_DQ<22> DQ22_A @T6G_MB_LIB.T6G(SCH_1):M_J_CPU0_SA_DQ(22)
 183 M_J_CPU0_SA_DQ<23> DQ23_A @T6G_MB_LIB.T6G(SCH_1):M_J_CPU0_SA_DQ(23)
  40 M_J_CPU0_SA_DQ<24> DQ24_A @T6G_MB_LIB.T6G(SCH_1):M_J_CPU0_SA_DQ(24)
  42 M_J_CPU0_SA_DQ<25> DQ25_A @T6G_MB_LIB.T6G(SCH_1):M_J_CPU0_SA_DQ(25)
 185 M_J_CPU0_SA_DQ<26> DQ26_A @T6G_MB_LIB.T6G(SCH_1):M_J_CPU0_SA_DQ(26)
 187 M_J_CPU0_SA_DQ<27> DQ27_A @T6G_MB_LIB.T6G(SCH_1):M_J_CPU0_SA_DQ(27)
  47 M_J_CPU0_SA_DQ<28> DQ28_A @T6G_MB_LIB.T6G(SCH_1):M_J_CPU0_SA_DQ(28)
  49 M_J_CPU0_SA_DQ<29> DQ29_A @T6G_MB_LIB.T6G(SCH_1):M_J_CPU0_SA_DQ(29)
 192 M_J_CPU0_SA_DQ<30> DQ30_A @T6G_MB_LIB.T6G(SCH_1):M_J_CPU0_SA_DQ(30)
 229 M_J_CPU0_SB_CS_N<1> CS1_B_N @T6G_MB_LIB.T6G(SCH_1):M_J_CPU0_SB_CS_N(1)
 209 M_J_CPU0_SA_CS_N<1> CS1_A_N @T6G_MB_LIB.T6G(SCH_1):M_J_CPU0_SA_CS_N(1)
  84 M_J_CPU0_SB_CS_N<0> CS0_B_N @T6G_MB_LIB.T6G(SCH_1):M_J_CPU0_SB_CS_N(0)
  64 M_J_CPU0_SA_CS_N<0> CS0_A_N @T6G_MB_LIB.T6G(SCH_1):M_J_CPU0_SA_CS_N(0)
 217 M_J_CPU0_CLK_DP<0>   CK_T @T6G_MB_LIB.T6G(SCH_1):M_J_CPU0_CLK_DP(0)
 218 M_J_CPU0_CLK_DN<0>   CK_C @T6G_MB_LIB.T6G(SCH_1):M_J_CPU0_CLK_DN(0)
  96 M_J_CPU0_SB_CB<0>  CB0_B @T6G_MB_LIB.T6G(SCH_1):M_J_CPU0_SB_CB(0)
  98 M_J_CPU0_SB_CB<1>  CB1_B @T6G_MB_LIB.T6G(SCH_1):M_J_CPU0_SB_CB(1)
 241 M_J_CPU0_SB_CB<2>  CB2_B @T6G_MB_LIB.T6G(SCH_1):M_J_CPU0_SB_CB(2)
 243 M_J_CPU0_SB_CB<3>  CB3_B @T6G_MB_LIB.T6G(SCH_1):M_J_CPU0_SB_CB(3)
  89 M_J_CPU0_SB_CB<4>  CB4_B @T6G_MB_LIB.T6G(SCH_1):M_J_CPU0_SB_CB(4)
  91 M_J_CPU0_SB_CB<5>  CB5_B @T6G_MB_LIB.T6G(SCH_1):M_J_CPU0_SB_CB(5)
 234 M_J_CPU0_SB_CB<6>  CB6_B @T6G_MB_LIB.T6G(SCH_1):M_J_CPU0_SB_CB(6)
  51 M_J_CPU0_SA_CB<0>  CB0_A @T6G_MB_LIB.T6G(SCH_1):M_J_CPU0_SA_CB(0)
 196 M_J_CPU0_SA_CB<2>  CB2_A @T6G_MB_LIB.T6G(SCH_1):M_J_CPU0_SA_CB(2)
 198 M_J_CPU0_SA_CB<3>  CB3_A @T6G_MB_LIB.T6G(SCH_1):M_J_CPU0_SA_CB(3)
  60 M_J_CPU0_SA_CB<5>  CB5_A @T6G_MB_LIB.T6G(SCH_1):M_J_CPU0_SA_CB(5)
 203 M_J_CPU0_SA_CB<6>  CB6_A @T6G_MB_LIB.T6G(SCH_1):M_J_CPU0_SA_CB(6)
  82 M_J_CPU0_SB_CA<6>  CA6_B @T6G_MB_LIB.T6G(SCH_1):M_J_CPU0_SB_CA(6)
  72 M_J_CPU0_SA_CA<6>  CA6_A @T6G_MB_LIB.T6G(SCH_1):M_J_CPU0_SA_CA(6)
 225 M_J_CPU0_SB_CA<5>  CA5_B @T6G_MB_LIB.T6G(SCH_1):M_J_CPU0_SB_CA(5)
 215 M_J_CPU0_SA_CA<5>  CA5_A @T6G_MB_LIB.T6G(SCH_1):M_J_CPU0_SA_CA(5)
  80 M_J_CPU0_SB_CA<4>  CA4_B @T6G_MB_LIB.T6G(SCH_1):M_J_CPU0_SB_CA(4)
  70 M_J_CPU0_SA_CA<4>  CA4_A @T6G_MB_LIB.T6G(SCH_1):M_J_CPU0_SA_CA(4)
 223 M_J_CPU0_SB_CA<3>  CA3_B @T6G_MB_LIB.T6G(SCH_1):M_J_CPU0_SB_CA(3)
 213 M_J_CPU0_SA_CA<3>  CA3_A @T6G_MB_LIB.T6G(SCH_1):M_J_CPU0_SA_CA(3)
  78 M_J_CPU0_SB_CA<2>  CA2_B @T6G_MB_LIB.T6G(SCH_1):M_J_CPU0_SB_CA(2)
  68 M_J_CPU0_SA_CA<2>  CA2_A @T6G_MB_LIB.T6G(SCH_1):M_J_CPU0_SA_CA(2)
 221 M_J_CPU0_SB_CA<1>  CA1_B @T6G_MB_LIB.T6G(SCH_1):M_J_CPU0_SB_CA(1)
 211 M_J_CPU0_SA_CA<1>  CA1_A @T6G_MB_LIB.T6G(SCH_1):M_J_CPU0_SA_CA(1)
  76 M_J_CPU0_SB_CA<0>  CA0_B @T6G_MB_LIB.T6G(SCH_1):M_J_CPU0_SB_CA(0)
  66 M_J_CPU0_SA_CA<0>  CA0_A @T6G_MB_LIB.T6G(SCH_1):M_J_CPU0_SA_CA(0)
  62 M_J_CPU0_ALERT_N ALERT_N @T6G_MB_LIB.T6G(SCH_1):M_J_CPU0_ALERT_N
 236 M_J_CPU0_SB_CB<7>  CB7_B @T6G_MB_LIB.T6G(SCH_1):M_J_CPU0_SB_CB(7)
  53 M_J_CPU0_SA_CB<1>  CB1_A @T6G_MB_LIB.T6G(SCH_1):M_J_CPU0_SA_CB(1)
  58 M_J_CPU0_SA_CB<4>  CB4_A @T6G_MB_LIB.T6G(SCH_1):M_J_CPU0_SA_CB(4)
 205 M_J_CPU0_SA_CB<7>  CB7_A @T6G_MB_LIB.T6G(SCH_1):M_J_CPU0_SA_CB(7)
 194 M_J_CPU0_SA_DQ<31> DQ31_A @T6G_MB_LIB.T6G(SCH_1):M_J_CPU0_SA_DQ(31)

Q_RES_0402LF-35.7K,1%,1/16W,CHIP,CS33572FB01  I129  R767
   1 PD_CHJ_CPU0_DIMM_SAA      A @T6G_MB_LIB.T6G(SCH_1):PD_CHJ_CPU0_DIMM_SAA
   2    GND      B @T6G_MB_LIB.T6G(SCH_1):GND

SCONN288_DDR506112002KQ-SCONN288_DDR506112002KQ,SMA  I177  J68
   6    GND   VSS0 @T6G_MB_LIB.T6G(SCH_1):GND
   8    GND   VSS1 @T6G_MB_LIB.T6G(SCH_1):GND
  10    GND   VSS2 @T6G_MB_LIB.T6G(SCH_1):GND
  13    GND   VSS3 @T6G_MB_LIB.T6G(SCH_1):GND
  15    GND   VSS4 @T6G_MB_LIB.T6G(SCH_1):GND
  17    GND   VSS5 @T6G_MB_LIB.T6G(SCH_1):GND
  19    GND   VSS6 @T6G_MB_LIB.T6G(SCH_1):GND
  21    GND   VSS7 @T6G_MB_LIB.T6G(SCH_1):GND
  24    GND   VSS8 @T6G_MB_LIB.T6G(SCH_1):GND
  26    GND   VSS9 @T6G_MB_LIB.T6G(SCH_1):GND
  28    GND  VSS10 @T6G_MB_LIB.T6G(SCH_1):GND
  30    GND  VSS11 @T6G_MB_LIB.T6G(SCH_1):GND
  32    GND  VSS12 @T6G_MB_LIB.T6G(SCH_1):GND
  35    GND  VSS13 @T6G_MB_LIB.T6G(SCH_1):GND
  37    GND  VSS14 @T6G_MB_LIB.T6G(SCH_1):GND
  39    GND  VSS15 @T6G_MB_LIB.T6G(SCH_1):GND
  41    GND  VSS16 @T6G_MB_LIB.T6G(SCH_1):GND
  43    GND  VSS17 @T6G_MB_LIB.T6G(SCH_1):GND
  46    GND  VSS18 @T6G_MB_LIB.T6G(SCH_1):GND
  48    GND  VSS19 @T6G_MB_LIB.T6G(SCH_1):GND
  50    GND  VSS20 @T6G_MB_LIB.T6G(SCH_1):GND
  52    GND  VSS21 @T6G_MB_LIB.T6G(SCH_1):GND
  54    GND  VSS22 @T6G_MB_LIB.T6G(SCH_1):GND
  57    GND  VSS23 @T6G_MB_LIB.T6G(SCH_1):GND
  59    GND  VSS24 @T6G_MB_LIB.T6G(SCH_1):GND
  61    GND  VSS25 @T6G_MB_LIB.T6G(SCH_1):GND
  63    GND  VSS26 @T6G_MB_LIB.T6G(SCH_1):GND
  65    GND  VSS27 @T6G_MB_LIB.T6G(SCH_1):GND
  67    GND  VSS28 @T6G_MB_LIB.T6G(SCH_1):GND
  69    GND  VSS29 @T6G_MB_LIB.T6G(SCH_1):GND
  71    GND  VSS30 @T6G_MB_LIB.T6G(SCH_1):GND
  73    GND  VSS31 @T6G_MB_LIB.T6G(SCH_1):GND
  75    GND  VSS32 @T6G_MB_LIB.T6G(SCH_1):GND
  77    GND  VSS33 @T6G_MB_LIB.T6G(SCH_1):GND
  79    GND  VSS34 @T6G_MB_LIB.T6G(SCH_1):GND
  81    GND  VSS35 @T6G_MB_LIB.T6G(SCH_1):GND
  83    GND  VSS36 @T6G_MB_LIB.T6G(SCH_1):GND
  85    GND  VSS37 @T6G_MB_LIB.T6G(SCH_1):GND
  88    GND  VSS38 @T6G_MB_LIB.T6G(SCH_1):GND
  90    GND  VSS39 @T6G_MB_LIB.T6G(SCH_1):GND
  92    GND  VSS40 @T6G_MB_LIB.T6G(SCH_1):GND
  95    GND  VSS41 @T6G_MB_LIB.T6G(SCH_1):GND
  97    GND  VSS42 @T6G_MB_LIB.T6G(SCH_1):GND
  99    GND  VSS43 @T6G_MB_LIB.T6G(SCH_1):GND
 101    GND  VSS44 @T6G_MB_LIB.T6G(SCH_1):GND
 103    GND  VSS45 @T6G_MB_LIB.T6G(SCH_1):GND
 106    GND  VSS46 @T6G_MB_LIB.T6G(SCH_1):GND
 108    GND  VSS47 @T6G_MB_LIB.T6G(SCH_1):GND
 110    GND  VSS48 @T6G_MB_LIB.T6G(SCH_1):GND
 112    GND  VSS49 @T6G_MB_LIB.T6G(SCH_1):GND
 114    GND  VSS50 @T6G_MB_LIB.T6G(SCH_1):GND
 117    GND  VSS51 @T6G_MB_LIB.T6G(SCH_1):GND
 119    GND  VSS52 @T6G_MB_LIB.T6G(SCH_1):GND
 121    GND  VSS53 @T6G_MB_LIB.T6G(SCH_1):GND
 123    GND  VSS54 @T6G_MB_LIB.T6G(SCH_1):GND
 125    GND  VSS55 @T6G_MB_LIB.T6G(SCH_1):GND
 128    GND  VSS56 @T6G_MB_LIB.T6G(SCH_1):GND
 130    GND  VSS57 @T6G_MB_LIB.T6G(SCH_1):GND
 134    GND  VSS59 @T6G_MB_LIB.T6G(SCH_1):GND
 143    GND  VSS63 @T6G_MB_LIB.T6G(SCH_1):GND
 151    GND  VSS64 @T6G_MB_LIB.T6G(SCH_1):GND
 153    GND  VSS65 @T6G_MB_LIB.T6G(SCH_1):GND
 155    GND  VSS66 @T6G_MB_LIB.T6G(SCH_1):GND
 158    GND  VSS67 @T6G_MB_LIB.T6G(SCH_1):GND
 160    GND  VSS68 @T6G_MB_LIB.T6G(SCH_1):GND
 162    GND  VSS69 @T6G_MB_LIB.T6G(SCH_1):GND
 164    GND  VSS70 @T6G_MB_LIB.T6G(SCH_1):GND
 166    GND  VSS71 @T6G_MB_LIB.T6G(SCH_1):GND
 169    GND  VSS72 @T6G_MB_LIB.T6G(SCH_1):GND
 171    GND  VSS73 @T6G_MB_LIB.T6G(SCH_1):GND
 173    GND  VSS74 @T6G_MB_LIB.T6G(SCH_1):GND
 175    GND  VSS75 @T6G_MB_LIB.T6G(SCH_1):GND
 177    GND  VSS76 @T6G_MB_LIB.T6G(SCH_1):GND
 180    GND  VSS77 @T6G_MB_LIB.T6G(SCH_1):GND
 182    GND  VSS78 @T6G_MB_LIB.T6G(SCH_1):GND
 184    GND  VSS79 @T6G_MB_LIB.T6G(SCH_1):GND
 186    GND  VSS80 @T6G_MB_LIB.T6G(SCH_1):GND
 188    GND  VSS81 @T6G_MB_LIB.T6G(SCH_1):GND
 191    GND  VSS82 @T6G_MB_LIB.T6G(SCH_1):GND
 193    GND  VSS83 @T6G_MB_LIB.T6G(SCH_1):GND
 195    GND  VSS84 @T6G_MB_LIB.T6G(SCH_1):GND
 197    GND  VSS85 @T6G_MB_LIB.T6G(SCH_1):GND
 199    GND  VSS86 @T6G_MB_LIB.T6G(SCH_1):GND
 202    GND  VSS87 @T6G_MB_LIB.T6G(SCH_1):GND
 204    GND  VSS88 @T6G_MB_LIB.T6G(SCH_1):GND
 206    GND  VSS89 @T6G_MB_LIB.T6G(SCH_1):GND
 208    GND  VSS90 @T6G_MB_LIB.T6G(SCH_1):GND
 210    GND  VSS91 @T6G_MB_LIB.T6G(SCH_1):GND
 212    GND  VSS92 @T6G_MB_LIB.T6G(SCH_1):GND
 214    GND  VSS93 @T6G_MB_LIB.T6G(SCH_1):GND
 216    GND  VSS94 @T6G_MB_LIB.T6G(SCH_1):GND
 219    GND  VSS95 @T6G_MB_LIB.T6G(SCH_1):GND
 222    GND  VSS96 @T6G_MB_LIB.T6G(SCH_1):GND
 224    GND  VSS97 @T6G_MB_LIB.T6G(SCH_1):GND
 226    GND  VSS98 @T6G_MB_LIB.T6G(SCH_1):GND
 228    GND  VSS99 @T6G_MB_LIB.T6G(SCH_1):GND
 233    GND VSS101 @T6G_MB_LIB.T6G(SCH_1):GND
 237    GND VSS103 @T6G_MB_LIB.T6G(SCH_1):GND
 242    GND VSS105 @T6G_MB_LIB.T6G(SCH_1):GND
 244    GND VSS106 @T6G_MB_LIB.T6G(SCH_1):GND
 246    GND VSS107 @T6G_MB_LIB.T6G(SCH_1):GND
 248    GND VSS108 @T6G_MB_LIB.T6G(SCH_1):GND
 251    GND VSS109 @T6G_MB_LIB.T6G(SCH_1):GND
 253    GND VSS110 @T6G_MB_LIB.T6G(SCH_1):GND
 255    GND VSS111 @T6G_MB_LIB.T6G(SCH_1):GND
 257    GND VSS112 @T6G_MB_LIB.T6G(SCH_1):GND
 259    GND VSS113 @T6G_MB_LIB.T6G(SCH_1):GND
 262    GND VSS114 @T6G_MB_LIB.T6G(SCH_1):GND
 264    GND VSS115 @T6G_MB_LIB.T6G(SCH_1):GND
 266    GND VSS116 @T6G_MB_LIB.T6G(SCH_1):GND
 268    GND VSS117 @T6G_MB_LIB.T6G(SCH_1):GND
 270    GND VSS118 @T6G_MB_LIB.T6G(SCH_1):GND
 273    GND VSS119 @T6G_MB_LIB.T6G(SCH_1):GND
 275    GND VSS120 @T6G_MB_LIB.T6G(SCH_1):GND
 277    GND VSS121 @T6G_MB_LIB.T6G(SCH_1):GND
 279    GND VSS122 @T6G_MB_LIB.T6G(SCH_1):GND
 281    GND VSS123 @T6G_MB_LIB.T6G(SCH_1):GND
 284    GND VSS124 @T6G_MB_LIB.T6G(SCH_1):GND
 286    GND VSS125 @T6G_MB_LIB.T6G(SCH_1):GND
 288    GND VSS126 @T6G_MB_LIB.T6G(SCH_1):GND
   1 P12V_MEM_CPU0 VIN_BULK0 @T6G_MB_LIB.T6G(SCH_1):P12V_MEM_CPU0
 145 P12V_MEM_CPU0 VIN_BULK1 @T6G_MB_LIB.T6G(SCH_1):P12V_MEM_CPU0
 146 P12V_MEM_CPU0 VIN_BULK2 @T6G_MB_LIB.T6G(SCH_1):P12V_MEM_CPU0
 230    GND VSS100 @T6G_MB_LIB.T6G(SCH_1):GND
 235    GND VSS102 @T6G_MB_LIB.T6G(SCH_1):GND
 240    GND VSS104 @T6G_MB_LIB.T6G(SCH_1):GND
 132    GND  VSS58 @T6G_MB_LIB.T6G(SCH_1):GND
 136    GND  VSS60 @T6G_MB_LIB.T6G(SCH_1):GND
 139    GND  VSS61 @T6G_MB_LIB.T6G(SCH_1):GND
 141    GND  VSS62 @T6G_MB_LIB.T6G(SCH_1):GND
  G1    GND     G1 @T6G_MB_LIB.T6G(SCH_1):GND
  G2    GND     G2 @T6G_MB_LIB.T6G(SCH_1):GND
  G3    GND     G3 @T6G_MB_LIB.T6G(SCH_1):GND

Q_CAP_0402-0.1UF,25V,10%,X7R,CH4104K1B00  I185  C124
   1 P3V3_AUX      A @T6G_MB_LIB.T6G(SCH_1):P3V3_AUX
   2    GND      B @T6G_MB_LIB.T6G(SCH_1):GND

Q_RES_0402LF-1K,1%,1/16W,CHIP,CS21002FB06  I188  R300
   1 PWRGD_CHJ_CPU0_DIMM      A @T6G_MB_LIB.T6G(SCH_1):PWRGD_CHJ_CPU0_DIMM
   2 PWRGD_CHGL_CPU0      B @T6G_MB_LIB.T6G(SCH_1):PWRGD_CHGL_CPU0

Q_RES_0402LF-1K,1%,1/16W,EMPTY,CS21002FB06  I189  R99
   1   P3V3      A @T6G_MB_LIB.T6G(SCH_1):P3V3
   2 PWRGD_CHJ_CPU0_DIMM      B @T6G_MB_LIB.T6G(SCH_1):PWRGD_CHJ_CPU0_DIMM

SCONN288_DDR506112002KQ-SCONN288_DDR506112002KQ,SMA  I236  J68
  93 M_J_CPU0_SB_DQS_DP<9> DQS9_B_T||TDQS9_B_T||DBI4_B_N @T6G_MB_LIB.T6G(SCH_1):M_J_CPU0_SB_DQS_DP(9)
  94 M_J_CPU0_SB_DQS_DN<9> DQS9_B_C||TDQS9_B_C @T6G_MB_LIB.T6G(SCH_1):M_J_CPU0_SB_DQS_DN(9)
 201 M_J_CPU0_SA_DQS_DP<9> DQS9_A_T||TDQS9_A_T @T6G_MB_LIB.T6G(SCH_1):M_J_CPU0_SA_DQS_DP(9)
 200 M_J_CPU0_SA_DQS_DN<9> DQS9_A_C||TDQS9_A_C @T6G_MB_LIB.T6G(SCH_1):M_J_CPU0_SA_DQS_DN(9)
 190 M_J_CPU0_SA_DQS_DP<8> DQS8_A_T||TDQS8_A_T @T6G_MB_LIB.T6G(SCH_1):M_J_CPU0_SA_DQS_DP(8)
 189 M_J_CPU0_SA_DQS_DN<8> DQS8_A_C||TDQS8_A_C @T6G_MB_LIB.T6G(SCH_1):M_J_CPU0_SA_DQS_DN(8)
 271 M_J_CPU0_SB_DQS_DN<7> DQS7_B_C||TDQS7_B_C @T6G_MB_LIB.T6G(SCH_1):M_J_CPU0_SB_DQS_DN(7)
 179 M_J_CPU0_SA_DQS_DP<7> DQS7_A_T||TDQS7_A_T @T6G_MB_LIB.T6G(SCH_1):M_J_CPU0_SA_DQS_DP(7)
 261 M_J_CPU0_SB_DQS_DP<6> DQS6_B_T||TDQS6_B_T @T6G_MB_LIB.T6G(SCH_1):M_J_CPU0_SB_DQS_DP(6)
 260 M_J_CPU0_SB_DQS_DN<6> DQS6_B_C||TDQS6_B_C @T6G_MB_LIB.T6G(SCH_1):M_J_CPU0_SB_DQS_DN(6)
 167 M_J_CPU0_SA_DQS_DN<6> DQS6_A_C||TDQS6_A_C||DQS6_A_T||TDQS6_A_T @T6G_MB_LIB.T6G(SCH_1):M_J_CPU0_SA_DQS_DN(6)
 250 M_J_CPU0_SB_DQS_DP<5> DQS5_B_T||TDQS5_B_T @T6G_MB_LIB.T6G(SCH_1):M_J_CPU0_SB_DQS_DP(5)
 249 M_J_CPU0_SB_DQS_DN<5> DQS5_B_C||TDQS5_B_C @T6G_MB_LIB.T6G(SCH_1):M_J_CPU0_SB_DQS_DN(5)
 157 M_J_CPU0_SA_DQS_DP<5> DQS5_A_T||TDQS5_A_T @T6G_MB_LIB.T6G(SCH_1):M_J_CPU0_SA_DQS_DP(5)
 156 M_J_CPU0_SA_DQS_DN<5> DQS5_A_C||TDQS5_A_C||DQS5_A_T||TDQS5_A_T @T6G_MB_LIB.T6G(SCH_1):M_J_CPU0_SA_DQS_DN(5)
 239 M_J_CPU0_SB_DQS_DP<4> DQS4_B_T @T6G_MB_LIB.T6G(SCH_1):M_J_CPU0_SB_DQS_DP(4)
 238 M_J_CPU0_SB_DQS_DN<4> DQS4_B_C @T6G_MB_LIB.T6G(SCH_1):M_J_CPU0_SB_DQS_DN(4)
  55 M_J_CPU0_SA_DQS_DP<4> DQS4_A_T @T6G_MB_LIB.T6G(SCH_1):M_J_CPU0_SA_DQS_DP(4)
  56 M_J_CPU0_SA_DQS_DN<4> DQS4_A_C @T6G_MB_LIB.T6G(SCH_1):M_J_CPU0_SA_DQS_DN(4)
 137 M_J_CPU0_SB_DQS_DP<3> DQS3_B_T @T6G_MB_LIB.T6G(SCH_1):M_J_CPU0_SB_DQS_DP(3)
 138 M_J_CPU0_SB_DQS_DN<3> DQS3_B_C @T6G_MB_LIB.T6G(SCH_1):M_J_CPU0_SB_DQS_DN(3)
  44 M_J_CPU0_SA_DQS_DP<3> DQS3_A_T @T6G_MB_LIB.T6G(SCH_1):M_J_CPU0_SA_DQS_DP(3)
  45 M_J_CPU0_SA_DQS_DN<3> DQS3_A_C @T6G_MB_LIB.T6G(SCH_1):M_J_CPU0_SA_DQS_DN(3)
 126 M_J_CPU0_SB_DQS_DP<2> DQS2_B_T @T6G_MB_LIB.T6G(SCH_1):M_J_CPU0_SB_DQS_DP(2)
 127 M_J_CPU0_SB_DQS_DN<2> DQS2_B_C @T6G_MB_LIB.T6G(SCH_1):M_J_CPU0_SB_DQS_DN(2)
  33 M_J_CPU0_SA_DQS_DP<2> DQS2_A_T @T6G_MB_LIB.T6G(SCH_1):M_J_CPU0_SA_DQS_DP(2)
  34 M_J_CPU0_SA_DQS_DN<2> DQS2_A_C @T6G_MB_LIB.T6G(SCH_1):M_J_CPU0_SA_DQS_DN(2)
 115 M_J_CPU0_SB_DQS_DP<1> DQS1_B_T @T6G_MB_LIB.T6G(SCH_1):M_J_CPU0_SB_DQS_DP(1)
 116 M_J_CPU0_SB_DQS_DN<1> DQS1_B_C @T6G_MB_LIB.T6G(SCH_1):M_J_CPU0_SB_DQS_DN(1)
  22 M_J_CPU0_SA_DQS_DP<1> DQS1_A_T @T6G_MB_LIB.T6G(SCH_1):M_J_CPU0_SA_DQS_DP(1)
  23 M_J_CPU0_SA_DQS_DN<1> DQS1_A_C @T6G_MB_LIB.T6G(SCH_1):M_J_CPU0_SA_DQS_DN(1)
 104 M_J_CPU0_SB_DQS_DP<0> DQS0_B_T @T6G_MB_LIB.T6G(SCH_1):M_J_CPU0_SB_DQS_DP(0)
 105 M_J_CPU0_SB_DQS_DN<0> DQS0_B_C @T6G_MB_LIB.T6G(SCH_1):M_J_CPU0_SB_DQS_DN(0)
  11 M_J_CPU0_SA_DQS_DP<0> DQS0_A_T @T6G_MB_LIB.T6G(SCH_1):M_J_CPU0_SA_DQS_DP(0)
  12 M_J_CPU0_SA_DQS_DN<0> DQS0_A_C @T6G_MB_LIB.T6G(SCH_1):M_J_CPU0_SA_DQS_DN(0)
 272 M_J_CPU0_SB_DQS_DP<7> DQS7_B_T||TDQS7_B_T @T6G_MB_LIB.T6G(SCH_1):M_J_CPU0_SB_DQS_DP(7)
 282 M_J_CPU0_SB_DQS_DN<8> DQS8_B_C||TDQS8_B_C @T6G_MB_LIB.T6G(SCH_1):M_J_CPU0_SB_DQS_DN(8)
 283 M_J_CPU0_SB_DQS_DP<8> DQS8_B_T||TDQS8_B_T @T6G_MB_LIB.T6G(SCH_1):M_J_CPU0_SB_DQS_DP(8)
 168 M_J_CPU0_SA_DQS_DP<6> DQS6_A_T||TDQS6_A_T @T6G_MB_LIB.T6G(SCH_1):M_J_CPU0_SA_DQS_DP(6)
 178 M_J_CPU0_SA_DQS_DN<7> DQS7_A_C||TDQS7_A_C @T6G_MB_LIB.T6G(SCH_1):M_J_CPU0_SA_DQS_DN(7)

Q_CAP_C0805-10UF,25V,10%,X6S,CH6104KEA00  I238  C165
   1 P12V_MEM_CPU0      A @T6G_MB_LIB.T6G(SCH_1):P12V_MEM_CPU0
   2    GND      B @T6G_MB_LIB.T6G(SCH_1):GND

Q_CAP_C0805-10UF,25V,10%,X6S,CH6104KEA00  I239  C166
   1 P12V_MEM_CPU0      A @T6G_MB_LIB.T6G(SCH_1):P12V_MEM_CPU0
   2    GND      B @T6G_MB_LIB.T6G(SCH_1):GND

Q_RES_0402LF-49.9,1%,1/16W,CHIP,CS04992FB07  I242  R1577
   1 I3C_SPD_DDRGL_CPU0_SCL      A @T6G_MB_LIB.T6G(SCH_1):I3C_SPD_DDRGL_CPU0_SCL
   2 I3C_SPD_DDRJ_CPU0_SCL      B @T6G_MB_LIB.T6G(SCH_1):I3C_SPD_DDRJ_CPU0_SCL

Q_RES_0402LF-10,1%,1/16W,CHIP,CS01002FB07  I243  R1684
   1 I3C_SPD_DDRGL_CPU0_SDA      A @T6G_MB_LIB.T6G(SCH_1):I3C_SPD_DDRGL_CPU0_SDA
   2 I3C_SPD_DDRJ_CPU0_SDA      B @T6G_MB_LIB.T6G(SCH_1):I3C_SPD_DDRJ_CPU0_SDA


DRAWING: @T6G_MB_LIB.T6G(SCH_1):PAGE95 

SCONN288_DDR506112002KQ-SCONN288_DDR506112002KQ,SMA  I22  J20
   3 P3V3_AUX VIN_MGMT @T6G_MB_LIB.T6G(SCH_1):P3V3_AUX
   2     NC   RFU0     NC
 144     NC   RFU1     NC
 149     NC   RFU2     NC
 150     NC   RFU3     NC
 220     NC   RFU4     NC
 231     NC   RFU5     NC
 232     NC   RFU6     NC
 207 M_K_CPU0_RESET_N RESET_N @T6G_MB_LIB.T6G(SCH_1):M_K_CPU0_RESET_N
 147 PWRGD_CHK_CPU0_DIMM PWR_GOOD||FAIL_N @T6G_MB_LIB.T6G(SCH_1):PWRGD_CHK_CPU0_DIMM
 227 M_K_CPU0_SB_PAR  PAR_B @T6G_MB_LIB.T6G(SCH_1):M_K_CPU0_SB_PAR
  74 M_K_CPU0_SA_PAR  PAR_A @T6G_MB_LIB.T6G(SCH_1):M_K_CPU0_SA_PAR
  87 M_K_CPU0_SB_RSP<0> LBS||RSP_B_N @T6G_MB_LIB.T6G(SCH_1):M_K_CPU0_SB_RSP(0)
  86 M_K_CPU0_SA_RSP<0> LBD||RSP_A_N @T6G_MB_LIB.T6G(SCH_1):M_K_CPU0_SA_RSP(0)
   5 I3C_SPD_DDRK_CPU0_SDA   HSDA @T6G_MB_LIB.T6G(SCH_1):I3C_SPD_DDRK_CPU0_SDA
   4 I3C_SPD_DDRK_CPU0_SCL   HSCL @T6G_MB_LIB.T6G(SCH_1):I3C_SPD_DDRK_CPU0_SCL
 148 PD_CHK_CPU0_DIMM_SAA    HAS @T6G_MB_LIB.T6G(SCH_1):PD_CHK_CPU0_DIMM_SAA
 100 M_K_CPU0_SB_DQ<0>  DQ0_B @T6G_MB_LIB.T6G(SCH_1):M_K_CPU0_SB_DQ(0)
 102 M_K_CPU0_SB_DQ<1>  DQ1_B @T6G_MB_LIB.T6G(SCH_1):M_K_CPU0_SB_DQ(1)
 245 M_K_CPU0_SB_DQ<2>  DQ2_B @T6G_MB_LIB.T6G(SCH_1):M_K_CPU0_SB_DQ(2)
 247 M_K_CPU0_SB_DQ<3>  DQ3_B @T6G_MB_LIB.T6G(SCH_1):M_K_CPU0_SB_DQ(3)
 107 M_K_CPU0_SB_DQ<4>  DQ4_B @T6G_MB_LIB.T6G(SCH_1):M_K_CPU0_SB_DQ(4)
 109 M_K_CPU0_SB_DQ<5>  DQ5_B @T6G_MB_LIB.T6G(SCH_1):M_K_CPU0_SB_DQ(5)
 252 M_K_CPU0_SB_DQ<6>  DQ6_B @T6G_MB_LIB.T6G(SCH_1):M_K_CPU0_SB_DQ(6)
 254 M_K_CPU0_SB_DQ<7>  DQ7_B @T6G_MB_LIB.T6G(SCH_1):M_K_CPU0_SB_DQ(7)
 111 M_K_CPU0_SB_DQ<8>  DQ8_B @T6G_MB_LIB.T6G(SCH_1):M_K_CPU0_SB_DQ(8)
 113 M_K_CPU0_SB_DQ<9>  DQ9_B @T6G_MB_LIB.T6G(SCH_1):M_K_CPU0_SB_DQ(9)
 256 M_K_CPU0_SB_DQ<10> DQ10_B @T6G_MB_LIB.T6G(SCH_1):M_K_CPU0_SB_DQ(10)
 258 M_K_CPU0_SB_DQ<11> DQ11_B @T6G_MB_LIB.T6G(SCH_1):M_K_CPU0_SB_DQ(11)
 118 M_K_CPU0_SB_DQ<12> DQ12_B @T6G_MB_LIB.T6G(SCH_1):M_K_CPU0_SB_DQ(12)
 120 M_K_CPU0_SB_DQ<13> DQ13_B @T6G_MB_LIB.T6G(SCH_1):M_K_CPU0_SB_DQ(13)
 263 M_K_CPU0_SB_DQ<14> DQ14_B @T6G_MB_LIB.T6G(SCH_1):M_K_CPU0_SB_DQ(14)
 265 M_K_CPU0_SB_DQ<15> DQ15_B @T6G_MB_LIB.T6G(SCH_1):M_K_CPU0_SB_DQ(15)
 122 M_K_CPU0_SB_DQ<16> DQ16_B @T6G_MB_LIB.T6G(SCH_1):M_K_CPU0_SB_DQ(16)
 124 M_K_CPU0_SB_DQ<17> DQ17_B @T6G_MB_LIB.T6G(SCH_1):M_K_CPU0_SB_DQ(17)
 267 M_K_CPU0_SB_DQ<18> DQ18_B @T6G_MB_LIB.T6G(SCH_1):M_K_CPU0_SB_DQ(18)
 269 M_K_CPU0_SB_DQ<19> DQ19_B @T6G_MB_LIB.T6G(SCH_1):M_K_CPU0_SB_DQ(19)
 129 M_K_CPU0_SB_DQ<20> DQ20_B @T6G_MB_LIB.T6G(SCH_1):M_K_CPU0_SB_DQ(20)
 131 M_K_CPU0_SB_DQ<21> DQ21_B @T6G_MB_LIB.T6G(SCH_1):M_K_CPU0_SB_DQ(21)
 274 M_K_CPU0_SB_DQ<22> DQ22_B @T6G_MB_LIB.T6G(SCH_1):M_K_CPU0_SB_DQ(22)
 276 M_K_CPU0_SB_DQ<23> DQ23_B @T6G_MB_LIB.T6G(SCH_1):M_K_CPU0_SB_DQ(23)
 133 M_K_CPU0_SB_DQ<24> DQ24_B @T6G_MB_LIB.T6G(SCH_1):M_K_CPU0_SB_DQ(24)
 135 M_K_CPU0_SB_DQ<25> DQ25_B @T6G_MB_LIB.T6G(SCH_1):M_K_CPU0_SB_DQ(25)
 278 M_K_CPU0_SB_DQ<26> DQ26_B @T6G_MB_LIB.T6G(SCH_1):M_K_CPU0_SB_DQ(26)
 280 M_K_CPU0_SB_DQ<27> DQ27_B @T6G_MB_LIB.T6G(SCH_1):M_K_CPU0_SB_DQ(27)
 140 M_K_CPU0_SB_DQ<28> DQ28_B @T6G_MB_LIB.T6G(SCH_1):M_K_CPU0_SB_DQ(28)
 142 M_K_CPU0_SB_DQ<29> DQ29_B @T6G_MB_LIB.T6G(SCH_1):M_K_CPU0_SB_DQ(29)
 285 M_K_CPU0_SB_DQ<30> DQ30_B @T6G_MB_LIB.T6G(SCH_1):M_K_CPU0_SB_DQ(30)
 287 M_K_CPU0_SB_DQ<31> DQ31_B @T6G_MB_LIB.T6G(SCH_1):M_K_CPU0_SB_DQ(31)
   7 M_K_CPU0_SA_DQ<0>  DQ0_A @T6G_MB_LIB.T6G(SCH_1):M_K_CPU0_SA_DQ(0)
   9 M_K_CPU0_SA_DQ<1>  DQ1_A @T6G_MB_LIB.T6G(SCH_1):M_K_CPU0_SA_DQ(1)
 152 M_K_CPU0_SA_DQ<2>  DQ2_A @T6G_MB_LIB.T6G(SCH_1):M_K_CPU0_SA_DQ(2)
 154 M_K_CPU0_SA_DQ<3>  DQ3_A @T6G_MB_LIB.T6G(SCH_1):M_K_CPU0_SA_DQ(3)
  14 M_K_CPU0_SA_DQ<4>  DQ4_A @T6G_MB_LIB.T6G(SCH_1):M_K_CPU0_SA_DQ(4)
  16 M_K_CPU0_SA_DQ<5>  DQ5_A @T6G_MB_LIB.T6G(SCH_1):M_K_CPU0_SA_DQ(5)
 159 M_K_CPU0_SA_DQ<6>  DQ6_A @T6G_MB_LIB.T6G(SCH_1):M_K_CPU0_SA_DQ(6)
 161 M_K_CPU0_SA_DQ<7>  DQ7_A @T6G_MB_LIB.T6G(SCH_1):M_K_CPU0_SA_DQ(7)
  18 M_K_CPU0_SA_DQ<8>  DQ8_A @T6G_MB_LIB.T6G(SCH_1):M_K_CPU0_SA_DQ(8)
  20 M_K_CPU0_SA_DQ<9>  DQ9_A @T6G_MB_LIB.T6G(SCH_1):M_K_CPU0_SA_DQ(9)
 163 M_K_CPU0_SA_DQ<10> DQ10_A @T6G_MB_LIB.T6G(SCH_1):M_K_CPU0_SA_DQ(10)
 165 M_K_CPU0_SA_DQ<11> DQ11_A @T6G_MB_LIB.T6G(SCH_1):M_K_CPU0_SA_DQ(11)
  25 M_K_CPU0_SA_DQ<12> DQ12_A @T6G_MB_LIB.T6G(SCH_1):M_K_CPU0_SA_DQ(12)
  27 M_K_CPU0_SA_DQ<13> DQ13_A @T6G_MB_LIB.T6G(SCH_1):M_K_CPU0_SA_DQ(13)
 170 M_K_CPU0_SA_DQ<14> DQ14_A @T6G_MB_LIB.T6G(SCH_1):M_K_CPU0_SA_DQ(14)
 172 M_K_CPU0_SA_DQ<15> DQ15_A @T6G_MB_LIB.T6G(SCH_1):M_K_CPU0_SA_DQ(15)
  29 M_K_CPU0_SA_DQ<16> DQ16_A @T6G_MB_LIB.T6G(SCH_1):M_K_CPU0_SA_DQ(16)
  31 M_K_CPU0_SA_DQ<17> DQ17_A @T6G_MB_LIB.T6G(SCH_1):M_K_CPU0_SA_DQ(17)
 174 M_K_CPU0_SA_DQ<18> DQ18_A @T6G_MB_LIB.T6G(SCH_1):M_K_CPU0_SA_DQ(18)
 176 M_K_CPU0_SA_DQ<19> DQ19_A @T6G_MB_LIB.T6G(SCH_1):M_K_CPU0_SA_DQ(19)
  36 M_K_CPU0_SA_DQ<20> DQ20_A @T6G_MB_LIB.T6G(SCH_1):M_K_CPU0_SA_DQ(20)
  38 M_K_CPU0_SA_DQ<21> DQ21_A @T6G_MB_LIB.T6G(SCH_1):M_K_CPU0_SA_DQ(21)
 181 M_K_CPU0_SA_DQ<22> DQ22_A @T6G_MB_LIB.T6G(SCH_1):M_K_CPU0_SA_DQ(22)
 183 M_K_CPU0_SA_DQ<23> DQ23_A @T6G_MB_LIB.T6G(SCH_1):M_K_CPU0_SA_DQ(23)
  40 M_K_CPU0_SA_DQ<24> DQ24_A @T6G_MB_LIB.T6G(SCH_1):M_K_CPU0_SA_DQ(24)
  42 M_K_CPU0_SA_DQ<25> DQ25_A @T6G_MB_LIB.T6G(SCH_1):M_K_CPU0_SA_DQ(25)
 185 M_K_CPU0_SA_DQ<26> DQ26_A @T6G_MB_LIB.T6G(SCH_1):M_K_CPU0_SA_DQ(26)
 187 M_K_CPU0_SA_DQ<27> DQ27_A @T6G_MB_LIB.T6G(SCH_1):M_K_CPU0_SA_DQ(27)
  47 M_K_CPU0_SA_DQ<28> DQ28_A @T6G_MB_LIB.T6G(SCH_1):M_K_CPU0_SA_DQ(28)
  49 M_K_CPU0_SA_DQ<29> DQ29_A @T6G_MB_LIB.T6G(SCH_1):M_K_CPU0_SA_DQ(29)
 192 M_K_CPU0_SA_DQ<30> DQ30_A @T6G_MB_LIB.T6G(SCH_1):M_K_CPU0_SA_DQ(30)
 229 M_K_CPU0_SB_CS_N<1> CS1_B_N @T6G_MB_LIB.T6G(SCH_1):M_K_CPU0_SB_CS_N(1)
 209 M_K_CPU0_SA_CS_N<1> CS1_A_N @T6G_MB_LIB.T6G(SCH_1):M_K_CPU0_SA_CS_N(1)
  84 M_K_CPU0_SB_CS_N<0> CS0_B_N @T6G_MB_LIB.T6G(SCH_1):M_K_CPU0_SB_CS_N(0)
  64 M_K_CPU0_SA_CS_N<0> CS0_A_N @T6G_MB_LIB.T6G(SCH_1):M_K_CPU0_SA_CS_N(0)
 217 M_K_CPU0_CLK_DP<0>   CK_T @T6G_MB_LIB.T6G(SCH_1):M_K_CPU0_CLK_DP(0)
 218 M_K_CPU0_CLK_DN<0>   CK_C @T6G_MB_LIB.T6G(SCH_1):M_K_CPU0_CLK_DN(0)
  96 M_K_CPU0_SB_CB<0>  CB0_B @T6G_MB_LIB.T6G(SCH_1):M_K_CPU0_SB_CB(0)
  98 M_K_CPU0_SB_CB<1>  CB1_B @T6G_MB_LIB.T6G(SCH_1):M_K_CPU0_SB_CB(1)
 241 M_K_CPU0_SB_CB<2>  CB2_B @T6G_MB_LIB.T6G(SCH_1):M_K_CPU0_SB_CB(2)
 243 M_K_CPU0_SB_CB<3>  CB3_B @T6G_MB_LIB.T6G(SCH_1):M_K_CPU0_SB_CB(3)
  89 M_K_CPU0_SB_CB<4>  CB4_B @T6G_MB_LIB.T6G(SCH_1):M_K_CPU0_SB_CB(4)
  91 M_K_CPU0_SB_CB<5>  CB5_B @T6G_MB_LIB.T6G(SCH_1):M_K_CPU0_SB_CB(5)
 234 M_K_CPU0_SB_CB<6>  CB6_B @T6G_MB_LIB.T6G(SCH_1):M_K_CPU0_SB_CB(6)
  51 M_K_CPU0_SA_CB<0>  CB0_A @T6G_MB_LIB.T6G(SCH_1):M_K_CPU0_SA_CB(0)
 196 M_K_CPU0_SA_CB<2>  CB2_A @T6G_MB_LIB.T6G(SCH_1):M_K_CPU0_SA_CB(2)
 198 M_K_CPU0_SA_CB<3>  CB3_A @T6G_MB_LIB.T6G(SCH_1):M_K_CPU0_SA_CB(3)
  60 M_K_CPU0_SA_CB<5>  CB5_A @T6G_MB_LIB.T6G(SCH_1):M_K_CPU0_SA_CB(5)
 203 M_K_CPU0_SA_CB<6>  CB6_A @T6G_MB_LIB.T6G(SCH_1):M_K_CPU0_SA_CB(6)
  82 M_K_CPU0_SB_CA<6>  CA6_B @T6G_MB_LIB.T6G(SCH_1):M_K_CPU0_SB_CA(6)
  72 M_K_CPU0_SA_CA<6>  CA6_A @T6G_MB_LIB.T6G(SCH_1):M_K_CPU0_SA_CA(6)
 225 M_K_CPU0_SB_CA<5>  CA5_B @T6G_MB_LIB.T6G(SCH_1):M_K_CPU0_SB_CA(5)
 215 M_K_CPU0_SA_CA<5>  CA5_A @T6G_MB_LIB.T6G(SCH_1):M_K_CPU0_SA_CA(5)
  80 M_K_CPU0_SB_CA<4>  CA4_B @T6G_MB_LIB.T6G(SCH_1):M_K_CPU0_SB_CA(4)
  70 M_K_CPU0_SA_CA<4>  CA4_A @T6G_MB_LIB.T6G(SCH_1):M_K_CPU0_SA_CA(4)
 223 M_K_CPU0_SB_CA<3>  CA3_B @T6G_MB_LIB.T6G(SCH_1):M_K_CPU0_SB_CA(3)
 213 M_K_CPU0_SA_CA<3>  CA3_A @T6G_MB_LIB.T6G(SCH_1):M_K_CPU0_SA_CA(3)
  78 M_K_CPU0_SB_CA<2>  CA2_B @T6G_MB_LIB.T6G(SCH_1):M_K_CPU0_SB_CA(2)
  68 M_K_CPU0_SA_CA<2>  CA2_A @T6G_MB_LIB.T6G(SCH_1):M_K_CPU0_SA_CA(2)
 221 M_K_CPU0_SB_CA<1>  CA1_B @T6G_MB_LIB.T6G(SCH_1):M_K_CPU0_SB_CA(1)
 211 M_K_CPU0_SA_CA<1>  CA1_A @T6G_MB_LIB.T6G(SCH_1):M_K_CPU0_SA_CA(1)
  76 M_K_CPU0_SB_CA<0>  CA0_B @T6G_MB_LIB.T6G(SCH_1):M_K_CPU0_SB_CA(0)
  66 M_K_CPU0_SA_CA<0>  CA0_A @T6G_MB_LIB.T6G(SCH_1):M_K_CPU0_SA_CA(0)
  62 M_K_CPU0_ALERT_N ALERT_N @T6G_MB_LIB.T6G(SCH_1):M_K_CPU0_ALERT_N
 236 M_K_CPU0_SB_CB<7>  CB7_B @T6G_MB_LIB.T6G(SCH_1):M_K_CPU0_SB_CB(7)
  53 M_K_CPU0_SA_CB<1>  CB1_A @T6G_MB_LIB.T6G(SCH_1):M_K_CPU0_SA_CB(1)
  58 M_K_CPU0_SA_CB<4>  CB4_A @T6G_MB_LIB.T6G(SCH_1):M_K_CPU0_SA_CB(4)
 205 M_K_CPU0_SA_CB<7>  CB7_A @T6G_MB_LIB.T6G(SCH_1):M_K_CPU0_SA_CB(7)
 194 M_K_CPU0_SA_DQ<31> DQ31_A @T6G_MB_LIB.T6G(SCH_1):M_K_CPU0_SA_DQ(31)

Q_RES_0402LF-54.9K,1%,1/16W,CHIP,CS35492FB03  I129  R768
   1 PD_CHK_CPU0_DIMM_SAA      A @T6G_MB_LIB.T6G(SCH_1):PD_CHK_CPU0_DIMM_SAA
   2    GND      B @T6G_MB_LIB.T6G(SCH_1):GND

SCONN288_DDR506112002KQ-SCONN288_DDR506112002KQ,SMA  I177  J20
   6    GND   VSS0 @T6G_MB_LIB.T6G(SCH_1):GND
   8    GND   VSS1 @T6G_MB_LIB.T6G(SCH_1):GND
  10    GND   VSS2 @T6G_MB_LIB.T6G(SCH_1):GND
  13    GND   VSS3 @T6G_MB_LIB.T6G(SCH_1):GND
  15    GND   VSS4 @T6G_MB_LIB.T6G(SCH_1):GND
  17    GND   VSS5 @T6G_MB_LIB.T6G(SCH_1):GND
  19    GND   VSS6 @T6G_MB_LIB.T6G(SCH_1):GND
  21    GND   VSS7 @T6G_MB_LIB.T6G(SCH_1):GND
  24    GND   VSS8 @T6G_MB_LIB.T6G(SCH_1):GND
  26    GND   VSS9 @T6G_MB_LIB.T6G(SCH_1):GND
  28    GND  VSS10 @T6G_MB_LIB.T6G(SCH_1):GND
  30    GND  VSS11 @T6G_MB_LIB.T6G(SCH_1):GND
  32    GND  VSS12 @T6G_MB_LIB.T6G(SCH_1):GND
  35    GND  VSS13 @T6G_MB_LIB.T6G(SCH_1):GND
  37    GND  VSS14 @T6G_MB_LIB.T6G(SCH_1):GND
  39    GND  VSS15 @T6G_MB_LIB.T6G(SCH_1):GND
  41    GND  VSS16 @T6G_MB_LIB.T6G(SCH_1):GND
  43    GND  VSS17 @T6G_MB_LIB.T6G(SCH_1):GND
  46    GND  VSS18 @T6G_MB_LIB.T6G(SCH_1):GND
  48    GND  VSS19 @T6G_MB_LIB.T6G(SCH_1):GND
  50    GND  VSS20 @T6G_MB_LIB.T6G(SCH_1):GND
  52    GND  VSS21 @T6G_MB_LIB.T6G(SCH_1):GND
  54    GND  VSS22 @T6G_MB_LIB.T6G(SCH_1):GND
  57    GND  VSS23 @T6G_MB_LIB.T6G(SCH_1):GND
  59    GND  VSS24 @T6G_MB_LIB.T6G(SCH_1):GND
  61    GND  VSS25 @T6G_MB_LIB.T6G(SCH_1):GND
  63    GND  VSS26 @T6G_MB_LIB.T6G(SCH_1):GND
  65    GND  VSS27 @T6G_MB_LIB.T6G(SCH_1):GND
  67    GND  VSS28 @T6G_MB_LIB.T6G(SCH_1):GND
  69    GND  VSS29 @T6G_MB_LIB.T6G(SCH_1):GND
  71    GND  VSS30 @T6G_MB_LIB.T6G(SCH_1):GND
  73    GND  VSS31 @T6G_MB_LIB.T6G(SCH_1):GND
  75    GND  VSS32 @T6G_MB_LIB.T6G(SCH_1):GND
  77    GND  VSS33 @T6G_MB_LIB.T6G(SCH_1):GND
  79    GND  VSS34 @T6G_MB_LIB.T6G(SCH_1):GND
  81    GND  VSS35 @T6G_MB_LIB.T6G(SCH_1):GND
  83    GND  VSS36 @T6G_MB_LIB.T6G(SCH_1):GND
  85    GND  VSS37 @T6G_MB_LIB.T6G(SCH_1):GND
  88    GND  VSS38 @T6G_MB_LIB.T6G(SCH_1):GND
  90    GND  VSS39 @T6G_MB_LIB.T6G(SCH_1):GND
  92    GND  VSS40 @T6G_MB_LIB.T6G(SCH_1):GND
  95    GND  VSS41 @T6G_MB_LIB.T6G(SCH_1):GND
  97    GND  VSS42 @T6G_MB_LIB.T6G(SCH_1):GND
  99    GND  VSS43 @T6G_MB_LIB.T6G(SCH_1):GND
 101    GND  VSS44 @T6G_MB_LIB.T6G(SCH_1):GND
 103    GND  VSS45 @T6G_MB_LIB.T6G(SCH_1):GND
 106    GND  VSS46 @T6G_MB_LIB.T6G(SCH_1):GND
 108    GND  VSS47 @T6G_MB_LIB.T6G(SCH_1):GND
 110    GND  VSS48 @T6G_MB_LIB.T6G(SCH_1):GND
 112    GND  VSS49 @T6G_MB_LIB.T6G(SCH_1):GND
 114    GND  VSS50 @T6G_MB_LIB.T6G(SCH_1):GND
 117    GND  VSS51 @T6G_MB_LIB.T6G(SCH_1):GND
 119    GND  VSS52 @T6G_MB_LIB.T6G(SCH_1):GND
 121    GND  VSS53 @T6G_MB_LIB.T6G(SCH_1):GND
 123    GND  VSS54 @T6G_MB_LIB.T6G(SCH_1):GND
 125    GND  VSS55 @T6G_MB_LIB.T6G(SCH_1):GND
 128    GND  VSS56 @T6G_MB_LIB.T6G(SCH_1):GND
 130    GND  VSS57 @T6G_MB_LIB.T6G(SCH_1):GND
 134    GND  VSS59 @T6G_MB_LIB.T6G(SCH_1):GND
 143    GND  VSS63 @T6G_MB_LIB.T6G(SCH_1):GND
 151    GND  VSS64 @T6G_MB_LIB.T6G(SCH_1):GND
 153    GND  VSS65 @T6G_MB_LIB.T6G(SCH_1):GND
 155    GND  VSS66 @T6G_MB_LIB.T6G(SCH_1):GND
 158    GND  VSS67 @T6G_MB_LIB.T6G(SCH_1):GND
 160    GND  VSS68 @T6G_MB_LIB.T6G(SCH_1):GND
 162    GND  VSS69 @T6G_MB_LIB.T6G(SCH_1):GND
 164    GND  VSS70 @T6G_MB_LIB.T6G(SCH_1):GND
 166    GND  VSS71 @T6G_MB_LIB.T6G(SCH_1):GND
 169    GND  VSS72 @T6G_MB_LIB.T6G(SCH_1):GND
 171    GND  VSS73 @T6G_MB_LIB.T6G(SCH_1):GND
 173    GND  VSS74 @T6G_MB_LIB.T6G(SCH_1):GND
 175    GND  VSS75 @T6G_MB_LIB.T6G(SCH_1):GND
 177    GND  VSS76 @T6G_MB_LIB.T6G(SCH_1):GND
 180    GND  VSS77 @T6G_MB_LIB.T6G(SCH_1):GND
 182    GND  VSS78 @T6G_MB_LIB.T6G(SCH_1):GND
 184    GND  VSS79 @T6G_MB_LIB.T6G(SCH_1):GND
 186    GND  VSS80 @T6G_MB_LIB.T6G(SCH_1):GND
 188    GND  VSS81 @T6G_MB_LIB.T6G(SCH_1):GND
 191    GND  VSS82 @T6G_MB_LIB.T6G(SCH_1):GND
 193    GND  VSS83 @T6G_MB_LIB.T6G(SCH_1):GND
 195    GND  VSS84 @T6G_MB_LIB.T6G(SCH_1):GND
 197    GND  VSS85 @T6G_MB_LIB.T6G(SCH_1):GND
 199    GND  VSS86 @T6G_MB_LIB.T6G(SCH_1):GND
 202    GND  VSS87 @T6G_MB_LIB.T6G(SCH_1):GND
 204    GND  VSS88 @T6G_MB_LIB.T6G(SCH_1):GND
 206    GND  VSS89 @T6G_MB_LIB.T6G(SCH_1):GND
 208    GND  VSS90 @T6G_MB_LIB.T6G(SCH_1):GND
 210    GND  VSS91 @T6G_MB_LIB.T6G(SCH_1):GND
 212    GND  VSS92 @T6G_MB_LIB.T6G(SCH_1):GND
 214    GND  VSS93 @T6G_MB_LIB.T6G(SCH_1):GND
 216    GND  VSS94 @T6G_MB_LIB.T6G(SCH_1):GND
 219    GND  VSS95 @T6G_MB_LIB.T6G(SCH_1):GND
 222    GND  VSS96 @T6G_MB_LIB.T6G(SCH_1):GND
 224    GND  VSS97 @T6G_MB_LIB.T6G(SCH_1):GND
 226    GND  VSS98 @T6G_MB_LIB.T6G(SCH_1):GND
 228    GND  VSS99 @T6G_MB_LIB.T6G(SCH_1):GND
 233    GND VSS101 @T6G_MB_LIB.T6G(SCH_1):GND
 237    GND VSS103 @T6G_MB_LIB.T6G(SCH_1):GND
 242    GND VSS105 @T6G_MB_LIB.T6G(SCH_1):GND
 244    GND VSS106 @T6G_MB_LIB.T6G(SCH_1):GND
 246    GND VSS107 @T6G_MB_LIB.T6G(SCH_1):GND
 248    GND VSS108 @T6G_MB_LIB.T6G(SCH_1):GND
 251    GND VSS109 @T6G_MB_LIB.T6G(SCH_1):GND
 253    GND VSS110 @T6G_MB_LIB.T6G(SCH_1):GND
 255    GND VSS111 @T6G_MB_LIB.T6G(SCH_1):GND
 257    GND VSS112 @T6G_MB_LIB.T6G(SCH_1):GND
 259    GND VSS113 @T6G_MB_LIB.T6G(SCH_1):GND
 262    GND VSS114 @T6G_MB_LIB.T6G(SCH_1):GND
 264    GND VSS115 @T6G_MB_LIB.T6G(SCH_1):GND
 266    GND VSS116 @T6G_MB_LIB.T6G(SCH_1):GND
 268    GND VSS117 @T6G_MB_LIB.T6G(SCH_1):GND
 270    GND VSS118 @T6G_MB_LIB.T6G(SCH_1):GND
 273    GND VSS119 @T6G_MB_LIB.T6G(SCH_1):GND
 275    GND VSS120 @T6G_MB_LIB.T6G(SCH_1):GND
 277    GND VSS121 @T6G_MB_LIB.T6G(SCH_1):GND
 279    GND VSS122 @T6G_MB_LIB.T6G(SCH_1):GND
 281    GND VSS123 @T6G_MB_LIB.T6G(SCH_1):GND
 284    GND VSS124 @T6G_MB_LIB.T6G(SCH_1):GND
 286    GND VSS125 @T6G_MB_LIB.T6G(SCH_1):GND
 288    GND VSS126 @T6G_MB_LIB.T6G(SCH_1):GND
   1 P12V_MEM_CPU0 VIN_BULK0 @T6G_MB_LIB.T6G(SCH_1):P12V_MEM_CPU0
 145 P12V_MEM_CPU0 VIN_BULK1 @T6G_MB_LIB.T6G(SCH_1):P12V_MEM_CPU0
 146 P12V_MEM_CPU0 VIN_BULK2 @T6G_MB_LIB.T6G(SCH_1):P12V_MEM_CPU0
 230    GND VSS100 @T6G_MB_LIB.T6G(SCH_1):GND
 235    GND VSS102 @T6G_MB_LIB.T6G(SCH_1):GND
 240    GND VSS104 @T6G_MB_LIB.T6G(SCH_1):GND
 132    GND  VSS58 @T6G_MB_LIB.T6G(SCH_1):GND
 136    GND  VSS60 @T6G_MB_LIB.T6G(SCH_1):GND
 139    GND  VSS61 @T6G_MB_LIB.T6G(SCH_1):GND
 141    GND  VSS62 @T6G_MB_LIB.T6G(SCH_1):GND
  G1    GND     G1 @T6G_MB_LIB.T6G(SCH_1):GND
  G2    GND     G2 @T6G_MB_LIB.T6G(SCH_1):GND
  G3    GND     G3 @T6G_MB_LIB.T6G(SCH_1):GND

Q_CAP_0402-0.1UF,25V,10%,X7R,CH4104K1B00  I185  C128
   1 P3V3_AUX      A @T6G_MB_LIB.T6G(SCH_1):P3V3_AUX
   2    GND      B @T6G_MB_LIB.T6G(SCH_1):GND

Q_RES_0402LF-1K,1%,1/16W,CHIP,CS21002FB06  I188  R301
   1 PWRGD_CHK_CPU0_DIMM      A @T6G_MB_LIB.T6G(SCH_1):PWRGD_CHK_CPU0_DIMM
   2 PWRGD_CHGL_CPU0      B @T6G_MB_LIB.T6G(SCH_1):PWRGD_CHGL_CPU0

Q_RES_0402LF-1K,1%,1/16W,EMPTY,CS21002FB06  I189  R100
   1   P3V3      A @T6G_MB_LIB.T6G(SCH_1):P3V3
   2 PWRGD_CHK_CPU0_DIMM      B @T6G_MB_LIB.T6G(SCH_1):PWRGD_CHK_CPU0_DIMM

SCONN288_DDR506112002KQ-SCONN288_DDR506112002KQ,SMA  I236  J20
  93 M_K_CPU0_SB_DQS_DP<9> DQS9_B_T||TDQS9_B_T||DBI4_B_N @T6G_MB_LIB.T6G(SCH_1):M_K_CPU0_SB_DQS_DP(9)
  94 M_K_CPU0_SB_DQS_DN<9> DQS9_B_C||TDQS9_B_C @T6G_MB_LIB.T6G(SCH_1):M_K_CPU0_SB_DQS_DN(9)
 201 M_K_CPU0_SA_DQS_DP<9> DQS9_A_T||TDQS9_A_T @T6G_MB_LIB.T6G(SCH_1):M_K_CPU0_SA_DQS_DP(9)
 200 M_K_CPU0_SA_DQS_DN<9> DQS9_A_C||TDQS9_A_C @T6G_MB_LIB.T6G(SCH_1):M_K_CPU0_SA_DQS_DN(9)
 190 M_K_CPU0_SA_DQS_DP<8> DQS8_A_T||TDQS8_A_T @T6G_MB_LIB.T6G(SCH_1):M_K_CPU0_SA_DQS_DP(8)
 189 M_K_CPU0_SA_DQS_DN<8> DQS8_A_C||TDQS8_A_C @T6G_MB_LIB.T6G(SCH_1):M_K_CPU0_SA_DQS_DN(8)
 271 M_K_CPU0_SB_DQS_DN<7> DQS7_B_C||TDQS7_B_C @T6G_MB_LIB.T6G(SCH_1):M_K_CPU0_SB_DQS_DN(7)
 179 M_K_CPU0_SA_DQS_DP<7> DQS7_A_T||TDQS7_A_T @T6G_MB_LIB.T6G(SCH_1):M_K_CPU0_SA_DQS_DP(7)
 261 M_K_CPU0_SB_DQS_DP<6> DQS6_B_T||TDQS6_B_T @T6G_MB_LIB.T6G(SCH_1):M_K_CPU0_SB_DQS_DP(6)
 260 M_K_CPU0_SB_DQS_DN<6> DQS6_B_C||TDQS6_B_C @T6G_MB_LIB.T6G(SCH_1):M_K_CPU0_SB_DQS_DN(6)
 167 M_K_CPU0_SA_DQS_DN<6> DQS6_A_C||TDQS6_A_C||DQS6_A_T||TDQS6_A_T @T6G_MB_LIB.T6G(SCH_1):M_K_CPU0_SA_DQS_DN(6)
 250 M_K_CPU0_SB_DQS_DP<5> DQS5_B_T||TDQS5_B_T @T6G_MB_LIB.T6G(SCH_1):M_K_CPU0_SB_DQS_DP(5)
 249 M_K_CPU0_SB_DQS_DN<5> DQS5_B_C||TDQS5_B_C @T6G_MB_LIB.T6G(SCH_1):M_K_CPU0_SB_DQS_DN(5)
 157 M_K_CPU0_SA_DQS_DP<5> DQS5_A_T||TDQS5_A_T @T6G_MB_LIB.T6G(SCH_1):M_K_CPU0_SA_DQS_DP(5)
 156 M_K_CPU0_SA_DQS_DN<5> DQS5_A_C||TDQS5_A_C||DQS5_A_T||TDQS5_A_T @T6G_MB_LIB.T6G(SCH_1):M_K_CPU0_SA_DQS_DN(5)
 239 M_K_CPU0_SB_DQS_DP<4> DQS4_B_T @T6G_MB_LIB.T6G(SCH_1):M_K_CPU0_SB_DQS_DP(4)
 238 M_K_CPU0_SB_DQS_DN<4> DQS4_B_C @T6G_MB_LIB.T6G(SCH_1):M_K_CPU0_SB_DQS_DN(4)
  55 M_K_CPU0_SA_DQS_DP<4> DQS4_A_T @T6G_MB_LIB.T6G(SCH_1):M_K_CPU0_SA_DQS_DP(4)
  56 M_K_CPU0_SA_DQS_DN<4> DQS4_A_C @T6G_MB_LIB.T6G(SCH_1):M_K_CPU0_SA_DQS_DN(4)
 137 M_K_CPU0_SB_DQS_DP<3> DQS3_B_T @T6G_MB_LIB.T6G(SCH_1):M_K_CPU0_SB_DQS_DP(3)
 138 M_K_CPU0_SB_DQS_DN<3> DQS3_B_C @T6G_MB_LIB.T6G(SCH_1):M_K_CPU0_SB_DQS_DN(3)
  44 M_K_CPU0_SA_DQS_DP<3> DQS3_A_T @T6G_MB_LIB.T6G(SCH_1):M_K_CPU0_SA_DQS_DP(3)
  45 M_K_CPU0_SA_DQS_DN<3> DQS3_A_C @T6G_MB_LIB.T6G(SCH_1):M_K_CPU0_SA_DQS_DN(3)
 126 M_K_CPU0_SB_DQS_DP<2> DQS2_B_T @T6G_MB_LIB.T6G(SCH_1):M_K_CPU0_SB_DQS_DP(2)
 127 M_K_CPU0_SB_DQS_DN<2> DQS2_B_C @T6G_MB_LIB.T6G(SCH_1):M_K_CPU0_SB_DQS_DN(2)
  33 M_K_CPU0_SA_DQS_DP<2> DQS2_A_T @T6G_MB_LIB.T6G(SCH_1):M_K_CPU0_SA_DQS_DP(2)
  34 M_K_CPU0_SA_DQS_DN<2> DQS2_A_C @T6G_MB_LIB.T6G(SCH_1):M_K_CPU0_SA_DQS_DN(2)
 115 M_K_CPU0_SB_DQS_DP<1> DQS1_B_T @T6G_MB_LIB.T6G(SCH_1):M_K_CPU0_SB_DQS_DP(1)
 116 M_K_CPU0_SB_DQS_DN<1> DQS1_B_C @T6G_MB_LIB.T6G(SCH_1):M_K_CPU0_SB_DQS_DN(1)
  22 M_K_CPU0_SA_DQS_DP<1> DQS1_A_T @T6G_MB_LIB.T6G(SCH_1):M_K_CPU0_SA_DQS_DP(1)
  23 M_K_CPU0_SA_DQS_DN<1> DQS1_A_C @T6G_MB_LIB.T6G(SCH_1):M_K_CPU0_SA_DQS_DN(1)
 104 M_K_CPU0_SB_DQS_DP<0> DQS0_B_T @T6G_MB_LIB.T6G(SCH_1):M_K_CPU0_SB_DQS_DP(0)
 105 M_K_CPU0_SB_DQS_DN<0> DQS0_B_C @T6G_MB_LIB.T6G(SCH_1):M_K_CPU0_SB_DQS_DN(0)
  11 M_K_CPU0_SA_DQS_DP<0> DQS0_A_T @T6G_MB_LIB.T6G(SCH_1):M_K_CPU0_SA_DQS_DP(0)
  12 M_K_CPU0_SA_DQS_DN<0> DQS0_A_C @T6G_MB_LIB.T6G(SCH_1):M_K_CPU0_SA_DQS_DN(0)
 272 M_K_CPU0_SB_DQS_DP<7> DQS7_B_T||TDQS7_B_T @T6G_MB_LIB.T6G(SCH_1):M_K_CPU0_SB_DQS_DP(7)
 282 M_K_CPU0_SB_DQS_DN<8> DQS8_B_C||TDQS8_B_C @T6G_MB_LIB.T6G(SCH_1):M_K_CPU0_SB_DQS_DN(8)
 283 M_K_CPU0_SB_DQS_DP<8> DQS8_B_T||TDQS8_B_T @T6G_MB_LIB.T6G(SCH_1):M_K_CPU0_SB_DQS_DP(8)
 168 M_K_CPU0_SA_DQS_DP<6> DQS6_A_T||TDQS6_A_T @T6G_MB_LIB.T6G(SCH_1):M_K_CPU0_SA_DQS_DP(6)
 178 M_K_CPU0_SA_DQS_DN<7> DQS7_A_C||TDQS7_A_C @T6G_MB_LIB.T6G(SCH_1):M_K_CPU0_SA_DQS_DN(7)

Q_CAP_C0805-10UF,25V,10%,X6S,CH6104KEA00  I238  C167
   1 P12V_MEM_CPU0      A @T6G_MB_LIB.T6G(SCH_1):P12V_MEM_CPU0
   2    GND      B @T6G_MB_LIB.T6G(SCH_1):GND

Q_CAP_C0805-10UF,25V,10%,X6S,CH6104KEA00  I239  C169
   1 P12V_MEM_CPU0      A @T6G_MB_LIB.T6G(SCH_1):P12V_MEM_CPU0
   2    GND      B @T6G_MB_LIB.T6G(SCH_1):GND

Q_RES_0402LF-49.9,1%,1/16W,CHIP,CS04992FB07  I242  R1578
   1 I3C_SPD_DDRGL_CPU0_SCL      A @T6G_MB_LIB.T6G(SCH_1):I3C_SPD_DDRGL_CPU0_SCL
   2 I3C_SPD_DDRK_CPU0_SCL      B @T6G_MB_LIB.T6G(SCH_1):I3C_SPD_DDRK_CPU0_SCL

Q_RES_0402LF-10,1%,1/16W,CHIP,CS01002FB07  I243  R1685
   1 I3C_SPD_DDRGL_CPU0_SDA      A @T6G_MB_LIB.T6G(SCH_1):I3C_SPD_DDRGL_CPU0_SDA
   2 I3C_SPD_DDRK_CPU0_SDA      B @T6G_MB_LIB.T6G(SCH_1):I3C_SPD_DDRK_CPU0_SDA


DRAWING: @T6G_MB_LIB.T6G(SCH_1):PAGE96 

SCONN288_DDR506112002KQ-SCONN288_DDR506112002KQ,SMA  I22  J67
   3 P3V3_AUX VIN_MGMT @T6G_MB_LIB.T6G(SCH_1):P3V3_AUX
   2     NC   RFU0     NC
 144     NC   RFU1     NC
 149     NC   RFU2     NC
 150     NC   RFU3     NC
 220     NC   RFU4     NC
 231     NC   RFU5     NC
 232     NC   RFU6     NC
 207 M_L_CPU0_RESET_N RESET_N @T6G_MB_LIB.T6G(SCH_1):M_L_CPU0_RESET_N
 147 PWRGD_CHL_CPU0_DIMM PWR_GOOD||FAIL_N @T6G_MB_LIB.T6G(SCH_1):PWRGD_CHL_CPU0_DIMM
 227 M_L_CPU0_SB_PAR  PAR_B @T6G_MB_LIB.T6G(SCH_1):M_L_CPU0_SB_PAR
  74 M_L_CPU0_SA_PAR  PAR_A @T6G_MB_LIB.T6G(SCH_1):M_L_CPU0_SA_PAR
  87 M_L_CPU0_SB_RSP<0> LBS||RSP_B_N @T6G_MB_LIB.T6G(SCH_1):M_L_CPU0_SB_RSP(0)
  86 M_L_CPU0_SA_RSP<0> LBD||RSP_A_N @T6G_MB_LIB.T6G(SCH_1):M_L_CPU0_SA_RSP(0)
   5 I3C_SPD_DDRL_CPU0_SDA   HSDA @T6G_MB_LIB.T6G(SCH_1):I3C_SPD_DDRL_CPU0_SDA
   4 I3C_SPD_DDRL_CPU0_SCL   HSCL @T6G_MB_LIB.T6G(SCH_1):I3C_SPD_DDRL_CPU0_SCL
 148 PD_CHL_CPU0_DIMM_SAA    HAS @T6G_MB_LIB.T6G(SCH_1):PD_CHL_CPU0_DIMM_SAA
 100 M_L_CPU0_SB_DQ<0>  DQ0_B @T6G_MB_LIB.T6G(SCH_1):M_L_CPU0_SB_DQ(0)
 102 M_L_CPU0_SB_DQ<1>  DQ1_B @T6G_MB_LIB.T6G(SCH_1):M_L_CPU0_SB_DQ(1)
 245 M_L_CPU0_SB_DQ<2>  DQ2_B @T6G_MB_LIB.T6G(SCH_1):M_L_CPU0_SB_DQ(2)
 247 M_L_CPU0_SB_DQ<3>  DQ3_B @T6G_MB_LIB.T6G(SCH_1):M_L_CPU0_SB_DQ(3)
 107 M_L_CPU0_SB_DQ<4>  DQ4_B @T6G_MB_LIB.T6G(SCH_1):M_L_CPU0_SB_DQ(4)
 109 M_L_CPU0_SB_DQ<5>  DQ5_B @T6G_MB_LIB.T6G(SCH_1):M_L_CPU0_SB_DQ(5)
 252 M_L_CPU0_SB_DQ<6>  DQ6_B @T6G_MB_LIB.T6G(SCH_1):M_L_CPU0_SB_DQ(6)
 254 M_L_CPU0_SB_DQ<7>  DQ7_B @T6G_MB_LIB.T6G(SCH_1):M_L_CPU0_SB_DQ(7)
 111 M_L_CPU0_SB_DQ<8>  DQ8_B @T6G_MB_LIB.T6G(SCH_1):M_L_CPU0_SB_DQ(8)
 113 M_L_CPU0_SB_DQ<9>  DQ9_B @T6G_MB_LIB.T6G(SCH_1):M_L_CPU0_SB_DQ(9)
 256 M_L_CPU0_SB_DQ<10> DQ10_B @T6G_MB_LIB.T6G(SCH_1):M_L_CPU0_SB_DQ(10)
 258 M_L_CPU0_SB_DQ<11> DQ11_B @T6G_MB_LIB.T6G(SCH_1):M_L_CPU0_SB_DQ(11)
 118 M_L_CPU0_SB_DQ<12> DQ12_B @T6G_MB_LIB.T6G(SCH_1):M_L_CPU0_SB_DQ(12)
 120 M_L_CPU0_SB_DQ<13> DQ13_B @T6G_MB_LIB.T6G(SCH_1):M_L_CPU0_SB_DQ(13)
 263 M_L_CPU0_SB_DQ<14> DQ14_B @T6G_MB_LIB.T6G(SCH_1):M_L_CPU0_SB_DQ(14)
 265 M_L_CPU0_SB_DQ<15> DQ15_B @T6G_MB_LIB.T6G(SCH_1):M_L_CPU0_SB_DQ(15)
 122 M_L_CPU0_SB_DQ<16> DQ16_B @T6G_MB_LIB.T6G(SCH_1):M_L_CPU0_SB_DQ(16)
 124 M_L_CPU0_SB_DQ<17> DQ17_B @T6G_MB_LIB.T6G(SCH_1):M_L_CPU0_SB_DQ(17)
 267 M_L_CPU0_SB_DQ<18> DQ18_B @T6G_MB_LIB.T6G(SCH_1):M_L_CPU0_SB_DQ(18)
 269 M_L_CPU0_SB_DQ<19> DQ19_B @T6G_MB_LIB.T6G(SCH_1):M_L_CPU0_SB_DQ(19)
 129 M_L_CPU0_SB_DQ<20> DQ20_B @T6G_MB_LIB.T6G(SCH_1):M_L_CPU0_SB_DQ(20)
 131 M_L_CPU0_SB_DQ<21> DQ21_B @T6G_MB_LIB.T6G(SCH_1):M_L_CPU0_SB_DQ(21)
 274 M_L_CPU0_SB_DQ<22> DQ22_B @T6G_MB_LIB.T6G(SCH_1):M_L_CPU0_SB_DQ(22)
 276 M_L_CPU0_SB_DQ<23> DQ23_B @T6G_MB_LIB.T6G(SCH_1):M_L_CPU0_SB_DQ(23)
 133 M_L_CPU0_SB_DQ<24> DQ24_B @T6G_MB_LIB.T6G(SCH_1):M_L_CPU0_SB_DQ(24)
 135 M_L_CPU0_SB_DQ<25> DQ25_B @T6G_MB_LIB.T6G(SCH_1):M_L_CPU0_SB_DQ(25)
 278 M_L_CPU0_SB_DQ<26> DQ26_B @T6G_MB_LIB.T6G(SCH_1):M_L_CPU0_SB_DQ(26)
 280 M_L_CPU0_SB_DQ<27> DQ27_B @T6G_MB_LIB.T6G(SCH_1):M_L_CPU0_SB_DQ(27)
 140 M_L_CPU0_SB_DQ<28> DQ28_B @T6G_MB_LIB.T6G(SCH_1):M_L_CPU0_SB_DQ(28)
 142 M_L_CPU0_SB_DQ<29> DQ29_B @T6G_MB_LIB.T6G(SCH_1):M_L_CPU0_SB_DQ(29)
 285 M_L_CPU0_SB_DQ<30> DQ30_B @T6G_MB_LIB.T6G(SCH_1):M_L_CPU0_SB_DQ(30)
 287 M_L_CPU0_SB_DQ<31> DQ31_B @T6G_MB_LIB.T6G(SCH_1):M_L_CPU0_SB_DQ(31)
   7 M_L_CPU0_SA_DQ<0>  DQ0_A @T6G_MB_LIB.T6G(SCH_1):M_L_CPU0_SA_DQ(0)
   9 M_L_CPU0_SA_DQ<1>  DQ1_A @T6G_MB_LIB.T6G(SCH_1):M_L_CPU0_SA_DQ(1)
 152 M_L_CPU0_SA_DQ<2>  DQ2_A @T6G_MB_LIB.T6G(SCH_1):M_L_CPU0_SA_DQ(2)
 154 M_L_CPU0_SA_DQ<3>  DQ3_A @T6G_MB_LIB.T6G(SCH_1):M_L_CPU0_SA_DQ(3)
  14 M_L_CPU0_SA_DQ<4>  DQ4_A @T6G_MB_LIB.T6G(SCH_1):M_L_CPU0_SA_DQ(4)
  16 M_L_CPU0_SA_DQ<5>  DQ5_A @T6G_MB_LIB.T6G(SCH_1):M_L_CPU0_SA_DQ(5)
 159 M_L_CPU0_SA_DQ<6>  DQ6_A @T6G_MB_LIB.T6G(SCH_1):M_L_CPU0_SA_DQ(6)
 161 M_L_CPU0_SA_DQ<7>  DQ7_A @T6G_MB_LIB.T6G(SCH_1):M_L_CPU0_SA_DQ(7)
  18 M_L_CPU0_SA_DQ<8>  DQ8_A @T6G_MB_LIB.T6G(SCH_1):M_L_CPU0_SA_DQ(8)
  20 M_L_CPU0_SA_DQ<9>  DQ9_A @T6G_MB_LIB.T6G(SCH_1):M_L_CPU0_SA_DQ(9)
 163 M_L_CPU0_SA_DQ<10> DQ10_A @T6G_MB_LIB.T6G(SCH_1):M_L_CPU0_SA_DQ(10)
 165 M_L_CPU0_SA_DQ<11> DQ11_A @T6G_MB_LIB.T6G(SCH_1):M_L_CPU0_SA_DQ(11)
  25 M_L_CPU0_SA_DQ<12> DQ12_A @T6G_MB_LIB.T6G(SCH_1):M_L_CPU0_SA_DQ(12)
  27 M_L_CPU0_SA_DQ<13> DQ13_A @T6G_MB_LIB.T6G(SCH_1):M_L_CPU0_SA_DQ(13)
 170 M_L_CPU0_SA_DQ<14> DQ14_A @T6G_MB_LIB.T6G(SCH_1):M_L_CPU0_SA_DQ(14)
 172 M_L_CPU0_SA_DQ<15> DQ15_A @T6G_MB_LIB.T6G(SCH_1):M_L_CPU0_SA_DQ(15)
  29 M_L_CPU0_SA_DQ<16> DQ16_A @T6G_MB_LIB.T6G(SCH_1):M_L_CPU0_SA_DQ(16)
  31 M_L_CPU0_SA_DQ<17> DQ17_A @T6G_MB_LIB.T6G(SCH_1):M_L_CPU0_SA_DQ(17)
 174 M_L_CPU0_SA_DQ<18> DQ18_A @T6G_MB_LIB.T6G(SCH_1):M_L_CPU0_SA_DQ(18)
 176 M_L_CPU0_SA_DQ<19> DQ19_A @T6G_MB_LIB.T6G(SCH_1):M_L_CPU0_SA_DQ(19)
  36 M_L_CPU0_SA_DQ<20> DQ20_A @T6G_MB_LIB.T6G(SCH_1):M_L_CPU0_SA_DQ(20)
  38 M_L_CPU0_SA_DQ<21> DQ21_A @T6G_MB_LIB.T6G(SCH_1):M_L_CPU0_SA_DQ(21)
 181 M_L_CPU0_SA_DQ<22> DQ22_A @T6G_MB_LIB.T6G(SCH_1):M_L_CPU0_SA_DQ(22)
 183 M_L_CPU0_SA_DQ<23> DQ23_A @T6G_MB_LIB.T6G(SCH_1):M_L_CPU0_SA_DQ(23)
  40 M_L_CPU0_SA_DQ<24> DQ24_A @T6G_MB_LIB.T6G(SCH_1):M_L_CPU0_SA_DQ(24)
  42 M_L_CPU0_SA_DQ<25> DQ25_A @T6G_MB_LIB.T6G(SCH_1):M_L_CPU0_SA_DQ(25)
 185 M_L_CPU0_SA_DQ<26> DQ26_A @T6G_MB_LIB.T6G(SCH_1):M_L_CPU0_SA_DQ(26)
 187 M_L_CPU0_SA_DQ<27> DQ27_A @T6G_MB_LIB.T6G(SCH_1):M_L_CPU0_SA_DQ(27)
  47 M_L_CPU0_SA_DQ<28> DQ28_A @T6G_MB_LIB.T6G(SCH_1):M_L_CPU0_SA_DQ(28)
  49 M_L_CPU0_SA_DQ<29> DQ29_A @T6G_MB_LIB.T6G(SCH_1):M_L_CPU0_SA_DQ(29)
 192 M_L_CPU0_SA_DQ<30> DQ30_A @T6G_MB_LIB.T6G(SCH_1):M_L_CPU0_SA_DQ(30)
 229 M_L_CPU0_SB_CS_N<1> CS1_B_N @T6G_MB_LIB.T6G(SCH_1):M_L_CPU0_SB_CS_N(1)
 209 M_L_CPU0_SA_CS_N<1> CS1_A_N @T6G_MB_LIB.T6G(SCH_1):M_L_CPU0_SA_CS_N(1)
  84 M_L_CPU0_SB_CS_N<0> CS0_B_N @T6G_MB_LIB.T6G(SCH_1):M_L_CPU0_SB_CS_N(0)
  64 M_L_CPU0_SA_CS_N<0> CS0_A_N @T6G_MB_LIB.T6G(SCH_1):M_L_CPU0_SA_CS_N(0)
 217 M_L_CPU0_CLK_DP<0>   CK_T @T6G_MB_LIB.T6G(SCH_1):M_L_CPU0_CLK_DP(0)
 218 M_L_CPU0_CLK_DN<0>   CK_C @T6G_MB_LIB.T6G(SCH_1):M_L_CPU0_CLK_DN(0)
  96 M_L_CPU0_SB_CB<0>  CB0_B @T6G_MB_LIB.T6G(SCH_1):M_L_CPU0_SB_CB(0)
  98 M_L_CPU0_SB_CB<1>  CB1_B @T6G_MB_LIB.T6G(SCH_1):M_L_CPU0_SB_CB(1)
 241 M_L_CPU0_SB_CB<2>  CB2_B @T6G_MB_LIB.T6G(SCH_1):M_L_CPU0_SB_CB(2)
 243 M_L_CPU0_SB_CB<3>  CB3_B @T6G_MB_LIB.T6G(SCH_1):M_L_CPU0_SB_CB(3)
  89 M_L_CPU0_SB_CB<4>  CB4_B @T6G_MB_LIB.T6G(SCH_1):M_L_CPU0_SB_CB(4)
  91 M_L_CPU0_SB_CB<5>  CB5_B @T6G_MB_LIB.T6G(SCH_1):M_L_CPU0_SB_CB(5)
 234 M_L_CPU0_SB_CB<6>  CB6_B @T6G_MB_LIB.T6G(SCH_1):M_L_CPU0_SB_CB(6)
  51 M_L_CPU0_SA_CB<0>  CB0_A @T6G_MB_LIB.T6G(SCH_1):M_L_CPU0_SA_CB(0)
 196 M_L_CPU0_SA_CB<2>  CB2_A @T6G_MB_LIB.T6G(SCH_1):M_L_CPU0_SA_CB(2)
 198 M_L_CPU0_SA_CB<3>  CB3_A @T6G_MB_LIB.T6G(SCH_1):M_L_CPU0_SA_CB(3)
  60 M_L_CPU0_SA_CB<5>  CB5_A @T6G_MB_LIB.T6G(SCH_1):M_L_CPU0_SA_CB(5)
 203 M_L_CPU0_SA_CB<6>  CB6_A @T6G_MB_LIB.T6G(SCH_1):M_L_CPU0_SA_CB(6)
  82 M_L_CPU0_SB_CA<6>  CA6_B @T6G_MB_LIB.T6G(SCH_1):M_L_CPU0_SB_CA(6)
  72 M_L_CPU0_SA_CA<6>  CA6_A @T6G_MB_LIB.T6G(SCH_1):M_L_CPU0_SA_CA(6)
 225 M_L_CPU0_SB_CA<5>  CA5_B @T6G_MB_LIB.T6G(SCH_1):M_L_CPU0_SB_CA(5)
 215 M_L_CPU0_SA_CA<5>  CA5_A @T6G_MB_LIB.T6G(SCH_1):M_L_CPU0_SA_CA(5)
  80 M_L_CPU0_SB_CA<4>  CA4_B @T6G_MB_LIB.T6G(SCH_1):M_L_CPU0_SB_CA(4)
  70 M_L_CPU0_SA_CA<4>  CA4_A @T6G_MB_LIB.T6G(SCH_1):M_L_CPU0_SA_CA(4)
 223 M_L_CPU0_SB_CA<3>  CA3_B @T6G_MB_LIB.T6G(SCH_1):M_L_CPU0_SB_CA(3)
 213 M_L_CPU0_SA_CA<3>  CA3_A @T6G_MB_LIB.T6G(SCH_1):M_L_CPU0_SA_CA(3)
  78 M_L_CPU0_SB_CA<2>  CA2_B @T6G_MB_LIB.T6G(SCH_1):M_L_CPU0_SB_CA(2)
  68 M_L_CPU0_SA_CA<2>  CA2_A @T6G_MB_LIB.T6G(SCH_1):M_L_CPU0_SA_CA(2)
 221 M_L_CPU0_SB_CA<1>  CA1_B @T6G_MB_LIB.T6G(SCH_1):M_L_CPU0_SB_CA(1)
 211 M_L_CPU0_SA_CA<1>  CA1_A @T6G_MB_LIB.T6G(SCH_1):M_L_CPU0_SA_CA(1)
  76 M_L_CPU0_SB_CA<0>  CA0_B @T6G_MB_LIB.T6G(SCH_1):M_L_CPU0_SB_CA(0)
  66 M_L_CPU0_SA_CA<0>  CA0_A @T6G_MB_LIB.T6G(SCH_1):M_L_CPU0_SA_CA(0)
  62 M_L_CPU0_ALERT_N ALERT_N @T6G_MB_LIB.T6G(SCH_1):M_L_CPU0_ALERT_N
 236 M_L_CPU0_SB_CB<7>  CB7_B @T6G_MB_LIB.T6G(SCH_1):M_L_CPU0_SB_CB(7)
  53 M_L_CPU0_SA_CB<1>  CB1_A @T6G_MB_LIB.T6G(SCH_1):M_L_CPU0_SA_CB(1)
  58 M_L_CPU0_SA_CB<4>  CB4_A @T6G_MB_LIB.T6G(SCH_1):M_L_CPU0_SA_CB(4)
 205 M_L_CPU0_SA_CB<7>  CB7_A @T6G_MB_LIB.T6G(SCH_1):M_L_CPU0_SA_CB(7)
 194 M_L_CPU0_SA_DQ<31> DQ31_A @T6G_MB_LIB.T6G(SCH_1):M_L_CPU0_SA_DQ(31)

Q_RES_0402LF-84.5K,1%,1/16W,CHIP,CS38452FB05  I127  R769
   1 PD_CHL_CPU0_DIMM_SAA      A @T6G_MB_LIB.T6G(SCH_1):PD_CHL_CPU0_DIMM_SAA
   2    GND      B @T6G_MB_LIB.T6G(SCH_1):GND

SCONN288_DDR506112002KQ-SCONN288_DDR506112002KQ,SMA  I140  J67
   6    GND   VSS0 @T6G_MB_LIB.T6G(SCH_1):GND
   8    GND   VSS1 @T6G_MB_LIB.T6G(SCH_1):GND
  10    GND   VSS2 @T6G_MB_LIB.T6G(SCH_1):GND
  13    GND   VSS3 @T6G_MB_LIB.T6G(SCH_1):GND
  15    GND   VSS4 @T6G_MB_LIB.T6G(SCH_1):GND
  17    GND   VSS5 @T6G_MB_LIB.T6G(SCH_1):GND
  19    GND   VSS6 @T6G_MB_LIB.T6G(SCH_1):GND
  21    GND   VSS7 @T6G_MB_LIB.T6G(SCH_1):GND
  24    GND   VSS8 @T6G_MB_LIB.T6G(SCH_1):GND
  26    GND   VSS9 @T6G_MB_LIB.T6G(SCH_1):GND
  28    GND  VSS10 @T6G_MB_LIB.T6G(SCH_1):GND
  30    GND  VSS11 @T6G_MB_LIB.T6G(SCH_1):GND
  32    GND  VSS12 @T6G_MB_LIB.T6G(SCH_1):GND
  35    GND  VSS13 @T6G_MB_LIB.T6G(SCH_1):GND
  37    GND  VSS14 @T6G_MB_LIB.T6G(SCH_1):GND
  39    GND  VSS15 @T6G_MB_LIB.T6G(SCH_1):GND
  41    GND  VSS16 @T6G_MB_LIB.T6G(SCH_1):GND
  43    GND  VSS17 @T6G_MB_LIB.T6G(SCH_1):GND
  46    GND  VSS18 @T6G_MB_LIB.T6G(SCH_1):GND
  48    GND  VSS19 @T6G_MB_LIB.T6G(SCH_1):GND
  50    GND  VSS20 @T6G_MB_LIB.T6G(SCH_1):GND
  52    GND  VSS21 @T6G_MB_LIB.T6G(SCH_1):GND
  54    GND  VSS22 @T6G_MB_LIB.T6G(SCH_1):GND
  57    GND  VSS23 @T6G_MB_LIB.T6G(SCH_1):GND
  59    GND  VSS24 @T6G_MB_LIB.T6G(SCH_1):GND
  61    GND  VSS25 @T6G_MB_LIB.T6G(SCH_1):GND
  63    GND  VSS26 @T6G_MB_LIB.T6G(SCH_1):GND
  65    GND  VSS27 @T6G_MB_LIB.T6G(SCH_1):GND
  67    GND  VSS28 @T6G_MB_LIB.T6G(SCH_1):GND
  69    GND  VSS29 @T6G_MB_LIB.T6G(SCH_1):GND
  71    GND  VSS30 @T6G_MB_LIB.T6G(SCH_1):GND
  73    GND  VSS31 @T6G_MB_LIB.T6G(SCH_1):GND
  75    GND  VSS32 @T6G_MB_LIB.T6G(SCH_1):GND
  77    GND  VSS33 @T6G_MB_LIB.T6G(SCH_1):GND
  79    GND  VSS34 @T6G_MB_LIB.T6G(SCH_1):GND
  81    GND  VSS35 @T6G_MB_LIB.T6G(SCH_1):GND
  83    GND  VSS36 @T6G_MB_LIB.T6G(SCH_1):GND
  85    GND  VSS37 @T6G_MB_LIB.T6G(SCH_1):GND
  88    GND  VSS38 @T6G_MB_LIB.T6G(SCH_1):GND
  90    GND  VSS39 @T6G_MB_LIB.T6G(SCH_1):GND
  92    GND  VSS40 @T6G_MB_LIB.T6G(SCH_1):GND
  95    GND  VSS41 @T6G_MB_LIB.T6G(SCH_1):GND
  97    GND  VSS42 @T6G_MB_LIB.T6G(SCH_1):GND
  99    GND  VSS43 @T6G_MB_LIB.T6G(SCH_1):GND
 101    GND  VSS44 @T6G_MB_LIB.T6G(SCH_1):GND
 103    GND  VSS45 @T6G_MB_LIB.T6G(SCH_1):GND
 106    GND  VSS46 @T6G_MB_LIB.T6G(SCH_1):GND
 108    GND  VSS47 @T6G_MB_LIB.T6G(SCH_1):GND
 110    GND  VSS48 @T6G_MB_LIB.T6G(SCH_1):GND
 112    GND  VSS49 @T6G_MB_LIB.T6G(SCH_1):GND
 114    GND  VSS50 @T6G_MB_LIB.T6G(SCH_1):GND
 117    GND  VSS51 @T6G_MB_LIB.T6G(SCH_1):GND
 119    GND  VSS52 @T6G_MB_LIB.T6G(SCH_1):GND
 121    GND  VSS53 @T6G_MB_LIB.T6G(SCH_1):GND
 123    GND  VSS54 @T6G_MB_LIB.T6G(SCH_1):GND
 125    GND  VSS55 @T6G_MB_LIB.T6G(SCH_1):GND
 128    GND  VSS56 @T6G_MB_LIB.T6G(SCH_1):GND
 130    GND  VSS57 @T6G_MB_LIB.T6G(SCH_1):GND
 134    GND  VSS59 @T6G_MB_LIB.T6G(SCH_1):GND
 143    GND  VSS63 @T6G_MB_LIB.T6G(SCH_1):GND
 151    GND  VSS64 @T6G_MB_LIB.T6G(SCH_1):GND
 153    GND  VSS65 @T6G_MB_LIB.T6G(SCH_1):GND
 155    GND  VSS66 @T6G_MB_LIB.T6G(SCH_1):GND
 158    GND  VSS67 @T6G_MB_LIB.T6G(SCH_1):GND
 160    GND  VSS68 @T6G_MB_LIB.T6G(SCH_1):GND
 162    GND  VSS69 @T6G_MB_LIB.T6G(SCH_1):GND
 164    GND  VSS70 @T6G_MB_LIB.T6G(SCH_1):GND
 166    GND  VSS71 @T6G_MB_LIB.T6G(SCH_1):GND
 169    GND  VSS72 @T6G_MB_LIB.T6G(SCH_1):GND
 171    GND  VSS73 @T6G_MB_LIB.T6G(SCH_1):GND
 173    GND  VSS74 @T6G_MB_LIB.T6G(SCH_1):GND
 175    GND  VSS75 @T6G_MB_LIB.T6G(SCH_1):GND
 177    GND  VSS76 @T6G_MB_LIB.T6G(SCH_1):GND
 180    GND  VSS77 @T6G_MB_LIB.T6G(SCH_1):GND
 182    GND  VSS78 @T6G_MB_LIB.T6G(SCH_1):GND
 184    GND  VSS79 @T6G_MB_LIB.T6G(SCH_1):GND
 186    GND  VSS80 @T6G_MB_LIB.T6G(SCH_1):GND
 188    GND  VSS81 @T6G_MB_LIB.T6G(SCH_1):GND
 191    GND  VSS82 @T6G_MB_LIB.T6G(SCH_1):GND
 193    GND  VSS83 @T6G_MB_LIB.T6G(SCH_1):GND
 195    GND  VSS84 @T6G_MB_LIB.T6G(SCH_1):GND
 197    GND  VSS85 @T6G_MB_LIB.T6G(SCH_1):GND
 199    GND  VSS86 @T6G_MB_LIB.T6G(SCH_1):GND
 202    GND  VSS87 @T6G_MB_LIB.T6G(SCH_1):GND
 204    GND  VSS88 @T6G_MB_LIB.T6G(SCH_1):GND
 206    GND  VSS89 @T6G_MB_LIB.T6G(SCH_1):GND
 208    GND  VSS90 @T6G_MB_LIB.T6G(SCH_1):GND
 210    GND  VSS91 @T6G_MB_LIB.T6G(SCH_1):GND
 212    GND  VSS92 @T6G_MB_LIB.T6G(SCH_1):GND
 214    GND  VSS93 @T6G_MB_LIB.T6G(SCH_1):GND
 216    GND  VSS94 @T6G_MB_LIB.T6G(SCH_1):GND
 219    GND  VSS95 @T6G_MB_LIB.T6G(SCH_1):GND
 222    GND  VSS96 @T6G_MB_LIB.T6G(SCH_1):GND
 224    GND  VSS97 @T6G_MB_LIB.T6G(SCH_1):GND
 226    GND  VSS98 @T6G_MB_LIB.T6G(SCH_1):GND
 228    GND  VSS99 @T6G_MB_LIB.T6G(SCH_1):GND
 233    GND VSS101 @T6G_MB_LIB.T6G(SCH_1):GND
 237    GND VSS103 @T6G_MB_LIB.T6G(SCH_1):GND
 242    GND VSS105 @T6G_MB_LIB.T6G(SCH_1):GND
 244    GND VSS106 @T6G_MB_LIB.T6G(SCH_1):GND
 246    GND VSS107 @T6G_MB_LIB.T6G(SCH_1):GND
 248    GND VSS108 @T6G_MB_LIB.T6G(SCH_1):GND
 251    GND VSS109 @T6G_MB_LIB.T6G(SCH_1):GND
 253    GND VSS110 @T6G_MB_LIB.T6G(SCH_1):GND
 255    GND VSS111 @T6G_MB_LIB.T6G(SCH_1):GND
 257    GND VSS112 @T6G_MB_LIB.T6G(SCH_1):GND
 259    GND VSS113 @T6G_MB_LIB.T6G(SCH_1):GND
 262    GND VSS114 @T6G_MB_LIB.T6G(SCH_1):GND
 264    GND VSS115 @T6G_MB_LIB.T6G(SCH_1):GND
 266    GND VSS116 @T6G_MB_LIB.T6G(SCH_1):GND
 268    GND VSS117 @T6G_MB_LIB.T6G(SCH_1):GND
 270    GND VSS118 @T6G_MB_LIB.T6G(SCH_1):GND
 273    GND VSS119 @T6G_MB_LIB.T6G(SCH_1):GND
 275    GND VSS120 @T6G_MB_LIB.T6G(SCH_1):GND
 277    GND VSS121 @T6G_MB_LIB.T6G(SCH_1):GND
 279    GND VSS122 @T6G_MB_LIB.T6G(SCH_1):GND
 281    GND VSS123 @T6G_MB_LIB.T6G(SCH_1):GND
 284    GND VSS124 @T6G_MB_LIB.T6G(SCH_1):GND
 286    GND VSS125 @T6G_MB_LIB.T6G(SCH_1):GND
 288    GND VSS126 @T6G_MB_LIB.T6G(SCH_1):GND
   1 P12V_MEM_CPU0 VIN_BULK0 @T6G_MB_LIB.T6G(SCH_1):P12V_MEM_CPU0
 145 P12V_MEM_CPU0 VIN_BULK1 @T6G_MB_LIB.T6G(SCH_1):P12V_MEM_CPU0
 146 P12V_MEM_CPU0 VIN_BULK2 @T6G_MB_LIB.T6G(SCH_1):P12V_MEM_CPU0
 230    GND VSS100 @T6G_MB_LIB.T6G(SCH_1):GND
 235    GND VSS102 @T6G_MB_LIB.T6G(SCH_1):GND
 240    GND VSS104 @T6G_MB_LIB.T6G(SCH_1):GND
 132    GND  VSS58 @T6G_MB_LIB.T6G(SCH_1):GND
 136    GND  VSS60 @T6G_MB_LIB.T6G(SCH_1):GND
 139    GND  VSS61 @T6G_MB_LIB.T6G(SCH_1):GND
 141    GND  VSS62 @T6G_MB_LIB.T6G(SCH_1):GND
  G1    GND     G1 @T6G_MB_LIB.T6G(SCH_1):GND
  G2    GND     G2 @T6G_MB_LIB.T6G(SCH_1):GND
  G3    GND     G3 @T6G_MB_LIB.T6G(SCH_1):GND

Q_CAP_0402-0.1UF,25V,10%,X7R,CH4104K1B00  I185  C132
   1 P3V3_AUX      A @T6G_MB_LIB.T6G(SCH_1):P3V3_AUX
   2    GND      B @T6G_MB_LIB.T6G(SCH_1):GND

Q_RES_0402LF-1K,1%,1/16W,CHIP,CS21002FB06  I188  R302
   1 PWRGD_CHL_CPU0_DIMM      A @T6G_MB_LIB.T6G(SCH_1):PWRGD_CHL_CPU0_DIMM
   2 PWRGD_CHGL_CPU0      B @T6G_MB_LIB.T6G(SCH_1):PWRGD_CHGL_CPU0

Q_RES_0402LF-1K,1%,1/16W,EMPTY,CS21002FB06  I189  R101
   1   P3V3      A @T6G_MB_LIB.T6G(SCH_1):P3V3
   2 PWRGD_CHL_CPU0_DIMM      B @T6G_MB_LIB.T6G(SCH_1):PWRGD_CHL_CPU0_DIMM

SCONN288_DDR506112002KQ-SCONN288_DDR506112002KQ,SMA  I236  J67
  93 M_L_CPU0_SB_DQS_DP<9> DQS9_B_T||TDQS9_B_T||DBI4_B_N @T6G_MB_LIB.T6G(SCH_1):M_L_CPU0_SB_DQS_DP(9)
  94 M_L_CPU0_SB_DQS_DN<9> DQS9_B_C||TDQS9_B_C @T6G_MB_LIB.T6G(SCH_1):M_L_CPU0_SB_DQS_DN(9)
 201 M_L_CPU0_SA_DQS_DP<9> DQS9_A_T||TDQS9_A_T @T6G_MB_LIB.T6G(SCH_1):M_L_CPU0_SA_DQS_DP(9)
 200 M_L_CPU0_SA_DQS_DN<9> DQS9_A_C||TDQS9_A_C @T6G_MB_LIB.T6G(SCH_1):M_L_CPU0_SA_DQS_DN(9)
 190 M_L_CPU0_SA_DQS_DP<8> DQS8_A_T||TDQS8_A_T @T6G_MB_LIB.T6G(SCH_1):M_L_CPU0_SA_DQS_DP(8)
 189 M_L_CPU0_SA_DQS_DN<8> DQS8_A_C||TDQS8_A_C @T6G_MB_LIB.T6G(SCH_1):M_L_CPU0_SA_DQS_DN(8)
 271 M_L_CPU0_SB_DQS_DN<7> DQS7_B_C||TDQS7_B_C @T6G_MB_LIB.T6G(SCH_1):M_L_CPU0_SB_DQS_DN(7)
 179 M_L_CPU0_SA_DQS_DP<7> DQS7_A_T||TDQS7_A_T @T6G_MB_LIB.T6G(SCH_1):M_L_CPU0_SA_DQS_DP(7)
 261 M_L_CPU0_SB_DQS_DP<6> DQS6_B_T||TDQS6_B_T @T6G_MB_LIB.T6G(SCH_1):M_L_CPU0_SB_DQS_DP(6)
 260 M_L_CPU0_SB_DQS_DN<6> DQS6_B_C||TDQS6_B_C @T6G_MB_LIB.T6G(SCH_1):M_L_CPU0_SB_DQS_DN(6)
 167 M_L_CPU0_SA_DQS_DN<6> DQS6_A_C||TDQS6_A_C||DQS6_A_T||TDQS6_A_T @T6G_MB_LIB.T6G(SCH_1):M_L_CPU0_SA_DQS_DN(6)
 250 M_L_CPU0_SB_DQS_DP<5> DQS5_B_T||TDQS5_B_T @T6G_MB_LIB.T6G(SCH_1):M_L_CPU0_SB_DQS_DP(5)
 249 M_L_CPU0_SB_DQS_DN<5> DQS5_B_C||TDQS5_B_C @T6G_MB_LIB.T6G(SCH_1):M_L_CPU0_SB_DQS_DN(5)
 157 M_L_CPU0_SA_DQS_DP<5> DQS5_A_T||TDQS5_A_T @T6G_MB_LIB.T6G(SCH_1):M_L_CPU0_SA_DQS_DP(5)
 156 M_L_CPU0_SA_DQS_DN<5> DQS5_A_C||TDQS5_A_C||DQS5_A_T||TDQS5_A_T @T6G_MB_LIB.T6G(SCH_1):M_L_CPU0_SA_DQS_DN(5)
 239 M_L_CPU0_SB_DQS_DP<4> DQS4_B_T @T6G_MB_LIB.T6G(SCH_1):M_L_CPU0_SB_DQS_DP(4)
 238 M_L_CPU0_SB_DQS_DN<4> DQS4_B_C @T6G_MB_LIB.T6G(SCH_1):M_L_CPU0_SB_DQS_DN(4)
  55 M_L_CPU0_SA_DQS_DP<4> DQS4_A_T @T6G_MB_LIB.T6G(SCH_1):M_L_CPU0_SA_DQS_DP(4)
  56 M_L_CPU0_SA_DQS_DN<4> DQS4_A_C @T6G_MB_LIB.T6G(SCH_1):M_L_CPU0_SA_DQS_DN(4)
 137 M_L_CPU0_SB_DQS_DP<3> DQS3_B_T @T6G_MB_LIB.T6G(SCH_1):M_L_CPU0_SB_DQS_DP(3)
 138 M_L_CPU0_SB_DQS_DN<3> DQS3_B_C @T6G_MB_LIB.T6G(SCH_1):M_L_CPU0_SB_DQS_DN(3)
  44 M_L_CPU0_SA_DQS_DP<3> DQS3_A_T @T6G_MB_LIB.T6G(SCH_1):M_L_CPU0_SA_DQS_DP(3)
  45 M_L_CPU0_SA_DQS_DN<3> DQS3_A_C @T6G_MB_LIB.T6G(SCH_1):M_L_CPU0_SA_DQS_DN(3)
 126 M_L_CPU0_SB_DQS_DP<2> DQS2_B_T @T6G_MB_LIB.T6G(SCH_1):M_L_CPU0_SB_DQS_DP(2)
 127 M_L_CPU0_SB_DQS_DN<2> DQS2_B_C @T6G_MB_LIB.T6G(SCH_1):M_L_CPU0_SB_DQS_DN(2)
  33 M_L_CPU0_SA_DQS_DP<2> DQS2_A_T @T6G_MB_LIB.T6G(SCH_1):M_L_CPU0_SA_DQS_DP(2)
  34 M_L_CPU0_SA_DQS_DN<2> DQS2_A_C @T6G_MB_LIB.T6G(SCH_1):M_L_CPU0_SA_DQS_DN(2)
 115 M_L_CPU0_SB_DQS_DP<1> DQS1_B_T @T6G_MB_LIB.T6G(SCH_1):M_L_CPU0_SB_DQS_DP(1)
 116 M_L_CPU0_SB_DQS_DN<1> DQS1_B_C @T6G_MB_LIB.T6G(SCH_1):M_L_CPU0_SB_DQS_DN(1)
  22 M_L_CPU0_SA_DQS_DP<1> DQS1_A_T @T6G_MB_LIB.T6G(SCH_1):M_L_CPU0_SA_DQS_DP(1)
  23 M_L_CPU0_SA_DQS_DN<1> DQS1_A_C @T6G_MB_LIB.T6G(SCH_1):M_L_CPU0_SA_DQS_DN(1)
 104 M_L_CPU0_SB_DQS_DP<0> DQS0_B_T @T6G_MB_LIB.T6G(SCH_1):M_L_CPU0_SB_DQS_DP(0)
 105 M_L_CPU0_SB_DQS_DN<0> DQS0_B_C @T6G_MB_LIB.T6G(SCH_1):M_L_CPU0_SB_DQS_DN(0)
  11 M_L_CPU0_SA_DQS_DP<0> DQS0_A_T @T6G_MB_LIB.T6G(SCH_1):M_L_CPU0_SA_DQS_DP(0)
  12 M_L_CPU0_SA_DQS_DN<0> DQS0_A_C @T6G_MB_LIB.T6G(SCH_1):M_L_CPU0_SA_DQS_DN(0)
 272 M_L_CPU0_SB_DQS_DP<7> DQS7_B_T||TDQS7_B_T @T6G_MB_LIB.T6G(SCH_1):M_L_CPU0_SB_DQS_DP(7)
 282 M_L_CPU0_SB_DQS_DN<8> DQS8_B_C||TDQS8_B_C @T6G_MB_LIB.T6G(SCH_1):M_L_CPU0_SB_DQS_DN(8)
 283 M_L_CPU0_SB_DQS_DP<8> DQS8_B_T||TDQS8_B_T @T6G_MB_LIB.T6G(SCH_1):M_L_CPU0_SB_DQS_DP(8)
 168 M_L_CPU0_SA_DQS_DP<6> DQS6_A_T||TDQS6_A_T @T6G_MB_LIB.T6G(SCH_1):M_L_CPU0_SA_DQS_DP(6)
 178 M_L_CPU0_SA_DQS_DN<7> DQS7_A_C||TDQS7_A_C @T6G_MB_LIB.T6G(SCH_1):M_L_CPU0_SA_DQS_DN(7)

Q_CAP_C0805-10UF,25V,10%,X6S,CH6104KEA00  I238  C170
   1 P12V_MEM_CPU0      A @T6G_MB_LIB.T6G(SCH_1):P12V_MEM_CPU0
   2    GND      B @T6G_MB_LIB.T6G(SCH_1):GND

Q_CAP_C0805-10UF,25V,10%,X6S,CH6104KEA00  I239  C171
   1 P12V_MEM_CPU0      A @T6G_MB_LIB.T6G(SCH_1):P12V_MEM_CPU0
   2    GND      B @T6G_MB_LIB.T6G(SCH_1):GND

Q_RES_0402LF-49.9,1%,1/16W,CHIP,CS04992FB07  I242  R1579
   1 I3C_SPD_DDRGL_CPU0_SCL      A @T6G_MB_LIB.T6G(SCH_1):I3C_SPD_DDRGL_CPU0_SCL
   2 I3C_SPD_DDRL_CPU0_SCL      B @T6G_MB_LIB.T6G(SCH_1):I3C_SPD_DDRL_CPU0_SCL

Q_RES_0402LF-10,1%,1/16W,CHIP,CS01002FB07  I243  R1686
   1 I3C_SPD_DDRGL_CPU0_SDA      A @T6G_MB_LIB.T6G(SCH_1):I3C_SPD_DDRGL_CPU0_SDA
   2 I3C_SPD_DDRL_CPU0_SDA      B @T6G_MB_LIB.T6G(SCH_1):I3C_SPD_DDRL_CPU0_SDA


DRAWING: @T6G_MB_LIB.T6G(SCH_1):PAGE97 

SCONN288_DDR506112002KQ-SCONN288_DDR506112002KQ,SMA  I22  J24
   3 P3V3_AUX VIN_MGMT @T6G_MB_LIB.T6G(SCH_1):P3V3_AUX
   2     NC   RFU0     NC
 144     NC   RFU1     NC
 149     NC   RFU2     NC
 150     NC   RFU3     NC
 220     NC   RFU4     NC
 231     NC   RFU5     NC
 232     NC   RFU6     NC
 207 M_A_CPU1_RESET_N RESET_N @T6G_MB_LIB.T6G(SCH_1):M_A_CPU1_RESET_N
 147 PWRGD_CHA_CPU1_DIMM0 PWR_GOOD||FAIL_N @T6G_MB_LIB.T6G(SCH_1):PWRGD_CHA_CPU1_DIMM0
 227 M_A_CPU1_SB_PAR  PAR_B @T6G_MB_LIB.T6G(SCH_1):M_A_CPU1_SB_PAR
  74 M_A_CPU1_SA_PAR  PAR_A @T6G_MB_LIB.T6G(SCH_1):M_A_CPU1_SA_PAR
  87 M_A_CPU1_SB_RSP<0> LBS||RSP_B_N @T6G_MB_LIB.T6G(SCH_1):M_A_CPU1_SB_RSP(0)
  86 M_A_CPU1_SA_RSP<0> LBD||RSP_A_N @T6G_MB_LIB.T6G(SCH_1):M_A_CPU1_SA_RSP(0)
   5 I3C_SPD_DDRA_CPU1_SDA   HSDA @T6G_MB_LIB.T6G(SCH_1):I3C_SPD_DDRA_CPU1_SDA
   4 I3C_SPD_DDRA_CPU1_SCL   HSCL @T6G_MB_LIB.T6G(SCH_1):I3C_SPD_DDRA_CPU1_SCL
 148 PD_CHA_CPU1_DIMM0_SAA    HAS @T6G_MB_LIB.T6G(SCH_1):PD_CHA_CPU1_DIMM0_SAA
 100 M_A_CPU1_SB_DQ<0>  DQ0_B @T6G_MB_LIB.T6G(SCH_1):M_A_CPU1_SB_DQ(0)
 102 M_A_CPU1_SB_DQ<1>  DQ1_B @T6G_MB_LIB.T6G(SCH_1):M_A_CPU1_SB_DQ(1)
 245 M_A_CPU1_SB_DQ<2>  DQ2_B @T6G_MB_LIB.T6G(SCH_1):M_A_CPU1_SB_DQ(2)
 247 M_A_CPU1_SB_DQ<3>  DQ3_B @T6G_MB_LIB.T6G(SCH_1):M_A_CPU1_SB_DQ(3)
 107 M_A_CPU1_SB_DQ<4>  DQ4_B @T6G_MB_LIB.T6G(SCH_1):M_A_CPU1_SB_DQ(4)
 109 M_A_CPU1_SB_DQ<5>  DQ5_B @T6G_MB_LIB.T6G(SCH_1):M_A_CPU1_SB_DQ(5)
 252 M_A_CPU1_SB_DQ<6>  DQ6_B @T6G_MB_LIB.T6G(SCH_1):M_A_CPU1_SB_DQ(6)
 254 M_A_CPU1_SB_DQ<7>  DQ7_B @T6G_MB_LIB.T6G(SCH_1):M_A_CPU1_SB_DQ(7)
 111 M_A_CPU1_SB_DQ<8>  DQ8_B @T6G_MB_LIB.T6G(SCH_1):M_A_CPU1_SB_DQ(8)
 113 M_A_CPU1_SB_DQ<9>  DQ9_B @T6G_MB_LIB.T6G(SCH_1):M_A_CPU1_SB_DQ(9)
 256 M_A_CPU1_SB_DQ<10> DQ10_B @T6G_MB_LIB.T6G(SCH_1):M_A_CPU1_SB_DQ(10)
 258 M_A_CPU1_SB_DQ<11> DQ11_B @T6G_MB_LIB.T6G(SCH_1):M_A_CPU1_SB_DQ(11)
 118 M_A_CPU1_SB_DQ<12> DQ12_B @T6G_MB_LIB.T6G(SCH_1):M_A_CPU1_SB_DQ(12)
 120 M_A_CPU1_SB_DQ<13> DQ13_B @T6G_MB_LIB.T6G(SCH_1):M_A_CPU1_SB_DQ(13)
 263 M_A_CPU1_SB_DQ<14> DQ14_B @T6G_MB_LIB.T6G(SCH_1):M_A_CPU1_SB_DQ(14)
 265 M_A_CPU1_SB_DQ<15> DQ15_B @T6G_MB_LIB.T6G(SCH_1):M_A_CPU1_SB_DQ(15)
 122 M_A_CPU1_SB_DQ<16> DQ16_B @T6G_MB_LIB.T6G(SCH_1):M_A_CPU1_SB_DQ(16)
 124 M_A_CPU1_SB_DQ<17> DQ17_B @T6G_MB_LIB.T6G(SCH_1):M_A_CPU1_SB_DQ(17)
 267 M_A_CPU1_SB_DQ<18> DQ18_B @T6G_MB_LIB.T6G(SCH_1):M_A_CPU1_SB_DQ(18)
 269 M_A_CPU1_SB_DQ<19> DQ19_B @T6G_MB_LIB.T6G(SCH_1):M_A_CPU1_SB_DQ(19)
 129 M_A_CPU1_SB_DQ<20> DQ20_B @T6G_MB_LIB.T6G(SCH_1):M_A_CPU1_SB_DQ(20)
 131 M_A_CPU1_SB_DQ<21> DQ21_B @T6G_MB_LIB.T6G(SCH_1):M_A_CPU1_SB_DQ(21)
 274 M_A_CPU1_SB_DQ<22> DQ22_B @T6G_MB_LIB.T6G(SCH_1):M_A_CPU1_SB_DQ(22)
 276 M_A_CPU1_SB_DQ<23> DQ23_B @T6G_MB_LIB.T6G(SCH_1):M_A_CPU1_SB_DQ(23)
 133 M_A_CPU1_SB_DQ<24> DQ24_B @T6G_MB_LIB.T6G(SCH_1):M_A_CPU1_SB_DQ(24)
 135 M_A_CPU1_SB_DQ<25> DQ25_B @T6G_MB_LIB.T6G(SCH_1):M_A_CPU1_SB_DQ(25)
 278 M_A_CPU1_SB_DQ<26> DQ26_B @T6G_MB_LIB.T6G(SCH_1):M_A_CPU1_SB_DQ(26)
 280 M_A_CPU1_SB_DQ<27> DQ27_B @T6G_MB_LIB.T6G(SCH_1):M_A_CPU1_SB_DQ(27)
 140 M_A_CPU1_SB_DQ<28> DQ28_B @T6G_MB_LIB.T6G(SCH_1):M_A_CPU1_SB_DQ(28)
 142 M_A_CPU1_SB_DQ<29> DQ29_B @T6G_MB_LIB.T6G(SCH_1):M_A_CPU1_SB_DQ(29)
 285 M_A_CPU1_SB_DQ<30> DQ30_B @T6G_MB_LIB.T6G(SCH_1):M_A_CPU1_SB_DQ(30)
 287 M_A_CPU1_SB_DQ<31> DQ31_B @T6G_MB_LIB.T6G(SCH_1):M_A_CPU1_SB_DQ(31)
   7 M_A_CPU1_SA_DQ<0>  DQ0_A @T6G_MB_LIB.T6G(SCH_1):M_A_CPU1_SA_DQ(0)
   9 M_A_CPU1_SA_DQ<1>  DQ1_A @T6G_MB_LIB.T6G(SCH_1):M_A_CPU1_SA_DQ(1)
 152 M_A_CPU1_SA_DQ<2>  DQ2_A @T6G_MB_LIB.T6G(SCH_1):M_A_CPU1_SA_DQ(2)
 154 M_A_CPU1_SA_DQ<3>  DQ3_A @T6G_MB_LIB.T6G(SCH_1):M_A_CPU1_SA_DQ(3)
  14 M_A_CPU1_SA_DQ<4>  DQ4_A @T6G_MB_LIB.T6G(SCH_1):M_A_CPU1_SA_DQ(4)
  16 M_A_CPU1_SA_DQ<5>  DQ5_A @T6G_MB_LIB.T6G(SCH_1):M_A_CPU1_SA_DQ(5)
 159 M_A_CPU1_SA_DQ<6>  DQ6_A @T6G_MB_LIB.T6G(SCH_1):M_A_CPU1_SA_DQ(6)
 161 M_A_CPU1_SA_DQ<7>  DQ7_A @T6G_MB_LIB.T6G(SCH_1):M_A_CPU1_SA_DQ(7)
  18 M_A_CPU1_SA_DQ<8>  DQ8_A @T6G_MB_LIB.T6G(SCH_1):M_A_CPU1_SA_DQ(8)
  20 M_A_CPU1_SA_DQ<9>  DQ9_A @T6G_MB_LIB.T6G(SCH_1):M_A_CPU1_SA_DQ(9)
 163 M_A_CPU1_SA_DQ<10> DQ10_A @T6G_MB_LIB.T6G(SCH_1):M_A_CPU1_SA_DQ(10)
 165 M_A_CPU1_SA_DQ<11> DQ11_A @T6G_MB_LIB.T6G(SCH_1):M_A_CPU1_SA_DQ(11)
  25 M_A_CPU1_SA_DQ<12> DQ12_A @T6G_MB_LIB.T6G(SCH_1):M_A_CPU1_SA_DQ(12)
  27 M_A_CPU1_SA_DQ<13> DQ13_A @T6G_MB_LIB.T6G(SCH_1):M_A_CPU1_SA_DQ(13)
 170 M_A_CPU1_SA_DQ<14> DQ14_A @T6G_MB_LIB.T6G(SCH_1):M_A_CPU1_SA_DQ(14)
 172 M_A_CPU1_SA_DQ<15> DQ15_A @T6G_MB_LIB.T6G(SCH_1):M_A_CPU1_SA_DQ(15)
  29 M_A_CPU1_SA_DQ<16> DQ16_A @T6G_MB_LIB.T6G(SCH_1):M_A_CPU1_SA_DQ(16)
  31 M_A_CPU1_SA_DQ<17> DQ17_A @T6G_MB_LIB.T6G(SCH_1):M_A_CPU1_SA_DQ(17)
 174 M_A_CPU1_SA_DQ<18> DQ18_A @T6G_MB_LIB.T6G(SCH_1):M_A_CPU1_SA_DQ(18)
 176 M_A_CPU1_SA_DQ<19> DQ19_A @T6G_MB_LIB.T6G(SCH_1):M_A_CPU1_SA_DQ(19)
  36 M_A_CPU1_SA_DQ<20> DQ20_A @T6G_MB_LIB.T6G(SCH_1):M_A_CPU1_SA_DQ(20)
  38 M_A_CPU1_SA_DQ<21> DQ21_A @T6G_MB_LIB.T6G(SCH_1):M_A_CPU1_SA_DQ(21)
 181 M_A_CPU1_SA_DQ<22> DQ22_A @T6G_MB_LIB.T6G(SCH_1):M_A_CPU1_SA_DQ(22)
 183 M_A_CPU1_SA_DQ<23> DQ23_A @T6G_MB_LIB.T6G(SCH_1):M_A_CPU1_SA_DQ(23)
  40 M_A_CPU1_SA_DQ<24> DQ24_A @T6G_MB_LIB.T6G(SCH_1):M_A_CPU1_SA_DQ(24)
  42 M_A_CPU1_SA_DQ<25> DQ25_A @T6G_MB_LIB.T6G(SCH_1):M_A_CPU1_SA_DQ(25)
 185 M_A_CPU1_SA_DQ<26> DQ26_A @T6G_MB_LIB.T6G(SCH_1):M_A_CPU1_SA_DQ(26)
 187 M_A_CPU1_SA_DQ<27> DQ27_A @T6G_MB_LIB.T6G(SCH_1):M_A_CPU1_SA_DQ(27)
  47 M_A_CPU1_SA_DQ<28> DQ28_A @T6G_MB_LIB.T6G(SCH_1):M_A_CPU1_SA_DQ(28)
  49 M_A_CPU1_SA_DQ<29> DQ29_A @T6G_MB_LIB.T6G(SCH_1):M_A_CPU1_SA_DQ(29)
 192 M_A_CPU1_SA_DQ<30> DQ30_A @T6G_MB_LIB.T6G(SCH_1):M_A_CPU1_SA_DQ(30)
 229 M_A_CPU1_SB_CS_N<1> CS1_B_N @T6G_MB_LIB.T6G(SCH_1):M_A_CPU1_SB_CS_N(1)
 209 M_A_CPU1_SA_CS_N<1> CS1_A_N @T6G_MB_LIB.T6G(SCH_1):M_A_CPU1_SA_CS_N(1)
  84 M_A_CPU1_SB_CS_N<0> CS0_B_N @T6G_MB_LIB.T6G(SCH_1):M_A_CPU1_SB_CS_N(0)
  64 M_A_CPU1_SA_CS_N<0> CS0_A_N @T6G_MB_LIB.T6G(SCH_1):M_A_CPU1_SA_CS_N(0)
 217 M_A_CPU1_CLK_DP<0>   CK_T @T6G_MB_LIB.T6G(SCH_1):M_A_CPU1_CLK_DP(0)
 218 M_A_CPU1_CLK_DN<0>   CK_C @T6G_MB_LIB.T6G(SCH_1):M_A_CPU1_CLK_DN(0)
  96 M_A_CPU1_SB_CB<0>  CB0_B @T6G_MB_LIB.T6G(SCH_1):M_A_CPU1_SB_CB(0)
  98 M_A_CPU1_SB_CB<1>  CB1_B @T6G_MB_LIB.T6G(SCH_1):M_A_CPU1_SB_CB(1)
 241 M_A_CPU1_SB_CB<2>  CB2_B @T6G_MB_LIB.T6G(SCH_1):M_A_CPU1_SB_CB(2)
 243 M_A_CPU1_SB_CB<3>  CB3_B @T6G_MB_LIB.T6G(SCH_1):M_A_CPU1_SB_CB(3)
  89 M_A_CPU1_SB_CB<4>  CB4_B @T6G_MB_LIB.T6G(SCH_1):M_A_CPU1_SB_CB(4)
  91 M_A_CPU1_SB_CB<5>  CB5_B @T6G_MB_LIB.T6G(SCH_1):M_A_CPU1_SB_CB(5)
 234 M_A_CPU1_SB_CB<6>  CB6_B @T6G_MB_LIB.T6G(SCH_1):M_A_CPU1_SB_CB(6)
  51 M_A_CPU1_SA_CB<0>  CB0_A @T6G_MB_LIB.T6G(SCH_1):M_A_CPU1_SA_CB(0)
 196 M_A_CPU1_SA_CB<2>  CB2_A @T6G_MB_LIB.T6G(SCH_1):M_A_CPU1_SA_CB(2)
 198 M_A_CPU1_SA_CB<3>  CB3_A @T6G_MB_LIB.T6G(SCH_1):M_A_CPU1_SA_CB(3)
  60 M_A_CPU1_SA_CB<5>  CB5_A @T6G_MB_LIB.T6G(SCH_1):M_A_CPU1_SA_CB(5)
 203 M_A_CPU1_SA_CB<6>  CB6_A @T6G_MB_LIB.T6G(SCH_1):M_A_CPU1_SA_CB(6)
  82 M_A_CPU1_SB_CA<6>  CA6_B @T6G_MB_LIB.T6G(SCH_1):M_A_CPU1_SB_CA(6)
  72 M_A_CPU1_SA_CA<6>  CA6_A @T6G_MB_LIB.T6G(SCH_1):M_A_CPU1_SA_CA(6)
 225 M_A_CPU1_SB_CA<5>  CA5_B @T6G_MB_LIB.T6G(SCH_1):M_A_CPU1_SB_CA(5)
 215 M_A_CPU1_SA_CA<5>  CA5_A @T6G_MB_LIB.T6G(SCH_1):M_A_CPU1_SA_CA(5)
  80 M_A_CPU1_SB_CA<4>  CA4_B @T6G_MB_LIB.T6G(SCH_1):M_A_CPU1_SB_CA(4)
  70 M_A_CPU1_SA_CA<4>  CA4_A @T6G_MB_LIB.T6G(SCH_1):M_A_CPU1_SA_CA(4)
 223 M_A_CPU1_SB_CA<3>  CA3_B @T6G_MB_LIB.T6G(SCH_1):M_A_CPU1_SB_CA(3)
 213 M_A_CPU1_SA_CA<3>  CA3_A @T6G_MB_LIB.T6G(SCH_1):M_A_CPU1_SA_CA(3)
  78 M_A_CPU1_SB_CA<2>  CA2_B @T6G_MB_LIB.T6G(SCH_1):M_A_CPU1_SB_CA(2)
  68 M_A_CPU1_SA_CA<2>  CA2_A @T6G_MB_LIB.T6G(SCH_1):M_A_CPU1_SA_CA(2)
 221 M_A_CPU1_SB_CA<1>  CA1_B @T6G_MB_LIB.T6G(SCH_1):M_A_CPU1_SB_CA(1)
 211 M_A_CPU1_SA_CA<1>  CA1_A @T6G_MB_LIB.T6G(SCH_1):M_A_CPU1_SA_CA(1)
  76 M_A_CPU1_SB_CA<0>  CA0_B @T6G_MB_LIB.T6G(SCH_1):M_A_CPU1_SB_CA(0)
  66 M_A_CPU1_SA_CA<0>  CA0_A @T6G_MB_LIB.T6G(SCH_1):M_A_CPU1_SA_CA(0)
  62 M_A_CPU1_ALERT_N ALERT_N @T6G_MB_LIB.T6G(SCH_1):M_A_CPU1_ALERT_N
 236 M_A_CPU1_SB_CB<7>  CB7_B @T6G_MB_LIB.T6G(SCH_1):M_A_CPU1_SB_CB(7)
  53 M_A_CPU1_SA_CB<1>  CB1_A @T6G_MB_LIB.T6G(SCH_1):M_A_CPU1_SA_CB(1)
  58 M_A_CPU1_SA_CB<4>  CB4_A @T6G_MB_LIB.T6G(SCH_1):M_A_CPU1_SA_CB(4)
 205 M_A_CPU1_SA_CB<7>  CB7_A @T6G_MB_LIB.T6G(SCH_1):M_A_CPU1_SA_CB(7)
 194 M_A_CPU1_SA_DQ<31> DQ31_A @T6G_MB_LIB.T6G(SCH_1):M_A_CPU1_SA_DQ(31)

Q_RES_0402LF-10K,1%,1/16W,CHIP,CS31002FB08  I129  R36
   1 PD_CHA_CPU1_DIMM0_SAA      A @T6G_MB_LIB.T6G(SCH_1):PD_CHA_CPU1_DIMM0_SAA
   2    GND      B @T6G_MB_LIB.T6G(SCH_1):GND

SCONN288_DDR506112002KQ-SCONN288_DDR506112002KQ,SMA  I177  J24
   6    GND   VSS0 @T6G_MB_LIB.T6G(SCH_1):GND
   8    GND   VSS1 @T6G_MB_LIB.T6G(SCH_1):GND
  10    GND   VSS2 @T6G_MB_LIB.T6G(SCH_1):GND
  13    GND   VSS3 @T6G_MB_LIB.T6G(SCH_1):GND
  15    GND   VSS4 @T6G_MB_LIB.T6G(SCH_1):GND
  17    GND   VSS5 @T6G_MB_LIB.T6G(SCH_1):GND
  19    GND   VSS6 @T6G_MB_LIB.T6G(SCH_1):GND
  21    GND   VSS7 @T6G_MB_LIB.T6G(SCH_1):GND
  24    GND   VSS8 @T6G_MB_LIB.T6G(SCH_1):GND
  26    GND   VSS9 @T6G_MB_LIB.T6G(SCH_1):GND
  28    GND  VSS10 @T6G_MB_LIB.T6G(SCH_1):GND
  30    GND  VSS11 @T6G_MB_LIB.T6G(SCH_1):GND
  32    GND  VSS12 @T6G_MB_LIB.T6G(SCH_1):GND
  35    GND  VSS13 @T6G_MB_LIB.T6G(SCH_1):GND
  37    GND  VSS14 @T6G_MB_LIB.T6G(SCH_1):GND
  39    GND  VSS15 @T6G_MB_LIB.T6G(SCH_1):GND
  41    GND  VSS16 @T6G_MB_LIB.T6G(SCH_1):GND
  43    GND  VSS17 @T6G_MB_LIB.T6G(SCH_1):GND
  46    GND  VSS18 @T6G_MB_LIB.T6G(SCH_1):GND
  48    GND  VSS19 @T6G_MB_LIB.T6G(SCH_1):GND
  50    GND  VSS20 @T6G_MB_LIB.T6G(SCH_1):GND
  52    GND  VSS21 @T6G_MB_LIB.T6G(SCH_1):GND
  54    GND  VSS22 @T6G_MB_LIB.T6G(SCH_1):GND
  57    GND  VSS23 @T6G_MB_LIB.T6G(SCH_1):GND
  59    GND  VSS24 @T6G_MB_LIB.T6G(SCH_1):GND
  61    GND  VSS25 @T6G_MB_LIB.T6G(SCH_1):GND
  63    GND  VSS26 @T6G_MB_LIB.T6G(SCH_1):GND
  65    GND  VSS27 @T6G_MB_LIB.T6G(SCH_1):GND
  67    GND  VSS28 @T6G_MB_LIB.T6G(SCH_1):GND
  69    GND  VSS29 @T6G_MB_LIB.T6G(SCH_1):GND
  71    GND  VSS30 @T6G_MB_LIB.T6G(SCH_1):GND
  73    GND  VSS31 @T6G_MB_LIB.T6G(SCH_1):GND
  75    GND  VSS32 @T6G_MB_LIB.T6G(SCH_1):GND
  77    GND  VSS33 @T6G_MB_LIB.T6G(SCH_1):GND
  79    GND  VSS34 @T6G_MB_LIB.T6G(SCH_1):GND
  81    GND  VSS35 @T6G_MB_LIB.T6G(SCH_1):GND
  83    GND  VSS36 @T6G_MB_LIB.T6G(SCH_1):GND
  85    GND  VSS37 @T6G_MB_LIB.T6G(SCH_1):GND
  88    GND  VSS38 @T6G_MB_LIB.T6G(SCH_1):GND
  90    GND  VSS39 @T6G_MB_LIB.T6G(SCH_1):GND
  92    GND  VSS40 @T6G_MB_LIB.T6G(SCH_1):GND
  95    GND  VSS41 @T6G_MB_LIB.T6G(SCH_1):GND
  97    GND  VSS42 @T6G_MB_LIB.T6G(SCH_1):GND
  99    GND  VSS43 @T6G_MB_LIB.T6G(SCH_1):GND
 101    GND  VSS44 @T6G_MB_LIB.T6G(SCH_1):GND
 103    GND  VSS45 @T6G_MB_LIB.T6G(SCH_1):GND
 106    GND  VSS46 @T6G_MB_LIB.T6G(SCH_1):GND
 108    GND  VSS47 @T6G_MB_LIB.T6G(SCH_1):GND
 110    GND  VSS48 @T6G_MB_LIB.T6G(SCH_1):GND
 112    GND  VSS49 @T6G_MB_LIB.T6G(SCH_1):GND
 114    GND  VSS50 @T6G_MB_LIB.T6G(SCH_1):GND
 117    GND  VSS51 @T6G_MB_LIB.T6G(SCH_1):GND
 119    GND  VSS52 @T6G_MB_LIB.T6G(SCH_1):GND
 121    GND  VSS53 @T6G_MB_LIB.T6G(SCH_1):GND
 123    GND  VSS54 @T6G_MB_LIB.T6G(SCH_1):GND
 125    GND  VSS55 @T6G_MB_LIB.T6G(SCH_1):GND
 128    GND  VSS56 @T6G_MB_LIB.T6G(SCH_1):GND
 130    GND  VSS57 @T6G_MB_LIB.T6G(SCH_1):GND
 134    GND  VSS59 @T6G_MB_LIB.T6G(SCH_1):GND
 143    GND  VSS63 @T6G_MB_LIB.T6G(SCH_1):GND
 151    GND  VSS64 @T6G_MB_LIB.T6G(SCH_1):GND
 153    GND  VSS65 @T6G_MB_LIB.T6G(SCH_1):GND
 155    GND  VSS66 @T6G_MB_LIB.T6G(SCH_1):GND
 158    GND  VSS67 @T6G_MB_LIB.T6G(SCH_1):GND
 160    GND  VSS68 @T6G_MB_LIB.T6G(SCH_1):GND
 162    GND  VSS69 @T6G_MB_LIB.T6G(SCH_1):GND
 164    GND  VSS70 @T6G_MB_LIB.T6G(SCH_1):GND
 166    GND  VSS71 @T6G_MB_LIB.T6G(SCH_1):GND
 169    GND  VSS72 @T6G_MB_LIB.T6G(SCH_1):GND
 171    GND  VSS73 @T6G_MB_LIB.T6G(SCH_1):GND
 173    GND  VSS74 @T6G_MB_LIB.T6G(SCH_1):GND
 175    GND  VSS75 @T6G_MB_LIB.T6G(SCH_1):GND
 177    GND  VSS76 @T6G_MB_LIB.T6G(SCH_1):GND
 180    GND  VSS77 @T6G_MB_LIB.T6G(SCH_1):GND
 182    GND  VSS78 @T6G_MB_LIB.T6G(SCH_1):GND
 184    GND  VSS79 @T6G_MB_LIB.T6G(SCH_1):GND
 186    GND  VSS80 @T6G_MB_LIB.T6G(SCH_1):GND
 188    GND  VSS81 @T6G_MB_LIB.T6G(SCH_1):GND
 191    GND  VSS82 @T6G_MB_LIB.T6G(SCH_1):GND
 193    GND  VSS83 @T6G_MB_LIB.T6G(SCH_1):GND
 195    GND  VSS84 @T6G_MB_LIB.T6G(SCH_1):GND
 197    GND  VSS85 @T6G_MB_LIB.T6G(SCH_1):GND
 199    GND  VSS86 @T6G_MB_LIB.T6G(SCH_1):GND
 202    GND  VSS87 @T6G_MB_LIB.T6G(SCH_1):GND
 204    GND  VSS88 @T6G_MB_LIB.T6G(SCH_1):GND
 206    GND  VSS89 @T6G_MB_LIB.T6G(SCH_1):GND
 208    GND  VSS90 @T6G_MB_LIB.T6G(SCH_1):GND
 210    GND  VSS91 @T6G_MB_LIB.T6G(SCH_1):GND
 212    GND  VSS92 @T6G_MB_LIB.T6G(SCH_1):GND
 214    GND  VSS93 @T6G_MB_LIB.T6G(SCH_1):GND
 216    GND  VSS94 @T6G_MB_LIB.T6G(SCH_1):GND
 219    GND  VSS95 @T6G_MB_LIB.T6G(SCH_1):GND
 222    GND  VSS96 @T6G_MB_LIB.T6G(SCH_1):GND
 224    GND  VSS97 @T6G_MB_LIB.T6G(SCH_1):GND
 226    GND  VSS98 @T6G_MB_LIB.T6G(SCH_1):GND
 228    GND  VSS99 @T6G_MB_LIB.T6G(SCH_1):GND
 233    GND VSS101 @T6G_MB_LIB.T6G(SCH_1):GND
 237    GND VSS103 @T6G_MB_LIB.T6G(SCH_1):GND
 242    GND VSS105 @T6G_MB_LIB.T6G(SCH_1):GND
 244    GND VSS106 @T6G_MB_LIB.T6G(SCH_1):GND
 246    GND VSS107 @T6G_MB_LIB.T6G(SCH_1):GND
 248    GND VSS108 @T6G_MB_LIB.T6G(SCH_1):GND
 251    GND VSS109 @T6G_MB_LIB.T6G(SCH_1):GND
 253    GND VSS110 @T6G_MB_LIB.T6G(SCH_1):GND
 255    GND VSS111 @T6G_MB_LIB.T6G(SCH_1):GND
 257    GND VSS112 @T6G_MB_LIB.T6G(SCH_1):GND
 259    GND VSS113 @T6G_MB_LIB.T6G(SCH_1):GND
 262    GND VSS114 @T6G_MB_LIB.T6G(SCH_1):GND
 264    GND VSS115 @T6G_MB_LIB.T6G(SCH_1):GND
 266    GND VSS116 @T6G_MB_LIB.T6G(SCH_1):GND
 268    GND VSS117 @T6G_MB_LIB.T6G(SCH_1):GND
 270    GND VSS118 @T6G_MB_LIB.T6G(SCH_1):GND
 273    GND VSS119 @T6G_MB_LIB.T6G(SCH_1):GND
 275    GND VSS120 @T6G_MB_LIB.T6G(SCH_1):GND
 277    GND VSS121 @T6G_MB_LIB.T6G(SCH_1):GND
 279    GND VSS122 @T6G_MB_LIB.T6G(SCH_1):GND
 281    GND VSS123 @T6G_MB_LIB.T6G(SCH_1):GND
 284    GND VSS124 @T6G_MB_LIB.T6G(SCH_1):GND
 286    GND VSS125 @T6G_MB_LIB.T6G(SCH_1):GND
 288    GND VSS126 @T6G_MB_LIB.T6G(SCH_1):GND
   1 P12V_MEM_CPU1 VIN_BULK0 @T6G_MB_LIB.T6G(SCH_1):P12V_MEM_CPU1
 145 P12V_MEM_CPU1 VIN_BULK1 @T6G_MB_LIB.T6G(SCH_1):P12V_MEM_CPU1
 146 P12V_MEM_CPU1 VIN_BULK2 @T6G_MB_LIB.T6G(SCH_1):P12V_MEM_CPU1
 230    GND VSS100 @T6G_MB_LIB.T6G(SCH_1):GND
 235    GND VSS102 @T6G_MB_LIB.T6G(SCH_1):GND
 240    GND VSS104 @T6G_MB_LIB.T6G(SCH_1):GND
 132    GND  VSS58 @T6G_MB_LIB.T6G(SCH_1):GND
 136    GND  VSS60 @T6G_MB_LIB.T6G(SCH_1):GND
 139    GND  VSS61 @T6G_MB_LIB.T6G(SCH_1):GND
 141    GND  VSS62 @T6G_MB_LIB.T6G(SCH_1):GND
  G1    GND     G1 @T6G_MB_LIB.T6G(SCH_1):GND
  G2    GND     G2 @T6G_MB_LIB.T6G(SCH_1):GND
  G3    GND     G3 @T6G_MB_LIB.T6G(SCH_1):GND

Q_CAP_0402-0.1UF,25V,10%,X7R,CH4104K1B00  I185  C136
   1 P3V3_AUX      A @T6G_MB_LIB.T6G(SCH_1):P3V3_AUX
   2    GND      B @T6G_MB_LIB.T6G(SCH_1):GND

Q_RES_0402LF-1K,1%,1/16W,EMPTY,CS21002FB06  I189  R102
   1   P3V3      A @T6G_MB_LIB.T6G(SCH_1):P3V3
   2 PWRGD_CHAF_CPU1      B @T6G_MB_LIB.T6G(SCH_1):PWRGD_CHAF_CPU1

Q_RES_0402LF-1K,1%,1/16W,CHIP,CS21002FB06  I190  R303
   1 PWRGD_CHA_CPU1_DIMM0      A @T6G_MB_LIB.T6G(SCH_1):PWRGD_CHA_CPU1_DIMM0
   2 PWRGD_CHAF_CPU1      B @T6G_MB_LIB.T6G(SCH_1):PWRGD_CHAF_CPU1

Q_RES_0402LF-1K,1%,1/16W,EMPTY,CS21002FB06  I191  R103
   1   P3V3      A @T6G_MB_LIB.T6G(SCH_1):P3V3
   2 PWRGD_CHA_CPU1_DIMM0      B @T6G_MB_LIB.T6G(SCH_1):PWRGD_CHA_CPU1_DIMM0

SCONN288_DDR506112002KQ-SCONN288_DDR506112002KQ,SMA  I238  J24
  93 M_A_CPU1_SB_DQS_DP<9> DQS9_B_T||TDQS9_B_T||DBI4_B_N @T6G_MB_LIB.T6G(SCH_1):M_A_CPU1_SB_DQS_DP(9)
  94 M_A_CPU1_SB_DQS_DN<9> DQS9_B_C||TDQS9_B_C @T6G_MB_LIB.T6G(SCH_1):M_A_CPU1_SB_DQS_DN(9)
 201 M_A_CPU1_SA_DQS_DP<9> DQS9_A_T||TDQS9_A_T @T6G_MB_LIB.T6G(SCH_1):M_A_CPU1_SA_DQS_DP(9)
 200 M_A_CPU1_SA_DQS_DN<9> DQS9_A_C||TDQS9_A_C @T6G_MB_LIB.T6G(SCH_1):M_A_CPU1_SA_DQS_DN(9)
 190 M_A_CPU1_SA_DQS_DP<8> DQS8_A_T||TDQS8_A_T @T6G_MB_LIB.T6G(SCH_1):M_A_CPU1_SA_DQS_DP(8)
 189 M_A_CPU1_SA_DQS_DN<8> DQS8_A_C||TDQS8_A_C @T6G_MB_LIB.T6G(SCH_1):M_A_CPU1_SA_DQS_DN(8)
 271 M_A_CPU1_SB_DQS_DN<7> DQS7_B_C||TDQS7_B_C @T6G_MB_LIB.T6G(SCH_1):M_A_CPU1_SB_DQS_DN(7)
 179 M_A_CPU1_SA_DQS_DP<7> DQS7_A_T||TDQS7_A_T @T6G_MB_LIB.T6G(SCH_1):M_A_CPU1_SA_DQS_DP(7)
 261 M_A_CPU1_SB_DQS_DP<6> DQS6_B_T||TDQS6_B_T @T6G_MB_LIB.T6G(SCH_1):M_A_CPU1_SB_DQS_DP(6)
 260 M_A_CPU1_SB_DQS_DN<6> DQS6_B_C||TDQS6_B_C @T6G_MB_LIB.T6G(SCH_1):M_A_CPU1_SB_DQS_DN(6)
 167 M_A_CPU1_SA_DQS_DN<6> DQS6_A_C||TDQS6_A_C||DQS6_A_T||TDQS6_A_T @T6G_MB_LIB.T6G(SCH_1):M_A_CPU1_SA_DQS_DN(6)
 250 M_A_CPU1_SB_DQS_DP<5> DQS5_B_T||TDQS5_B_T @T6G_MB_LIB.T6G(SCH_1):M_A_CPU1_SB_DQS_DP(5)
 249 M_A_CPU1_SB_DQS_DN<5> DQS5_B_C||TDQS5_B_C @T6G_MB_LIB.T6G(SCH_1):M_A_CPU1_SB_DQS_DN(5)
 157 M_A_CPU1_SA_DQS_DP<5> DQS5_A_T||TDQS5_A_T @T6G_MB_LIB.T6G(SCH_1):M_A_CPU1_SA_DQS_DP(5)
 156 M_A_CPU1_SA_DQS_DN<5> DQS5_A_C||TDQS5_A_C||DQS5_A_T||TDQS5_A_T @T6G_MB_LIB.T6G(SCH_1):M_A_CPU1_SA_DQS_DN(5)
 239 M_A_CPU1_SB_DQS_DP<4> DQS4_B_T @T6G_MB_LIB.T6G(SCH_1):M_A_CPU1_SB_DQS_DP(4)
 238 M_A_CPU1_SB_DQS_DN<4> DQS4_B_C @T6G_MB_LIB.T6G(SCH_1):M_A_CPU1_SB_DQS_DN(4)
  55 M_A_CPU1_SA_DQS_DP<4> DQS4_A_T @T6G_MB_LIB.T6G(SCH_1):M_A_CPU1_SA_DQS_DP(4)
  56 M_A_CPU1_SA_DQS_DN<4> DQS4_A_C @T6G_MB_LIB.T6G(SCH_1):M_A_CPU1_SA_DQS_DN(4)
 137 M_A_CPU1_SB_DQS_DP<3> DQS3_B_T @T6G_MB_LIB.T6G(SCH_1):M_A_CPU1_SB_DQS_DP(3)
 138 M_A_CPU1_SB_DQS_DN<3> DQS3_B_C @T6G_MB_LIB.T6G(SCH_1):M_A_CPU1_SB_DQS_DN(3)
  44 M_A_CPU1_SA_DQS_DP<3> DQS3_A_T @T6G_MB_LIB.T6G(SCH_1):M_A_CPU1_SA_DQS_DP(3)
  45 M_A_CPU1_SA_DQS_DN<3> DQS3_A_C @T6G_MB_LIB.T6G(SCH_1):M_A_CPU1_SA_DQS_DN(3)
 126 M_A_CPU1_SB_DQS_DP<2> DQS2_B_T @T6G_MB_LIB.T6G(SCH_1):M_A_CPU1_SB_DQS_DP(2)
 127 M_A_CPU1_SB_DQS_DN<2> DQS2_B_C @T6G_MB_LIB.T6G(SCH_1):M_A_CPU1_SB_DQS_DN(2)
  33 M_A_CPU1_SA_DQS_DP<2> DQS2_A_T @T6G_MB_LIB.T6G(SCH_1):M_A_CPU1_SA_DQS_DP(2)
  34 M_A_CPU1_SA_DQS_DN<2> DQS2_A_C @T6G_MB_LIB.T6G(SCH_1):M_A_CPU1_SA_DQS_DN(2)
 115 M_A_CPU1_SB_DQS_DP<1> DQS1_B_T @T6G_MB_LIB.T6G(SCH_1):M_A_CPU1_SB_DQS_DP(1)
 116 M_A_CPU1_SB_DQS_DN<1> DQS1_B_C @T6G_MB_LIB.T6G(SCH_1):M_A_CPU1_SB_DQS_DN(1)
  22 M_A_CPU1_SA_DQS_DP<1> DQS1_A_T @T6G_MB_LIB.T6G(SCH_1):M_A_CPU1_SA_DQS_DP(1)
  23 M_A_CPU1_SA_DQS_DN<1> DQS1_A_C @T6G_MB_LIB.T6G(SCH_1):M_A_CPU1_SA_DQS_DN(1)
 104 M_A_CPU1_SB_DQS_DP<0> DQS0_B_T @T6G_MB_LIB.T6G(SCH_1):M_A_CPU1_SB_DQS_DP(0)
 105 M_A_CPU1_SB_DQS_DN<0> DQS0_B_C @T6G_MB_LIB.T6G(SCH_1):M_A_CPU1_SB_DQS_DN(0)
  11 M_A_CPU1_SA_DQS_DP<0> DQS0_A_T @T6G_MB_LIB.T6G(SCH_1):M_A_CPU1_SA_DQS_DP(0)
  12 M_A_CPU1_SA_DQS_DN<0> DQS0_A_C @T6G_MB_LIB.T6G(SCH_1):M_A_CPU1_SA_DQS_DN(0)
 272 M_A_CPU1_SB_DQS_DP<7> DQS7_B_T||TDQS7_B_T @T6G_MB_LIB.T6G(SCH_1):M_A_CPU1_SB_DQS_DP(7)
 282 M_A_CPU1_SB_DQS_DN<8> DQS8_B_C||TDQS8_B_C @T6G_MB_LIB.T6G(SCH_1):M_A_CPU1_SB_DQS_DN(8)
 283 M_A_CPU1_SB_DQS_DP<8> DQS8_B_T||TDQS8_B_T @T6G_MB_LIB.T6G(SCH_1):M_A_CPU1_SB_DQS_DP(8)
 168 M_A_CPU1_SA_DQS_DP<6> DQS6_A_T||TDQS6_A_T @T6G_MB_LIB.T6G(SCH_1):M_A_CPU1_SA_DQS_DP(6)
 178 M_A_CPU1_SA_DQS_DN<7> DQS7_A_C||TDQS7_A_C @T6G_MB_LIB.T6G(SCH_1):M_A_CPU1_SA_DQS_DN(7)

Q_CAP_C0805-10UF,25V,10%,X6S,CH6104KEA00  I240  C173
   1 P12V_MEM_CPU1      A @T6G_MB_LIB.T6G(SCH_1):P12V_MEM_CPU1
   2    GND      B @T6G_MB_LIB.T6G(SCH_1):GND

Q_CAP_C0805-10UF,25V,10%,X6S,CH6104KEA00  I241  C174
   1 P12V_MEM_CPU1      A @T6G_MB_LIB.T6G(SCH_1):P12V_MEM_CPU1
   2    GND      B @T6G_MB_LIB.T6G(SCH_1):GND

Q_RES_0402LF-49.9,1%,1/16W,CHIP,CS04992FB07  I244  R1580
   1 I3C_SPD_DDRAF_CPU1_SCL      A @T6G_MB_LIB.T6G(SCH_1):I3C_SPD_DDRAF_CPU1_SCL
   2 I3C_SPD_DDRA_CPU1_SCL      B @T6G_MB_LIB.T6G(SCH_1):I3C_SPD_DDRA_CPU1_SCL

Q_RES_0402LF-10K,1%,1/16W,CHIP,CS31002FB08  I245  R8039
   1 P3V3_AUX      A @T6G_MB_LIB.T6G(SCH_1):P3V3_AUX
   2 PWRGD_CHAF_CPU1      B @T6G_MB_LIB.T6G(SCH_1):PWRGD_CHAF_CPU1

Q_RES_0402LF-0,5%,1/16W,CHIP,CS00002JB13  I250  R8086
   1 PWRGD_CHAF_CPU1      A @T6G_MB_LIB.T6G(SCH_1):PWRGD_CHAF_CPU1
   2 PWRGD_CHAF_CPU1_R1      B @T6G_MB_LIB.T6G(SCH_1):PWRGD_CHAF_CPU1_R1

Q_RES_0402LF-10K,1%,1/16W,EMPTY,CS31002FB08  I251  R8088
   1 P3V3_AUX      A @T6G_MB_LIB.T6G(SCH_1):P3V3_AUX
   2 PWRGD_CHAF_CPU1_R1      B @T6G_MB_LIB.T6G(SCH_1):PWRGD_CHAF_CPU1_R1

Q_RES_0402LF-0,5%,1/16W,CHIP,CS00002JB13  I252  R8087
   1 PWRGD_CHAF_CPU1_R1      A @T6G_MB_LIB.T6G(SCH_1):PWRGD_CHAF_CPU1_R1
   2 PWRGD_CHAF_CPU1_R2      B @T6G_MB_LIB.T6G(SCH_1):PWRGD_CHAF_CPU1_R2

SCHOTTKY_12-B0530WS7F,SMLF,EMPTY,BC000530Z41  I253  D8005
   1 PWRGD_CHAF_CPU1_R1      A @T6G_MB_LIB.T6G(SCH_1):PWRGD_CHAF_CPU1_R1
   2 P3V3_AUX      C @T6G_MB_LIB.T6G(SCH_1):P3V3_AUX

Q_RES_0402LF-10,1%,1/16W,CHIP,CS01002FB07  I256  R1687
   1 I3C_SPD_DDRAF_CPU1_SDA      A @T6G_MB_LIB.T6G(SCH_1):I3C_SPD_DDRAF_CPU1_SDA
   2 I3C_SPD_DDRA_CPU1_SDA      B @T6G_MB_LIB.T6G(SCH_1):I3C_SPD_DDRA_CPU1_SDA


DRAWING: @T6G_MB_LIB.T6G(SCH_1):PAGE98 

SCONN288_DDR506112002KQ-SCONN288_DDR506112002KQ,SMA  I22  J26
   3 P3V3_AUX VIN_MGMT @T6G_MB_LIB.T6G(SCH_1):P3V3_AUX
   2     NC   RFU0     NC
 144     NC   RFU1     NC
 149     NC   RFU2     NC
 150     NC   RFU3     NC
 220     NC   RFU4     NC
 231     NC   RFU5     NC
 232     NC   RFU6     NC
 207 M_B_CPU1_RESET_N RESET_N @T6G_MB_LIB.T6G(SCH_1):M_B_CPU1_RESET_N
 147 PWRGD_CHB_CPU1_DIMM PWR_GOOD||FAIL_N @T6G_MB_LIB.T6G(SCH_1):PWRGD_CHB_CPU1_DIMM
 227 M_B_CPU1_SB_PAR  PAR_B @T6G_MB_LIB.T6G(SCH_1):M_B_CPU1_SB_PAR
  74 M_B_CPU1_SA_PAR  PAR_A @T6G_MB_LIB.T6G(SCH_1):M_B_CPU1_SA_PAR
  87 M_B_CPU1_SB_RSP<0> LBS||RSP_B_N @T6G_MB_LIB.T6G(SCH_1):M_B_CPU1_SB_RSP(0)
  86 M_B_CPU1_SA_RSP<0> LBD||RSP_A_N @T6G_MB_LIB.T6G(SCH_1):M_B_CPU1_SA_RSP(0)
   5 I3C_SPD_DDRB_CPU1_SDA   HSDA @T6G_MB_LIB.T6G(SCH_1):I3C_SPD_DDRB_CPU1_SDA
   4 I3C_SPD_DDRB_CPU1_SCL   HSCL @T6G_MB_LIB.T6G(SCH_1):I3C_SPD_DDRB_CPU1_SCL
 148 PD_CHB_CPU1_DIMM_SAA    HAS @T6G_MB_LIB.T6G(SCH_1):PD_CHB_CPU1_DIMM_SAA
 100 M_B_CPU1_SB_DQ<0>  DQ0_B @T6G_MB_LIB.T6G(SCH_1):M_B_CPU1_SB_DQ(0)
 102 M_B_CPU1_SB_DQ<1>  DQ1_B @T6G_MB_LIB.T6G(SCH_1):M_B_CPU1_SB_DQ(1)
 245 M_B_CPU1_SB_DQ<2>  DQ2_B @T6G_MB_LIB.T6G(SCH_1):M_B_CPU1_SB_DQ(2)
 247 M_B_CPU1_SB_DQ<3>  DQ3_B @T6G_MB_LIB.T6G(SCH_1):M_B_CPU1_SB_DQ(3)
 107 M_B_CPU1_SB_DQ<4>  DQ4_B @T6G_MB_LIB.T6G(SCH_1):M_B_CPU1_SB_DQ(4)
 109 M_B_CPU1_SB_DQ<5>  DQ5_B @T6G_MB_LIB.T6G(SCH_1):M_B_CPU1_SB_DQ(5)
 252 M_B_CPU1_SB_DQ<6>  DQ6_B @T6G_MB_LIB.T6G(SCH_1):M_B_CPU1_SB_DQ(6)
 254 M_B_CPU1_SB_DQ<7>  DQ7_B @T6G_MB_LIB.T6G(SCH_1):M_B_CPU1_SB_DQ(7)
 111 M_B_CPU1_SB_DQ<8>  DQ8_B @T6G_MB_LIB.T6G(SCH_1):M_B_CPU1_SB_DQ(8)
 113 M_B_CPU1_SB_DQ<9>  DQ9_B @T6G_MB_LIB.T6G(SCH_1):M_B_CPU1_SB_DQ(9)
 256 M_B_CPU1_SB_DQ<10> DQ10_B @T6G_MB_LIB.T6G(SCH_1):M_B_CPU1_SB_DQ(10)
 258 M_B_CPU1_SB_DQ<11> DQ11_B @T6G_MB_LIB.T6G(SCH_1):M_B_CPU1_SB_DQ(11)
 118 M_B_CPU1_SB_DQ<12> DQ12_B @T6G_MB_LIB.T6G(SCH_1):M_B_CPU1_SB_DQ(12)
 120 M_B_CPU1_SB_DQ<13> DQ13_B @T6G_MB_LIB.T6G(SCH_1):M_B_CPU1_SB_DQ(13)
 263 M_B_CPU1_SB_DQ<14> DQ14_B @T6G_MB_LIB.T6G(SCH_1):M_B_CPU1_SB_DQ(14)
 265 M_B_CPU1_SB_DQ<15> DQ15_B @T6G_MB_LIB.T6G(SCH_1):M_B_CPU1_SB_DQ(15)
 122 M_B_CPU1_SB_DQ<16> DQ16_B @T6G_MB_LIB.T6G(SCH_1):M_B_CPU1_SB_DQ(16)
 124 M_B_CPU1_SB_DQ<17> DQ17_B @T6G_MB_LIB.T6G(SCH_1):M_B_CPU1_SB_DQ(17)
 267 M_B_CPU1_SB_DQ<18> DQ18_B @T6G_MB_LIB.T6G(SCH_1):M_B_CPU1_SB_DQ(18)
 269 M_B_CPU1_SB_DQ<19> DQ19_B @T6G_MB_LIB.T6G(SCH_1):M_B_CPU1_SB_DQ(19)
 129 M_B_CPU1_SB_DQ<20> DQ20_B @T6G_MB_LIB.T6G(SCH_1):M_B_CPU1_SB_DQ(20)
 131 M_B_CPU1_SB_DQ<21> DQ21_B @T6G_MB_LIB.T6G(SCH_1):M_B_CPU1_SB_DQ(21)
 274 M_B_CPU1_SB_DQ<22> DQ22_B @T6G_MB_LIB.T6G(SCH_1):M_B_CPU1_SB_DQ(22)
 276 M_B_CPU1_SB_DQ<23> DQ23_B @T6G_MB_LIB.T6G(SCH_1):M_B_CPU1_SB_DQ(23)
 133 M_B_CPU1_SB_DQ<24> DQ24_B @T6G_MB_LIB.T6G(SCH_1):M_B_CPU1_SB_DQ(24)
 135 M_B_CPU1_SB_DQ<25> DQ25_B @T6G_MB_LIB.T6G(SCH_1):M_B_CPU1_SB_DQ(25)
 278 M_B_CPU1_SB_DQ<26> DQ26_B @T6G_MB_LIB.T6G(SCH_1):M_B_CPU1_SB_DQ(26)
 280 M_B_CPU1_SB_DQ<27> DQ27_B @T6G_MB_LIB.T6G(SCH_1):M_B_CPU1_SB_DQ(27)
 140 M_B_CPU1_SB_DQ<28> DQ28_B @T6G_MB_LIB.T6G(SCH_1):M_B_CPU1_SB_DQ(28)
 142 M_B_CPU1_SB_DQ<29> DQ29_B @T6G_MB_LIB.T6G(SCH_1):M_B_CPU1_SB_DQ(29)
 285 M_B_CPU1_SB_DQ<30> DQ30_B @T6G_MB_LIB.T6G(SCH_1):M_B_CPU1_SB_DQ(30)
 287 M_B_CPU1_SB_DQ<31> DQ31_B @T6G_MB_LIB.T6G(SCH_1):M_B_CPU1_SB_DQ(31)
   7 M_B_CPU1_SA_DQ<0>  DQ0_A @T6G_MB_LIB.T6G(SCH_1):M_B_CPU1_SA_DQ(0)
   9 M_B_CPU1_SA_DQ<1>  DQ1_A @T6G_MB_LIB.T6G(SCH_1):M_B_CPU1_SA_DQ(1)
 152 M_B_CPU1_SA_DQ<2>  DQ2_A @T6G_MB_LIB.T6G(SCH_1):M_B_CPU1_SA_DQ(2)
 154 M_B_CPU1_SA_DQ<3>  DQ3_A @T6G_MB_LIB.T6G(SCH_1):M_B_CPU1_SA_DQ(3)
  14 M_B_CPU1_SA_DQ<4>  DQ4_A @T6G_MB_LIB.T6G(SCH_1):M_B_CPU1_SA_DQ(4)
  16 M_B_CPU1_SA_DQ<5>  DQ5_A @T6G_MB_LIB.T6G(SCH_1):M_B_CPU1_SA_DQ(5)
 159 M_B_CPU1_SA_DQ<6>  DQ6_A @T6G_MB_LIB.T6G(SCH_1):M_B_CPU1_SA_DQ(6)
 161 M_B_CPU1_SA_DQ<7>  DQ7_A @T6G_MB_LIB.T6G(SCH_1):M_B_CPU1_SA_DQ(7)
  18 M_B_CPU1_SA_DQ<8>  DQ8_A @T6G_MB_LIB.T6G(SCH_1):M_B_CPU1_SA_DQ(8)
  20 M_B_CPU1_SA_DQ<9>  DQ9_A @T6G_MB_LIB.T6G(SCH_1):M_B_CPU1_SA_DQ(9)
 163 M_B_CPU1_SA_DQ<10> DQ10_A @T6G_MB_LIB.T6G(SCH_1):M_B_CPU1_SA_DQ(10)
 165 M_B_CPU1_SA_DQ<11> DQ11_A @T6G_MB_LIB.T6G(SCH_1):M_B_CPU1_SA_DQ(11)
  25 M_B_CPU1_SA_DQ<12> DQ12_A @T6G_MB_LIB.T6G(SCH_1):M_B_CPU1_SA_DQ(12)
  27 M_B_CPU1_SA_DQ<13> DQ13_A @T6G_MB_LIB.T6G(SCH_1):M_B_CPU1_SA_DQ(13)
 170 M_B_CPU1_SA_DQ<14> DQ14_A @T6G_MB_LIB.T6G(SCH_1):M_B_CPU1_SA_DQ(14)
 172 M_B_CPU1_SA_DQ<15> DQ15_A @T6G_MB_LIB.T6G(SCH_1):M_B_CPU1_SA_DQ(15)
  29 M_B_CPU1_SA_DQ<16> DQ16_A @T6G_MB_LIB.T6G(SCH_1):M_B_CPU1_SA_DQ(16)
  31 M_B_CPU1_SA_DQ<17> DQ17_A @T6G_MB_LIB.T6G(SCH_1):M_B_CPU1_SA_DQ(17)
 174 M_B_CPU1_SA_DQ<18> DQ18_A @T6G_MB_LIB.T6G(SCH_1):M_B_CPU1_SA_DQ(18)
 176 M_B_CPU1_SA_DQ<19> DQ19_A @T6G_MB_LIB.T6G(SCH_1):M_B_CPU1_SA_DQ(19)
  36 M_B_CPU1_SA_DQ<20> DQ20_A @T6G_MB_LIB.T6G(SCH_1):M_B_CPU1_SA_DQ(20)
  38 M_B_CPU1_SA_DQ<21> DQ21_A @T6G_MB_LIB.T6G(SCH_1):M_B_CPU1_SA_DQ(21)
 181 M_B_CPU1_SA_DQ<22> DQ22_A @T6G_MB_LIB.T6G(SCH_1):M_B_CPU1_SA_DQ(22)
 183 M_B_CPU1_SA_DQ<23> DQ23_A @T6G_MB_LIB.T6G(SCH_1):M_B_CPU1_SA_DQ(23)
  40 M_B_CPU1_SA_DQ<24> DQ24_A @T6G_MB_LIB.T6G(SCH_1):M_B_CPU1_SA_DQ(24)
  42 M_B_CPU1_SA_DQ<25> DQ25_A @T6G_MB_LIB.T6G(SCH_1):M_B_CPU1_SA_DQ(25)
 185 M_B_CPU1_SA_DQ<26> DQ26_A @T6G_MB_LIB.T6G(SCH_1):M_B_CPU1_SA_DQ(26)
 187 M_B_CPU1_SA_DQ<27> DQ27_A @T6G_MB_LIB.T6G(SCH_1):M_B_CPU1_SA_DQ(27)
  47 M_B_CPU1_SA_DQ<28> DQ28_A @T6G_MB_LIB.T6G(SCH_1):M_B_CPU1_SA_DQ(28)
  49 M_B_CPU1_SA_DQ<29> DQ29_A @T6G_MB_LIB.T6G(SCH_1):M_B_CPU1_SA_DQ(29)
 192 M_B_CPU1_SA_DQ<30> DQ30_A @T6G_MB_LIB.T6G(SCH_1):M_B_CPU1_SA_DQ(30)
 229 M_B_CPU1_SB_CS_N<1> CS1_B_N @T6G_MB_LIB.T6G(SCH_1):M_B_CPU1_SB_CS_N(1)
 209 M_B_CPU1_SA_CS_N<1> CS1_A_N @T6G_MB_LIB.T6G(SCH_1):M_B_CPU1_SA_CS_N(1)
  84 M_B_CPU1_SB_CS_N<0> CS0_B_N @T6G_MB_LIB.T6G(SCH_1):M_B_CPU1_SB_CS_N(0)
  64 M_B_CPU1_SA_CS_N<0> CS0_A_N @T6G_MB_LIB.T6G(SCH_1):M_B_CPU1_SA_CS_N(0)
 217 M_B_CPU1_CLK_DP<0>   CK_T @T6G_MB_LIB.T6G(SCH_1):M_B_CPU1_CLK_DP(0)
 218 M_B_CPU1_CLK_DN<0>   CK_C @T6G_MB_LIB.T6G(SCH_1):M_B_CPU1_CLK_DN(0)
  96 M_B_CPU1_SB_CB<0>  CB0_B @T6G_MB_LIB.T6G(SCH_1):M_B_CPU1_SB_CB(0)
  98 M_B_CPU1_SB_CB<1>  CB1_B @T6G_MB_LIB.T6G(SCH_1):M_B_CPU1_SB_CB(1)
 241 M_B_CPU1_SB_CB<2>  CB2_B @T6G_MB_LIB.T6G(SCH_1):M_B_CPU1_SB_CB(2)
 243 M_B_CPU1_SB_CB<3>  CB3_B @T6G_MB_LIB.T6G(SCH_1):M_B_CPU1_SB_CB(3)
  89 M_B_CPU1_SB_CB<4>  CB4_B @T6G_MB_LIB.T6G(SCH_1):M_B_CPU1_SB_CB(4)
  91 M_B_CPU1_SB_CB<5>  CB5_B @T6G_MB_LIB.T6G(SCH_1):M_B_CPU1_SB_CB(5)
 234 M_B_CPU1_SB_CB<6>  CB6_B @T6G_MB_LIB.T6G(SCH_1):M_B_CPU1_SB_CB(6)
  51 M_B_CPU1_SA_CB<0>  CB0_A @T6G_MB_LIB.T6G(SCH_1):M_B_CPU1_SA_CB(0)
 196 M_B_CPU1_SA_CB<2>  CB2_A @T6G_MB_LIB.T6G(SCH_1):M_B_CPU1_SA_CB(2)
 198 M_B_CPU1_SA_CB<3>  CB3_A @T6G_MB_LIB.T6G(SCH_1):M_B_CPU1_SA_CB(3)
  60 M_B_CPU1_SA_CB<5>  CB5_A @T6G_MB_LIB.T6G(SCH_1):M_B_CPU1_SA_CB(5)
 203 M_B_CPU1_SA_CB<6>  CB6_A @T6G_MB_LIB.T6G(SCH_1):M_B_CPU1_SA_CB(6)
  82 M_B_CPU1_SB_CA<6>  CA6_B @T6G_MB_LIB.T6G(SCH_1):M_B_CPU1_SB_CA(6)
  72 M_B_CPU1_SA_CA<6>  CA6_A @T6G_MB_LIB.T6G(SCH_1):M_B_CPU1_SA_CA(6)
 225 M_B_CPU1_SB_CA<5>  CA5_B @T6G_MB_LIB.T6G(SCH_1):M_B_CPU1_SB_CA(5)
 215 M_B_CPU1_SA_CA<5>  CA5_A @T6G_MB_LIB.T6G(SCH_1):M_B_CPU1_SA_CA(5)
  80 M_B_CPU1_SB_CA<4>  CA4_B @T6G_MB_LIB.T6G(SCH_1):M_B_CPU1_SB_CA(4)
  70 M_B_CPU1_SA_CA<4>  CA4_A @T6G_MB_LIB.T6G(SCH_1):M_B_CPU1_SA_CA(4)
 223 M_B_CPU1_SB_CA<3>  CA3_B @T6G_MB_LIB.T6G(SCH_1):M_B_CPU1_SB_CA(3)
 213 M_B_CPU1_SA_CA<3>  CA3_A @T6G_MB_LIB.T6G(SCH_1):M_B_CPU1_SA_CA(3)
  78 M_B_CPU1_SB_CA<2>  CA2_B @T6G_MB_LIB.T6G(SCH_1):M_B_CPU1_SB_CA(2)
  68 M_B_CPU1_SA_CA<2>  CA2_A @T6G_MB_LIB.T6G(SCH_1):M_B_CPU1_SA_CA(2)
 221 M_B_CPU1_SB_CA<1>  CA1_B @T6G_MB_LIB.T6G(SCH_1):M_B_CPU1_SB_CA(1)
 211 M_B_CPU1_SA_CA<1>  CA1_A @T6G_MB_LIB.T6G(SCH_1):M_B_CPU1_SA_CA(1)
  76 M_B_CPU1_SB_CA<0>  CA0_B @T6G_MB_LIB.T6G(SCH_1):M_B_CPU1_SB_CA(0)
  66 M_B_CPU1_SA_CA<0>  CA0_A @T6G_MB_LIB.T6G(SCH_1):M_B_CPU1_SA_CA(0)
  62 M_B_CPU1_ALERT_N ALERT_N @T6G_MB_LIB.T6G(SCH_1):M_B_CPU1_ALERT_N
 236 M_B_CPU1_SB_CB<7>  CB7_B @T6G_MB_LIB.T6G(SCH_1):M_B_CPU1_SB_CB(7)
  53 M_B_CPU1_SA_CB<1>  CB1_A @T6G_MB_LIB.T6G(SCH_1):M_B_CPU1_SA_CB(1)
  58 M_B_CPU1_SA_CB<4>  CB4_A @T6G_MB_LIB.T6G(SCH_1):M_B_CPU1_SA_CB(4)
 205 M_B_CPU1_SA_CB<7>  CB7_A @T6G_MB_LIB.T6G(SCH_1):M_B_CPU1_SA_CB(7)
 194 M_B_CPU1_SA_DQ<31> DQ31_A @T6G_MB_LIB.T6G(SCH_1):M_B_CPU1_SA_DQ(31)

Q_RES_0402LF-15.4K,1%,1/16W,CHIP,CS31542FB02  I127  R770
   1 PD_CHB_CPU1_DIMM_SAA      A @T6G_MB_LIB.T6G(SCH_1):PD_CHB_CPU1_DIMM_SAA
   2    GND      B @T6G_MB_LIB.T6G(SCH_1):GND

SCONN288_DDR506112002KQ-SCONN288_DDR506112002KQ,SMA  I160  J26
   6    GND   VSS0 @T6G_MB_LIB.T6G(SCH_1):GND
   8    GND   VSS1 @T6G_MB_LIB.T6G(SCH_1):GND
  10    GND   VSS2 @T6G_MB_LIB.T6G(SCH_1):GND
  13    GND   VSS3 @T6G_MB_LIB.T6G(SCH_1):GND
  15    GND   VSS4 @T6G_MB_LIB.T6G(SCH_1):GND
  17    GND   VSS5 @T6G_MB_LIB.T6G(SCH_1):GND
  19    GND   VSS6 @T6G_MB_LIB.T6G(SCH_1):GND
  21    GND   VSS7 @T6G_MB_LIB.T6G(SCH_1):GND
  24    GND   VSS8 @T6G_MB_LIB.T6G(SCH_1):GND
  26    GND   VSS9 @T6G_MB_LIB.T6G(SCH_1):GND
  28    GND  VSS10 @T6G_MB_LIB.T6G(SCH_1):GND
  30    GND  VSS11 @T6G_MB_LIB.T6G(SCH_1):GND
  32    GND  VSS12 @T6G_MB_LIB.T6G(SCH_1):GND
  35    GND  VSS13 @T6G_MB_LIB.T6G(SCH_1):GND
  37    GND  VSS14 @T6G_MB_LIB.T6G(SCH_1):GND
  39    GND  VSS15 @T6G_MB_LIB.T6G(SCH_1):GND
  41    GND  VSS16 @T6G_MB_LIB.T6G(SCH_1):GND
  43    GND  VSS17 @T6G_MB_LIB.T6G(SCH_1):GND
  46    GND  VSS18 @T6G_MB_LIB.T6G(SCH_1):GND
  48    GND  VSS19 @T6G_MB_LIB.T6G(SCH_1):GND
  50    GND  VSS20 @T6G_MB_LIB.T6G(SCH_1):GND
  52    GND  VSS21 @T6G_MB_LIB.T6G(SCH_1):GND
  54    GND  VSS22 @T6G_MB_LIB.T6G(SCH_1):GND
  57    GND  VSS23 @T6G_MB_LIB.T6G(SCH_1):GND
  59    GND  VSS24 @T6G_MB_LIB.T6G(SCH_1):GND
  61    GND  VSS25 @T6G_MB_LIB.T6G(SCH_1):GND
  63    GND  VSS26 @T6G_MB_LIB.T6G(SCH_1):GND
  65    GND  VSS27 @T6G_MB_LIB.T6G(SCH_1):GND
  67    GND  VSS28 @T6G_MB_LIB.T6G(SCH_1):GND
  69    GND  VSS29 @T6G_MB_LIB.T6G(SCH_1):GND
  71    GND  VSS30 @T6G_MB_LIB.T6G(SCH_1):GND
  73    GND  VSS31 @T6G_MB_LIB.T6G(SCH_1):GND
  75    GND  VSS32 @T6G_MB_LIB.T6G(SCH_1):GND
  77    GND  VSS33 @T6G_MB_LIB.T6G(SCH_1):GND
  79    GND  VSS34 @T6G_MB_LIB.T6G(SCH_1):GND
  81    GND  VSS35 @T6G_MB_LIB.T6G(SCH_1):GND
  83    GND  VSS36 @T6G_MB_LIB.T6G(SCH_1):GND
  85    GND  VSS37 @T6G_MB_LIB.T6G(SCH_1):GND
  88    GND  VSS38 @T6G_MB_LIB.T6G(SCH_1):GND
  90    GND  VSS39 @T6G_MB_LIB.T6G(SCH_1):GND
  92    GND  VSS40 @T6G_MB_LIB.T6G(SCH_1):GND
  95    GND  VSS41 @T6G_MB_LIB.T6G(SCH_1):GND
  97    GND  VSS42 @T6G_MB_LIB.T6G(SCH_1):GND
  99    GND  VSS43 @T6G_MB_LIB.T6G(SCH_1):GND
 101    GND  VSS44 @T6G_MB_LIB.T6G(SCH_1):GND
 103    GND  VSS45 @T6G_MB_LIB.T6G(SCH_1):GND
 106    GND  VSS46 @T6G_MB_LIB.T6G(SCH_1):GND
 108    GND  VSS47 @T6G_MB_LIB.T6G(SCH_1):GND
 110    GND  VSS48 @T6G_MB_LIB.T6G(SCH_1):GND
 112    GND  VSS49 @T6G_MB_LIB.T6G(SCH_1):GND
 114    GND  VSS50 @T6G_MB_LIB.T6G(SCH_1):GND
 117    GND  VSS51 @T6G_MB_LIB.T6G(SCH_1):GND
 119    GND  VSS52 @T6G_MB_LIB.T6G(SCH_1):GND
 121    GND  VSS53 @T6G_MB_LIB.T6G(SCH_1):GND
 123    GND  VSS54 @T6G_MB_LIB.T6G(SCH_1):GND
 125    GND  VSS55 @T6G_MB_LIB.T6G(SCH_1):GND
 128    GND  VSS56 @T6G_MB_LIB.T6G(SCH_1):GND
 130    GND  VSS57 @T6G_MB_LIB.T6G(SCH_1):GND
 134    GND  VSS59 @T6G_MB_LIB.T6G(SCH_1):GND
 143    GND  VSS63 @T6G_MB_LIB.T6G(SCH_1):GND
 151    GND  VSS64 @T6G_MB_LIB.T6G(SCH_1):GND
 153    GND  VSS65 @T6G_MB_LIB.T6G(SCH_1):GND
 155    GND  VSS66 @T6G_MB_LIB.T6G(SCH_1):GND
 158    GND  VSS67 @T6G_MB_LIB.T6G(SCH_1):GND
 160    GND  VSS68 @T6G_MB_LIB.T6G(SCH_1):GND
 162    GND  VSS69 @T6G_MB_LIB.T6G(SCH_1):GND
 164    GND  VSS70 @T6G_MB_LIB.T6G(SCH_1):GND
 166    GND  VSS71 @T6G_MB_LIB.T6G(SCH_1):GND
 169    GND  VSS72 @T6G_MB_LIB.T6G(SCH_1):GND
 171    GND  VSS73 @T6G_MB_LIB.T6G(SCH_1):GND
 173    GND  VSS74 @T6G_MB_LIB.T6G(SCH_1):GND
 175    GND  VSS75 @T6G_MB_LIB.T6G(SCH_1):GND
 177    GND  VSS76 @T6G_MB_LIB.T6G(SCH_1):GND
 180    GND  VSS77 @T6G_MB_LIB.T6G(SCH_1):GND
 182    GND  VSS78 @T6G_MB_LIB.T6G(SCH_1):GND
 184    GND  VSS79 @T6G_MB_LIB.T6G(SCH_1):GND
 186    GND  VSS80 @T6G_MB_LIB.T6G(SCH_1):GND
 188    GND  VSS81 @T6G_MB_LIB.T6G(SCH_1):GND
 191    GND  VSS82 @T6G_MB_LIB.T6G(SCH_1):GND
 193    GND  VSS83 @T6G_MB_LIB.T6G(SCH_1):GND
 195    GND  VSS84 @T6G_MB_LIB.T6G(SCH_1):GND
 197    GND  VSS85 @T6G_MB_LIB.T6G(SCH_1):GND
 199    GND  VSS86 @T6G_MB_LIB.T6G(SCH_1):GND
 202    GND  VSS87 @T6G_MB_LIB.T6G(SCH_1):GND
 204    GND  VSS88 @T6G_MB_LIB.T6G(SCH_1):GND
 206    GND  VSS89 @T6G_MB_LIB.T6G(SCH_1):GND
 208    GND  VSS90 @T6G_MB_LIB.T6G(SCH_1):GND
 210    GND  VSS91 @T6G_MB_LIB.T6G(SCH_1):GND
 212    GND  VSS92 @T6G_MB_LIB.T6G(SCH_1):GND
 214    GND  VSS93 @T6G_MB_LIB.T6G(SCH_1):GND
 216    GND  VSS94 @T6G_MB_LIB.T6G(SCH_1):GND
 219    GND  VSS95 @T6G_MB_LIB.T6G(SCH_1):GND
 222    GND  VSS96 @T6G_MB_LIB.T6G(SCH_1):GND
 224    GND  VSS97 @T6G_MB_LIB.T6G(SCH_1):GND
 226    GND  VSS98 @T6G_MB_LIB.T6G(SCH_1):GND
 228    GND  VSS99 @T6G_MB_LIB.T6G(SCH_1):GND
 233    GND VSS101 @T6G_MB_LIB.T6G(SCH_1):GND
 237    GND VSS103 @T6G_MB_LIB.T6G(SCH_1):GND
 242    GND VSS105 @T6G_MB_LIB.T6G(SCH_1):GND
 244    GND VSS106 @T6G_MB_LIB.T6G(SCH_1):GND
 246    GND VSS107 @T6G_MB_LIB.T6G(SCH_1):GND
 248    GND VSS108 @T6G_MB_LIB.T6G(SCH_1):GND
 251    GND VSS109 @T6G_MB_LIB.T6G(SCH_1):GND
 253    GND VSS110 @T6G_MB_LIB.T6G(SCH_1):GND
 255    GND VSS111 @T6G_MB_LIB.T6G(SCH_1):GND
 257    GND VSS112 @T6G_MB_LIB.T6G(SCH_1):GND
 259    GND VSS113 @T6G_MB_LIB.T6G(SCH_1):GND
 262    GND VSS114 @T6G_MB_LIB.T6G(SCH_1):GND
 264    GND VSS115 @T6G_MB_LIB.T6G(SCH_1):GND
 266    GND VSS116 @T6G_MB_LIB.T6G(SCH_1):GND
 268    GND VSS117 @T6G_MB_LIB.T6G(SCH_1):GND
 270    GND VSS118 @T6G_MB_LIB.T6G(SCH_1):GND
 273    GND VSS119 @T6G_MB_LIB.T6G(SCH_1):GND
 275    GND VSS120 @T6G_MB_LIB.T6G(SCH_1):GND
 277    GND VSS121 @T6G_MB_LIB.T6G(SCH_1):GND
 279    GND VSS122 @T6G_MB_LIB.T6G(SCH_1):GND
 281    GND VSS123 @T6G_MB_LIB.T6G(SCH_1):GND
 284    GND VSS124 @T6G_MB_LIB.T6G(SCH_1):GND
 286    GND VSS125 @T6G_MB_LIB.T6G(SCH_1):GND
 288    GND VSS126 @T6G_MB_LIB.T6G(SCH_1):GND
   1 P12V_MEM_CPU1 VIN_BULK0 @T6G_MB_LIB.T6G(SCH_1):P12V_MEM_CPU1
 145 P12V_MEM_CPU1 VIN_BULK1 @T6G_MB_LIB.T6G(SCH_1):P12V_MEM_CPU1
 146 P12V_MEM_CPU1 VIN_BULK2 @T6G_MB_LIB.T6G(SCH_1):P12V_MEM_CPU1
 230    GND VSS100 @T6G_MB_LIB.T6G(SCH_1):GND
 235    GND VSS102 @T6G_MB_LIB.T6G(SCH_1):GND
 240    GND VSS104 @T6G_MB_LIB.T6G(SCH_1):GND
 132    GND  VSS58 @T6G_MB_LIB.T6G(SCH_1):GND
 136    GND  VSS60 @T6G_MB_LIB.T6G(SCH_1):GND
 139    GND  VSS61 @T6G_MB_LIB.T6G(SCH_1):GND
 141    GND  VSS62 @T6G_MB_LIB.T6G(SCH_1):GND
  G1    GND     G1 @T6G_MB_LIB.T6G(SCH_1):GND
  G2    GND     G2 @T6G_MB_LIB.T6G(SCH_1):GND
  G3    GND     G3 @T6G_MB_LIB.T6G(SCH_1):GND

Q_CAP_0402-0.1UF,25V,10%,X7R,CH4104K1B00  I185  C140
   1 P3V3_AUX      A @T6G_MB_LIB.T6G(SCH_1):P3V3_AUX
   2    GND      B @T6G_MB_LIB.T6G(SCH_1):GND

Q_RES_0402LF-1K,1%,1/16W,CHIP,CS21002FB06  I188  R304
   1 PWRGD_CHB_CPU1_DIMM      A @T6G_MB_LIB.T6G(SCH_1):PWRGD_CHB_CPU1_DIMM
   2 PWRGD_CHAF_CPU1      B @T6G_MB_LIB.T6G(SCH_1):PWRGD_CHAF_CPU1

Q_RES_0402LF-1K,1%,1/16W,EMPTY,CS21002FB06  I190  R104
   1   P3V3      A @T6G_MB_LIB.T6G(SCH_1):P3V3
   2 PWRGD_CHB_CPU1_DIMM      B @T6G_MB_LIB.T6G(SCH_1):PWRGD_CHB_CPU1_DIMM

SCONN288_DDR506112002KQ-SCONN288_DDR506112002KQ,SMA  I236  J26
  93 M_B_CPU1_SB_DQS_DP<9> DQS9_B_T||TDQS9_B_T||DBI4_B_N @T6G_MB_LIB.T6G(SCH_1):M_B_CPU1_SB_DQS_DP(9)
  94 M_B_CPU1_SB_DQS_DN<9> DQS9_B_C||TDQS9_B_C @T6G_MB_LIB.T6G(SCH_1):M_B_CPU1_SB_DQS_DN(9)
 201 M_B_CPU1_SA_DQS_DP<9> DQS9_A_T||TDQS9_A_T @T6G_MB_LIB.T6G(SCH_1):M_B_CPU1_SA_DQS_DP(9)
 200 M_B_CPU1_SA_DQS_DN<9> DQS9_A_C||TDQS9_A_C @T6G_MB_LIB.T6G(SCH_1):M_B_CPU1_SA_DQS_DN(9)
 190 M_B_CPU1_SA_DQS_DP<8> DQS8_A_T||TDQS8_A_T @T6G_MB_LIB.T6G(SCH_1):M_B_CPU1_SA_DQS_DP(8)
 189 M_B_CPU1_SA_DQS_DN<8> DQS8_A_C||TDQS8_A_C @T6G_MB_LIB.T6G(SCH_1):M_B_CPU1_SA_DQS_DN(8)
 271 M_B_CPU1_SB_DQS_DN<7> DQS7_B_C||TDQS7_B_C @T6G_MB_LIB.T6G(SCH_1):M_B_CPU1_SB_DQS_DN(7)
 179 M_B_CPU1_SA_DQS_DP<7> DQS7_A_T||TDQS7_A_T @T6G_MB_LIB.T6G(SCH_1):M_B_CPU1_SA_DQS_DP(7)
 261 M_B_CPU1_SB_DQS_DP<6> DQS6_B_T||TDQS6_B_T @T6G_MB_LIB.T6G(SCH_1):M_B_CPU1_SB_DQS_DP(6)
 260 M_B_CPU1_SB_DQS_DN<6> DQS6_B_C||TDQS6_B_C @T6G_MB_LIB.T6G(SCH_1):M_B_CPU1_SB_DQS_DN(6)
 167 M_B_CPU1_SA_DQS_DN<6> DQS6_A_C||TDQS6_A_C||DQS6_A_T||TDQS6_A_T @T6G_MB_LIB.T6G(SCH_1):M_B_CPU1_SA_DQS_DN(6)
 250 M_B_CPU1_SB_DQS_DP<5> DQS5_B_T||TDQS5_B_T @T6G_MB_LIB.T6G(SCH_1):M_B_CPU1_SB_DQS_DP(5)
 249 M_B_CPU1_SB_DQS_DN<5> DQS5_B_C||TDQS5_B_C @T6G_MB_LIB.T6G(SCH_1):M_B_CPU1_SB_DQS_DN(5)
 157 M_B_CPU1_SA_DQS_DP<5> DQS5_A_T||TDQS5_A_T @T6G_MB_LIB.T6G(SCH_1):M_B_CPU1_SA_DQS_DP(5)
 156 M_B_CPU1_SA_DQS_DN<5> DQS5_A_C||TDQS5_A_C||DQS5_A_T||TDQS5_A_T @T6G_MB_LIB.T6G(SCH_1):M_B_CPU1_SA_DQS_DN(5)
 239 M_B_CPU1_SB_DQS_DP<4> DQS4_B_T @T6G_MB_LIB.T6G(SCH_1):M_B_CPU1_SB_DQS_DP(4)
 238 M_B_CPU1_SB_DQS_DN<4> DQS4_B_C @T6G_MB_LIB.T6G(SCH_1):M_B_CPU1_SB_DQS_DN(4)
  55 M_B_CPU1_SA_DQS_DP<4> DQS4_A_T @T6G_MB_LIB.T6G(SCH_1):M_B_CPU1_SA_DQS_DP(4)
  56 M_B_CPU1_SA_DQS_DN<4> DQS4_A_C @T6G_MB_LIB.T6G(SCH_1):M_B_CPU1_SA_DQS_DN(4)
 137 M_B_CPU1_SB_DQS_DP<3> DQS3_B_T @T6G_MB_LIB.T6G(SCH_1):M_B_CPU1_SB_DQS_DP(3)
 138 M_B_CPU1_SB_DQS_DN<3> DQS3_B_C @T6G_MB_LIB.T6G(SCH_1):M_B_CPU1_SB_DQS_DN(3)
  44 M_B_CPU1_SA_DQS_DP<3> DQS3_A_T @T6G_MB_LIB.T6G(SCH_1):M_B_CPU1_SA_DQS_DP(3)
  45 M_B_CPU1_SA_DQS_DN<3> DQS3_A_C @T6G_MB_LIB.T6G(SCH_1):M_B_CPU1_SA_DQS_DN(3)
 126 M_B_CPU1_SB_DQS_DP<2> DQS2_B_T @T6G_MB_LIB.T6G(SCH_1):M_B_CPU1_SB_DQS_DP(2)
 127 M_B_CPU1_SB_DQS_DN<2> DQS2_B_C @T6G_MB_LIB.T6G(SCH_1):M_B_CPU1_SB_DQS_DN(2)
  33 M_B_CPU1_SA_DQS_DP<2> DQS2_A_T @T6G_MB_LIB.T6G(SCH_1):M_B_CPU1_SA_DQS_DP(2)
  34 M_B_CPU1_SA_DQS_DN<2> DQS2_A_C @T6G_MB_LIB.T6G(SCH_1):M_B_CPU1_SA_DQS_DN(2)
 115 M_B_CPU1_SB_DQS_DP<1> DQS1_B_T @T6G_MB_LIB.T6G(SCH_1):M_B_CPU1_SB_DQS_DP(1)
 116 M_B_CPU1_SB_DQS_DN<1> DQS1_B_C @T6G_MB_LIB.T6G(SCH_1):M_B_CPU1_SB_DQS_DN(1)
  22 M_B_CPU1_SA_DQS_DP<1> DQS1_A_T @T6G_MB_LIB.T6G(SCH_1):M_B_CPU1_SA_DQS_DP(1)
  23 M_B_CPU1_SA_DQS_DN<1> DQS1_A_C @T6G_MB_LIB.T6G(SCH_1):M_B_CPU1_SA_DQS_DN(1)
 104 M_B_CPU1_SB_DQS_DP<0> DQS0_B_T @T6G_MB_LIB.T6G(SCH_1):M_B_CPU1_SB_DQS_DP(0)
 105 M_B_CPU1_SB_DQS_DN<0> DQS0_B_C @T6G_MB_LIB.T6G(SCH_1):M_B_CPU1_SB_DQS_DN(0)
  11 M_B_CPU1_SA_DQS_DP<0> DQS0_A_T @T6G_MB_LIB.T6G(SCH_1):M_B_CPU1_SA_DQS_DP(0)
  12 M_B_CPU1_SA_DQS_DN<0> DQS0_A_C @T6G_MB_LIB.T6G(SCH_1):M_B_CPU1_SA_DQS_DN(0)
 272 M_B_CPU1_SB_DQS_DP<7> DQS7_B_T||TDQS7_B_T @T6G_MB_LIB.T6G(SCH_1):M_B_CPU1_SB_DQS_DP(7)
 282 M_B_CPU1_SB_DQS_DN<8> DQS8_B_C||TDQS8_B_C @T6G_MB_LIB.T6G(SCH_1):M_B_CPU1_SB_DQS_DN(8)
 283 M_B_CPU1_SB_DQS_DP<8> DQS8_B_T||TDQS8_B_T @T6G_MB_LIB.T6G(SCH_1):M_B_CPU1_SB_DQS_DP(8)
 168 M_B_CPU1_SA_DQS_DP<6> DQS6_A_T||TDQS6_A_T @T6G_MB_LIB.T6G(SCH_1):M_B_CPU1_SA_DQS_DP(6)
 178 M_B_CPU1_SA_DQS_DN<7> DQS7_A_C||TDQS7_A_C @T6G_MB_LIB.T6G(SCH_1):M_B_CPU1_SA_DQS_DN(7)

Q_CAP_C0805-10UF,25V,10%,X6S,CH6104KEA00  I238  C175
   1 P12V_MEM_CPU1      A @T6G_MB_LIB.T6G(SCH_1):P12V_MEM_CPU1
   2    GND      B @T6G_MB_LIB.T6G(SCH_1):GND

Q_CAP_C0805-10UF,25V,10%,X6S,CH6104KEA00  I239  C177
   1 P12V_MEM_CPU1      A @T6G_MB_LIB.T6G(SCH_1):P12V_MEM_CPU1
   2    GND      B @T6G_MB_LIB.T6G(SCH_1):GND

Q_RES_0402LF-49.9,1%,1/16W,CHIP,CS04992FB07  I242  R1581
   1 I3C_SPD_DDRAF_CPU1_SCL      A @T6G_MB_LIB.T6G(SCH_1):I3C_SPD_DDRAF_CPU1_SCL
   2 I3C_SPD_DDRB_CPU1_SCL      B @T6G_MB_LIB.T6G(SCH_1):I3C_SPD_DDRB_CPU1_SCL

Q_RES_0402LF-10,1%,1/16W,CHIP,CS01002FB07  I243  R1696
   1 I3C_SPD_DDRAF_CPU1_SDA      A @T6G_MB_LIB.T6G(SCH_1):I3C_SPD_DDRAF_CPU1_SDA
   2 I3C_SPD_DDRB_CPU1_SDA      B @T6G_MB_LIB.T6G(SCH_1):I3C_SPD_DDRB_CPU1_SDA


DRAWING: @T6G_MB_LIB.T6G(SCH_1):PAGE99 

SCONN288_DDR506112002KQ-SCONN288_DDR506112002KQ,SMA  I22  J28
   3 P3V3_AUX VIN_MGMT @T6G_MB_LIB.T6G(SCH_1):P3V3_AUX
   2     NC   RFU0     NC
 144     NC   RFU1     NC
 149     NC   RFU2     NC
 150     NC   RFU3     NC
 220     NC   RFU4     NC
 231     NC   RFU5     NC
 232     NC   RFU6     NC
 207 M_C_CPU1_RESET_N RESET_N @T6G_MB_LIB.T6G(SCH_1):M_C_CPU1_RESET_N
 147 PWRGD_CHC_CPU1_DIMM PWR_GOOD||FAIL_N @T6G_MB_LIB.T6G(SCH_1):PWRGD_CHC_CPU1_DIMM
 227 M_C_CPU1_SB_PAR  PAR_B @T6G_MB_LIB.T6G(SCH_1):M_C_CPU1_SB_PAR
  74 M_C_CPU1_SA_PAR  PAR_A @T6G_MB_LIB.T6G(SCH_1):M_C_CPU1_SA_PAR
  87 M_C_CPU1_SB_RSP<0> LBS||RSP_B_N @T6G_MB_LIB.T6G(SCH_1):M_C_CPU1_SB_RSP(0)
  86 M_C_CPU1_SA_RSP<0> LBD||RSP_A_N @T6G_MB_LIB.T6G(SCH_1):M_C_CPU1_SA_RSP(0)
   5 I3C_SPD_DDRC_CPU1_SDA   HSDA @T6G_MB_LIB.T6G(SCH_1):I3C_SPD_DDRC_CPU1_SDA
   4 I3C_SPD_DDRC_CPU1_SCL   HSCL @T6G_MB_LIB.T6G(SCH_1):I3C_SPD_DDRC_CPU1_SCL
 148 PD_CHC_CPU1_DIMM_SAA    HAS @T6G_MB_LIB.T6G(SCH_1):PD_CHC_CPU1_DIMM_SAA
 100 M_C_CPU1_SB_DQ<0>  DQ0_B @T6G_MB_LIB.T6G(SCH_1):M_C_CPU1_SB_DQ(0)
 102 M_C_CPU1_SB_DQ<1>  DQ1_B @T6G_MB_LIB.T6G(SCH_1):M_C_CPU1_SB_DQ(1)
 245 M_C_CPU1_SB_DQ<2>  DQ2_B @T6G_MB_LIB.T6G(SCH_1):M_C_CPU1_SB_DQ(2)
 247 M_C_CPU1_SB_DQ<3>  DQ3_B @T6G_MB_LIB.T6G(SCH_1):M_C_CPU1_SB_DQ(3)
 107 M_C_CPU1_SB_DQ<4>  DQ4_B @T6G_MB_LIB.T6G(SCH_1):M_C_CPU1_SB_DQ(4)
 109 M_C_CPU1_SB_DQ<5>  DQ5_B @T6G_MB_LIB.T6G(SCH_1):M_C_CPU1_SB_DQ(5)
 252 M_C_CPU1_SB_DQ<6>  DQ6_B @T6G_MB_LIB.T6G(SCH_1):M_C_CPU1_SB_DQ(6)
 254 M_C_CPU1_SB_DQ<7>  DQ7_B @T6G_MB_LIB.T6G(SCH_1):M_C_CPU1_SB_DQ(7)
 111 M_C_CPU1_SB_DQ<8>  DQ8_B @T6G_MB_LIB.T6G(SCH_1):M_C_CPU1_SB_DQ(8)
 113 M_C_CPU1_SB_DQ<9>  DQ9_B @T6G_MB_LIB.T6G(SCH_1):M_C_CPU1_SB_DQ(9)
 256 M_C_CPU1_SB_DQ<10> DQ10_B @T6G_MB_LIB.T6G(SCH_1):M_C_CPU1_SB_DQ(10)
 258 M_C_CPU1_SB_DQ<11> DQ11_B @T6G_MB_LIB.T6G(SCH_1):M_C_CPU1_SB_DQ(11)
 118 M_C_CPU1_SB_DQ<12> DQ12_B @T6G_MB_LIB.T6G(SCH_1):M_C_CPU1_SB_DQ(12)
 120 M_C_CPU1_SB_DQ<13> DQ13_B @T6G_MB_LIB.T6G(SCH_1):M_C_CPU1_SB_DQ(13)
 263 M_C_CPU1_SB_DQ<14> DQ14_B @T6G_MB_LIB.T6G(SCH_1):M_C_CPU1_SB_DQ(14)
 265 M_C_CPU1_SB_DQ<15> DQ15_B @T6G_MB_LIB.T6G(SCH_1):M_C_CPU1_SB_DQ(15)
 122 M_C_CPU1_SB_DQ<16> DQ16_B @T6G_MB_LIB.T6G(SCH_1):M_C_CPU1_SB_DQ(16)
 124 M_C_CPU1_SB_DQ<17> DQ17_B @T6G_MB_LIB.T6G(SCH_1):M_C_CPU1_SB_DQ(17)
 267 M_C_CPU1_SB_DQ<18> DQ18_B @T6G_MB_LIB.T6G(SCH_1):M_C_CPU1_SB_DQ(18)
 269 M_C_CPU1_SB_DQ<19> DQ19_B @T6G_MB_LIB.T6G(SCH_1):M_C_CPU1_SB_DQ(19)
 129 M_C_CPU1_SB_DQ<20> DQ20_B @T6G_MB_LIB.T6G(SCH_1):M_C_CPU1_SB_DQ(20)
 131 M_C_CPU1_SB_DQ<21> DQ21_B @T6G_MB_LIB.T6G(SCH_1):M_C_CPU1_SB_DQ(21)
 274 M_C_CPU1_SB_DQ<22> DQ22_B @T6G_MB_LIB.T6G(SCH_1):M_C_CPU1_SB_DQ(22)
 276 M_C_CPU1_SB_DQ<23> DQ23_B @T6G_MB_LIB.T6G(SCH_1):M_C_CPU1_SB_DQ(23)
 133 M_C_CPU1_SB_DQ<24> DQ24_B @T6G_MB_LIB.T6G(SCH_1):M_C_CPU1_SB_DQ(24)
 135 M_C_CPU1_SB_DQ<25> DQ25_B @T6G_MB_LIB.T6G(SCH_1):M_C_CPU1_SB_DQ(25)
 278 M_C_CPU1_SB_DQ<26> DQ26_B @T6G_MB_LIB.T6G(SCH_1):M_C_CPU1_SB_DQ(26)
 280 M_C_CPU1_SB_DQ<27> DQ27_B @T6G_MB_LIB.T6G(SCH_1):M_C_CPU1_SB_DQ(27)
 140 M_C_CPU1_SB_DQ<28> DQ28_B @T6G_MB_LIB.T6G(SCH_1):M_C_CPU1_SB_DQ(28)
 142 M_C_CPU1_SB_DQ<29> DQ29_B @T6G_MB_LIB.T6G(SCH_1):M_C_CPU1_SB_DQ(29)
 285 M_C_CPU1_SB_DQ<30> DQ30_B @T6G_MB_LIB.T6G(SCH_1):M_C_CPU1_SB_DQ(30)
 287 M_C_CPU1_SB_DQ<31> DQ31_B @T6G_MB_LIB.T6G(SCH_1):M_C_CPU1_SB_DQ(31)
   7 M_C_CPU1_SA_DQ<0>  DQ0_A @T6G_MB_LIB.T6G(SCH_1):M_C_CPU1_SA_DQ(0)
   9 M_C_CPU1_SA_DQ<1>  DQ1_A @T6G_MB_LIB.T6G(SCH_1):M_C_CPU1_SA_DQ(1)
 152 M_C_CPU1_SA_DQ<2>  DQ2_A @T6G_MB_LIB.T6G(SCH_1):M_C_CPU1_SA_DQ(2)
 154 M_C_CPU1_SA_DQ<3>  DQ3_A @T6G_MB_LIB.T6G(SCH_1):M_C_CPU1_SA_DQ(3)
  14 M_C_CPU1_SA_DQ<4>  DQ4_A @T6G_MB_LIB.T6G(SCH_1):M_C_CPU1_SA_DQ(4)
  16 M_C_CPU1_SA_DQ<5>  DQ5_A @T6G_MB_LIB.T6G(SCH_1):M_C_CPU1_SA_DQ(5)
 159 M_C_CPU1_SA_DQ<6>  DQ6_A @T6G_MB_LIB.T6G(SCH_1):M_C_CPU1_SA_DQ(6)
 161 M_C_CPU1_SA_DQ<7>  DQ7_A @T6G_MB_LIB.T6G(SCH_1):M_C_CPU1_SA_DQ(7)
  18 M_C_CPU1_SA_DQ<8>  DQ8_A @T6G_MB_LIB.T6G(SCH_1):M_C_CPU1_SA_DQ(8)
  20 M_C_CPU1_SA_DQ<9>  DQ9_A @T6G_MB_LIB.T6G(SCH_1):M_C_CPU1_SA_DQ(9)
 163 M_C_CPU1_SA_DQ<10> DQ10_A @T6G_MB_LIB.T6G(SCH_1):M_C_CPU1_SA_DQ(10)
 165 M_C_CPU1_SA_DQ<11> DQ11_A @T6G_MB_LIB.T6G(SCH_1):M_C_CPU1_SA_DQ(11)
  25 M_C_CPU1_SA_DQ<12> DQ12_A @T6G_MB_LIB.T6G(SCH_1):M_C_CPU1_SA_DQ(12)
  27 M_C_CPU1_SA_DQ<13> DQ13_A @T6G_MB_LIB.T6G(SCH_1):M_C_CPU1_SA_DQ(13)
 170 M_C_CPU1_SA_DQ<14> DQ14_A @T6G_MB_LIB.T6G(SCH_1):M_C_CPU1_SA_DQ(14)
 172 M_C_CPU1_SA_DQ<15> DQ15_A @T6G_MB_LIB.T6G(SCH_1):M_C_CPU1_SA_DQ(15)
  29 M_C_CPU1_SA_DQ<16> DQ16_A @T6G_MB_LIB.T6G(SCH_1):M_C_CPU1_SA_DQ(16)
  31 M_C_CPU1_SA_DQ<17> DQ17_A @T6G_MB_LIB.T6G(SCH_1):M_C_CPU1_SA_DQ(17)
 174 M_C_CPU1_SA_DQ<18> DQ18_A @T6G_MB_LIB.T6G(SCH_1):M_C_CPU1_SA_DQ(18)
 176 M_C_CPU1_SA_DQ<19> DQ19_A @T6G_MB_LIB.T6G(SCH_1):M_C_CPU1_SA_DQ(19)
  36 M_C_CPU1_SA_DQ<20> DQ20_A @T6G_MB_LIB.T6G(SCH_1):M_C_CPU1_SA_DQ(20)
  38 M_C_CPU1_SA_DQ<21> DQ21_A @T6G_MB_LIB.T6G(SCH_1):M_C_CPU1_SA_DQ(21)
 181 M_C_CPU1_SA_DQ<22> DQ22_A @T6G_MB_LIB.T6G(SCH_1):M_C_CPU1_SA_DQ(22)
 183 M_C_CPU1_SA_DQ<23> DQ23_A @T6G_MB_LIB.T6G(SCH_1):M_C_CPU1_SA_DQ(23)
  40 M_C_CPU1_SA_DQ<24> DQ24_A @T6G_MB_LIB.T6G(SCH_1):M_C_CPU1_SA_DQ(24)
  42 M_C_CPU1_SA_DQ<25> DQ25_A @T6G_MB_LIB.T6G(SCH_1):M_C_CPU1_SA_DQ(25)
 185 M_C_CPU1_SA_DQ<26> DQ26_A @T6G_MB_LIB.T6G(SCH_1):M_C_CPU1_SA_DQ(26)
 187 M_C_CPU1_SA_DQ<27> DQ27_A @T6G_MB_LIB.T6G(SCH_1):M_C_CPU1_SA_DQ(27)
  47 M_C_CPU1_SA_DQ<28> DQ28_A @T6G_MB_LIB.T6G(SCH_1):M_C_CPU1_SA_DQ(28)
  49 M_C_CPU1_SA_DQ<29> DQ29_A @T6G_MB_LIB.T6G(SCH_1):M_C_CPU1_SA_DQ(29)
 192 M_C_CPU1_SA_DQ<30> DQ30_A @T6G_MB_LIB.T6G(SCH_1):M_C_CPU1_SA_DQ(30)
 229 M_C_CPU1_SB_CS_N<1> CS1_B_N @T6G_MB_LIB.T6G(SCH_1):M_C_CPU1_SB_CS_N(1)
 209 M_C_CPU1_SA_CS_N<1> CS1_A_N @T6G_MB_LIB.T6G(SCH_1):M_C_CPU1_SA_CS_N(1)
  84 M_C_CPU1_SB_CS_N<0> CS0_B_N @T6G_MB_LIB.T6G(SCH_1):M_C_CPU1_SB_CS_N(0)
  64 M_C_CPU1_SA_CS_N<0> CS0_A_N @T6G_MB_LIB.T6G(SCH_1):M_C_CPU1_SA_CS_N(0)
 217 M_C_CPU1_CLK_DP<0>   CK_T @T6G_MB_LIB.T6G(SCH_1):M_C_CPU1_CLK_DP(0)
 218 M_C_CPU1_CLK_DN<0>   CK_C @T6G_MB_LIB.T6G(SCH_1):M_C_CPU1_CLK_DN(0)
  96 M_C_CPU1_SB_CB<0>  CB0_B @T6G_MB_LIB.T6G(SCH_1):M_C_CPU1_SB_CB(0)
  98 M_C_CPU1_SB_CB<1>  CB1_B @T6G_MB_LIB.T6G(SCH_1):M_C_CPU1_SB_CB(1)
 241 M_C_CPU1_SB_CB<2>  CB2_B @T6G_MB_LIB.T6G(SCH_1):M_C_CPU1_SB_CB(2)
 243 M_C_CPU1_SB_CB<3>  CB3_B @T6G_MB_LIB.T6G(SCH_1):M_C_CPU1_SB_CB(3)
  89 M_C_CPU1_SB_CB<4>  CB4_B @T6G_MB_LIB.T6G(SCH_1):M_C_CPU1_SB_CB(4)
  91 M_C_CPU1_SB_CB<5>  CB5_B @T6G_MB_LIB.T6G(SCH_1):M_C_CPU1_SB_CB(5)
 234 M_C_CPU1_SB_CB<6>  CB6_B @T6G_MB_LIB.T6G(SCH_1):M_C_CPU1_SB_CB(6)
  51 M_C_CPU1_SA_CB<0>  CB0_A @T6G_MB_LIB.T6G(SCH_1):M_C_CPU1_SA_CB(0)
 196 M_C_CPU1_SA_CB<2>  CB2_A @T6G_MB_LIB.T6G(SCH_1):M_C_CPU1_SA_CB(2)
 198 M_C_CPU1_SA_CB<3>  CB3_A @T6G_MB_LIB.T6G(SCH_1):M_C_CPU1_SA_CB(3)
  60 M_C_CPU1_SA_CB<5>  CB5_A @T6G_MB_LIB.T6G(SCH_1):M_C_CPU1_SA_CB(5)
 203 M_C_CPU1_SA_CB<6>  CB6_A @T6G_MB_LIB.T6G(SCH_1):M_C_CPU1_SA_CB(6)
  82 M_C_CPU1_SB_CA<6>  CA6_B @T6G_MB_LIB.T6G(SCH_1):M_C_CPU1_SB_CA(6)
  72 M_C_CPU1_SA_CA<6>  CA6_A @T6G_MB_LIB.T6G(SCH_1):M_C_CPU1_SA_CA(6)
 225 M_C_CPU1_SB_CA<5>  CA5_B @T6G_MB_LIB.T6G(SCH_1):M_C_CPU1_SB_CA(5)
 215 M_C_CPU1_SA_CA<5>  CA5_A @T6G_MB_LIB.T6G(SCH_1):M_C_CPU1_SA_CA(5)
  80 M_C_CPU1_SB_CA<4>  CA4_B @T6G_MB_LIB.T6G(SCH_1):M_C_CPU1_SB_CA(4)
  70 M_C_CPU1_SA_CA<4>  CA4_A @T6G_MB_LIB.T6G(SCH_1):M_C_CPU1_SA_CA(4)
 223 M_C_CPU1_SB_CA<3>  CA3_B @T6G_MB_LIB.T6G(SCH_1):M_C_CPU1_SB_CA(3)
 213 M_C_CPU1_SA_CA<3>  CA3_A @T6G_MB_LIB.T6G(SCH_1):M_C_CPU1_SA_CA(3)
  78 M_C_CPU1_SB_CA<2>  CA2_B @T6G_MB_LIB.T6G(SCH_1):M_C_CPU1_SB_CA(2)
  68 M_C_CPU1_SA_CA<2>  CA2_A @T6G_MB_LIB.T6G(SCH_1):M_C_CPU1_SA_CA(2)
 221 M_C_CPU1_SB_CA<1>  CA1_B @T6G_MB_LIB.T6G(SCH_1):M_C_CPU1_SB_CA(1)
 211 M_C_CPU1_SA_CA<1>  CA1_A @T6G_MB_LIB.T6G(SCH_1):M_C_CPU1_SA_CA(1)
  76 M_C_CPU1_SB_CA<0>  CA0_B @T6G_MB_LIB.T6G(SCH_1):M_C_CPU1_SB_CA(0)
  66 M_C_CPU1_SA_CA<0>  CA0_A @T6G_MB_LIB.T6G(SCH_1):M_C_CPU1_SA_CA(0)
  62 M_C_CPU1_ALERT_N ALERT_N @T6G_MB_LIB.T6G(SCH_1):M_C_CPU1_ALERT_N
 236 M_C_CPU1_SB_CB<7>  CB7_B @T6G_MB_LIB.T6G(SCH_1):M_C_CPU1_SB_CB(7)
  53 M_C_CPU1_SA_CB<1>  CB1_A @T6G_MB_LIB.T6G(SCH_1):M_C_CPU1_SA_CB(1)
  58 M_C_CPU1_SA_CB<4>  CB4_A @T6G_MB_LIB.T6G(SCH_1):M_C_CPU1_SA_CB(4)
 205 M_C_CPU1_SA_CB<7>  CB7_A @T6G_MB_LIB.T6G(SCH_1):M_C_CPU1_SA_CB(7)
 194 M_C_CPU1_SA_DQ<31> DQ31_A @T6G_MB_LIB.T6G(SCH_1):M_C_CPU1_SA_DQ(31)

Q_RES_0402LF-23.2K,1%,1/16W,CHIP,CS32322FB03  I148  R771
   1 PD_CHC_CPU1_DIMM_SAA      A @T6G_MB_LIB.T6G(SCH_1):PD_CHC_CPU1_DIMM_SAA
   2    GND      B @T6G_MB_LIB.T6G(SCH_1):GND

SCONN288_DDR506112002KQ-SCONN288_DDR506112002KQ,SMA  I155  J28
   6    GND   VSS0 @T6G_MB_LIB.T6G(SCH_1):GND
   8    GND   VSS1 @T6G_MB_LIB.T6G(SCH_1):GND
  10    GND   VSS2 @T6G_MB_LIB.T6G(SCH_1):GND
  13    GND   VSS3 @T6G_MB_LIB.T6G(SCH_1):GND
  15    GND   VSS4 @T6G_MB_LIB.T6G(SCH_1):GND
  17    GND   VSS5 @T6G_MB_LIB.T6G(SCH_1):GND
  19    GND   VSS6 @T6G_MB_LIB.T6G(SCH_1):GND
  21    GND   VSS7 @T6G_MB_LIB.T6G(SCH_1):GND
  24    GND   VSS8 @T6G_MB_LIB.T6G(SCH_1):GND
  26    GND   VSS9 @T6G_MB_LIB.T6G(SCH_1):GND
  28    GND  VSS10 @T6G_MB_LIB.T6G(SCH_1):GND
  30    GND  VSS11 @T6G_MB_LIB.T6G(SCH_1):GND
  32    GND  VSS12 @T6G_MB_LIB.T6G(SCH_1):GND
  35    GND  VSS13 @T6G_MB_LIB.T6G(SCH_1):GND
  37    GND  VSS14 @T6G_MB_LIB.T6G(SCH_1):GND
  39    GND  VSS15 @T6G_MB_LIB.T6G(SCH_1):GND
  41    GND  VSS16 @T6G_MB_LIB.T6G(SCH_1):GND
  43    GND  VSS17 @T6G_MB_LIB.T6G(SCH_1):GND
  46    GND  VSS18 @T6G_MB_LIB.T6G(SCH_1):GND
  48    GND  VSS19 @T6G_MB_LIB.T6G(SCH_1):GND
  50    GND  VSS20 @T6G_MB_LIB.T6G(SCH_1):GND
  52    GND  VSS21 @T6G_MB_LIB.T6G(SCH_1):GND
  54    GND  VSS22 @T6G_MB_LIB.T6G(SCH_1):GND
  57    GND  VSS23 @T6G_MB_LIB.T6G(SCH_1):GND
  59    GND  VSS24 @T6G_MB_LIB.T6G(SCH_1):GND
  61    GND  VSS25 @T6G_MB_LIB.T6G(SCH_1):GND
  63    GND  VSS26 @T6G_MB_LIB.T6G(SCH_1):GND
  65    GND  VSS27 @T6G_MB_LIB.T6G(SCH_1):GND
  67    GND  VSS28 @T6G_MB_LIB.T6G(SCH_1):GND
  69    GND  VSS29 @T6G_MB_LIB.T6G(SCH_1):GND
  71    GND  VSS30 @T6G_MB_LIB.T6G(SCH_1):GND
  73    GND  VSS31 @T6G_MB_LIB.T6G(SCH_1):GND
  75    GND  VSS32 @T6G_MB_LIB.T6G(SCH_1):GND
  77    GND  VSS33 @T6G_MB_LIB.T6G(SCH_1):GND
  79    GND  VSS34 @T6G_MB_LIB.T6G(SCH_1):GND
  81    GND  VSS35 @T6G_MB_LIB.T6G(SCH_1):GND
  83    GND  VSS36 @T6G_MB_LIB.T6G(SCH_1):GND
  85    GND  VSS37 @T6G_MB_LIB.T6G(SCH_1):GND
  88    GND  VSS38 @T6G_MB_LIB.T6G(SCH_1):GND
  90    GND  VSS39 @T6G_MB_LIB.T6G(SCH_1):GND
  92    GND  VSS40 @T6G_MB_LIB.T6G(SCH_1):GND
  95    GND  VSS41 @T6G_MB_LIB.T6G(SCH_1):GND
  97    GND  VSS42 @T6G_MB_LIB.T6G(SCH_1):GND
  99    GND  VSS43 @T6G_MB_LIB.T6G(SCH_1):GND
 101    GND  VSS44 @T6G_MB_LIB.T6G(SCH_1):GND
 103    GND  VSS45 @T6G_MB_LIB.T6G(SCH_1):GND
 106    GND  VSS46 @T6G_MB_LIB.T6G(SCH_1):GND
 108    GND  VSS47 @T6G_MB_LIB.T6G(SCH_1):GND
 110    GND  VSS48 @T6G_MB_LIB.T6G(SCH_1):GND
 112    GND  VSS49 @T6G_MB_LIB.T6G(SCH_1):GND
 114    GND  VSS50 @T6G_MB_LIB.T6G(SCH_1):GND
 117    GND  VSS51 @T6G_MB_LIB.T6G(SCH_1):GND
 119    GND  VSS52 @T6G_MB_LIB.T6G(SCH_1):GND
 121    GND  VSS53 @T6G_MB_LIB.T6G(SCH_1):GND
 123    GND  VSS54 @T6G_MB_LIB.T6G(SCH_1):GND
 125    GND  VSS55 @T6G_MB_LIB.T6G(SCH_1):GND
 128    GND  VSS56 @T6G_MB_LIB.T6G(SCH_1):GND
 130    GND  VSS57 @T6G_MB_LIB.T6G(SCH_1):GND
 134    GND  VSS59 @T6G_MB_LIB.T6G(SCH_1):GND
 143    GND  VSS63 @T6G_MB_LIB.T6G(SCH_1):GND
 151    GND  VSS64 @T6G_MB_LIB.T6G(SCH_1):GND
 153    GND  VSS65 @T6G_MB_LIB.T6G(SCH_1):GND
 155    GND  VSS66 @T6G_MB_LIB.T6G(SCH_1):GND
 158    GND  VSS67 @T6G_MB_LIB.T6G(SCH_1):GND
 160    GND  VSS68 @T6G_MB_LIB.T6G(SCH_1):GND
 162    GND  VSS69 @T6G_MB_LIB.T6G(SCH_1):GND
 164    GND  VSS70 @T6G_MB_LIB.T6G(SCH_1):GND
 166    GND  VSS71 @T6G_MB_LIB.T6G(SCH_1):GND
 169    GND  VSS72 @T6G_MB_LIB.T6G(SCH_1):GND
 171    GND  VSS73 @T6G_MB_LIB.T6G(SCH_1):GND
 173    GND  VSS74 @T6G_MB_LIB.T6G(SCH_1):GND
 175    GND  VSS75 @T6G_MB_LIB.T6G(SCH_1):GND
 177    GND  VSS76 @T6G_MB_LIB.T6G(SCH_1):GND
 180    GND  VSS77 @T6G_MB_LIB.T6G(SCH_1):GND
 182    GND  VSS78 @T6G_MB_LIB.T6G(SCH_1):GND
 184    GND  VSS79 @T6G_MB_LIB.T6G(SCH_1):GND
 186    GND  VSS80 @T6G_MB_LIB.T6G(SCH_1):GND
 188    GND  VSS81 @T6G_MB_LIB.T6G(SCH_1):GND
 191    GND  VSS82 @T6G_MB_LIB.T6G(SCH_1):GND
 193    GND  VSS83 @T6G_MB_LIB.T6G(SCH_1):GND
 195    GND  VSS84 @T6G_MB_LIB.T6G(SCH_1):GND
 197    GND  VSS85 @T6G_MB_LIB.T6G(SCH_1):GND
 199    GND  VSS86 @T6G_MB_LIB.T6G(SCH_1):GND
 202    GND  VSS87 @T6G_MB_LIB.T6G(SCH_1):GND
 204    GND  VSS88 @T6G_MB_LIB.T6G(SCH_1):GND
 206    GND  VSS89 @T6G_MB_LIB.T6G(SCH_1):GND
 208    GND  VSS90 @T6G_MB_LIB.T6G(SCH_1):GND
 210    GND  VSS91 @T6G_MB_LIB.T6G(SCH_1):GND
 212    GND  VSS92 @T6G_MB_LIB.T6G(SCH_1):GND
 214    GND  VSS93 @T6G_MB_LIB.T6G(SCH_1):GND
 216    GND  VSS94 @T6G_MB_LIB.T6G(SCH_1):GND
 219    GND  VSS95 @T6G_MB_LIB.T6G(SCH_1):GND
 222    GND  VSS96 @T6G_MB_LIB.T6G(SCH_1):GND
 224    GND  VSS97 @T6G_MB_LIB.T6G(SCH_1):GND
 226    GND  VSS98 @T6G_MB_LIB.T6G(SCH_1):GND
 228    GND  VSS99 @T6G_MB_LIB.T6G(SCH_1):GND
 233    GND VSS101 @T6G_MB_LIB.T6G(SCH_1):GND
 237    GND VSS103 @T6G_MB_LIB.T6G(SCH_1):GND
 242    GND VSS105 @T6G_MB_LIB.T6G(SCH_1):GND
 244    GND VSS106 @T6G_MB_LIB.T6G(SCH_1):GND
 246    GND VSS107 @T6G_MB_LIB.T6G(SCH_1):GND
 248    GND VSS108 @T6G_MB_LIB.T6G(SCH_1):GND
 251    GND VSS109 @T6G_MB_LIB.T6G(SCH_1):GND
 253    GND VSS110 @T6G_MB_LIB.T6G(SCH_1):GND
 255    GND VSS111 @T6G_MB_LIB.T6G(SCH_1):GND
 257    GND VSS112 @T6G_MB_LIB.T6G(SCH_1):GND
 259    GND VSS113 @T6G_MB_LIB.T6G(SCH_1):GND
 262    GND VSS114 @T6G_MB_LIB.T6G(SCH_1):GND
 264    GND VSS115 @T6G_MB_LIB.T6G(SCH_1):GND
 266    GND VSS116 @T6G_MB_LIB.T6G(SCH_1):GND
 268    GND VSS117 @T6G_MB_LIB.T6G(SCH_1):GND
 270    GND VSS118 @T6G_MB_LIB.T6G(SCH_1):GND
 273    GND VSS119 @T6G_MB_LIB.T6G(SCH_1):GND
 275    GND VSS120 @T6G_MB_LIB.T6G(SCH_1):GND
 277    GND VSS121 @T6G_MB_LIB.T6G(SCH_1):GND
 279    GND VSS122 @T6G_MB_LIB.T6G(SCH_1):GND
 281    GND VSS123 @T6G_MB_LIB.T6G(SCH_1):GND
 284    GND VSS124 @T6G_MB_LIB.T6G(SCH_1):GND
 286    GND VSS125 @T6G_MB_LIB.T6G(SCH_1):GND
 288    GND VSS126 @T6G_MB_LIB.T6G(SCH_1):GND
   1 P12V_MEM_CPU1 VIN_BULK0 @T6G_MB_LIB.T6G(SCH_1):P12V_MEM_CPU1
 145 P12V_MEM_CPU1 VIN_BULK1 @T6G_MB_LIB.T6G(SCH_1):P12V_MEM_CPU1
 146 P12V_MEM_CPU1 VIN_BULK2 @T6G_MB_LIB.T6G(SCH_1):P12V_MEM_CPU1
 230    GND VSS100 @T6G_MB_LIB.T6G(SCH_1):GND
 235    GND VSS102 @T6G_MB_LIB.T6G(SCH_1):GND
 240    GND VSS104 @T6G_MB_LIB.T6G(SCH_1):GND
 132    GND  VSS58 @T6G_MB_LIB.T6G(SCH_1):GND
 136    GND  VSS60 @T6G_MB_LIB.T6G(SCH_1):GND
 139    GND  VSS61 @T6G_MB_LIB.T6G(SCH_1):GND
 141    GND  VSS62 @T6G_MB_LIB.T6G(SCH_1):GND
  G1    GND     G1 @T6G_MB_LIB.T6G(SCH_1):GND
  G2    GND     G2 @T6G_MB_LIB.T6G(SCH_1):GND
  G3    GND     G3 @T6G_MB_LIB.T6G(SCH_1):GND

Q_CAP_0402-0.1UF,25V,10%,X7R,CH4104K1B00  I185  C144
   1 P3V3_AUX      A @T6G_MB_LIB.T6G(SCH_1):P3V3_AUX
   2    GND      B @T6G_MB_LIB.T6G(SCH_1):GND

Q_RES_0402LF-1K,1%,1/16W,CHIP,CS21002FB06  I188  R305
   1 PWRGD_CHC_CPU1_DIMM      A @T6G_MB_LIB.T6G(SCH_1):PWRGD_CHC_CPU1_DIMM
   2 PWRGD_CHAF_CPU1      B @T6G_MB_LIB.T6G(SCH_1):PWRGD_CHAF_CPU1

Q_RES_0402LF-1K,1%,1/16W,EMPTY,CS21002FB06  I190  R105
   1   P3V3      A @T6G_MB_LIB.T6G(SCH_1):P3V3
   2 PWRGD_CHC_CPU1_DIMM      B @T6G_MB_LIB.T6G(SCH_1):PWRGD_CHC_CPU1_DIMM

SCONN288_DDR506112002KQ-SCONN288_DDR506112002KQ,SMA  I236  J28
  93 M_C_CPU1_SB_DQS_DP<9> DQS9_B_T||TDQS9_B_T||DBI4_B_N @T6G_MB_LIB.T6G(SCH_1):M_C_CPU1_SB_DQS_DP(9)
  94 M_C_CPU1_SB_DQS_DN<9> DQS9_B_C||TDQS9_B_C @T6G_MB_LIB.T6G(SCH_1):M_C_CPU1_SB_DQS_DN(9)
 201 M_C_CPU1_SA_DQS_DP<9> DQS9_A_T||TDQS9_A_T @T6G_MB_LIB.T6G(SCH_1):M_C_CPU1_SA_DQS_DP(9)
 200 M_C_CPU1_SA_DQS_DN<9> DQS9_A_C||TDQS9_A_C @T6G_MB_LIB.T6G(SCH_1):M_C_CPU1_SA_DQS_DN(9)
 190 M_C_CPU1_SA_DQS_DP<8> DQS8_A_T||TDQS8_A_T @T6G_MB_LIB.T6G(SCH_1):M_C_CPU1_SA_DQS_DP(8)
 189 M_C_CPU1_SA_DQS_DN<8> DQS8_A_C||TDQS8_A_C @T6G_MB_LIB.T6G(SCH_1):M_C_CPU1_SA_DQS_DN(8)
 271 M_C_CPU1_SB_DQS_DN<7> DQS7_B_C||TDQS7_B_C @T6G_MB_LIB.T6G(SCH_1):M_C_CPU1_SB_DQS_DN(7)
 179 M_C_CPU1_SA_DQS_DP<7> DQS7_A_T||TDQS7_A_T @T6G_MB_LIB.T6G(SCH_1):M_C_CPU1_SA_DQS_DP(7)
 261 M_C_CPU1_SB_DQS_DP<6> DQS6_B_T||TDQS6_B_T @T6G_MB_LIB.T6G(SCH_1):M_C_CPU1_SB_DQS_DP(6)
 260 M_C_CPU1_SB_DQS_DN<6> DQS6_B_C||TDQS6_B_C @T6G_MB_LIB.T6G(SCH_1):M_C_CPU1_SB_DQS_DN(6)
 167 M_C_CPU1_SA_DQS_DN<6> DQS6_A_C||TDQS6_A_C||DQS6_A_T||TDQS6_A_T @T6G_MB_LIB.T6G(SCH_1):M_C_CPU1_SA_DQS_DN(6)
 250 M_C_CPU1_SB_DQS_DP<5> DQS5_B_T||TDQS5_B_T @T6G_MB_LIB.T6G(SCH_1):M_C_CPU1_SB_DQS_DP(5)
 249 M_C_CPU1_SB_DQS_DN<5> DQS5_B_C||TDQS5_B_C @T6G_MB_LIB.T6G(SCH_1):M_C_CPU1_SB_DQS_DN(5)
 157 M_C_CPU1_SA_DQS_DP<5> DQS5_A_T||TDQS5_A_T @T6G_MB_LIB.T6G(SCH_1):M_C_CPU1_SA_DQS_DP(5)
 156 M_C_CPU1_SA_DQS_DN<5> DQS5_A_C||TDQS5_A_C||DQS5_A_T||TDQS5_A_T @T6G_MB_LIB.T6G(SCH_1):M_C_CPU1_SA_DQS_DN(5)
 239 M_C_CPU1_SB_DQS_DP<4> DQS4_B_T @T6G_MB_LIB.T6G(SCH_1):M_C_CPU1_SB_DQS_DP(4)
 238 M_C_CPU1_SB_DQS_DN<4> DQS4_B_C @T6G_MB_LIB.T6G(SCH_1):M_C_CPU1_SB_DQS_DN(4)
  55 M_C_CPU1_SA_DQS_DP<4> DQS4_A_T @T6G_MB_LIB.T6G(SCH_1):M_C_CPU1_SA_DQS_DP(4)
  56 M_C_CPU1_SA_DQS_DN<4> DQS4_A_C @T6G_MB_LIB.T6G(SCH_1):M_C_CPU1_SA_DQS_DN(4)
 137 M_C_CPU1_SB_DQS_DP<3> DQS3_B_T @T6G_MB_LIB.T6G(SCH_1):M_C_CPU1_SB_DQS_DP(3)
 138 M_C_CPU1_SB_DQS_DN<3> DQS3_B_C @T6G_MB_LIB.T6G(SCH_1):M_C_CPU1_SB_DQS_DN(3)
  44 M_C_CPU1_SA_DQS_DP<3> DQS3_A_T @T6G_MB_LIB.T6G(SCH_1):M_C_CPU1_SA_DQS_DP(3)
  45 M_C_CPU1_SA_DQS_DN<3> DQS3_A_C @T6G_MB_LIB.T6G(SCH_1):M_C_CPU1_SA_DQS_DN(3)
 126 M_C_CPU1_SB_DQS_DP<2> DQS2_B_T @T6G_MB_LIB.T6G(SCH_1):M_C_CPU1_SB_DQS_DP(2)
 127 M_C_CPU1_SB_DQS_DN<2> DQS2_B_C @T6G_MB_LIB.T6G(SCH_1):M_C_CPU1_SB_DQS_DN(2)
  33 M_C_CPU1_SA_DQS_DP<2> DQS2_A_T @T6G_MB_LIB.T6G(SCH_1):M_C_CPU1_SA_DQS_DP(2)
  34 M_C_CPU1_SA_DQS_DN<2> DQS2_A_C @T6G_MB_LIB.T6G(SCH_1):M_C_CPU1_SA_DQS_DN(2)
 115 M_C_CPU1_SB_DQS_DP<1> DQS1_B_T @T6G_MB_LIB.T6G(SCH_1):M_C_CPU1_SB_DQS_DP(1)
 116 M_C_CPU1_SB_DQS_DN<1> DQS1_B_C @T6G_MB_LIB.T6G(SCH_1):M_C_CPU1_SB_DQS_DN(1)
  22 M_C_CPU1_SA_DQS_DP<1> DQS1_A_T @T6G_MB_LIB.T6G(SCH_1):M_C_CPU1_SA_DQS_DP(1)
  23 M_C_CPU1_SA_DQS_DN<1> DQS1_A_C @T6G_MB_LIB.T6G(SCH_1):M_C_CPU1_SA_DQS_DN(1)
 104 M_C_CPU1_SB_DQS_DP<0> DQS0_B_T @T6G_MB_LIB.T6G(SCH_1):M_C_CPU1_SB_DQS_DP(0)
 105 M_C_CPU1_SB_DQS_DN<0> DQS0_B_C @T6G_MB_LIB.T6G(SCH_1):M_C_CPU1_SB_DQS_DN(0)
  11 M_C_CPU1_SA_DQS_DP<0> DQS0_A_T @T6G_MB_LIB.T6G(SCH_1):M_C_CPU1_SA_DQS_DP(0)
  12 M_C_CPU1_SA_DQS_DN<0> DQS0_A_C @T6G_MB_LIB.T6G(SCH_1):M_C_CPU1_SA_DQS_DN(0)
 272 M_C_CPU1_SB_DQS_DP<7> DQS7_B_T||TDQS7_B_T @T6G_MB_LIB.T6G(SCH_1):M_C_CPU1_SB_DQS_DP(7)
 282 M_C_CPU1_SB_DQS_DN<8> DQS8_B_C||TDQS8_B_C @T6G_MB_LIB.T6G(SCH_1):M_C_CPU1_SB_DQS_DN(8)
 283 M_C_CPU1_SB_DQS_DP<8> DQS8_B_T||TDQS8_B_T @T6G_MB_LIB.T6G(SCH_1):M_C_CPU1_SB_DQS_DP(8)
 168 M_C_CPU1_SA_DQS_DP<6> DQS6_A_T||TDQS6_A_T @T6G_MB_LIB.T6G(SCH_1):M_C_CPU1_SA_DQS_DP(6)
 178 M_C_CPU1_SA_DQS_DN<7> DQS7_A_C||TDQS7_A_C @T6G_MB_LIB.T6G(SCH_1):M_C_CPU1_SA_DQS_DN(7)

Q_CAP_C0805-10UF,25V,10%,X6S,CH6104KEA00  I238  C178
   1 P12V_MEM_CPU1      A @T6G_MB_LIB.T6G(SCH_1):P12V_MEM_CPU1
   2    GND      B @T6G_MB_LIB.T6G(SCH_1):GND

Q_CAP_C0805-10UF,25V,10%,X6S,CH6104KEA00  I239  C179
   1 P12V_MEM_CPU1      A @T6G_MB_LIB.T6G(SCH_1):P12V_MEM_CPU1
   2    GND      B @T6G_MB_LIB.T6G(SCH_1):GND

Q_RES_0402LF-49.9,1%,1/16W,CHIP,CS04992FB07  I242  R1582
   1 I3C_SPD_DDRAF_CPU1_SCL      A @T6G_MB_LIB.T6G(SCH_1):I3C_SPD_DDRAF_CPU1_SCL
   2 I3C_SPD_DDRC_CPU1_SCL      B @T6G_MB_LIB.T6G(SCH_1):I3C_SPD_DDRC_CPU1_SCL

Q_RES_0402LF-10,1%,1/16W,CHIP,CS01002FB07  I243  R1697
   1 I3C_SPD_DDRAF_CPU1_SDA      A @T6G_MB_LIB.T6G(SCH_1):I3C_SPD_DDRAF_CPU1_SDA
   2 I3C_SPD_DDRC_CPU1_SDA      B @T6G_MB_LIB.T6G(SCH_1):I3C_SPD_DDRC_CPU1_SDA


DRAWING: @T6G_MB_LIB.T6G(SCH_1):PAGE100 

SCONN288_DDR506112002KQ-SCONN288_DDR506112002KQ,SMA  I52  J30
   3 P3V3_AUX VIN_MGMT @T6G_MB_LIB.T6G(SCH_1):P3V3_AUX
   2     NC   RFU0     NC
 144     NC   RFU1     NC
 149     NC   RFU2     NC
 150     NC   RFU3     NC
 220     NC   RFU4     NC
 231     NC   RFU5     NC
 232     NC   RFU6     NC
 207 M_D_CPU1_RESET_N RESET_N @T6G_MB_LIB.T6G(SCH_1):M_D_CPU1_RESET_N
 147 PWRGD_CHD_CPU1_DIMM PWR_GOOD||FAIL_N @T6G_MB_LIB.T6G(SCH_1):PWRGD_CHD_CPU1_DIMM
 227 M_D_CPU1_SB_PAR  PAR_B @T6G_MB_LIB.T6G(SCH_1):M_D_CPU1_SB_PAR
  74 M_D_CPU1_SA_PAR  PAR_A @T6G_MB_LIB.T6G(SCH_1):M_D_CPU1_SA_PAR
  87 M_D_CPU1_SB_RSP<0> LBS||RSP_B_N @T6G_MB_LIB.T6G(SCH_1):M_D_CPU1_SB_RSP(0)
  86 M_D_CPU1_SA_RSP<0> LBD||RSP_A_N @T6G_MB_LIB.T6G(SCH_1):M_D_CPU1_SA_RSP(0)
   5 I3C_SPD_DDRD_CPU1_SDA   HSDA @T6G_MB_LIB.T6G(SCH_1):I3C_SPD_DDRD_CPU1_SDA
   4 I3C_SPD_DDRD_CPU1_SCL   HSCL @T6G_MB_LIB.T6G(SCH_1):I3C_SPD_DDRD_CPU1_SCL
 148 PD_CHD_CPU1_DIMM_SAA    HAS @T6G_MB_LIB.T6G(SCH_1):PD_CHD_CPU1_DIMM_SAA
 100 M_D_CPU1_SB_DQ<0>  DQ0_B @T6G_MB_LIB.T6G(SCH_1):M_D_CPU1_SB_DQ(0)
 102 M_D_CPU1_SB_DQ<1>  DQ1_B @T6G_MB_LIB.T6G(SCH_1):M_D_CPU1_SB_DQ(1)
 245 M_D_CPU1_SB_DQ<2>  DQ2_B @T6G_MB_LIB.T6G(SCH_1):M_D_CPU1_SB_DQ(2)
 247 M_D_CPU1_SB_DQ<3>  DQ3_B @T6G_MB_LIB.T6G(SCH_1):M_D_CPU1_SB_DQ(3)
 107 M_D_CPU1_SB_DQ<4>  DQ4_B @T6G_MB_LIB.T6G(SCH_1):M_D_CPU1_SB_DQ(4)
 109 M_D_CPU1_SB_DQ<5>  DQ5_B @T6G_MB_LIB.T6G(SCH_1):M_D_CPU1_SB_DQ(5)
 252 M_D_CPU1_SB_DQ<6>  DQ6_B @T6G_MB_LIB.T6G(SCH_1):M_D_CPU1_SB_DQ(6)
 254 M_D_CPU1_SB_DQ<7>  DQ7_B @T6G_MB_LIB.T6G(SCH_1):M_D_CPU1_SB_DQ(7)
 111 M_D_CPU1_SB_DQ<8>  DQ8_B @T6G_MB_LIB.T6G(SCH_1):M_D_CPU1_SB_DQ(8)
 113 M_D_CPU1_SB_DQ<9>  DQ9_B @T6G_MB_LIB.T6G(SCH_1):M_D_CPU1_SB_DQ(9)
 256 M_D_CPU1_SB_DQ<10> DQ10_B @T6G_MB_LIB.T6G(SCH_1):M_D_CPU1_SB_DQ(10)
 258 M_D_CPU1_SB_DQ<11> DQ11_B @T6G_MB_LIB.T6G(SCH_1):M_D_CPU1_SB_DQ(11)
 118 M_D_CPU1_SB_DQ<12> DQ12_B @T6G_MB_LIB.T6G(SCH_1):M_D_CPU1_SB_DQ(12)
 120 M_D_CPU1_SB_DQ<13> DQ13_B @T6G_MB_LIB.T6G(SCH_1):M_D_CPU1_SB_DQ(13)
 263 M_D_CPU1_SB_DQ<14> DQ14_B @T6G_MB_LIB.T6G(SCH_1):M_D_CPU1_SB_DQ(14)
 265 M_D_CPU1_SB_DQ<15> DQ15_B @T6G_MB_LIB.T6G(SCH_1):M_D_CPU1_SB_DQ(15)
 122 M_D_CPU1_SB_DQ<16> DQ16_B @T6G_MB_LIB.T6G(SCH_1):M_D_CPU1_SB_DQ(16)
 124 M_D_CPU1_SB_DQ<17> DQ17_B @T6G_MB_LIB.T6G(SCH_1):M_D_CPU1_SB_DQ(17)
 267 M_D_CPU1_SB_DQ<18> DQ18_B @T6G_MB_LIB.T6G(SCH_1):M_D_CPU1_SB_DQ(18)
 269 M_D_CPU1_SB_DQ<19> DQ19_B @T6G_MB_LIB.T6G(SCH_1):M_D_CPU1_SB_DQ(19)
 129 M_D_CPU1_SB_DQ<20> DQ20_B @T6G_MB_LIB.T6G(SCH_1):M_D_CPU1_SB_DQ(20)
 131 M_D_CPU1_SB_DQ<21> DQ21_B @T6G_MB_LIB.T6G(SCH_1):M_D_CPU1_SB_DQ(21)
 274 M_D_CPU1_SB_DQ<22> DQ22_B @T6G_MB_LIB.T6G(SCH_1):M_D_CPU1_SB_DQ(22)
 276 M_D_CPU1_SB_DQ<23> DQ23_B @T6G_MB_LIB.T6G(SCH_1):M_D_CPU1_SB_DQ(23)
 133 M_D_CPU1_SB_DQ<24> DQ24_B @T6G_MB_LIB.T6G(SCH_1):M_D_CPU1_SB_DQ(24)
 135 M_D_CPU1_SB_DQ<25> DQ25_B @T6G_MB_LIB.T6G(SCH_1):M_D_CPU1_SB_DQ(25)
 278 M_D_CPU1_SB_DQ<26> DQ26_B @T6G_MB_LIB.T6G(SCH_1):M_D_CPU1_SB_DQ(26)
 280 M_D_CPU1_SB_DQ<27> DQ27_B @T6G_MB_LIB.T6G(SCH_1):M_D_CPU1_SB_DQ(27)
 140 M_D_CPU1_SB_DQ<28> DQ28_B @T6G_MB_LIB.T6G(SCH_1):M_D_CPU1_SB_DQ(28)
 142 M_D_CPU1_SB_DQ<29> DQ29_B @T6G_MB_LIB.T6G(SCH_1):M_D_CPU1_SB_DQ(29)
 285 M_D_CPU1_SB_DQ<30> DQ30_B @T6G_MB_LIB.T6G(SCH_1):M_D_CPU1_SB_DQ(30)
 287 M_D_CPU1_SB_DQ<31> DQ31_B @T6G_MB_LIB.T6G(SCH_1):M_D_CPU1_SB_DQ(31)
   7 M_D_CPU1_SA_DQ<0>  DQ0_A @T6G_MB_LIB.T6G(SCH_1):M_D_CPU1_SA_DQ(0)
   9 M_D_CPU1_SA_DQ<1>  DQ1_A @T6G_MB_LIB.T6G(SCH_1):M_D_CPU1_SA_DQ(1)
 152 M_D_CPU1_SA_DQ<2>  DQ2_A @T6G_MB_LIB.T6G(SCH_1):M_D_CPU1_SA_DQ(2)
 154 M_D_CPU1_SA_DQ<3>  DQ3_A @T6G_MB_LIB.T6G(SCH_1):M_D_CPU1_SA_DQ(3)
  14 M_D_CPU1_SA_DQ<4>  DQ4_A @T6G_MB_LIB.T6G(SCH_1):M_D_CPU1_SA_DQ(4)
  16 M_D_CPU1_SA_DQ<5>  DQ5_A @T6G_MB_LIB.T6G(SCH_1):M_D_CPU1_SA_DQ(5)
 159 M_D_CPU1_SA_DQ<6>  DQ6_A @T6G_MB_LIB.T6G(SCH_1):M_D_CPU1_SA_DQ(6)
 161 M_D_CPU1_SA_DQ<7>  DQ7_A @T6G_MB_LIB.T6G(SCH_1):M_D_CPU1_SA_DQ(7)
  18 M_D_CPU1_SA_DQ<8>  DQ8_A @T6G_MB_LIB.T6G(SCH_1):M_D_CPU1_SA_DQ(8)
  20 M_D_CPU1_SA_DQ<9>  DQ9_A @T6G_MB_LIB.T6G(SCH_1):M_D_CPU1_SA_DQ(9)
 163 M_D_CPU1_SA_DQ<10> DQ10_A @T6G_MB_LIB.T6G(SCH_1):M_D_CPU1_SA_DQ(10)
 165 M_D_CPU1_SA_DQ<11> DQ11_A @T6G_MB_LIB.T6G(SCH_1):M_D_CPU1_SA_DQ(11)
  25 M_D_CPU1_SA_DQ<12> DQ12_A @T6G_MB_LIB.T6G(SCH_1):M_D_CPU1_SA_DQ(12)
  27 M_D_CPU1_SA_DQ<13> DQ13_A @T6G_MB_LIB.T6G(SCH_1):M_D_CPU1_SA_DQ(13)
 170 M_D_CPU1_SA_DQ<14> DQ14_A @T6G_MB_LIB.T6G(SCH_1):M_D_CPU1_SA_DQ(14)
 172 M_D_CPU1_SA_DQ<15> DQ15_A @T6G_MB_LIB.T6G(SCH_1):M_D_CPU1_SA_DQ(15)
  29 M_D_CPU1_SA_DQ<16> DQ16_A @T6G_MB_LIB.T6G(SCH_1):M_D_CPU1_SA_DQ(16)
  31 M_D_CPU1_SA_DQ<17> DQ17_A @T6G_MB_LIB.T6G(SCH_1):M_D_CPU1_SA_DQ(17)
 174 M_D_CPU1_SA_DQ<18> DQ18_A @T6G_MB_LIB.T6G(SCH_1):M_D_CPU1_SA_DQ(18)
 176 M_D_CPU1_SA_DQ<19> DQ19_A @T6G_MB_LIB.T6G(SCH_1):M_D_CPU1_SA_DQ(19)
  36 M_D_CPU1_SA_DQ<20> DQ20_A @T6G_MB_LIB.T6G(SCH_1):M_D_CPU1_SA_DQ(20)
  38 M_D_CPU1_SA_DQ<21> DQ21_A @T6G_MB_LIB.T6G(SCH_1):M_D_CPU1_SA_DQ(21)
 181 M_D_CPU1_SA_DQ<22> DQ22_A @T6G_MB_LIB.T6G(SCH_1):M_D_CPU1_SA_DQ(22)
 183 M_D_CPU1_SA_DQ<23> DQ23_A @T6G_MB_LIB.T6G(SCH_1):M_D_CPU1_SA_DQ(23)
  40 M_D_CPU1_SA_DQ<24> DQ24_A @T6G_MB_LIB.T6G(SCH_1):M_D_CPU1_SA_DQ(24)
  42 M_D_CPU1_SA_DQ<25> DQ25_A @T6G_MB_LIB.T6G(SCH_1):M_D_CPU1_SA_DQ(25)
 185 M_D_CPU1_SA_DQ<26> DQ26_A @T6G_MB_LIB.T6G(SCH_1):M_D_CPU1_SA_DQ(26)
 187 M_D_CPU1_SA_DQ<27> DQ27_A @T6G_MB_LIB.T6G(SCH_1):M_D_CPU1_SA_DQ(27)
  47 M_D_CPU1_SA_DQ<28> DQ28_A @T6G_MB_LIB.T6G(SCH_1):M_D_CPU1_SA_DQ(28)
  49 M_D_CPU1_SA_DQ<29> DQ29_A @T6G_MB_LIB.T6G(SCH_1):M_D_CPU1_SA_DQ(29)
 192 M_D_CPU1_SA_DQ<30> DQ30_A @T6G_MB_LIB.T6G(SCH_1):M_D_CPU1_SA_DQ(30)
 229 M_D_CPU1_SB_CS_N<1> CS1_B_N @T6G_MB_LIB.T6G(SCH_1):M_D_CPU1_SB_CS_N(1)
 209 M_D_CPU1_SA_CS_N<1> CS1_A_N @T6G_MB_LIB.T6G(SCH_1):M_D_CPU1_SA_CS_N(1)
  84 M_D_CPU1_SB_CS_N<0> CS0_B_N @T6G_MB_LIB.T6G(SCH_1):M_D_CPU1_SB_CS_N(0)
  64 M_D_CPU1_SA_CS_N<0> CS0_A_N @T6G_MB_LIB.T6G(SCH_1):M_D_CPU1_SA_CS_N(0)
 217 M_D_CPU1_CLK_DP<0>   CK_T @T6G_MB_LIB.T6G(SCH_1):M_D_CPU1_CLK_DP(0)
 218 M_D_CPU1_CLK_DN<0>   CK_C @T6G_MB_LIB.T6G(SCH_1):M_D_CPU1_CLK_DN(0)
  96 M_D_CPU1_SB_CB<0>  CB0_B @T6G_MB_LIB.T6G(SCH_1):M_D_CPU1_SB_CB(0)
  98 M_D_CPU1_SB_CB<1>  CB1_B @T6G_MB_LIB.T6G(SCH_1):M_D_CPU1_SB_CB(1)
 241 M_D_CPU1_SB_CB<2>  CB2_B @T6G_MB_LIB.T6G(SCH_1):M_D_CPU1_SB_CB(2)
 243 M_D_CPU1_SB_CB<3>  CB3_B @T6G_MB_LIB.T6G(SCH_1):M_D_CPU1_SB_CB(3)
  89 M_D_CPU1_SB_CB<4>  CB4_B @T6G_MB_LIB.T6G(SCH_1):M_D_CPU1_SB_CB(4)
  91 M_D_CPU1_SB_CB<5>  CB5_B @T6G_MB_LIB.T6G(SCH_1):M_D_CPU1_SB_CB(5)
 234 M_D_CPU1_SB_CB<6>  CB6_B @T6G_MB_LIB.T6G(SCH_1):M_D_CPU1_SB_CB(6)
  51 M_D_CPU1_SA_CB<0>  CB0_A @T6G_MB_LIB.T6G(SCH_1):M_D_CPU1_SA_CB(0)
 196 M_D_CPU1_SA_CB<2>  CB2_A @T6G_MB_LIB.T6G(SCH_1):M_D_CPU1_SA_CB(2)
 198 M_D_CPU1_SA_CB<3>  CB3_A @T6G_MB_LIB.T6G(SCH_1):M_D_CPU1_SA_CB(3)
  60 M_D_CPU1_SA_CB<5>  CB5_A @T6G_MB_LIB.T6G(SCH_1):M_D_CPU1_SA_CB(5)
 203 M_D_CPU1_SA_CB<6>  CB6_A @T6G_MB_LIB.T6G(SCH_1):M_D_CPU1_SA_CB(6)
  82 M_D_CPU1_SB_CA<6>  CA6_B @T6G_MB_LIB.T6G(SCH_1):M_D_CPU1_SB_CA(6)
  72 M_D_CPU1_SA_CA<6>  CA6_A @T6G_MB_LIB.T6G(SCH_1):M_D_CPU1_SA_CA(6)
 225 M_D_CPU1_SB_CA<5>  CA5_B @T6G_MB_LIB.T6G(SCH_1):M_D_CPU1_SB_CA(5)
 215 M_D_CPU1_SA_CA<5>  CA5_A @T6G_MB_LIB.T6G(SCH_1):M_D_CPU1_SA_CA(5)
  80 M_D_CPU1_SB_CA<4>  CA4_B @T6G_MB_LIB.T6G(SCH_1):M_D_CPU1_SB_CA(4)
  70 M_D_CPU1_SA_CA<4>  CA4_A @T6G_MB_LIB.T6G(SCH_1):M_D_CPU1_SA_CA(4)
 223 M_D_CPU1_SB_CA<3>  CA3_B @T6G_MB_LIB.T6G(SCH_1):M_D_CPU1_SB_CA(3)
 213 M_D_CPU1_SA_CA<3>  CA3_A @T6G_MB_LIB.T6G(SCH_1):M_D_CPU1_SA_CA(3)
  78 M_D_CPU1_SB_CA<2>  CA2_B @T6G_MB_LIB.T6G(SCH_1):M_D_CPU1_SB_CA(2)
  68 M_D_CPU1_SA_CA<2>  CA2_A @T6G_MB_LIB.T6G(SCH_1):M_D_CPU1_SA_CA(2)
 221 M_D_CPU1_SB_CA<1>  CA1_B @T6G_MB_LIB.T6G(SCH_1):M_D_CPU1_SB_CA(1)
 211 M_D_CPU1_SA_CA<1>  CA1_A @T6G_MB_LIB.T6G(SCH_1):M_D_CPU1_SA_CA(1)
  76 M_D_CPU1_SB_CA<0>  CA0_B @T6G_MB_LIB.T6G(SCH_1):M_D_CPU1_SB_CA(0)
  66 M_D_CPU1_SA_CA<0>  CA0_A @T6G_MB_LIB.T6G(SCH_1):M_D_CPU1_SA_CA(0)
  62 M_D_CPU1_ALERT_N ALERT_N @T6G_MB_LIB.T6G(SCH_1):M_D_CPU1_ALERT_N
 236 M_D_CPU1_SB_CB<7>  CB7_B @T6G_MB_LIB.T6G(SCH_1):M_D_CPU1_SB_CB(7)
  53 M_D_CPU1_SA_CB<1>  CB1_A @T6G_MB_LIB.T6G(SCH_1):M_D_CPU1_SA_CB(1)
  58 M_D_CPU1_SA_CB<4>  CB4_A @T6G_MB_LIB.T6G(SCH_1):M_D_CPU1_SA_CB(4)
 205 M_D_CPU1_SA_CB<7>  CB7_A @T6G_MB_LIB.T6G(SCH_1):M_D_CPU1_SA_CB(7)
 194 M_D_CPU1_SA_DQ<31> DQ31_A @T6G_MB_LIB.T6G(SCH_1):M_D_CPU1_SA_DQ(31)

Q_RES_0402LF-35.7K,1%,1/16W,CHIP,CS33572FB01  I146  R772
   1 PD_CHD_CPU1_DIMM_SAA      A @T6G_MB_LIB.T6G(SCH_1):PD_CHD_CPU1_DIMM_SAA
   2    GND      B @T6G_MB_LIB.T6G(SCH_1):GND

SCONN288_DDR506112002KQ-SCONN288_DDR506112002KQ,SMA  I161  J30
   6    GND   VSS0 @T6G_MB_LIB.T6G(SCH_1):GND
   8    GND   VSS1 @T6G_MB_LIB.T6G(SCH_1):GND
  10    GND   VSS2 @T6G_MB_LIB.T6G(SCH_1):GND
  13    GND   VSS3 @T6G_MB_LIB.T6G(SCH_1):GND
  15    GND   VSS4 @T6G_MB_LIB.T6G(SCH_1):GND
  17    GND   VSS5 @T6G_MB_LIB.T6G(SCH_1):GND
  19    GND   VSS6 @T6G_MB_LIB.T6G(SCH_1):GND
  21    GND   VSS7 @T6G_MB_LIB.T6G(SCH_1):GND
  24    GND   VSS8 @T6G_MB_LIB.T6G(SCH_1):GND
  26    GND   VSS9 @T6G_MB_LIB.T6G(SCH_1):GND
  28    GND  VSS10 @T6G_MB_LIB.T6G(SCH_1):GND
  30    GND  VSS11 @T6G_MB_LIB.T6G(SCH_1):GND
  32    GND  VSS12 @T6G_MB_LIB.T6G(SCH_1):GND
  35    GND  VSS13 @T6G_MB_LIB.T6G(SCH_1):GND
  37    GND  VSS14 @T6G_MB_LIB.T6G(SCH_1):GND
  39    GND  VSS15 @T6G_MB_LIB.T6G(SCH_1):GND
  41    GND  VSS16 @T6G_MB_LIB.T6G(SCH_1):GND
  43    GND  VSS17 @T6G_MB_LIB.T6G(SCH_1):GND
  46    GND  VSS18 @T6G_MB_LIB.T6G(SCH_1):GND
  48    GND  VSS19 @T6G_MB_LIB.T6G(SCH_1):GND
  50    GND  VSS20 @T6G_MB_LIB.T6G(SCH_1):GND
  52    GND  VSS21 @T6G_MB_LIB.T6G(SCH_1):GND
  54    GND  VSS22 @T6G_MB_LIB.T6G(SCH_1):GND
  57    GND  VSS23 @T6G_MB_LIB.T6G(SCH_1):GND
  59    GND  VSS24 @T6G_MB_LIB.T6G(SCH_1):GND
  61    GND  VSS25 @T6G_MB_LIB.T6G(SCH_1):GND
  63    GND  VSS26 @T6G_MB_LIB.T6G(SCH_1):GND
  65    GND  VSS27 @T6G_MB_LIB.T6G(SCH_1):GND
  67    GND  VSS28 @T6G_MB_LIB.T6G(SCH_1):GND
  69    GND  VSS29 @T6G_MB_LIB.T6G(SCH_1):GND
  71    GND  VSS30 @T6G_MB_LIB.T6G(SCH_1):GND
  73    GND  VSS31 @T6G_MB_LIB.T6G(SCH_1):GND
  75    GND  VSS32 @T6G_MB_LIB.T6G(SCH_1):GND
  77    GND  VSS33 @T6G_MB_LIB.T6G(SCH_1):GND
  79    GND  VSS34 @T6G_MB_LIB.T6G(SCH_1):GND
  81    GND  VSS35 @T6G_MB_LIB.T6G(SCH_1):GND
  83    GND  VSS36 @T6G_MB_LIB.T6G(SCH_1):GND
  85    GND  VSS37 @T6G_MB_LIB.T6G(SCH_1):GND
  88    GND  VSS38 @T6G_MB_LIB.T6G(SCH_1):GND
  90    GND  VSS39 @T6G_MB_LIB.T6G(SCH_1):GND
  92    GND  VSS40 @T6G_MB_LIB.T6G(SCH_1):GND
  95    GND  VSS41 @T6G_MB_LIB.T6G(SCH_1):GND
  97    GND  VSS42 @T6G_MB_LIB.T6G(SCH_1):GND
  99    GND  VSS43 @T6G_MB_LIB.T6G(SCH_1):GND
 101    GND  VSS44 @T6G_MB_LIB.T6G(SCH_1):GND
 103    GND  VSS45 @T6G_MB_LIB.T6G(SCH_1):GND
 106    GND  VSS46 @T6G_MB_LIB.T6G(SCH_1):GND
 108    GND  VSS47 @T6G_MB_LIB.T6G(SCH_1):GND
 110    GND  VSS48 @T6G_MB_LIB.T6G(SCH_1):GND
 112    GND  VSS49 @T6G_MB_LIB.T6G(SCH_1):GND
 114    GND  VSS50 @T6G_MB_LIB.T6G(SCH_1):GND
 117    GND  VSS51 @T6G_MB_LIB.T6G(SCH_1):GND
 119    GND  VSS52 @T6G_MB_LIB.T6G(SCH_1):GND
 121    GND  VSS53 @T6G_MB_LIB.T6G(SCH_1):GND
 123    GND  VSS54 @T6G_MB_LIB.T6G(SCH_1):GND
 125    GND  VSS55 @T6G_MB_LIB.T6G(SCH_1):GND
 128    GND  VSS56 @T6G_MB_LIB.T6G(SCH_1):GND
 130    GND  VSS57 @T6G_MB_LIB.T6G(SCH_1):GND
 134    GND  VSS59 @T6G_MB_LIB.T6G(SCH_1):GND
 143    GND  VSS63 @T6G_MB_LIB.T6G(SCH_1):GND
 151    GND  VSS64 @T6G_MB_LIB.T6G(SCH_1):GND
 153    GND  VSS65 @T6G_MB_LIB.T6G(SCH_1):GND
 155    GND  VSS66 @T6G_MB_LIB.T6G(SCH_1):GND
 158    GND  VSS67 @T6G_MB_LIB.T6G(SCH_1):GND
 160    GND  VSS68 @T6G_MB_LIB.T6G(SCH_1):GND
 162    GND  VSS69 @T6G_MB_LIB.T6G(SCH_1):GND
 164    GND  VSS70 @T6G_MB_LIB.T6G(SCH_1):GND
 166    GND  VSS71 @T6G_MB_LIB.T6G(SCH_1):GND
 169    GND  VSS72 @T6G_MB_LIB.T6G(SCH_1):GND
 171    GND  VSS73 @T6G_MB_LIB.T6G(SCH_1):GND
 173    GND  VSS74 @T6G_MB_LIB.T6G(SCH_1):GND
 175    GND  VSS75 @T6G_MB_LIB.T6G(SCH_1):GND
 177    GND  VSS76 @T6G_MB_LIB.T6G(SCH_1):GND
 180    GND  VSS77 @T6G_MB_LIB.T6G(SCH_1):GND
 182    GND  VSS78 @T6G_MB_LIB.T6G(SCH_1):GND
 184    GND  VSS79 @T6G_MB_LIB.T6G(SCH_1):GND
 186    GND  VSS80 @T6G_MB_LIB.T6G(SCH_1):GND
 188    GND  VSS81 @T6G_MB_LIB.T6G(SCH_1):GND
 191    GND  VSS82 @T6G_MB_LIB.T6G(SCH_1):GND
 193    GND  VSS83 @T6G_MB_LIB.T6G(SCH_1):GND
 195    GND  VSS84 @T6G_MB_LIB.T6G(SCH_1):GND
 197    GND  VSS85 @T6G_MB_LIB.T6G(SCH_1):GND
 199    GND  VSS86 @T6G_MB_LIB.T6G(SCH_1):GND
 202    GND  VSS87 @T6G_MB_LIB.T6G(SCH_1):GND
 204    GND  VSS88 @T6G_MB_LIB.T6G(SCH_1):GND
 206    GND  VSS89 @T6G_MB_LIB.T6G(SCH_1):GND
 208    GND  VSS90 @T6G_MB_LIB.T6G(SCH_1):GND
 210    GND  VSS91 @T6G_MB_LIB.T6G(SCH_1):GND
 212    GND  VSS92 @T6G_MB_LIB.T6G(SCH_1):GND
 214    GND  VSS93 @T6G_MB_LIB.T6G(SCH_1):GND
 216    GND  VSS94 @T6G_MB_LIB.T6G(SCH_1):GND
 219    GND  VSS95 @T6G_MB_LIB.T6G(SCH_1):GND
 222    GND  VSS96 @T6G_MB_LIB.T6G(SCH_1):GND
 224    GND  VSS97 @T6G_MB_LIB.T6G(SCH_1):GND
 226    GND  VSS98 @T6G_MB_LIB.T6G(SCH_1):GND
 228    GND  VSS99 @T6G_MB_LIB.T6G(SCH_1):GND
 233    GND VSS101 @T6G_MB_LIB.T6G(SCH_1):GND
 237    GND VSS103 @T6G_MB_LIB.T6G(SCH_1):GND
 242    GND VSS105 @T6G_MB_LIB.T6G(SCH_1):GND
 244    GND VSS106 @T6G_MB_LIB.T6G(SCH_1):GND
 246    GND VSS107 @T6G_MB_LIB.T6G(SCH_1):GND
 248    GND VSS108 @T6G_MB_LIB.T6G(SCH_1):GND
 251    GND VSS109 @T6G_MB_LIB.T6G(SCH_1):GND
 253    GND VSS110 @T6G_MB_LIB.T6G(SCH_1):GND
 255    GND VSS111 @T6G_MB_LIB.T6G(SCH_1):GND
 257    GND VSS112 @T6G_MB_LIB.T6G(SCH_1):GND
 259    GND VSS113 @T6G_MB_LIB.T6G(SCH_1):GND
 262    GND VSS114 @T6G_MB_LIB.T6G(SCH_1):GND
 264    GND VSS115 @T6G_MB_LIB.T6G(SCH_1):GND
 266    GND VSS116 @T6G_MB_LIB.T6G(SCH_1):GND
 268    GND VSS117 @T6G_MB_LIB.T6G(SCH_1):GND
 270    GND VSS118 @T6G_MB_LIB.T6G(SCH_1):GND
 273    GND VSS119 @T6G_MB_LIB.T6G(SCH_1):GND
 275    GND VSS120 @T6G_MB_LIB.T6G(SCH_1):GND
 277    GND VSS121 @T6G_MB_LIB.T6G(SCH_1):GND
 279    GND VSS122 @T6G_MB_LIB.T6G(SCH_1):GND
 281    GND VSS123 @T6G_MB_LIB.T6G(SCH_1):GND
 284    GND VSS124 @T6G_MB_LIB.T6G(SCH_1):GND
 286    GND VSS125 @T6G_MB_LIB.T6G(SCH_1):GND
 288    GND VSS126 @T6G_MB_LIB.T6G(SCH_1):GND
   1 P12V_MEM_CPU1 VIN_BULK0 @T6G_MB_LIB.T6G(SCH_1):P12V_MEM_CPU1
 145 P12V_MEM_CPU1 VIN_BULK1 @T6G_MB_LIB.T6G(SCH_1):P12V_MEM_CPU1
 146 P12V_MEM_CPU1 VIN_BULK2 @T6G_MB_LIB.T6G(SCH_1):P12V_MEM_CPU1
 230    GND VSS100 @T6G_MB_LIB.T6G(SCH_1):GND
 235    GND VSS102 @T6G_MB_LIB.T6G(SCH_1):GND
 240    GND VSS104 @T6G_MB_LIB.T6G(SCH_1):GND
 132    GND  VSS58 @T6G_MB_LIB.T6G(SCH_1):GND
 136    GND  VSS60 @T6G_MB_LIB.T6G(SCH_1):GND
 139    GND  VSS61 @T6G_MB_LIB.T6G(SCH_1):GND
 141    GND  VSS62 @T6G_MB_LIB.T6G(SCH_1):GND
  G1    GND     G1 @T6G_MB_LIB.T6G(SCH_1):GND
  G2    GND     G2 @T6G_MB_LIB.T6G(SCH_1):GND
  G3    GND     G3 @T6G_MB_LIB.T6G(SCH_1):GND

Q_CAP_0402-0.1UF,25V,10%,X7R,CH4104K1B00  I185  C148
   1 P3V3_AUX      A @T6G_MB_LIB.T6G(SCH_1):P3V3_AUX
   2    GND      B @T6G_MB_LIB.T6G(SCH_1):GND

Q_RES_0402LF-1K,1%,1/16W,CHIP,CS21002FB06  I188  R306
   1 PWRGD_CHD_CPU1_DIMM      A @T6G_MB_LIB.T6G(SCH_1):PWRGD_CHD_CPU1_DIMM
   2 PWRGD_CHAF_CPU1      B @T6G_MB_LIB.T6G(SCH_1):PWRGD_CHAF_CPU1

Q_RES_0402LF-1K,1%,1/16W,EMPTY,CS21002FB06  I190  R106
   1   P3V3      A @T6G_MB_LIB.T6G(SCH_1):P3V3
   2 PWRGD_CHD_CPU1_DIMM      B @T6G_MB_LIB.T6G(SCH_1):PWRGD_CHD_CPU1_DIMM

SCONN288_DDR506112002KQ-SCONN288_DDR506112002KQ,SMA  I236  J30
  93 M_D_CPU1_SB_DQS_DP<9> DQS9_B_T||TDQS9_B_T||DBI4_B_N @T6G_MB_LIB.T6G(SCH_1):M_D_CPU1_SB_DQS_DP(9)
  94 M_D_CPU1_SB_DQS_DN<9> DQS9_B_C||TDQS9_B_C @T6G_MB_LIB.T6G(SCH_1):M_D_CPU1_SB_DQS_DN(9)
 201 M_D_CPU1_SA_DQS_DP<9> DQS9_A_T||TDQS9_A_T @T6G_MB_LIB.T6G(SCH_1):M_D_CPU1_SA_DQS_DP(9)
 200 M_D_CPU1_SA_DQS_DN<9> DQS9_A_C||TDQS9_A_C @T6G_MB_LIB.T6G(SCH_1):M_D_CPU1_SA_DQS_DN(9)
 190 M_D_CPU1_SA_DQS_DP<8> DQS8_A_T||TDQS8_A_T @T6G_MB_LIB.T6G(SCH_1):M_D_CPU1_SA_DQS_DP(8)
 189 M_D_CPU1_SA_DQS_DN<8> DQS8_A_C||TDQS8_A_C @T6G_MB_LIB.T6G(SCH_1):M_D_CPU1_SA_DQS_DN(8)
 271 M_D_CPU1_SB_DQS_DN<7> DQS7_B_C||TDQS7_B_C @T6G_MB_LIB.T6G(SCH_1):M_D_CPU1_SB_DQS_DN(7)
 179 M_D_CPU1_SA_DQS_DP<7> DQS7_A_T||TDQS7_A_T @T6G_MB_LIB.T6G(SCH_1):M_D_CPU1_SA_DQS_DP(7)
 261 M_D_CPU1_SB_DQS_DP<6> DQS6_B_T||TDQS6_B_T @T6G_MB_LIB.T6G(SCH_1):M_D_CPU1_SB_DQS_DP(6)
 260 M_D_CPU1_SB_DQS_DN<6> DQS6_B_C||TDQS6_B_C @T6G_MB_LIB.T6G(SCH_1):M_D_CPU1_SB_DQS_DN(6)
 167 M_D_CPU1_SA_DQS_DN<6> DQS6_A_C||TDQS6_A_C||DQS6_A_T||TDQS6_A_T @T6G_MB_LIB.T6G(SCH_1):M_D_CPU1_SA_DQS_DN(6)
 250 M_D_CPU1_SB_DQS_DP<5> DQS5_B_T||TDQS5_B_T @T6G_MB_LIB.T6G(SCH_1):M_D_CPU1_SB_DQS_DP(5)
 249 M_D_CPU1_SB_DQS_DN<5> DQS5_B_C||TDQS5_B_C @T6G_MB_LIB.T6G(SCH_1):M_D_CPU1_SB_DQS_DN(5)
 157 M_D_CPU1_SA_DQS_DP<5> DQS5_A_T||TDQS5_A_T @T6G_MB_LIB.T6G(SCH_1):M_D_CPU1_SA_DQS_DP(5)
 156 M_D_CPU1_SA_DQS_DN<5> DQS5_A_C||TDQS5_A_C||DQS5_A_T||TDQS5_A_T @T6G_MB_LIB.T6G(SCH_1):M_D_CPU1_SA_DQS_DN(5)
 239 M_D_CPU1_SB_DQS_DP<4> DQS4_B_T @T6G_MB_LIB.T6G(SCH_1):M_D_CPU1_SB_DQS_DP(4)
 238 M_D_CPU1_SB_DQS_DN<4> DQS4_B_C @T6G_MB_LIB.T6G(SCH_1):M_D_CPU1_SB_DQS_DN(4)
  55 M_D_CPU1_SA_DQS_DP<4> DQS4_A_T @T6G_MB_LIB.T6G(SCH_1):M_D_CPU1_SA_DQS_DP(4)
  56 M_D_CPU1_SA_DQS_DN<4> DQS4_A_C @T6G_MB_LIB.T6G(SCH_1):M_D_CPU1_SA_DQS_DN(4)
 137 M_D_CPU1_SB_DQS_DP<3> DQS3_B_T @T6G_MB_LIB.T6G(SCH_1):M_D_CPU1_SB_DQS_DP(3)
 138 M_D_CPU1_SB_DQS_DN<3> DQS3_B_C @T6G_MB_LIB.T6G(SCH_1):M_D_CPU1_SB_DQS_DN(3)
  44 M_D_CPU1_SA_DQS_DP<3> DQS3_A_T @T6G_MB_LIB.T6G(SCH_1):M_D_CPU1_SA_DQS_DP(3)
  45 M_D_CPU1_SA_DQS_DN<3> DQS3_A_C @T6G_MB_LIB.T6G(SCH_1):M_D_CPU1_SA_DQS_DN(3)
 126 M_D_CPU1_SB_DQS_DP<2> DQS2_B_T @T6G_MB_LIB.T6G(SCH_1):M_D_CPU1_SB_DQS_DP(2)
 127 M_D_CPU1_SB_DQS_DN<2> DQS2_B_C @T6G_MB_LIB.T6G(SCH_1):M_D_CPU1_SB_DQS_DN(2)
  33 M_D_CPU1_SA_DQS_DP<2> DQS2_A_T @T6G_MB_LIB.T6G(SCH_1):M_D_CPU1_SA_DQS_DP(2)
  34 M_D_CPU1_SA_DQS_DN<2> DQS2_A_C @T6G_MB_LIB.T6G(SCH_1):M_D_CPU1_SA_DQS_DN(2)
 115 M_D_CPU1_SB_DQS_DP<1> DQS1_B_T @T6G_MB_LIB.T6G(SCH_1):M_D_CPU1_SB_DQS_DP(1)
 116 M_D_CPU1_SB_DQS_DN<1> DQS1_B_C @T6G_MB_LIB.T6G(SCH_1):M_D_CPU1_SB_DQS_DN(1)
  22 M_D_CPU1_SA_DQS_DP<1> DQS1_A_T @T6G_MB_LIB.T6G(SCH_1):M_D_CPU1_SA_DQS_DP(1)
  23 M_D_CPU1_SA_DQS_DN<1> DQS1_A_C @T6G_MB_LIB.T6G(SCH_1):M_D_CPU1_SA_DQS_DN(1)
 104 M_D_CPU1_SB_DQS_DP<0> DQS0_B_T @T6G_MB_LIB.T6G(SCH_1):M_D_CPU1_SB_DQS_DP(0)
 105 M_D_CPU1_SB_DQS_DN<0> DQS0_B_C @T6G_MB_LIB.T6G(SCH_1):M_D_CPU1_SB_DQS_DN(0)
  11 M_D_CPU1_SA_DQS_DP<0> DQS0_A_T @T6G_MB_LIB.T6G(SCH_1):M_D_CPU1_SA_DQS_DP(0)
  12 M_D_CPU1_SA_DQS_DN<0> DQS0_A_C @T6G_MB_LIB.T6G(SCH_1):M_D_CPU1_SA_DQS_DN(0)
 272 M_D_CPU1_SB_DQS_DP<7> DQS7_B_T||TDQS7_B_T @T6G_MB_LIB.T6G(SCH_1):M_D_CPU1_SB_DQS_DP(7)
 282 M_D_CPU1_SB_DQS_DN<8> DQS8_B_C||TDQS8_B_C @T6G_MB_LIB.T6G(SCH_1):M_D_CPU1_SB_DQS_DN(8)
 283 M_D_CPU1_SB_DQS_DP<8> DQS8_B_T||TDQS8_B_T @T6G_MB_LIB.T6G(SCH_1):M_D_CPU1_SB_DQS_DP(8)
 168 M_D_CPU1_SA_DQS_DP<6> DQS6_A_T||TDQS6_A_T @T6G_MB_LIB.T6G(SCH_1):M_D_CPU1_SA_DQS_DP(6)
 178 M_D_CPU1_SA_DQS_DN<7> DQS7_A_C||TDQS7_A_C @T6G_MB_LIB.T6G(SCH_1):M_D_CPU1_SA_DQS_DN(7)

Q_CAP_C0805-10UF,25V,10%,X6S,CH6104KEA00  I238  C181
   1 P12V_MEM_CPU1      A @T6G_MB_LIB.T6G(SCH_1):P12V_MEM_CPU1
   2    GND      B @T6G_MB_LIB.T6G(SCH_1):GND

Q_CAP_C0805-10UF,25V,10%,X6S,CH6104KEA00  I239  C182
   1 P12V_MEM_CPU1      A @T6G_MB_LIB.T6G(SCH_1):P12V_MEM_CPU1
   2    GND      B @T6G_MB_LIB.T6G(SCH_1):GND

Q_RES_0402LF-49.9,1%,1/16W,CHIP,CS04992FB07  I242  R1583
   1 I3C_SPD_DDRAF_CPU1_SCL      A @T6G_MB_LIB.T6G(SCH_1):I3C_SPD_DDRAF_CPU1_SCL
   2 I3C_SPD_DDRD_CPU1_SCL      B @T6G_MB_LIB.T6G(SCH_1):I3C_SPD_DDRD_CPU1_SCL

Q_RES_0402LF-10,1%,1/16W,CHIP,CS01002FB07  I243  R1699
   1 I3C_SPD_DDRAF_CPU1_SDA      A @T6G_MB_LIB.T6G(SCH_1):I3C_SPD_DDRAF_CPU1_SDA
   2 I3C_SPD_DDRD_CPU1_SDA      B @T6G_MB_LIB.T6G(SCH_1):I3C_SPD_DDRD_CPU1_SDA


DRAWING: @T6G_MB_LIB.T6G(SCH_1):PAGE101 

SCONN288_DDR506112002KQ-SCONN288_DDR506112002KQ,SMA  I52  J32
   3 P3V3_AUX VIN_MGMT @T6G_MB_LIB.T6G(SCH_1):P3V3_AUX
   2     NC   RFU0     NC
 144     NC   RFU1     NC
 149     NC   RFU2     NC
 150     NC   RFU3     NC
 220     NC   RFU4     NC
 231     NC   RFU5     NC
 232     NC   RFU6     NC
 207 M_E_CPU1_RESET_N RESET_N @T6G_MB_LIB.T6G(SCH_1):M_E_CPU1_RESET_N
 147 PWRGD_CHE_CPU1_DIMM PWR_GOOD||FAIL_N @T6G_MB_LIB.T6G(SCH_1):PWRGD_CHE_CPU1_DIMM
 227 M_E_CPU1_SB_PAR  PAR_B @T6G_MB_LIB.T6G(SCH_1):M_E_CPU1_SB_PAR
  74 M_E_CPU1_SA_PAR  PAR_A @T6G_MB_LIB.T6G(SCH_1):M_E_CPU1_SA_PAR
  87 M_E_CPU1_SB_RSP<0> LBS||RSP_B_N @T6G_MB_LIB.T6G(SCH_1):M_E_CPU1_SB_RSP(0)
  86 M_E_CPU1_SA_RSP<0> LBD||RSP_A_N @T6G_MB_LIB.T6G(SCH_1):M_E_CPU1_SA_RSP(0)
   5 I3C_SPD_DDRE_CPU1_SDA   HSDA @T6G_MB_LIB.T6G(SCH_1):I3C_SPD_DDRE_CPU1_SDA
   4 I3C_SPD_DDRE_CPU1_SCL   HSCL @T6G_MB_LIB.T6G(SCH_1):I3C_SPD_DDRE_CPU1_SCL
 148 PD_CHE_CPU1_DIMM_SAA    HAS @T6G_MB_LIB.T6G(SCH_1):PD_CHE_CPU1_DIMM_SAA
 100 M_E_CPU1_SB_DQ<0>  DQ0_B @T6G_MB_LIB.T6G(SCH_1):M_E_CPU1_SB_DQ(0)
 102 M_E_CPU1_SB_DQ<1>  DQ1_B @T6G_MB_LIB.T6G(SCH_1):M_E_CPU1_SB_DQ(1)
 245 M_E_CPU1_SB_DQ<2>  DQ2_B @T6G_MB_LIB.T6G(SCH_1):M_E_CPU1_SB_DQ(2)
 247 M_E_CPU1_SB_DQ<3>  DQ3_B @T6G_MB_LIB.T6G(SCH_1):M_E_CPU1_SB_DQ(3)
 107 M_E_CPU1_SB_DQ<4>  DQ4_B @T6G_MB_LIB.T6G(SCH_1):M_E_CPU1_SB_DQ(4)
 109 M_E_CPU1_SB_DQ<5>  DQ5_B @T6G_MB_LIB.T6G(SCH_1):M_E_CPU1_SB_DQ(5)
 252 M_E_CPU1_SB_DQ<6>  DQ6_B @T6G_MB_LIB.T6G(SCH_1):M_E_CPU1_SB_DQ(6)
 254 M_E_CPU1_SB_DQ<7>  DQ7_B @T6G_MB_LIB.T6G(SCH_1):M_E_CPU1_SB_DQ(7)
 111 M_E_CPU1_SB_DQ<8>  DQ8_B @T6G_MB_LIB.T6G(SCH_1):M_E_CPU1_SB_DQ(8)
 113 M_E_CPU1_SB_DQ<9>  DQ9_B @T6G_MB_LIB.T6G(SCH_1):M_E_CPU1_SB_DQ(9)
 256 M_E_CPU1_SB_DQ<10> DQ10_B @T6G_MB_LIB.T6G(SCH_1):M_E_CPU1_SB_DQ(10)
 258 M_E_CPU1_SB_DQ<11> DQ11_B @T6G_MB_LIB.T6G(SCH_1):M_E_CPU1_SB_DQ(11)
 118 M_E_CPU1_SB_DQ<12> DQ12_B @T6G_MB_LIB.T6G(SCH_1):M_E_CPU1_SB_DQ(12)
 120 M_E_CPU1_SB_DQ<13> DQ13_B @T6G_MB_LIB.T6G(SCH_1):M_E_CPU1_SB_DQ(13)
 263 M_E_CPU1_SB_DQ<14> DQ14_B @T6G_MB_LIB.T6G(SCH_1):M_E_CPU1_SB_DQ(14)
 265 M_E_CPU1_SB_DQ<15> DQ15_B @T6G_MB_LIB.T6G(SCH_1):M_E_CPU1_SB_DQ(15)
 122 M_E_CPU1_SB_DQ<16> DQ16_B @T6G_MB_LIB.T6G(SCH_1):M_E_CPU1_SB_DQ(16)
 124 M_E_CPU1_SB_DQ<17> DQ17_B @T6G_MB_LIB.T6G(SCH_1):M_E_CPU1_SB_DQ(17)
 267 M_E_CPU1_SB_DQ<18> DQ18_B @T6G_MB_LIB.T6G(SCH_1):M_E_CPU1_SB_DQ(18)
 269 M_E_CPU1_SB_DQ<19> DQ19_B @T6G_MB_LIB.T6G(SCH_1):M_E_CPU1_SB_DQ(19)
 129 M_E_CPU1_SB_DQ<20> DQ20_B @T6G_MB_LIB.T6G(SCH_1):M_E_CPU1_SB_DQ(20)
 131 M_E_CPU1_SB_DQ<21> DQ21_B @T6G_MB_LIB.T6G(SCH_1):M_E_CPU1_SB_DQ(21)
 274 M_E_CPU1_SB_DQ<22> DQ22_B @T6G_MB_LIB.T6G(SCH_1):M_E_CPU1_SB_DQ(22)
 276 M_E_CPU1_SB_DQ<23> DQ23_B @T6G_MB_LIB.T6G(SCH_1):M_E_CPU1_SB_DQ(23)
 133 M_E_CPU1_SB_DQ<24> DQ24_B @T6G_MB_LIB.T6G(SCH_1):M_E_CPU1_SB_DQ(24)
 135 M_E_CPU1_SB_DQ<25> DQ25_B @T6G_MB_LIB.T6G(SCH_1):M_E_CPU1_SB_DQ(25)
 278 M_E_CPU1_SB_DQ<26> DQ26_B @T6G_MB_LIB.T6G(SCH_1):M_E_CPU1_SB_DQ(26)
 280 M_E_CPU1_SB_DQ<27> DQ27_B @T6G_MB_LIB.T6G(SCH_1):M_E_CPU1_SB_DQ(27)
 140 M_E_CPU1_SB_DQ<28> DQ28_B @T6G_MB_LIB.T6G(SCH_1):M_E_CPU1_SB_DQ(28)
 142 M_E_CPU1_SB_DQ<29> DQ29_B @T6G_MB_LIB.T6G(SCH_1):M_E_CPU1_SB_DQ(29)
 285 M_E_CPU1_SB_DQ<30> DQ30_B @T6G_MB_LIB.T6G(SCH_1):M_E_CPU1_SB_DQ(30)
 287 M_E_CPU1_SB_DQ<31> DQ31_B @T6G_MB_LIB.T6G(SCH_1):M_E_CPU1_SB_DQ(31)
   7 M_E_CPU1_SA_DQ<0>  DQ0_A @T6G_MB_LIB.T6G(SCH_1):M_E_CPU1_SA_DQ(0)
   9 M_E_CPU1_SA_DQ<1>  DQ1_A @T6G_MB_LIB.T6G(SCH_1):M_E_CPU1_SA_DQ(1)
 152 M_E_CPU1_SA_DQ<2>  DQ2_A @T6G_MB_LIB.T6G(SCH_1):M_E_CPU1_SA_DQ(2)
 154 M_E_CPU1_SA_DQ<3>  DQ3_A @T6G_MB_LIB.T6G(SCH_1):M_E_CPU1_SA_DQ(3)
  14 M_E_CPU1_SA_DQ<4>  DQ4_A @T6G_MB_LIB.T6G(SCH_1):M_E_CPU1_SA_DQ(4)
  16 M_E_CPU1_SA_DQ<5>  DQ5_A @T6G_MB_LIB.T6G(SCH_1):M_E_CPU1_SA_DQ(5)
 159 M_E_CPU1_SA_DQ<6>  DQ6_A @T6G_MB_LIB.T6G(SCH_1):M_E_CPU1_SA_DQ(6)
 161 M_E_CPU1_SA_DQ<7>  DQ7_A @T6G_MB_LIB.T6G(SCH_1):M_E_CPU1_SA_DQ(7)
  18 M_E_CPU1_SA_DQ<8>  DQ8_A @T6G_MB_LIB.T6G(SCH_1):M_E_CPU1_SA_DQ(8)
  20 M_E_CPU1_SA_DQ<9>  DQ9_A @T6G_MB_LIB.T6G(SCH_1):M_E_CPU1_SA_DQ(9)
 163 M_E_CPU1_SA_DQ<10> DQ10_A @T6G_MB_LIB.T6G(SCH_1):M_E_CPU1_SA_DQ(10)
 165 M_E_CPU1_SA_DQ<11> DQ11_A @T6G_MB_LIB.T6G(SCH_1):M_E_CPU1_SA_DQ(11)
  25 M_E_CPU1_SA_DQ<12> DQ12_A @T6G_MB_LIB.T6G(SCH_1):M_E_CPU1_SA_DQ(12)
  27 M_E_CPU1_SA_DQ<13> DQ13_A @T6G_MB_LIB.T6G(SCH_1):M_E_CPU1_SA_DQ(13)
 170 M_E_CPU1_SA_DQ<14> DQ14_A @T6G_MB_LIB.T6G(SCH_1):M_E_CPU1_SA_DQ(14)
 172 M_E_CPU1_SA_DQ<15> DQ15_A @T6G_MB_LIB.T6G(SCH_1):M_E_CPU1_SA_DQ(15)
  29 M_E_CPU1_SA_DQ<16> DQ16_A @T6G_MB_LIB.T6G(SCH_1):M_E_CPU1_SA_DQ(16)
  31 M_E_CPU1_SA_DQ<17> DQ17_A @T6G_MB_LIB.T6G(SCH_1):M_E_CPU1_SA_DQ(17)
 174 M_E_CPU1_SA_DQ<18> DQ18_A @T6G_MB_LIB.T6G(SCH_1):M_E_CPU1_SA_DQ(18)
 176 M_E_CPU1_SA_DQ<19> DQ19_A @T6G_MB_LIB.T6G(SCH_1):M_E_CPU1_SA_DQ(19)
  36 M_E_CPU1_SA_DQ<20> DQ20_A @T6G_MB_LIB.T6G(SCH_1):M_E_CPU1_SA_DQ(20)
  38 M_E_CPU1_SA_DQ<21> DQ21_A @T6G_MB_LIB.T6G(SCH_1):M_E_CPU1_SA_DQ(21)
 181 M_E_CPU1_SA_DQ<22> DQ22_A @T6G_MB_LIB.T6G(SCH_1):M_E_CPU1_SA_DQ(22)
 183 M_E_CPU1_SA_DQ<23> DQ23_A @T6G_MB_LIB.T6G(SCH_1):M_E_CPU1_SA_DQ(23)
  40 M_E_CPU1_SA_DQ<24> DQ24_A @T6G_MB_LIB.T6G(SCH_1):M_E_CPU1_SA_DQ(24)
  42 M_E_CPU1_SA_DQ<25> DQ25_A @T6G_MB_LIB.T6G(SCH_1):M_E_CPU1_SA_DQ(25)
 185 M_E_CPU1_SA_DQ<26> DQ26_A @T6G_MB_LIB.T6G(SCH_1):M_E_CPU1_SA_DQ(26)
 187 M_E_CPU1_SA_DQ<27> DQ27_A @T6G_MB_LIB.T6G(SCH_1):M_E_CPU1_SA_DQ(27)
  47 M_E_CPU1_SA_DQ<28> DQ28_A @T6G_MB_LIB.T6G(SCH_1):M_E_CPU1_SA_DQ(28)
  49 M_E_CPU1_SA_DQ<29> DQ29_A @T6G_MB_LIB.T6G(SCH_1):M_E_CPU1_SA_DQ(29)
 192 M_E_CPU1_SA_DQ<30> DQ30_A @T6G_MB_LIB.T6G(SCH_1):M_E_CPU1_SA_DQ(30)
 229 M_E_CPU1_SB_CS_N<1> CS1_B_N @T6G_MB_LIB.T6G(SCH_1):M_E_CPU1_SB_CS_N(1)
 209 M_E_CPU1_SA_CS_N<1> CS1_A_N @T6G_MB_LIB.T6G(SCH_1):M_E_CPU1_SA_CS_N(1)
  84 M_E_CPU1_SB_CS_N<0> CS0_B_N @T6G_MB_LIB.T6G(SCH_1):M_E_CPU1_SB_CS_N(0)
  64 M_E_CPU1_SA_CS_N<0> CS0_A_N @T6G_MB_LIB.T6G(SCH_1):M_E_CPU1_SA_CS_N(0)
 217 M_E_CPU1_CLK_DP<0>   CK_T @T6G_MB_LIB.T6G(SCH_1):M_E_CPU1_CLK_DP(0)
 218 M_E_CPU1_CLK_DN<0>   CK_C @T6G_MB_LIB.T6G(SCH_1):M_E_CPU1_CLK_DN(0)
  96 M_E_CPU1_SB_CB<0>  CB0_B @T6G_MB_LIB.T6G(SCH_1):M_E_CPU1_SB_CB(0)
  98 M_E_CPU1_SB_CB<1>  CB1_B @T6G_MB_LIB.T6G(SCH_1):M_E_CPU1_SB_CB(1)
 241 M_E_CPU1_SB_CB<2>  CB2_B @T6G_MB_LIB.T6G(SCH_1):M_E_CPU1_SB_CB(2)
 243 M_E_CPU1_SB_CB<3>  CB3_B @T6G_MB_LIB.T6G(SCH_1):M_E_CPU1_SB_CB(3)
  89 M_E_CPU1_SB_CB<4>  CB4_B @T6G_MB_LIB.T6G(SCH_1):M_E_CPU1_SB_CB(4)
  91 M_E_CPU1_SB_CB<5>  CB5_B @T6G_MB_LIB.T6G(SCH_1):M_E_CPU1_SB_CB(5)
 234 M_E_CPU1_SB_CB<6>  CB6_B @T6G_MB_LIB.T6G(SCH_1):M_E_CPU1_SB_CB(6)
  51 M_E_CPU1_SA_CB<0>  CB0_A @T6G_MB_LIB.T6G(SCH_1):M_E_CPU1_SA_CB(0)
 196 M_E_CPU1_SA_CB<2>  CB2_A @T6G_MB_LIB.T6G(SCH_1):M_E_CPU1_SA_CB(2)
 198 M_E_CPU1_SA_CB<3>  CB3_A @T6G_MB_LIB.T6G(SCH_1):M_E_CPU1_SA_CB(3)
  60 M_E_CPU1_SA_CB<5>  CB5_A @T6G_MB_LIB.T6G(SCH_1):M_E_CPU1_SA_CB(5)
 203 M_E_CPU1_SA_CB<6>  CB6_A @T6G_MB_LIB.T6G(SCH_1):M_E_CPU1_SA_CB(6)
  82 M_E_CPU1_SB_CA<6>  CA6_B @T6G_MB_LIB.T6G(SCH_1):M_E_CPU1_SB_CA(6)
  72 M_E_CPU1_SA_CA<6>  CA6_A @T6G_MB_LIB.T6G(SCH_1):M_E_CPU1_SA_CA(6)
 225 M_E_CPU1_SB_CA<5>  CA5_B @T6G_MB_LIB.T6G(SCH_1):M_E_CPU1_SB_CA(5)
 215 M_E_CPU1_SA_CA<5>  CA5_A @T6G_MB_LIB.T6G(SCH_1):M_E_CPU1_SA_CA(5)
  80 M_E_CPU1_SB_CA<4>  CA4_B @T6G_MB_LIB.T6G(SCH_1):M_E_CPU1_SB_CA(4)
  70 M_E_CPU1_SA_CA<4>  CA4_A @T6G_MB_LIB.T6G(SCH_1):M_E_CPU1_SA_CA(4)
 223 M_E_CPU1_SB_CA<3>  CA3_B @T6G_MB_LIB.T6G(SCH_1):M_E_CPU1_SB_CA(3)
 213 M_E_CPU1_SA_CA<3>  CA3_A @T6G_MB_LIB.T6G(SCH_1):M_E_CPU1_SA_CA(3)
  78 M_E_CPU1_SB_CA<2>  CA2_B @T6G_MB_LIB.T6G(SCH_1):M_E_CPU1_SB_CA(2)
  68 M_E_CPU1_SA_CA<2>  CA2_A @T6G_MB_LIB.T6G(SCH_1):M_E_CPU1_SA_CA(2)
 221 M_E_CPU1_SB_CA<1>  CA1_B @T6G_MB_LIB.T6G(SCH_1):M_E_CPU1_SB_CA(1)
 211 M_E_CPU1_SA_CA<1>  CA1_A @T6G_MB_LIB.T6G(SCH_1):M_E_CPU1_SA_CA(1)
  76 M_E_CPU1_SB_CA<0>  CA0_B @T6G_MB_LIB.T6G(SCH_1):M_E_CPU1_SB_CA(0)
  66 M_E_CPU1_SA_CA<0>  CA0_A @T6G_MB_LIB.T6G(SCH_1):M_E_CPU1_SA_CA(0)
  62 M_E_CPU1_ALERT_N ALERT_N @T6G_MB_LIB.T6G(SCH_1):M_E_CPU1_ALERT_N
 236 M_E_CPU1_SB_CB<7>  CB7_B @T6G_MB_LIB.T6G(SCH_1):M_E_CPU1_SB_CB(7)
  53 M_E_CPU1_SA_CB<1>  CB1_A @T6G_MB_LIB.T6G(SCH_1):M_E_CPU1_SA_CB(1)
  58 M_E_CPU1_SA_CB<4>  CB4_A @T6G_MB_LIB.T6G(SCH_1):M_E_CPU1_SA_CB(4)
 205 M_E_CPU1_SA_CB<7>  CB7_A @T6G_MB_LIB.T6G(SCH_1):M_E_CPU1_SA_CB(7)
 194 M_E_CPU1_SA_DQ<31> DQ31_A @T6G_MB_LIB.T6G(SCH_1):M_E_CPU1_SA_DQ(31)

Q_RES_0402LF-54.9K,1%,1/16W,CHIP,CS35492FB03  I127  R6
   1 PD_CHE_CPU1_DIMM_SAA      A @T6G_MB_LIB.T6G(SCH_1):PD_CHE_CPU1_DIMM_SAA
   2    GND      B @T6G_MB_LIB.T6G(SCH_1):GND

SCONN288_DDR506112002KQ-SCONN288_DDR506112002KQ,SMA  I175  J32
   6    GND   VSS0 @T6G_MB_LIB.T6G(SCH_1):GND
   8    GND   VSS1 @T6G_MB_LIB.T6G(SCH_1):GND
  10    GND   VSS2 @T6G_MB_LIB.T6G(SCH_1):GND
  13    GND   VSS3 @T6G_MB_LIB.T6G(SCH_1):GND
  15    GND   VSS4 @T6G_MB_LIB.T6G(SCH_1):GND
  17    GND   VSS5 @T6G_MB_LIB.T6G(SCH_1):GND
  19    GND   VSS6 @T6G_MB_LIB.T6G(SCH_1):GND
  21    GND   VSS7 @T6G_MB_LIB.T6G(SCH_1):GND
  24    GND   VSS8 @T6G_MB_LIB.T6G(SCH_1):GND
  26    GND   VSS9 @T6G_MB_LIB.T6G(SCH_1):GND
  28    GND  VSS10 @T6G_MB_LIB.T6G(SCH_1):GND
  30    GND  VSS11 @T6G_MB_LIB.T6G(SCH_1):GND
  32    GND  VSS12 @T6G_MB_LIB.T6G(SCH_1):GND
  35    GND  VSS13 @T6G_MB_LIB.T6G(SCH_1):GND
  37    GND  VSS14 @T6G_MB_LIB.T6G(SCH_1):GND
  39    GND  VSS15 @T6G_MB_LIB.T6G(SCH_1):GND
  41    GND  VSS16 @T6G_MB_LIB.T6G(SCH_1):GND
  43    GND  VSS17 @T6G_MB_LIB.T6G(SCH_1):GND
  46    GND  VSS18 @T6G_MB_LIB.T6G(SCH_1):GND
  48    GND  VSS19 @T6G_MB_LIB.T6G(SCH_1):GND
  50    GND  VSS20 @T6G_MB_LIB.T6G(SCH_1):GND
  52    GND  VSS21 @T6G_MB_LIB.T6G(SCH_1):GND
  54    GND  VSS22 @T6G_MB_LIB.T6G(SCH_1):GND
  57    GND  VSS23 @T6G_MB_LIB.T6G(SCH_1):GND
  59    GND  VSS24 @T6G_MB_LIB.T6G(SCH_1):GND
  61    GND  VSS25 @T6G_MB_LIB.T6G(SCH_1):GND
  63    GND  VSS26 @T6G_MB_LIB.T6G(SCH_1):GND
  65    GND  VSS27 @T6G_MB_LIB.T6G(SCH_1):GND
  67    GND  VSS28 @T6G_MB_LIB.T6G(SCH_1):GND
  69    GND  VSS29 @T6G_MB_LIB.T6G(SCH_1):GND
  71    GND  VSS30 @T6G_MB_LIB.T6G(SCH_1):GND
  73    GND  VSS31 @T6G_MB_LIB.T6G(SCH_1):GND
  75    GND  VSS32 @T6G_MB_LIB.T6G(SCH_1):GND
  77    GND  VSS33 @T6G_MB_LIB.T6G(SCH_1):GND
  79    GND  VSS34 @T6G_MB_LIB.T6G(SCH_1):GND
  81    GND  VSS35 @T6G_MB_LIB.T6G(SCH_1):GND
  83    GND  VSS36 @T6G_MB_LIB.T6G(SCH_1):GND
  85    GND  VSS37 @T6G_MB_LIB.T6G(SCH_1):GND
  88    GND  VSS38 @T6G_MB_LIB.T6G(SCH_1):GND
  90    GND  VSS39 @T6G_MB_LIB.T6G(SCH_1):GND
  92    GND  VSS40 @T6G_MB_LIB.T6G(SCH_1):GND
  95    GND  VSS41 @T6G_MB_LIB.T6G(SCH_1):GND
  97    GND  VSS42 @T6G_MB_LIB.T6G(SCH_1):GND
  99    GND  VSS43 @T6G_MB_LIB.T6G(SCH_1):GND
 101    GND  VSS44 @T6G_MB_LIB.T6G(SCH_1):GND
 103    GND  VSS45 @T6G_MB_LIB.T6G(SCH_1):GND
 106    GND  VSS46 @T6G_MB_LIB.T6G(SCH_1):GND
 108    GND  VSS47 @T6G_MB_LIB.T6G(SCH_1):GND
 110    GND  VSS48 @T6G_MB_LIB.T6G(SCH_1):GND
 112    GND  VSS49 @T6G_MB_LIB.T6G(SCH_1):GND
 114    GND  VSS50 @T6G_MB_LIB.T6G(SCH_1):GND
 117    GND  VSS51 @T6G_MB_LIB.T6G(SCH_1):GND
 119    GND  VSS52 @T6G_MB_LIB.T6G(SCH_1):GND
 121    GND  VSS53 @T6G_MB_LIB.T6G(SCH_1):GND
 123    GND  VSS54 @T6G_MB_LIB.T6G(SCH_1):GND
 125    GND  VSS55 @T6G_MB_LIB.T6G(SCH_1):GND
 128    GND  VSS56 @T6G_MB_LIB.T6G(SCH_1):GND
 130    GND  VSS57 @T6G_MB_LIB.T6G(SCH_1):GND
 134    GND  VSS59 @T6G_MB_LIB.T6G(SCH_1):GND
 143    GND  VSS63 @T6G_MB_LIB.T6G(SCH_1):GND
 151    GND  VSS64 @T6G_MB_LIB.T6G(SCH_1):GND
 153    GND  VSS65 @T6G_MB_LIB.T6G(SCH_1):GND
 155    GND  VSS66 @T6G_MB_LIB.T6G(SCH_1):GND
 158    GND  VSS67 @T6G_MB_LIB.T6G(SCH_1):GND
 160    GND  VSS68 @T6G_MB_LIB.T6G(SCH_1):GND
 162    GND  VSS69 @T6G_MB_LIB.T6G(SCH_1):GND
 164    GND  VSS70 @T6G_MB_LIB.T6G(SCH_1):GND
 166    GND  VSS71 @T6G_MB_LIB.T6G(SCH_1):GND
 169    GND  VSS72 @T6G_MB_LIB.T6G(SCH_1):GND
 171    GND  VSS73 @T6G_MB_LIB.T6G(SCH_1):GND
 173    GND  VSS74 @T6G_MB_LIB.T6G(SCH_1):GND
 175    GND  VSS75 @T6G_MB_LIB.T6G(SCH_1):GND
 177    GND  VSS76 @T6G_MB_LIB.T6G(SCH_1):GND
 180    GND  VSS77 @T6G_MB_LIB.T6G(SCH_1):GND
 182    GND  VSS78 @T6G_MB_LIB.T6G(SCH_1):GND
 184    GND  VSS79 @T6G_MB_LIB.T6G(SCH_1):GND
 186    GND  VSS80 @T6G_MB_LIB.T6G(SCH_1):GND
 188    GND  VSS81 @T6G_MB_LIB.T6G(SCH_1):GND
 191    GND  VSS82 @T6G_MB_LIB.T6G(SCH_1):GND
 193    GND  VSS83 @T6G_MB_LIB.T6G(SCH_1):GND
 195    GND  VSS84 @T6G_MB_LIB.T6G(SCH_1):GND
 197    GND  VSS85 @T6G_MB_LIB.T6G(SCH_1):GND
 199    GND  VSS86 @T6G_MB_LIB.T6G(SCH_1):GND
 202    GND  VSS87 @T6G_MB_LIB.T6G(SCH_1):GND
 204    GND  VSS88 @T6G_MB_LIB.T6G(SCH_1):GND
 206    GND  VSS89 @T6G_MB_LIB.T6G(SCH_1):GND
 208    GND  VSS90 @T6G_MB_LIB.T6G(SCH_1):GND
 210    GND  VSS91 @T6G_MB_LIB.T6G(SCH_1):GND
 212    GND  VSS92 @T6G_MB_LIB.T6G(SCH_1):GND
 214    GND  VSS93 @T6G_MB_LIB.T6G(SCH_1):GND
 216    GND  VSS94 @T6G_MB_LIB.T6G(SCH_1):GND
 219    GND  VSS95 @T6G_MB_LIB.T6G(SCH_1):GND
 222    GND  VSS96 @T6G_MB_LIB.T6G(SCH_1):GND
 224    GND  VSS97 @T6G_MB_LIB.T6G(SCH_1):GND
 226    GND  VSS98 @T6G_MB_LIB.T6G(SCH_1):GND
 228    GND  VSS99 @T6G_MB_LIB.T6G(SCH_1):GND
 233    GND VSS101 @T6G_MB_LIB.T6G(SCH_1):GND
 237    GND VSS103 @T6G_MB_LIB.T6G(SCH_1):GND
 242    GND VSS105 @T6G_MB_LIB.T6G(SCH_1):GND
 244    GND VSS106 @T6G_MB_LIB.T6G(SCH_1):GND
 246    GND VSS107 @T6G_MB_LIB.T6G(SCH_1):GND
 248    GND VSS108 @T6G_MB_LIB.T6G(SCH_1):GND
 251    GND VSS109 @T6G_MB_LIB.T6G(SCH_1):GND
 253    GND VSS110 @T6G_MB_LIB.T6G(SCH_1):GND
 255    GND VSS111 @T6G_MB_LIB.T6G(SCH_1):GND
 257    GND VSS112 @T6G_MB_LIB.T6G(SCH_1):GND
 259    GND VSS113 @T6G_MB_LIB.T6G(SCH_1):GND
 262    GND VSS114 @T6G_MB_LIB.T6G(SCH_1):GND
 264    GND VSS115 @T6G_MB_LIB.T6G(SCH_1):GND
 266    GND VSS116 @T6G_MB_LIB.T6G(SCH_1):GND
 268    GND VSS117 @T6G_MB_LIB.T6G(SCH_1):GND
 270    GND VSS118 @T6G_MB_LIB.T6G(SCH_1):GND
 273    GND VSS119 @T6G_MB_LIB.T6G(SCH_1):GND
 275    GND VSS120 @T6G_MB_LIB.T6G(SCH_1):GND
 277    GND VSS121 @T6G_MB_LIB.T6G(SCH_1):GND
 279    GND VSS122 @T6G_MB_LIB.T6G(SCH_1):GND
 281    GND VSS123 @T6G_MB_LIB.T6G(SCH_1):GND
 284    GND VSS124 @T6G_MB_LIB.T6G(SCH_1):GND
 286    GND VSS125 @T6G_MB_LIB.T6G(SCH_1):GND
 288    GND VSS126 @T6G_MB_LIB.T6G(SCH_1):GND
   1 P12V_MEM_CPU1 VIN_BULK0 @T6G_MB_LIB.T6G(SCH_1):P12V_MEM_CPU1
 145 P12V_MEM_CPU1 VIN_BULK1 @T6G_MB_LIB.T6G(SCH_1):P12V_MEM_CPU1
 146 P12V_MEM_CPU1 VIN_BULK2 @T6G_MB_LIB.T6G(SCH_1):P12V_MEM_CPU1
 230    GND VSS100 @T6G_MB_LIB.T6G(SCH_1):GND
 235    GND VSS102 @T6G_MB_LIB.T6G(SCH_1):GND
 240    GND VSS104 @T6G_MB_LIB.T6G(SCH_1):GND
 132    GND  VSS58 @T6G_MB_LIB.T6G(SCH_1):GND
 136    GND  VSS60 @T6G_MB_LIB.T6G(SCH_1):GND
 139    GND  VSS61 @T6G_MB_LIB.T6G(SCH_1):GND
 141    GND  VSS62 @T6G_MB_LIB.T6G(SCH_1):GND
  G1    GND     G1 @T6G_MB_LIB.T6G(SCH_1):GND
  G2    GND     G2 @T6G_MB_LIB.T6G(SCH_1):GND
  G3    GND     G3 @T6G_MB_LIB.T6G(SCH_1):GND

Q_CAP_0402-0.1UF,25V,10%,X7R,CH4104K1B00  I185  C152
   1 P3V3_AUX      A @T6G_MB_LIB.T6G(SCH_1):P3V3_AUX
   2    GND      B @T6G_MB_LIB.T6G(SCH_1):GND

Q_RES_0402LF-1K,1%,1/16W,CHIP,CS21002FB06  I188  R307
   1 PWRGD_CHE_CPU1_DIMM      A @T6G_MB_LIB.T6G(SCH_1):PWRGD_CHE_CPU1_DIMM
   2 PWRGD_CHAF_CPU1      B @T6G_MB_LIB.T6G(SCH_1):PWRGD_CHAF_CPU1

Q_RES_0402LF-1K,1%,1/16W,EMPTY,CS21002FB06  I190  R107
   1   P3V3      A @T6G_MB_LIB.T6G(SCH_1):P3V3
   2 PWRGD_CHE_CPU1_DIMM      B @T6G_MB_LIB.T6G(SCH_1):PWRGD_CHE_CPU1_DIMM

SCONN288_DDR506112002KQ-SCONN288_DDR506112002KQ,SMA  I236  J32
  93 M_E_CPU1_SB_DQS_DP<9> DQS9_B_T||TDQS9_B_T||DBI4_B_N @T6G_MB_LIB.T6G(SCH_1):M_E_CPU1_SB_DQS_DP(9)
  94 M_E_CPU1_SB_DQS_DN<9> DQS9_B_C||TDQS9_B_C @T6G_MB_LIB.T6G(SCH_1):M_E_CPU1_SB_DQS_DN(9)
 201 M_E_CPU1_SA_DQS_DP<9> DQS9_A_T||TDQS9_A_T @T6G_MB_LIB.T6G(SCH_1):M_E_CPU1_SA_DQS_DP(9)
 200 M_E_CPU1_SA_DQS_DN<9> DQS9_A_C||TDQS9_A_C @T6G_MB_LIB.T6G(SCH_1):M_E_CPU1_SA_DQS_DN(9)
 190 M_E_CPU1_SA_DQS_DP<8> DQS8_A_T||TDQS8_A_T @T6G_MB_LIB.T6G(SCH_1):M_E_CPU1_SA_DQS_DP(8)
 189 M_E_CPU1_SA_DQS_DN<8> DQS8_A_C||TDQS8_A_C @T6G_MB_LIB.T6G(SCH_1):M_E_CPU1_SA_DQS_DN(8)
 271 M_E_CPU1_SB_DQS_DN<7> DQS7_B_C||TDQS7_B_C @T6G_MB_LIB.T6G(SCH_1):M_E_CPU1_SB_DQS_DN(7)
 179 M_E_CPU1_SA_DQS_DP<7> DQS7_A_T||TDQS7_A_T @T6G_MB_LIB.T6G(SCH_1):M_E_CPU1_SA_DQS_DP(7)
 261 M_E_CPU1_SB_DQS_DP<6> DQS6_B_T||TDQS6_B_T @T6G_MB_LIB.T6G(SCH_1):M_E_CPU1_SB_DQS_DP(6)
 260 M_E_CPU1_SB_DQS_DN<6> DQS6_B_C||TDQS6_B_C @T6G_MB_LIB.T6G(SCH_1):M_E_CPU1_SB_DQS_DN(6)
 167 M_E_CPU1_SA_DQS_DN<6> DQS6_A_C||TDQS6_A_C||DQS6_A_T||TDQS6_A_T @T6G_MB_LIB.T6G(SCH_1):M_E_CPU1_SA_DQS_DN(6)
 250 M_E_CPU1_SB_DQS_DP<5> DQS5_B_T||TDQS5_B_T @T6G_MB_LIB.T6G(SCH_1):M_E_CPU1_SB_DQS_DP(5)
 249 M_E_CPU1_SB_DQS_DN<5> DQS5_B_C||TDQS5_B_C @T6G_MB_LIB.T6G(SCH_1):M_E_CPU1_SB_DQS_DN(5)
 157 M_E_CPU1_SA_DQS_DP<5> DQS5_A_T||TDQS5_A_T @T6G_MB_LIB.T6G(SCH_1):M_E_CPU1_SA_DQS_DP(5)
 156 M_E_CPU1_SA_DQS_DN<5> DQS5_A_C||TDQS5_A_C||DQS5_A_T||TDQS5_A_T @T6G_MB_LIB.T6G(SCH_1):M_E_CPU1_SA_DQS_DN(5)
 239 M_E_CPU1_SB_DQS_DP<4> DQS4_B_T @T6G_MB_LIB.T6G(SCH_1):M_E_CPU1_SB_DQS_DP(4)
 238 M_E_CPU1_SB_DQS_DN<4> DQS4_B_C @T6G_MB_LIB.T6G(SCH_1):M_E_CPU1_SB_DQS_DN(4)
  55 M_E_CPU1_SA_DQS_DP<4> DQS4_A_T @T6G_MB_LIB.T6G(SCH_1):M_E_CPU1_SA_DQS_DP(4)
  56 M_E_CPU1_SA_DQS_DN<4> DQS4_A_C @T6G_MB_LIB.T6G(SCH_1):M_E_CPU1_SA_DQS_DN(4)
 137 M_E_CPU1_SB_DQS_DP<3> DQS3_B_T @T6G_MB_LIB.T6G(SCH_1):M_E_CPU1_SB_DQS_DP(3)
 138 M_E_CPU1_SB_DQS_DN<3> DQS3_B_C @T6G_MB_LIB.T6G(SCH_1):M_E_CPU1_SB_DQS_DN(3)
  44 M_E_CPU1_SA_DQS_DP<3> DQS3_A_T @T6G_MB_LIB.T6G(SCH_1):M_E_CPU1_SA_DQS_DP(3)
  45 M_E_CPU1_SA_DQS_DN<3> DQS3_A_C @T6G_MB_LIB.T6G(SCH_1):M_E_CPU1_SA_DQS_DN(3)
 126 M_E_CPU1_SB_DQS_DP<2> DQS2_B_T @T6G_MB_LIB.T6G(SCH_1):M_E_CPU1_SB_DQS_DP(2)
 127 M_E_CPU1_SB_DQS_DN<2> DQS2_B_C @T6G_MB_LIB.T6G(SCH_1):M_E_CPU1_SB_DQS_DN(2)
  33 M_E_CPU1_SA_DQS_DP<2> DQS2_A_T @T6G_MB_LIB.T6G(SCH_1):M_E_CPU1_SA_DQS_DP(2)
  34 M_E_CPU1_SA_DQS_DN<2> DQS2_A_C @T6G_MB_LIB.T6G(SCH_1):M_E_CPU1_SA_DQS_DN(2)
 115 M_E_CPU1_SB_DQS_DP<1> DQS1_B_T @T6G_MB_LIB.T6G(SCH_1):M_E_CPU1_SB_DQS_DP(1)
 116 M_E_CPU1_SB_DQS_DN<1> DQS1_B_C @T6G_MB_LIB.T6G(SCH_1):M_E_CPU1_SB_DQS_DN(1)
  22 M_E_CPU1_SA_DQS_DP<1> DQS1_A_T @T6G_MB_LIB.T6G(SCH_1):M_E_CPU1_SA_DQS_DP(1)
  23 M_E_CPU1_SA_DQS_DN<1> DQS1_A_C @T6G_MB_LIB.T6G(SCH_1):M_E_CPU1_SA_DQS_DN(1)
 104 M_E_CPU1_SB_DQS_DP<0> DQS0_B_T @T6G_MB_LIB.T6G(SCH_1):M_E_CPU1_SB_DQS_DP(0)
 105 M_E_CPU1_SB_DQS_DN<0> DQS0_B_C @T6G_MB_LIB.T6G(SCH_1):M_E_CPU1_SB_DQS_DN(0)
  11 M_E_CPU1_SA_DQS_DP<0> DQS0_A_T @T6G_MB_LIB.T6G(SCH_1):M_E_CPU1_SA_DQS_DP(0)
  12 M_E_CPU1_SA_DQS_DN<0> DQS0_A_C @T6G_MB_LIB.T6G(SCH_1):M_E_CPU1_SA_DQS_DN(0)
 272 M_E_CPU1_SB_DQS_DP<7> DQS7_B_T||TDQS7_B_T @T6G_MB_LIB.T6G(SCH_1):M_E_CPU1_SB_DQS_DP(7)
 282 M_E_CPU1_SB_DQS_DN<8> DQS8_B_C||TDQS8_B_C @T6G_MB_LIB.T6G(SCH_1):M_E_CPU1_SB_DQS_DN(8)
 283 M_E_CPU1_SB_DQS_DP<8> DQS8_B_T||TDQS8_B_T @T6G_MB_LIB.T6G(SCH_1):M_E_CPU1_SB_DQS_DP(8)
 168 M_E_CPU1_SA_DQS_DP<6> DQS6_A_T||TDQS6_A_T @T6G_MB_LIB.T6G(SCH_1):M_E_CPU1_SA_DQS_DP(6)
 178 M_E_CPU1_SA_DQS_DN<7> DQS7_A_C||TDQS7_A_C @T6G_MB_LIB.T6G(SCH_1):M_E_CPU1_SA_DQS_DN(7)

Q_CAP_C0805-10UF,25V,10%,X6S,CH6104KEA00  I238  C183
   1 P12V_MEM_CPU1      A @T6G_MB_LIB.T6G(SCH_1):P12V_MEM_CPU1
   2    GND      B @T6G_MB_LIB.T6G(SCH_1):GND

Q_CAP_C0805-10UF,25V,10%,X6S,CH6104KEA00  I239  C509
   1 P12V_MEM_CPU1      A @T6G_MB_LIB.T6G(SCH_1):P12V_MEM_CPU1
   2    GND      B @T6G_MB_LIB.T6G(SCH_1):GND

Q_RES_0402LF-49.9,1%,1/16W,CHIP,CS04992FB07  I242  R1584
   1 I3C_SPD_DDRAF_CPU1_SCL      A @T6G_MB_LIB.T6G(SCH_1):I3C_SPD_DDRAF_CPU1_SCL
   2 I3C_SPD_DDRE_CPU1_SCL      B @T6G_MB_LIB.T6G(SCH_1):I3C_SPD_DDRE_CPU1_SCL

Q_RES_0402LF-10,1%,1/16W,CHIP,CS01002FB07  I243  R1701
   1 I3C_SPD_DDRAF_CPU1_SDA      A @T6G_MB_LIB.T6G(SCH_1):I3C_SPD_DDRAF_CPU1_SDA
   2 I3C_SPD_DDRE_CPU1_SDA      B @T6G_MB_LIB.T6G(SCH_1):I3C_SPD_DDRE_CPU1_SDA


DRAWING: @T6G_MB_LIB.T6G(SCH_1):PAGE102 

SCONN288_DDR506112002KQ-SCONN288_DDR506112002KQ,SMA  I22  J33
   3 P3V3_AUX VIN_MGMT @T6G_MB_LIB.T6G(SCH_1):P3V3_AUX
   2     NC   RFU0     NC
 144     NC   RFU1     NC
 149     NC   RFU2     NC
 150     NC   RFU3     NC
 220     NC   RFU4     NC
 231     NC   RFU5     NC
 232     NC   RFU6     NC
 207 M_F_CPU1_RESET_N RESET_N @T6G_MB_LIB.T6G(SCH_1):M_F_CPU1_RESET_N
 147 PWRGD_CHF_CPU1_DIMM PWR_GOOD||FAIL_N @T6G_MB_LIB.T6G(SCH_1):PWRGD_CHF_CPU1_DIMM
 227 M_F_CPU1_SB_PAR  PAR_B @T6G_MB_LIB.T6G(SCH_1):M_F_CPU1_SB_PAR
  74 M_F_CPU1_SA_PAR  PAR_A @T6G_MB_LIB.T6G(SCH_1):M_F_CPU1_SA_PAR
  87 M_F_CPU1_SB_RSP<0> LBS||RSP_B_N @T6G_MB_LIB.T6G(SCH_1):M_F_CPU1_SB_RSP(0)
  86 M_F_CPU1_SA_RSP<0> LBD||RSP_A_N @T6G_MB_LIB.T6G(SCH_1):M_F_CPU1_SA_RSP(0)
   5 I3C_SPD_DDRF_CPU1_SDA   HSDA @T6G_MB_LIB.T6G(SCH_1):I3C_SPD_DDRF_CPU1_SDA
   4 I3C_SPD_DDRF_CPU1_SCL   HSCL @T6G_MB_LIB.T6G(SCH_1):I3C_SPD_DDRF_CPU1_SCL
 148 PD_CHF_CPU1_DIMM_SAA    HAS @T6G_MB_LIB.T6G(SCH_1):PD_CHF_CPU1_DIMM_SAA
 100 M_F_CPU1_SB_DQ<0>  DQ0_B @T6G_MB_LIB.T6G(SCH_1):M_F_CPU1_SB_DQ(0)
 102 M_F_CPU1_SB_DQ<1>  DQ1_B @T6G_MB_LIB.T6G(SCH_1):M_F_CPU1_SB_DQ(1)
 245 M_F_CPU1_SB_DQ<2>  DQ2_B @T6G_MB_LIB.T6G(SCH_1):M_F_CPU1_SB_DQ(2)
 247 M_F_CPU1_SB_DQ<3>  DQ3_B @T6G_MB_LIB.T6G(SCH_1):M_F_CPU1_SB_DQ(3)
 107 M_F_CPU1_SB_DQ<4>  DQ4_B @T6G_MB_LIB.T6G(SCH_1):M_F_CPU1_SB_DQ(4)
 109 M_F_CPU1_SB_DQ<5>  DQ5_B @T6G_MB_LIB.T6G(SCH_1):M_F_CPU1_SB_DQ(5)
 252 M_F_CPU1_SB_DQ<6>  DQ6_B @T6G_MB_LIB.T6G(SCH_1):M_F_CPU1_SB_DQ(6)
 254 M_F_CPU1_SB_DQ<7>  DQ7_B @T6G_MB_LIB.T6G(SCH_1):M_F_CPU1_SB_DQ(7)
 111 M_F_CPU1_SB_DQ<8>  DQ8_B @T6G_MB_LIB.T6G(SCH_1):M_F_CPU1_SB_DQ(8)
 113 M_F_CPU1_SB_DQ<9>  DQ9_B @T6G_MB_LIB.T6G(SCH_1):M_F_CPU1_SB_DQ(9)
 256 M_F_CPU1_SB_DQ<10> DQ10_B @T6G_MB_LIB.T6G(SCH_1):M_F_CPU1_SB_DQ(10)
 258 M_F_CPU1_SB_DQ<11> DQ11_B @T6G_MB_LIB.T6G(SCH_1):M_F_CPU1_SB_DQ(11)
 118 M_F_CPU1_SB_DQ<12> DQ12_B @T6G_MB_LIB.T6G(SCH_1):M_F_CPU1_SB_DQ(12)
 120 M_F_CPU1_SB_DQ<13> DQ13_B @T6G_MB_LIB.T6G(SCH_1):M_F_CPU1_SB_DQ(13)
 263 M_F_CPU1_SB_DQ<14> DQ14_B @T6G_MB_LIB.T6G(SCH_1):M_F_CPU1_SB_DQ(14)
 265 M_F_CPU1_SB_DQ<15> DQ15_B @T6G_MB_LIB.T6G(SCH_1):M_F_CPU1_SB_DQ(15)
 122 M_F_CPU1_SB_DQ<16> DQ16_B @T6G_MB_LIB.T6G(SCH_1):M_F_CPU1_SB_DQ(16)
 124 M_F_CPU1_SB_DQ<17> DQ17_B @T6G_MB_LIB.T6G(SCH_1):M_F_CPU1_SB_DQ(17)
 267 M_F_CPU1_SB_DQ<18> DQ18_B @T6G_MB_LIB.T6G(SCH_1):M_F_CPU1_SB_DQ(18)
 269 M_F_CPU1_SB_DQ<19> DQ19_B @T6G_MB_LIB.T6G(SCH_1):M_F_CPU1_SB_DQ(19)
 129 M_F_CPU1_SB_DQ<20> DQ20_B @T6G_MB_LIB.T6G(SCH_1):M_F_CPU1_SB_DQ(20)
 131 M_F_CPU1_SB_DQ<21> DQ21_B @T6G_MB_LIB.T6G(SCH_1):M_F_CPU1_SB_DQ(21)
 274 M_F_CPU1_SB_DQ<22> DQ22_B @T6G_MB_LIB.T6G(SCH_1):M_F_CPU1_SB_DQ(22)
 276 M_F_CPU1_SB_DQ<23> DQ23_B @T6G_MB_LIB.T6G(SCH_1):M_F_CPU1_SB_DQ(23)
 133 M_F_CPU1_SB_DQ<24> DQ24_B @T6G_MB_LIB.T6G(SCH_1):M_F_CPU1_SB_DQ(24)
 135 M_F_CPU1_SB_DQ<25> DQ25_B @T6G_MB_LIB.T6G(SCH_1):M_F_CPU1_SB_DQ(25)
 278 M_F_CPU1_SB_DQ<26> DQ26_B @T6G_MB_LIB.T6G(SCH_1):M_F_CPU1_SB_DQ(26)
 280 M_F_CPU1_SB_DQ<27> DQ27_B @T6G_MB_LIB.T6G(SCH_1):M_F_CPU1_SB_DQ(27)
 140 M_F_CPU1_SB_DQ<28> DQ28_B @T6G_MB_LIB.T6G(SCH_1):M_F_CPU1_SB_DQ(28)
 142 M_F_CPU1_SB_DQ<29> DQ29_B @T6G_MB_LIB.T6G(SCH_1):M_F_CPU1_SB_DQ(29)
 285 M_F_CPU1_SB_DQ<30> DQ30_B @T6G_MB_LIB.T6G(SCH_1):M_F_CPU1_SB_DQ(30)
 287 M_F_CPU1_SB_DQ<31> DQ31_B @T6G_MB_LIB.T6G(SCH_1):M_F_CPU1_SB_DQ(31)
   7 M_F_CPU1_SA_DQ<0>  DQ0_A @T6G_MB_LIB.T6G(SCH_1):M_F_CPU1_SA_DQ(0)
   9 M_F_CPU1_SA_DQ<1>  DQ1_A @T6G_MB_LIB.T6G(SCH_1):M_F_CPU1_SA_DQ(1)
 152 M_F_CPU1_SA_DQ<2>  DQ2_A @T6G_MB_LIB.T6G(SCH_1):M_F_CPU1_SA_DQ(2)
 154 M_F_CPU1_SA_DQ<3>  DQ3_A @T6G_MB_LIB.T6G(SCH_1):M_F_CPU1_SA_DQ(3)
  14 M_F_CPU1_SA_DQ<4>  DQ4_A @T6G_MB_LIB.T6G(SCH_1):M_F_CPU1_SA_DQ(4)
  16 M_F_CPU1_SA_DQ<5>  DQ5_A @T6G_MB_LIB.T6G(SCH_1):M_F_CPU1_SA_DQ(5)
 159 M_F_CPU1_SA_DQ<6>  DQ6_A @T6G_MB_LIB.T6G(SCH_1):M_F_CPU1_SA_DQ(6)
 161 M_F_CPU1_SA_DQ<7>  DQ7_A @T6G_MB_LIB.T6G(SCH_1):M_F_CPU1_SA_DQ(7)
  18 M_F_CPU1_SA_DQ<8>  DQ8_A @T6G_MB_LIB.T6G(SCH_1):M_F_CPU1_SA_DQ(8)
  20 M_F_CPU1_SA_DQ<9>  DQ9_A @T6G_MB_LIB.T6G(SCH_1):M_F_CPU1_SA_DQ(9)
 163 M_F_CPU1_SA_DQ<10> DQ10_A @T6G_MB_LIB.T6G(SCH_1):M_F_CPU1_SA_DQ(10)
 165 M_F_CPU1_SA_DQ<11> DQ11_A @T6G_MB_LIB.T6G(SCH_1):M_F_CPU1_SA_DQ(11)
  25 M_F_CPU1_SA_DQ<12> DQ12_A @T6G_MB_LIB.T6G(SCH_1):M_F_CPU1_SA_DQ(12)
  27 M_F_CPU1_SA_DQ<13> DQ13_A @T6G_MB_LIB.T6G(SCH_1):M_F_CPU1_SA_DQ(13)
 170 M_F_CPU1_SA_DQ<14> DQ14_A @T6G_MB_LIB.T6G(SCH_1):M_F_CPU1_SA_DQ(14)
 172 M_F_CPU1_SA_DQ<15> DQ15_A @T6G_MB_LIB.T6G(SCH_1):M_F_CPU1_SA_DQ(15)
  29 M_F_CPU1_SA_DQ<16> DQ16_A @T6G_MB_LIB.T6G(SCH_1):M_F_CPU1_SA_DQ(16)
  31 M_F_CPU1_SA_DQ<17> DQ17_A @T6G_MB_LIB.T6G(SCH_1):M_F_CPU1_SA_DQ(17)
 174 M_F_CPU1_SA_DQ<18> DQ18_A @T6G_MB_LIB.T6G(SCH_1):M_F_CPU1_SA_DQ(18)
 176 M_F_CPU1_SA_DQ<19> DQ19_A @T6G_MB_LIB.T6G(SCH_1):M_F_CPU1_SA_DQ(19)
  36 M_F_CPU1_SA_DQ<20> DQ20_A @T6G_MB_LIB.T6G(SCH_1):M_F_CPU1_SA_DQ(20)
  38 M_F_CPU1_SA_DQ<21> DQ21_A @T6G_MB_LIB.T6G(SCH_1):M_F_CPU1_SA_DQ(21)
 181 M_F_CPU1_SA_DQ<22> DQ22_A @T6G_MB_LIB.T6G(SCH_1):M_F_CPU1_SA_DQ(22)
 183 M_F_CPU1_SA_DQ<23> DQ23_A @T6G_MB_LIB.T6G(SCH_1):M_F_CPU1_SA_DQ(23)
  40 M_F_CPU1_SA_DQ<24> DQ24_A @T6G_MB_LIB.T6G(SCH_1):M_F_CPU1_SA_DQ(24)
  42 M_F_CPU1_SA_DQ<25> DQ25_A @T6G_MB_LIB.T6G(SCH_1):M_F_CPU1_SA_DQ(25)
 185 M_F_CPU1_SA_DQ<26> DQ26_A @T6G_MB_LIB.T6G(SCH_1):M_F_CPU1_SA_DQ(26)
 187 M_F_CPU1_SA_DQ<27> DQ27_A @T6G_MB_LIB.T6G(SCH_1):M_F_CPU1_SA_DQ(27)
  47 M_F_CPU1_SA_DQ<28> DQ28_A @T6G_MB_LIB.T6G(SCH_1):M_F_CPU1_SA_DQ(28)
  49 M_F_CPU1_SA_DQ<29> DQ29_A @T6G_MB_LIB.T6G(SCH_1):M_F_CPU1_SA_DQ(29)
 192 M_F_CPU1_SA_DQ<30> DQ30_A @T6G_MB_LIB.T6G(SCH_1):M_F_CPU1_SA_DQ(30)
 229 M_F_CPU1_SB_CS_N<1> CS1_B_N @T6G_MB_LIB.T6G(SCH_1):M_F_CPU1_SB_CS_N(1)
 209 M_F_CPU1_SA_CS_N<1> CS1_A_N @T6G_MB_LIB.T6G(SCH_1):M_F_CPU1_SA_CS_N(1)
  84 M_F_CPU1_SB_CS_N<0> CS0_B_N @T6G_MB_LIB.T6G(SCH_1):M_F_CPU1_SB_CS_N(0)
  64 M_F_CPU1_SA_CS_N<0> CS0_A_N @T6G_MB_LIB.T6G(SCH_1):M_F_CPU1_SA_CS_N(0)
 217 M_F_CPU1_CLK_DP<0>   CK_T @T6G_MB_LIB.T6G(SCH_1):M_F_CPU1_CLK_DP(0)
 218 M_F_CPU1_CLK_DN<0>   CK_C @T6G_MB_LIB.T6G(SCH_1):M_F_CPU1_CLK_DN(0)
  96 M_F_CPU1_SB_CB<0>  CB0_B @T6G_MB_LIB.T6G(SCH_1):M_F_CPU1_SB_CB(0)
  98 M_F_CPU1_SB_CB<1>  CB1_B @T6G_MB_LIB.T6G(SCH_1):M_F_CPU1_SB_CB(1)
 241 M_F_CPU1_SB_CB<2>  CB2_B @T6G_MB_LIB.T6G(SCH_1):M_F_CPU1_SB_CB(2)
 243 M_F_CPU1_SB_CB<3>  CB3_B @T6G_MB_LIB.T6G(SCH_1):M_F_CPU1_SB_CB(3)
  89 M_F_CPU1_SB_CB<4>  CB4_B @T6G_MB_LIB.T6G(SCH_1):M_F_CPU1_SB_CB(4)
  91 M_F_CPU1_SB_CB<5>  CB5_B @T6G_MB_LIB.T6G(SCH_1):M_F_CPU1_SB_CB(5)
 234 M_F_CPU1_SB_CB<6>  CB6_B @T6G_MB_LIB.T6G(SCH_1):M_F_CPU1_SB_CB(6)
  51 M_F_CPU1_SA_CB<0>  CB0_A @T6G_MB_LIB.T6G(SCH_1):M_F_CPU1_SA_CB(0)
 196 M_F_CPU1_SA_CB<2>  CB2_A @T6G_MB_LIB.T6G(SCH_1):M_F_CPU1_SA_CB(2)
 198 M_F_CPU1_SA_CB<3>  CB3_A @T6G_MB_LIB.T6G(SCH_1):M_F_CPU1_SA_CB(3)
  60 M_F_CPU1_SA_CB<5>  CB5_A @T6G_MB_LIB.T6G(SCH_1):M_F_CPU1_SA_CB(5)
 203 M_F_CPU1_SA_CB<6>  CB6_A @T6G_MB_LIB.T6G(SCH_1):M_F_CPU1_SA_CB(6)
  82 M_F_CPU1_SB_CA<6>  CA6_B @T6G_MB_LIB.T6G(SCH_1):M_F_CPU1_SB_CA(6)
  72 M_F_CPU1_SA_CA<6>  CA6_A @T6G_MB_LIB.T6G(SCH_1):M_F_CPU1_SA_CA(6)
 225 M_F_CPU1_SB_CA<5>  CA5_B @T6G_MB_LIB.T6G(SCH_1):M_F_CPU1_SB_CA(5)
 215 M_F_CPU1_SA_CA<5>  CA5_A @T6G_MB_LIB.T6G(SCH_1):M_F_CPU1_SA_CA(5)
  80 M_F_CPU1_SB_CA<4>  CA4_B @T6G_MB_LIB.T6G(SCH_1):M_F_CPU1_SB_CA(4)
  70 M_F_CPU1_SA_CA<4>  CA4_A @T6G_MB_LIB.T6G(SCH_1):M_F_CPU1_SA_CA(4)
 223 M_F_CPU1_SB_CA<3>  CA3_B @T6G_MB_LIB.T6G(SCH_1):M_F_CPU1_SB_CA(3)
 213 M_F_CPU1_SA_CA<3>  CA3_A @T6G_MB_LIB.T6G(SCH_1):M_F_CPU1_SA_CA(3)
  78 M_F_CPU1_SB_CA<2>  CA2_B @T6G_MB_LIB.T6G(SCH_1):M_F_CPU1_SB_CA(2)
  68 M_F_CPU1_SA_CA<2>  CA2_A @T6G_MB_LIB.T6G(SCH_1):M_F_CPU1_SA_CA(2)
 221 M_F_CPU1_SB_CA<1>  CA1_B @T6G_MB_LIB.T6G(SCH_1):M_F_CPU1_SB_CA(1)
 211 M_F_CPU1_SA_CA<1>  CA1_A @T6G_MB_LIB.T6G(SCH_1):M_F_CPU1_SA_CA(1)
  76 M_F_CPU1_SB_CA<0>  CA0_B @T6G_MB_LIB.T6G(SCH_1):M_F_CPU1_SB_CA(0)
  66 M_F_CPU1_SA_CA<0>  CA0_A @T6G_MB_LIB.T6G(SCH_1):M_F_CPU1_SA_CA(0)
  62 M_F_CPU1_ALERT_N ALERT_N @T6G_MB_LIB.T6G(SCH_1):M_F_CPU1_ALERT_N
 236 M_F_CPU1_SB_CB<7>  CB7_B @T6G_MB_LIB.T6G(SCH_1):M_F_CPU1_SB_CB(7)
  53 M_F_CPU1_SA_CB<1>  CB1_A @T6G_MB_LIB.T6G(SCH_1):M_F_CPU1_SA_CB(1)
  58 M_F_CPU1_SA_CB<4>  CB4_A @T6G_MB_LIB.T6G(SCH_1):M_F_CPU1_SA_CB(4)
 205 M_F_CPU1_SA_CB<7>  CB7_A @T6G_MB_LIB.T6G(SCH_1):M_F_CPU1_SA_CB(7)
 194 M_F_CPU1_SA_DQ<31> DQ31_A @T6G_MB_LIB.T6G(SCH_1):M_F_CPU1_SA_DQ(31)

Q_RES_0402LF-84.5K,1%,1/16W,CHIP,CS38452FB05  I129  R773
   1 PD_CHF_CPU1_DIMM_SAA      A @T6G_MB_LIB.T6G(SCH_1):PD_CHF_CPU1_DIMM_SAA
   2    GND      B @T6G_MB_LIB.T6G(SCH_1):GND

SCONN288_DDR506112002KQ-SCONN288_DDR506112002KQ,SMA  I142  J33
   6    GND   VSS0 @T6G_MB_LIB.T6G(SCH_1):GND
   8    GND   VSS1 @T6G_MB_LIB.T6G(SCH_1):GND
  10    GND   VSS2 @T6G_MB_LIB.T6G(SCH_1):GND
  13    GND   VSS3 @T6G_MB_LIB.T6G(SCH_1):GND
  15    GND   VSS4 @T6G_MB_LIB.T6G(SCH_1):GND
  17    GND   VSS5 @T6G_MB_LIB.T6G(SCH_1):GND
  19    GND   VSS6 @T6G_MB_LIB.T6G(SCH_1):GND
  21    GND   VSS7 @T6G_MB_LIB.T6G(SCH_1):GND
  24    GND   VSS8 @T6G_MB_LIB.T6G(SCH_1):GND
  26    GND   VSS9 @T6G_MB_LIB.T6G(SCH_1):GND
  28    GND  VSS10 @T6G_MB_LIB.T6G(SCH_1):GND
  30    GND  VSS11 @T6G_MB_LIB.T6G(SCH_1):GND
  32    GND  VSS12 @T6G_MB_LIB.T6G(SCH_1):GND
  35    GND  VSS13 @T6G_MB_LIB.T6G(SCH_1):GND
  37    GND  VSS14 @T6G_MB_LIB.T6G(SCH_1):GND
  39    GND  VSS15 @T6G_MB_LIB.T6G(SCH_1):GND
  41    GND  VSS16 @T6G_MB_LIB.T6G(SCH_1):GND
  43    GND  VSS17 @T6G_MB_LIB.T6G(SCH_1):GND
  46    GND  VSS18 @T6G_MB_LIB.T6G(SCH_1):GND
  48    GND  VSS19 @T6G_MB_LIB.T6G(SCH_1):GND
  50    GND  VSS20 @T6G_MB_LIB.T6G(SCH_1):GND
  52    GND  VSS21 @T6G_MB_LIB.T6G(SCH_1):GND
  54    GND  VSS22 @T6G_MB_LIB.T6G(SCH_1):GND
  57    GND  VSS23 @T6G_MB_LIB.T6G(SCH_1):GND
  59    GND  VSS24 @T6G_MB_LIB.T6G(SCH_1):GND
  61    GND  VSS25 @T6G_MB_LIB.T6G(SCH_1):GND
  63    GND  VSS26 @T6G_MB_LIB.T6G(SCH_1):GND
  65    GND  VSS27 @T6G_MB_LIB.T6G(SCH_1):GND
  67    GND  VSS28 @T6G_MB_LIB.T6G(SCH_1):GND
  69    GND  VSS29 @T6G_MB_LIB.T6G(SCH_1):GND
  71    GND  VSS30 @T6G_MB_LIB.T6G(SCH_1):GND
  73    GND  VSS31 @T6G_MB_LIB.T6G(SCH_1):GND
  75    GND  VSS32 @T6G_MB_LIB.T6G(SCH_1):GND
  77    GND  VSS33 @T6G_MB_LIB.T6G(SCH_1):GND
  79    GND  VSS34 @T6G_MB_LIB.T6G(SCH_1):GND
  81    GND  VSS35 @T6G_MB_LIB.T6G(SCH_1):GND
  83    GND  VSS36 @T6G_MB_LIB.T6G(SCH_1):GND
  85    GND  VSS37 @T6G_MB_LIB.T6G(SCH_1):GND
  88    GND  VSS38 @T6G_MB_LIB.T6G(SCH_1):GND
  90    GND  VSS39 @T6G_MB_LIB.T6G(SCH_1):GND
  92    GND  VSS40 @T6G_MB_LIB.T6G(SCH_1):GND
  95    GND  VSS41 @T6G_MB_LIB.T6G(SCH_1):GND
  97    GND  VSS42 @T6G_MB_LIB.T6G(SCH_1):GND
  99    GND  VSS43 @T6G_MB_LIB.T6G(SCH_1):GND
 101    GND  VSS44 @T6G_MB_LIB.T6G(SCH_1):GND
 103    GND  VSS45 @T6G_MB_LIB.T6G(SCH_1):GND
 106    GND  VSS46 @T6G_MB_LIB.T6G(SCH_1):GND
 108    GND  VSS47 @T6G_MB_LIB.T6G(SCH_1):GND
 110    GND  VSS48 @T6G_MB_LIB.T6G(SCH_1):GND
 112    GND  VSS49 @T6G_MB_LIB.T6G(SCH_1):GND
 114    GND  VSS50 @T6G_MB_LIB.T6G(SCH_1):GND
 117    GND  VSS51 @T6G_MB_LIB.T6G(SCH_1):GND
 119    GND  VSS52 @T6G_MB_LIB.T6G(SCH_1):GND
 121    GND  VSS53 @T6G_MB_LIB.T6G(SCH_1):GND
 123    GND  VSS54 @T6G_MB_LIB.T6G(SCH_1):GND
 125    GND  VSS55 @T6G_MB_LIB.T6G(SCH_1):GND
 128    GND  VSS56 @T6G_MB_LIB.T6G(SCH_1):GND
 130    GND  VSS57 @T6G_MB_LIB.T6G(SCH_1):GND
 134    GND  VSS59 @T6G_MB_LIB.T6G(SCH_1):GND
 143    GND  VSS63 @T6G_MB_LIB.T6G(SCH_1):GND
 151    GND  VSS64 @T6G_MB_LIB.T6G(SCH_1):GND
 153    GND  VSS65 @T6G_MB_LIB.T6G(SCH_1):GND
 155    GND  VSS66 @T6G_MB_LIB.T6G(SCH_1):GND
 158    GND  VSS67 @T6G_MB_LIB.T6G(SCH_1):GND
 160    GND  VSS68 @T6G_MB_LIB.T6G(SCH_1):GND
 162    GND  VSS69 @T6G_MB_LIB.T6G(SCH_1):GND
 164    GND  VSS70 @T6G_MB_LIB.T6G(SCH_1):GND
 166    GND  VSS71 @T6G_MB_LIB.T6G(SCH_1):GND
 169    GND  VSS72 @T6G_MB_LIB.T6G(SCH_1):GND
 171    GND  VSS73 @T6G_MB_LIB.T6G(SCH_1):GND
 173    GND  VSS74 @T6G_MB_LIB.T6G(SCH_1):GND
 175    GND  VSS75 @T6G_MB_LIB.T6G(SCH_1):GND
 177    GND  VSS76 @T6G_MB_LIB.T6G(SCH_1):GND
 180    GND  VSS77 @T6G_MB_LIB.T6G(SCH_1):GND
 182    GND  VSS78 @T6G_MB_LIB.T6G(SCH_1):GND
 184    GND  VSS79 @T6G_MB_LIB.T6G(SCH_1):GND
 186    GND  VSS80 @T6G_MB_LIB.T6G(SCH_1):GND
 188    GND  VSS81 @T6G_MB_LIB.T6G(SCH_1):GND
 191    GND  VSS82 @T6G_MB_LIB.T6G(SCH_1):GND
 193    GND  VSS83 @T6G_MB_LIB.T6G(SCH_1):GND
 195    GND  VSS84 @T6G_MB_LIB.T6G(SCH_1):GND
 197    GND  VSS85 @T6G_MB_LIB.T6G(SCH_1):GND
 199    GND  VSS86 @T6G_MB_LIB.T6G(SCH_1):GND
 202    GND  VSS87 @T6G_MB_LIB.T6G(SCH_1):GND
 204    GND  VSS88 @T6G_MB_LIB.T6G(SCH_1):GND
 206    GND  VSS89 @T6G_MB_LIB.T6G(SCH_1):GND
 208    GND  VSS90 @T6G_MB_LIB.T6G(SCH_1):GND
 210    GND  VSS91 @T6G_MB_LIB.T6G(SCH_1):GND
 212    GND  VSS92 @T6G_MB_LIB.T6G(SCH_1):GND
 214    GND  VSS93 @T6G_MB_LIB.T6G(SCH_1):GND
 216    GND  VSS94 @T6G_MB_LIB.T6G(SCH_1):GND
 219    GND  VSS95 @T6G_MB_LIB.T6G(SCH_1):GND
 222    GND  VSS96 @T6G_MB_LIB.T6G(SCH_1):GND
 224    GND  VSS97 @T6G_MB_LIB.T6G(SCH_1):GND
 226    GND  VSS98 @T6G_MB_LIB.T6G(SCH_1):GND
 228    GND  VSS99 @T6G_MB_LIB.T6G(SCH_1):GND
 233    GND VSS101 @T6G_MB_LIB.T6G(SCH_1):GND
 237    GND VSS103 @T6G_MB_LIB.T6G(SCH_1):GND
 242    GND VSS105 @T6G_MB_LIB.T6G(SCH_1):GND
 244    GND VSS106 @T6G_MB_LIB.T6G(SCH_1):GND
 246    GND VSS107 @T6G_MB_LIB.T6G(SCH_1):GND
 248    GND VSS108 @T6G_MB_LIB.T6G(SCH_1):GND
 251    GND VSS109 @T6G_MB_LIB.T6G(SCH_1):GND
 253    GND VSS110 @T6G_MB_LIB.T6G(SCH_1):GND
 255    GND VSS111 @T6G_MB_LIB.T6G(SCH_1):GND
 257    GND VSS112 @T6G_MB_LIB.T6G(SCH_1):GND
 259    GND VSS113 @T6G_MB_LIB.T6G(SCH_1):GND
 262    GND VSS114 @T6G_MB_LIB.T6G(SCH_1):GND
 264    GND VSS115 @T6G_MB_LIB.T6G(SCH_1):GND
 266    GND VSS116 @T6G_MB_LIB.T6G(SCH_1):GND
 268    GND VSS117 @T6G_MB_LIB.T6G(SCH_1):GND
 270    GND VSS118 @T6G_MB_LIB.T6G(SCH_1):GND
 273    GND VSS119 @T6G_MB_LIB.T6G(SCH_1):GND
 275    GND VSS120 @T6G_MB_LIB.T6G(SCH_1):GND
 277    GND VSS121 @T6G_MB_LIB.T6G(SCH_1):GND
 279    GND VSS122 @T6G_MB_LIB.T6G(SCH_1):GND
 281    GND VSS123 @T6G_MB_LIB.T6G(SCH_1):GND
 284    GND VSS124 @T6G_MB_LIB.T6G(SCH_1):GND
 286    GND VSS125 @T6G_MB_LIB.T6G(SCH_1):GND
 288    GND VSS126 @T6G_MB_LIB.T6G(SCH_1):GND
   1 P12V_MEM_CPU1 VIN_BULK0 @T6G_MB_LIB.T6G(SCH_1):P12V_MEM_CPU1
 145 P12V_MEM_CPU1 VIN_BULK1 @T6G_MB_LIB.T6G(SCH_1):P12V_MEM_CPU1
 146 P12V_MEM_CPU1 VIN_BULK2 @T6G_MB_LIB.T6G(SCH_1):P12V_MEM_CPU1
 230    GND VSS100 @T6G_MB_LIB.T6G(SCH_1):GND
 235    GND VSS102 @T6G_MB_LIB.T6G(SCH_1):GND
 240    GND VSS104 @T6G_MB_LIB.T6G(SCH_1):GND
 132    GND  VSS58 @T6G_MB_LIB.T6G(SCH_1):GND
 136    GND  VSS60 @T6G_MB_LIB.T6G(SCH_1):GND
 139    GND  VSS61 @T6G_MB_LIB.T6G(SCH_1):GND
 141    GND  VSS62 @T6G_MB_LIB.T6G(SCH_1):GND
  G1    GND     G1 @T6G_MB_LIB.T6G(SCH_1):GND
  G2    GND     G2 @T6G_MB_LIB.T6G(SCH_1):GND
  G3    GND     G3 @T6G_MB_LIB.T6G(SCH_1):GND

Q_CAP_0402-0.1UF,25V,10%,X7R,CH4104K1B00  I185  C156
   1 P3V3_AUX      A @T6G_MB_LIB.T6G(SCH_1):P3V3_AUX
   2    GND      B @T6G_MB_LIB.T6G(SCH_1):GND

Q_RES_0402LF-1K,1%,1/16W,CHIP,CS21002FB06  I188  R1183
   1 PWRGD_CHF_CPU1_DIMM      A @T6G_MB_LIB.T6G(SCH_1):PWRGD_CHF_CPU1_DIMM
   2 PWRGD_CHAF_CPU1      B @T6G_MB_LIB.T6G(SCH_1):PWRGD_CHAF_CPU1

Q_RES_0402LF-1K,1%,1/16W,EMPTY,CS21002FB06  I190  R108
   1   P3V3      A @T6G_MB_LIB.T6G(SCH_1):P3V3
   2 PWRGD_CHF_CPU1_DIMM      B @T6G_MB_LIB.T6G(SCH_1):PWRGD_CHF_CPU1_DIMM

SCONN288_DDR506112002KQ-SCONN288_DDR506112002KQ,SMA  I236  J33
  93 M_F_CPU1_SB_DQS_DP<9> DQS9_B_T||TDQS9_B_T||DBI4_B_N @T6G_MB_LIB.T6G(SCH_1):M_F_CPU1_SB_DQS_DP(9)
  94 M_F_CPU1_SB_DQS_DN<9> DQS9_B_C||TDQS9_B_C @T6G_MB_LIB.T6G(SCH_1):M_F_CPU1_SB_DQS_DN(9)
 201 M_F_CPU1_SA_DQS_DP<9> DQS9_A_T||TDQS9_A_T @T6G_MB_LIB.T6G(SCH_1):M_F_CPU1_SA_DQS_DP(9)
 200 M_F_CPU1_SA_DQS_DN<9> DQS9_A_C||TDQS9_A_C @T6G_MB_LIB.T6G(SCH_1):M_F_CPU1_SA_DQS_DN(9)
 190 M_F_CPU1_SA_DQS_DP<8> DQS8_A_T||TDQS8_A_T @T6G_MB_LIB.T6G(SCH_1):M_F_CPU1_SA_DQS_DP(8)
 189 M_F_CPU1_SA_DQS_DN<8> DQS8_A_C||TDQS8_A_C @T6G_MB_LIB.T6G(SCH_1):M_F_CPU1_SA_DQS_DN(8)
 271 M_F_CPU1_SB_DQS_DN<7> DQS7_B_C||TDQS7_B_C @T6G_MB_LIB.T6G(SCH_1):M_F_CPU1_SB_DQS_DN(7)
 179 M_F_CPU1_SA_DQS_DP<7> DQS7_A_T||TDQS7_A_T @T6G_MB_LIB.T6G(SCH_1):M_F_CPU1_SA_DQS_DP(7)
 261 M_F_CPU1_SB_DQS_DP<6> DQS6_B_T||TDQS6_B_T @T6G_MB_LIB.T6G(SCH_1):M_F_CPU1_SB_DQS_DP(6)
 260 M_F_CPU1_SB_DQS_DN<6> DQS6_B_C||TDQS6_B_C @T6G_MB_LIB.T6G(SCH_1):M_F_CPU1_SB_DQS_DN(6)
 167 M_F_CPU1_SA_DQS_DN<6> DQS6_A_C||TDQS6_A_C||DQS6_A_T||TDQS6_A_T @T6G_MB_LIB.T6G(SCH_1):M_F_CPU1_SA_DQS_DN(6)
 250 M_F_CPU1_SB_DQS_DP<5> DQS5_B_T||TDQS5_B_T @T6G_MB_LIB.T6G(SCH_1):M_F_CPU1_SB_DQS_DP(5)
 249 M_F_CPU1_SB_DQS_DN<5> DQS5_B_C||TDQS5_B_C @T6G_MB_LIB.T6G(SCH_1):M_F_CPU1_SB_DQS_DN(5)
 157 M_F_CPU1_SA_DQS_DP<5> DQS5_A_T||TDQS5_A_T @T6G_MB_LIB.T6G(SCH_1):M_F_CPU1_SA_DQS_DP(5)
 156 M_F_CPU1_SA_DQS_DN<5> DQS5_A_C||TDQS5_A_C||DQS5_A_T||TDQS5_A_T @T6G_MB_LIB.T6G(SCH_1):M_F_CPU1_SA_DQS_DN(5)
 239 M_F_CPU1_SB_DQS_DP<4> DQS4_B_T @T6G_MB_LIB.T6G(SCH_1):M_F_CPU1_SB_DQS_DP(4)
 238 M_F_CPU1_SB_DQS_DN<4> DQS4_B_C @T6G_MB_LIB.T6G(SCH_1):M_F_CPU1_SB_DQS_DN(4)
  55 M_F_CPU1_SA_DQS_DP<4> DQS4_A_T @T6G_MB_LIB.T6G(SCH_1):M_F_CPU1_SA_DQS_DP(4)
  56 M_F_CPU1_SA_DQS_DN<4> DQS4_A_C @T6G_MB_LIB.T6G(SCH_1):M_F_CPU1_SA_DQS_DN(4)
 137 M_F_CPU1_SB_DQS_DP<3> DQS3_B_T @T6G_MB_LIB.T6G(SCH_1):M_F_CPU1_SB_DQS_DP(3)
 138 M_F_CPU1_SB_DQS_DN<3> DQS3_B_C @T6G_MB_LIB.T6G(SCH_1):M_F_CPU1_SB_DQS_DN(3)
  44 M_F_CPU1_SA_DQS_DP<3> DQS3_A_T @T6G_MB_LIB.T6G(SCH_1):M_F_CPU1_SA_DQS_DP(3)
  45 M_F_CPU1_SA_DQS_DN<3> DQS3_A_C @T6G_MB_LIB.T6G(SCH_1):M_F_CPU1_SA_DQS_DN(3)
 126 M_F_CPU1_SB_DQS_DP<2> DQS2_B_T @T6G_MB_LIB.T6G(SCH_1):M_F_CPU1_SB_DQS_DP(2)
 127 M_F_CPU1_SB_DQS_DN<2> DQS2_B_C @T6G_MB_LIB.T6G(SCH_1):M_F_CPU1_SB_DQS_DN(2)
  33 M_F_CPU1_SA_DQS_DP<2> DQS2_A_T @T6G_MB_LIB.T6G(SCH_1):M_F_CPU1_SA_DQS_DP(2)
  34 M_F_CPU1_SA_DQS_DN<2> DQS2_A_C @T6G_MB_LIB.T6G(SCH_1):M_F_CPU1_SA_DQS_DN(2)
 115 M_F_CPU1_SB_DQS_DP<1> DQS1_B_T @T6G_MB_LIB.T6G(SCH_1):M_F_CPU1_SB_DQS_DP(1)
 116 M_F_CPU1_SB_DQS_DN<1> DQS1_B_C @T6G_MB_LIB.T6G(SCH_1):M_F_CPU1_SB_DQS_DN(1)
  22 M_F_CPU1_SA_DQS_DP<1> DQS1_A_T @T6G_MB_LIB.T6G(SCH_1):M_F_CPU1_SA_DQS_DP(1)
  23 M_F_CPU1_SA_DQS_DN<1> DQS1_A_C @T6G_MB_LIB.T6G(SCH_1):M_F_CPU1_SA_DQS_DN(1)
 104 M_F_CPU1_SB_DQS_DP<0> DQS0_B_T @T6G_MB_LIB.T6G(SCH_1):M_F_CPU1_SB_DQS_DP(0)
 105 M_F_CPU1_SB_DQS_DN<0> DQS0_B_C @T6G_MB_LIB.T6G(SCH_1):M_F_CPU1_SB_DQS_DN(0)
  11 M_F_CPU1_SA_DQS_DP<0> DQS0_A_T @T6G_MB_LIB.T6G(SCH_1):M_F_CPU1_SA_DQS_DP(0)
  12 M_F_CPU1_SA_DQS_DN<0> DQS0_A_C @T6G_MB_LIB.T6G(SCH_1):M_F_CPU1_SA_DQS_DN(0)
 272 M_F_CPU1_SB_DQS_DP<7> DQS7_B_T||TDQS7_B_T @T6G_MB_LIB.T6G(SCH_1):M_F_CPU1_SB_DQS_DP(7)
 282 M_F_CPU1_SB_DQS_DN<8> DQS8_B_C||TDQS8_B_C @T6G_MB_LIB.T6G(SCH_1):M_F_CPU1_SB_DQS_DN(8)
 283 M_F_CPU1_SB_DQS_DP<8> DQS8_B_T||TDQS8_B_T @T6G_MB_LIB.T6G(SCH_1):M_F_CPU1_SB_DQS_DP(8)
 168 M_F_CPU1_SA_DQS_DP<6> DQS6_A_T||TDQS6_A_T @T6G_MB_LIB.T6G(SCH_1):M_F_CPU1_SA_DQS_DP(6)
 178 M_F_CPU1_SA_DQS_DN<7> DQS7_A_C||TDQS7_A_C @T6G_MB_LIB.T6G(SCH_1):M_F_CPU1_SA_DQS_DN(7)

Q_CAP_C0805-10UF,25V,10%,X6S,CH6104KEA00  I238  C518
   1 P12V_MEM_CPU1      A @T6G_MB_LIB.T6G(SCH_1):P12V_MEM_CPU1
   2    GND      B @T6G_MB_LIB.T6G(SCH_1):GND

Q_CAP_C0805-10UF,25V,10%,X6S,CH6104KEA00  I239  C527
   1 P12V_MEM_CPU1      A @T6G_MB_LIB.T6G(SCH_1):P12V_MEM_CPU1
   2    GND      B @T6G_MB_LIB.T6G(SCH_1):GND

Q_RES_0402LF-49.9,1%,1/16W,CHIP,CS04992FB07  I242  R1585
   1 I3C_SPD_DDRAF_CPU1_SCL      A @T6G_MB_LIB.T6G(SCH_1):I3C_SPD_DDRAF_CPU1_SCL
   2 I3C_SPD_DDRF_CPU1_SCL      B @T6G_MB_LIB.T6G(SCH_1):I3C_SPD_DDRF_CPU1_SCL

Q_RES_0402LF-10,1%,1/16W,CHIP,CS01002FB07  I243  R1704
   1 I3C_SPD_DDRAF_CPU1_SDA      A @T6G_MB_LIB.T6G(SCH_1):I3C_SPD_DDRAF_CPU1_SDA
   2 I3C_SPD_DDRF_CPU1_SDA      B @T6G_MB_LIB.T6G(SCH_1):I3C_SPD_DDRF_CPU1_SDA


DRAWING: @T6G_MB_LIB.T6G(SCH_1):PAGE103 

SCONN288_DDR506112002KQ-SCONN288_DDR506112002KQ,SMA  I22  J102
   3 P3V3_AUX VIN_MGMT @T6G_MB_LIB.T6G(SCH_1):P3V3_AUX
   2     NC   RFU0     NC
 144     NC   RFU1     NC
 149     NC   RFU2     NC
 150     NC   RFU3     NC
 220     NC   RFU4     NC
 231     NC   RFU5     NC
 232     NC   RFU6     NC
 207 M_G_CPU1_RESET_N RESET_N @T6G_MB_LIB.T6G(SCH_1):M_G_CPU1_RESET_N
 147 PWRGD_CHG_CPU1_DIMM0 PWR_GOOD||FAIL_N @T6G_MB_LIB.T6G(SCH_1):PWRGD_CHG_CPU1_DIMM0
 227 M_G_CPU1_SB_PAR  PAR_B @T6G_MB_LIB.T6G(SCH_1):M_G_CPU1_SB_PAR
  74 M_G_CPU1_SA_PAR  PAR_A @T6G_MB_LIB.T6G(SCH_1):M_G_CPU1_SA_PAR
  87 M_G_CPU1_SB_RSP<0> LBS||RSP_B_N @T6G_MB_LIB.T6G(SCH_1):M_G_CPU1_SB_RSP(0)
  86 M_G_CPU1_SA_RSP<0> LBD||RSP_A_N @T6G_MB_LIB.T6G(SCH_1):M_G_CPU1_SA_RSP(0)
   5 I3C_SPD_DDRG_CPU1_SDA   HSDA @T6G_MB_LIB.T6G(SCH_1):I3C_SPD_DDRG_CPU1_SDA
   4 I3C_SPD_DDRG_CPU1_SCL   HSCL @T6G_MB_LIB.T6G(SCH_1):I3C_SPD_DDRG_CPU1_SCL
 148 PD_CHG_CPU1_DIMM0_SAA    HAS @T6G_MB_LIB.T6G(SCH_1):PD_CHG_CPU1_DIMM0_SAA
 100 M_G_CPU1_SB_DQ<0>  DQ0_B @T6G_MB_LIB.T6G(SCH_1):M_G_CPU1_SB_DQ(0)
 102 M_G_CPU1_SB_DQ<1>  DQ1_B @T6G_MB_LIB.T6G(SCH_1):M_G_CPU1_SB_DQ(1)
 245 M_G_CPU1_SB_DQ<2>  DQ2_B @T6G_MB_LIB.T6G(SCH_1):M_G_CPU1_SB_DQ(2)
 247 M_G_CPU1_SB_DQ<3>  DQ3_B @T6G_MB_LIB.T6G(SCH_1):M_G_CPU1_SB_DQ(3)
 107 M_G_CPU1_SB_DQ<4>  DQ4_B @T6G_MB_LIB.T6G(SCH_1):M_G_CPU1_SB_DQ(4)
 109 M_G_CPU1_SB_DQ<5>  DQ5_B @T6G_MB_LIB.T6G(SCH_1):M_G_CPU1_SB_DQ(5)
 252 M_G_CPU1_SB_DQ<6>  DQ6_B @T6G_MB_LIB.T6G(SCH_1):M_G_CPU1_SB_DQ(6)
 254 M_G_CPU1_SB_DQ<7>  DQ7_B @T6G_MB_LIB.T6G(SCH_1):M_G_CPU1_SB_DQ(7)
 111 M_G_CPU1_SB_DQ<8>  DQ8_B @T6G_MB_LIB.T6G(SCH_1):M_G_CPU1_SB_DQ(8)
 113 M_G_CPU1_SB_DQ<9>  DQ9_B @T6G_MB_LIB.T6G(SCH_1):M_G_CPU1_SB_DQ(9)
 256 M_G_CPU1_SB_DQ<10> DQ10_B @T6G_MB_LIB.T6G(SCH_1):M_G_CPU1_SB_DQ(10)
 258 M_G_CPU1_SB_DQ<11> DQ11_B @T6G_MB_LIB.T6G(SCH_1):M_G_CPU1_SB_DQ(11)
 118 M_G_CPU1_SB_DQ<12> DQ12_B @T6G_MB_LIB.T6G(SCH_1):M_G_CPU1_SB_DQ(12)
 120 M_G_CPU1_SB_DQ<13> DQ13_B @T6G_MB_LIB.T6G(SCH_1):M_G_CPU1_SB_DQ(13)
 263 M_G_CPU1_SB_DQ<14> DQ14_B @T6G_MB_LIB.T6G(SCH_1):M_G_CPU1_SB_DQ(14)
 265 M_G_CPU1_SB_DQ<15> DQ15_B @T6G_MB_LIB.T6G(SCH_1):M_G_CPU1_SB_DQ(15)
 122 M_G_CPU1_SB_DQ<16> DQ16_B @T6G_MB_LIB.T6G(SCH_1):M_G_CPU1_SB_DQ(16)
 124 M_G_CPU1_SB_DQ<17> DQ17_B @T6G_MB_LIB.T6G(SCH_1):M_G_CPU1_SB_DQ(17)
 267 M_G_CPU1_SB_DQ<18> DQ18_B @T6G_MB_LIB.T6G(SCH_1):M_G_CPU1_SB_DQ(18)
 269 M_G_CPU1_SB_DQ<19> DQ19_B @T6G_MB_LIB.T6G(SCH_1):M_G_CPU1_SB_DQ(19)
 129 M_G_CPU1_SB_DQ<20> DQ20_B @T6G_MB_LIB.T6G(SCH_1):M_G_CPU1_SB_DQ(20)
 131 M_G_CPU1_SB_DQ<21> DQ21_B @T6G_MB_LIB.T6G(SCH_1):M_G_CPU1_SB_DQ(21)
 274 M_G_CPU1_SB_DQ<22> DQ22_B @T6G_MB_LIB.T6G(SCH_1):M_G_CPU1_SB_DQ(22)
 276 M_G_CPU1_SB_DQ<23> DQ23_B @T6G_MB_LIB.T6G(SCH_1):M_G_CPU1_SB_DQ(23)
 133 M_G_CPU1_SB_DQ<24> DQ24_B @T6G_MB_LIB.T6G(SCH_1):M_G_CPU1_SB_DQ(24)
 135 M_G_CPU1_SB_DQ<25> DQ25_B @T6G_MB_LIB.T6G(SCH_1):M_G_CPU1_SB_DQ(25)
 278 M_G_CPU1_SB_DQ<26> DQ26_B @T6G_MB_LIB.T6G(SCH_1):M_G_CPU1_SB_DQ(26)
 280 M_G_CPU1_SB_DQ<27> DQ27_B @T6G_MB_LIB.T6G(SCH_1):M_G_CPU1_SB_DQ(27)
 140 M_G_CPU1_SB_DQ<28> DQ28_B @T6G_MB_LIB.T6G(SCH_1):M_G_CPU1_SB_DQ(28)
 142 M_G_CPU1_SB_DQ<29> DQ29_B @T6G_MB_LIB.T6G(SCH_1):M_G_CPU1_SB_DQ(29)
 285 M_G_CPU1_SB_DQ<30> DQ30_B @T6G_MB_LIB.T6G(SCH_1):M_G_CPU1_SB_DQ(30)
 287 M_G_CPU1_SB_DQ<31> DQ31_B @T6G_MB_LIB.T6G(SCH_1):M_G_CPU1_SB_DQ(31)
   7 M_G_CPU1_SA_DQ<0>  DQ0_A @T6G_MB_LIB.T6G(SCH_1):M_G_CPU1_SA_DQ(0)
   9 M_G_CPU1_SA_DQ<1>  DQ1_A @T6G_MB_LIB.T6G(SCH_1):M_G_CPU1_SA_DQ(1)
 152 M_G_CPU1_SA_DQ<2>  DQ2_A @T6G_MB_LIB.T6G(SCH_1):M_G_CPU1_SA_DQ(2)
 154 M_G_CPU1_SA_DQ<3>  DQ3_A @T6G_MB_LIB.T6G(SCH_1):M_G_CPU1_SA_DQ(3)
  14 M_G_CPU1_SA_DQ<4>  DQ4_A @T6G_MB_LIB.T6G(SCH_1):M_G_CPU1_SA_DQ(4)
  16 M_G_CPU1_SA_DQ<5>  DQ5_A @T6G_MB_LIB.T6G(SCH_1):M_G_CPU1_SA_DQ(5)
 159 M_G_CPU1_SA_DQ<6>  DQ6_A @T6G_MB_LIB.T6G(SCH_1):M_G_CPU1_SA_DQ(6)
 161 M_G_CPU1_SA_DQ<7>  DQ7_A @T6G_MB_LIB.T6G(SCH_1):M_G_CPU1_SA_DQ(7)
  18 M_G_CPU1_SA_DQ<8>  DQ8_A @T6G_MB_LIB.T6G(SCH_1):M_G_CPU1_SA_DQ(8)
  20 M_G_CPU1_SA_DQ<9>  DQ9_A @T6G_MB_LIB.T6G(SCH_1):M_G_CPU1_SA_DQ(9)
 163 M_G_CPU1_SA_DQ<10> DQ10_A @T6G_MB_LIB.T6G(SCH_1):M_G_CPU1_SA_DQ(10)
 165 M_G_CPU1_SA_DQ<11> DQ11_A @T6G_MB_LIB.T6G(SCH_1):M_G_CPU1_SA_DQ(11)
  25 M_G_CPU1_SA_DQ<12> DQ12_A @T6G_MB_LIB.T6G(SCH_1):M_G_CPU1_SA_DQ(12)
  27 M_G_CPU1_SA_DQ<13> DQ13_A @T6G_MB_LIB.T6G(SCH_1):M_G_CPU1_SA_DQ(13)
 170 M_G_CPU1_SA_DQ<14> DQ14_A @T6G_MB_LIB.T6G(SCH_1):M_G_CPU1_SA_DQ(14)
 172 M_G_CPU1_SA_DQ<15> DQ15_A @T6G_MB_LIB.T6G(SCH_1):M_G_CPU1_SA_DQ(15)
  29 M_G_CPU1_SA_DQ<16> DQ16_A @T6G_MB_LIB.T6G(SCH_1):M_G_CPU1_SA_DQ(16)
  31 M_G_CPU1_SA_DQ<17> DQ17_A @T6G_MB_LIB.T6G(SCH_1):M_G_CPU1_SA_DQ(17)
 174 M_G_CPU1_SA_DQ<18> DQ18_A @T6G_MB_LIB.T6G(SCH_1):M_G_CPU1_SA_DQ(18)
 176 M_G_CPU1_SA_DQ<19> DQ19_A @T6G_MB_LIB.T6G(SCH_1):M_G_CPU1_SA_DQ(19)
  36 M_G_CPU1_SA_DQ<20> DQ20_A @T6G_MB_LIB.T6G(SCH_1):M_G_CPU1_SA_DQ(20)
  38 M_G_CPU1_SA_DQ<21> DQ21_A @T6G_MB_LIB.T6G(SCH_1):M_G_CPU1_SA_DQ(21)
 181 M_G_CPU1_SA_DQ<22> DQ22_A @T6G_MB_LIB.T6G(SCH_1):M_G_CPU1_SA_DQ(22)
 183 M_G_CPU1_SA_DQ<23> DQ23_A @T6G_MB_LIB.T6G(SCH_1):M_G_CPU1_SA_DQ(23)
  40 M_G_CPU1_SA_DQ<24> DQ24_A @T6G_MB_LIB.T6G(SCH_1):M_G_CPU1_SA_DQ(24)
  42 M_G_CPU1_SA_DQ<25> DQ25_A @T6G_MB_LIB.T6G(SCH_1):M_G_CPU1_SA_DQ(25)
 185 M_G_CPU1_SA_DQ<26> DQ26_A @T6G_MB_LIB.T6G(SCH_1):M_G_CPU1_SA_DQ(26)
 187 M_G_CPU1_SA_DQ<27> DQ27_A @T6G_MB_LIB.T6G(SCH_1):M_G_CPU1_SA_DQ(27)
  47 M_G_CPU1_SA_DQ<28> DQ28_A @T6G_MB_LIB.T6G(SCH_1):M_G_CPU1_SA_DQ(28)
  49 M_G_CPU1_SA_DQ<29> DQ29_A @T6G_MB_LIB.T6G(SCH_1):M_G_CPU1_SA_DQ(29)
 192 M_G_CPU1_SA_DQ<30> DQ30_A @T6G_MB_LIB.T6G(SCH_1):M_G_CPU1_SA_DQ(30)
 229 M_G_CPU1_SB_CS_N<1> CS1_B_N @T6G_MB_LIB.T6G(SCH_1):M_G_CPU1_SB_CS_N(1)
 209 M_G_CPU1_SA_CS_N<1> CS1_A_N @T6G_MB_LIB.T6G(SCH_1):M_G_CPU1_SA_CS_N(1)
  84 M_G_CPU1_SB_CS_N<0> CS0_B_N @T6G_MB_LIB.T6G(SCH_1):M_G_CPU1_SB_CS_N(0)
  64 M_G_CPU1_SA_CS_N<0> CS0_A_N @T6G_MB_LIB.T6G(SCH_1):M_G_CPU1_SA_CS_N(0)
 217 M_G_CPU1_CLK_DP<0>   CK_T @T6G_MB_LIB.T6G(SCH_1):M_G_CPU1_CLK_DP(0)
 218 M_G_CPU1_CLK_DN<0>   CK_C @T6G_MB_LIB.T6G(SCH_1):M_G_CPU1_CLK_DN(0)
  96 M_G_CPU1_SB_CB<0>  CB0_B @T6G_MB_LIB.T6G(SCH_1):M_G_CPU1_SB_CB(0)
  98 M_G_CPU1_SB_CB<1>  CB1_B @T6G_MB_LIB.T6G(SCH_1):M_G_CPU1_SB_CB(1)
 241 M_G_CPU1_SB_CB<2>  CB2_B @T6G_MB_LIB.T6G(SCH_1):M_G_CPU1_SB_CB(2)
 243 M_G_CPU1_SB_CB<3>  CB3_B @T6G_MB_LIB.T6G(SCH_1):M_G_CPU1_SB_CB(3)
  89 M_G_CPU1_SB_CB<4>  CB4_B @T6G_MB_LIB.T6G(SCH_1):M_G_CPU1_SB_CB(4)
  91 M_G_CPU1_SB_CB<5>  CB5_B @T6G_MB_LIB.T6G(SCH_1):M_G_CPU1_SB_CB(5)
 234 M_G_CPU1_SB_CB<6>  CB6_B @T6G_MB_LIB.T6G(SCH_1):M_G_CPU1_SB_CB(6)
  51 M_G_CPU1_SA_CB<0>  CB0_A @T6G_MB_LIB.T6G(SCH_1):M_G_CPU1_SA_CB(0)
 196 M_G_CPU1_SA_CB<2>  CB2_A @T6G_MB_LIB.T6G(SCH_1):M_G_CPU1_SA_CB(2)
 198 M_G_CPU1_SA_CB<3>  CB3_A @T6G_MB_LIB.T6G(SCH_1):M_G_CPU1_SA_CB(3)
  60 M_G_CPU1_SA_CB<5>  CB5_A @T6G_MB_LIB.T6G(SCH_1):M_G_CPU1_SA_CB(5)
 203 M_G_CPU1_SA_CB<6>  CB6_A @T6G_MB_LIB.T6G(SCH_1):M_G_CPU1_SA_CB(6)
  82 M_G_CPU1_SB_CA<6>  CA6_B @T6G_MB_LIB.T6G(SCH_1):M_G_CPU1_SB_CA(6)
  72 M_G_CPU1_SA_CA<6>  CA6_A @T6G_MB_LIB.T6G(SCH_1):M_G_CPU1_SA_CA(6)
 225 M_G_CPU1_SB_CA<5>  CA5_B @T6G_MB_LIB.T6G(SCH_1):M_G_CPU1_SB_CA(5)
 215 M_G_CPU1_SA_CA<5>  CA5_A @T6G_MB_LIB.T6G(SCH_1):M_G_CPU1_SA_CA(5)
  80 M_G_CPU1_SB_CA<4>  CA4_B @T6G_MB_LIB.T6G(SCH_1):M_G_CPU1_SB_CA(4)
  70 M_G_CPU1_SA_CA<4>  CA4_A @T6G_MB_LIB.T6G(SCH_1):M_G_CPU1_SA_CA(4)
 223 M_G_CPU1_SB_CA<3>  CA3_B @T6G_MB_LIB.T6G(SCH_1):M_G_CPU1_SB_CA(3)
 213 M_G_CPU1_SA_CA<3>  CA3_A @T6G_MB_LIB.T6G(SCH_1):M_G_CPU1_SA_CA(3)
  78 M_G_CPU1_SB_CA<2>  CA2_B @T6G_MB_LIB.T6G(SCH_1):M_G_CPU1_SB_CA(2)
  68 M_G_CPU1_SA_CA<2>  CA2_A @T6G_MB_LIB.T6G(SCH_1):M_G_CPU1_SA_CA(2)
 221 M_G_CPU1_SB_CA<1>  CA1_B @T6G_MB_LIB.T6G(SCH_1):M_G_CPU1_SB_CA(1)
 211 M_G_CPU1_SA_CA<1>  CA1_A @T6G_MB_LIB.T6G(SCH_1):M_G_CPU1_SA_CA(1)
  76 M_G_CPU1_SB_CA<0>  CA0_B @T6G_MB_LIB.T6G(SCH_1):M_G_CPU1_SB_CA(0)
  66 M_G_CPU1_SA_CA<0>  CA0_A @T6G_MB_LIB.T6G(SCH_1):M_G_CPU1_SA_CA(0)
  62 M_G_CPU1_ALERT_N ALERT_N @T6G_MB_LIB.T6G(SCH_1):M_G_CPU1_ALERT_N
 236 M_G_CPU1_SB_CB<7>  CB7_B @T6G_MB_LIB.T6G(SCH_1):M_G_CPU1_SB_CB(7)
  53 M_G_CPU1_SA_CB<1>  CB1_A @T6G_MB_LIB.T6G(SCH_1):M_G_CPU1_SA_CB(1)
  58 M_G_CPU1_SA_CB<4>  CB4_A @T6G_MB_LIB.T6G(SCH_1):M_G_CPU1_SA_CB(4)
 205 M_G_CPU1_SA_CB<7>  CB7_A @T6G_MB_LIB.T6G(SCH_1):M_G_CPU1_SA_CB(7)
 194 M_G_CPU1_SA_DQ<31> DQ31_A @T6G_MB_LIB.T6G(SCH_1):M_G_CPU1_SA_DQ(31)

Q_RES_0402LF-10K,1%,1/16W,CHIP,CS31002FB08  I129  R37
   1 PD_CHG_CPU1_DIMM0_SAA      A @T6G_MB_LIB.T6G(SCH_1):PD_CHG_CPU1_DIMM0_SAA
   2    GND      B @T6G_MB_LIB.T6G(SCH_1):GND

SCONN288_DDR506112002KQ-SCONN288_DDR506112002KQ,SMA  I142  J102
   6    GND   VSS0 @T6G_MB_LIB.T6G(SCH_1):GND
   8    GND   VSS1 @T6G_MB_LIB.T6G(SCH_1):GND
  10    GND   VSS2 @T6G_MB_LIB.T6G(SCH_1):GND
  13    GND   VSS3 @T6G_MB_LIB.T6G(SCH_1):GND
  15    GND   VSS4 @T6G_MB_LIB.T6G(SCH_1):GND
  17    GND   VSS5 @T6G_MB_LIB.T6G(SCH_1):GND
  19    GND   VSS6 @T6G_MB_LIB.T6G(SCH_1):GND
  21    GND   VSS7 @T6G_MB_LIB.T6G(SCH_1):GND
  24    GND   VSS8 @T6G_MB_LIB.T6G(SCH_1):GND
  26    GND   VSS9 @T6G_MB_LIB.T6G(SCH_1):GND
  28    GND  VSS10 @T6G_MB_LIB.T6G(SCH_1):GND
  30    GND  VSS11 @T6G_MB_LIB.T6G(SCH_1):GND
  32    GND  VSS12 @T6G_MB_LIB.T6G(SCH_1):GND
  35    GND  VSS13 @T6G_MB_LIB.T6G(SCH_1):GND
  37    GND  VSS14 @T6G_MB_LIB.T6G(SCH_1):GND
  39    GND  VSS15 @T6G_MB_LIB.T6G(SCH_1):GND
  41    GND  VSS16 @T6G_MB_LIB.T6G(SCH_1):GND
  43    GND  VSS17 @T6G_MB_LIB.T6G(SCH_1):GND
  46    GND  VSS18 @T6G_MB_LIB.T6G(SCH_1):GND
  48    GND  VSS19 @T6G_MB_LIB.T6G(SCH_1):GND
  50    GND  VSS20 @T6G_MB_LIB.T6G(SCH_1):GND
  52    GND  VSS21 @T6G_MB_LIB.T6G(SCH_1):GND
  54    GND  VSS22 @T6G_MB_LIB.T6G(SCH_1):GND
  57    GND  VSS23 @T6G_MB_LIB.T6G(SCH_1):GND
  59    GND  VSS24 @T6G_MB_LIB.T6G(SCH_1):GND
  61    GND  VSS25 @T6G_MB_LIB.T6G(SCH_1):GND
  63    GND  VSS26 @T6G_MB_LIB.T6G(SCH_1):GND
  65    GND  VSS27 @T6G_MB_LIB.T6G(SCH_1):GND
  67    GND  VSS28 @T6G_MB_LIB.T6G(SCH_1):GND
  69    GND  VSS29 @T6G_MB_LIB.T6G(SCH_1):GND
  71    GND  VSS30 @T6G_MB_LIB.T6G(SCH_1):GND
  73    GND  VSS31 @T6G_MB_LIB.T6G(SCH_1):GND
  75    GND  VSS32 @T6G_MB_LIB.T6G(SCH_1):GND
  77    GND  VSS33 @T6G_MB_LIB.T6G(SCH_1):GND
  79    GND  VSS34 @T6G_MB_LIB.T6G(SCH_1):GND
  81    GND  VSS35 @T6G_MB_LIB.T6G(SCH_1):GND
  83    GND  VSS36 @T6G_MB_LIB.T6G(SCH_1):GND
  85    GND  VSS37 @T6G_MB_LIB.T6G(SCH_1):GND
  88    GND  VSS38 @T6G_MB_LIB.T6G(SCH_1):GND
  90    GND  VSS39 @T6G_MB_LIB.T6G(SCH_1):GND
  92    GND  VSS40 @T6G_MB_LIB.T6G(SCH_1):GND
  95    GND  VSS41 @T6G_MB_LIB.T6G(SCH_1):GND
  97    GND  VSS42 @T6G_MB_LIB.T6G(SCH_1):GND
  99    GND  VSS43 @T6G_MB_LIB.T6G(SCH_1):GND
 101    GND  VSS44 @T6G_MB_LIB.T6G(SCH_1):GND
 103    GND  VSS45 @T6G_MB_LIB.T6G(SCH_1):GND
 106    GND  VSS46 @T6G_MB_LIB.T6G(SCH_1):GND
 108    GND  VSS47 @T6G_MB_LIB.T6G(SCH_1):GND
 110    GND  VSS48 @T6G_MB_LIB.T6G(SCH_1):GND
 112    GND  VSS49 @T6G_MB_LIB.T6G(SCH_1):GND
 114    GND  VSS50 @T6G_MB_LIB.T6G(SCH_1):GND
 117    GND  VSS51 @T6G_MB_LIB.T6G(SCH_1):GND
 119    GND  VSS52 @T6G_MB_LIB.T6G(SCH_1):GND
 121    GND  VSS53 @T6G_MB_LIB.T6G(SCH_1):GND
 123    GND  VSS54 @T6G_MB_LIB.T6G(SCH_1):GND
 125    GND  VSS55 @T6G_MB_LIB.T6G(SCH_1):GND
 128    GND  VSS56 @T6G_MB_LIB.T6G(SCH_1):GND
 130    GND  VSS57 @T6G_MB_LIB.T6G(SCH_1):GND
 134    GND  VSS59 @T6G_MB_LIB.T6G(SCH_1):GND
 143    GND  VSS63 @T6G_MB_LIB.T6G(SCH_1):GND
 151    GND  VSS64 @T6G_MB_LIB.T6G(SCH_1):GND
 153    GND  VSS65 @T6G_MB_LIB.T6G(SCH_1):GND
 155    GND  VSS66 @T6G_MB_LIB.T6G(SCH_1):GND
 158    GND  VSS67 @T6G_MB_LIB.T6G(SCH_1):GND
 160    GND  VSS68 @T6G_MB_LIB.T6G(SCH_1):GND
 162    GND  VSS69 @T6G_MB_LIB.T6G(SCH_1):GND
 164    GND  VSS70 @T6G_MB_LIB.T6G(SCH_1):GND
 166    GND  VSS71 @T6G_MB_LIB.T6G(SCH_1):GND
 169    GND  VSS72 @T6G_MB_LIB.T6G(SCH_1):GND
 171    GND  VSS73 @T6G_MB_LIB.T6G(SCH_1):GND
 173    GND  VSS74 @T6G_MB_LIB.T6G(SCH_1):GND
 175    GND  VSS75 @T6G_MB_LIB.T6G(SCH_1):GND
 177    GND  VSS76 @T6G_MB_LIB.T6G(SCH_1):GND
 180    GND  VSS77 @T6G_MB_LIB.T6G(SCH_1):GND
 182    GND  VSS78 @T6G_MB_LIB.T6G(SCH_1):GND
 184    GND  VSS79 @T6G_MB_LIB.T6G(SCH_1):GND
 186    GND  VSS80 @T6G_MB_LIB.T6G(SCH_1):GND
 188    GND  VSS81 @T6G_MB_LIB.T6G(SCH_1):GND
 191    GND  VSS82 @T6G_MB_LIB.T6G(SCH_1):GND
 193    GND  VSS83 @T6G_MB_LIB.T6G(SCH_1):GND
 195    GND  VSS84 @T6G_MB_LIB.T6G(SCH_1):GND
 197    GND  VSS85 @T6G_MB_LIB.T6G(SCH_1):GND
 199    GND  VSS86 @T6G_MB_LIB.T6G(SCH_1):GND
 202    GND  VSS87 @T6G_MB_LIB.T6G(SCH_1):GND
 204    GND  VSS88 @T6G_MB_LIB.T6G(SCH_1):GND
 206    GND  VSS89 @T6G_MB_LIB.T6G(SCH_1):GND
 208    GND  VSS90 @T6G_MB_LIB.T6G(SCH_1):GND
 210    GND  VSS91 @T6G_MB_LIB.T6G(SCH_1):GND
 212    GND  VSS92 @T6G_MB_LIB.T6G(SCH_1):GND
 214    GND  VSS93 @T6G_MB_LIB.T6G(SCH_1):GND
 216    GND  VSS94 @T6G_MB_LIB.T6G(SCH_1):GND
 219    GND  VSS95 @T6G_MB_LIB.T6G(SCH_1):GND
 222    GND  VSS96 @T6G_MB_LIB.T6G(SCH_1):GND
 224    GND  VSS97 @T6G_MB_LIB.T6G(SCH_1):GND
 226    GND  VSS98 @T6G_MB_LIB.T6G(SCH_1):GND
 228    GND  VSS99 @T6G_MB_LIB.T6G(SCH_1):GND
 233    GND VSS101 @T6G_MB_LIB.T6G(SCH_1):GND
 237    GND VSS103 @T6G_MB_LIB.T6G(SCH_1):GND
 242    GND VSS105 @T6G_MB_LIB.T6G(SCH_1):GND
 244    GND VSS106 @T6G_MB_LIB.T6G(SCH_1):GND
 246    GND VSS107 @T6G_MB_LIB.T6G(SCH_1):GND
 248    GND VSS108 @T6G_MB_LIB.T6G(SCH_1):GND
 251    GND VSS109 @T6G_MB_LIB.T6G(SCH_1):GND
 253    GND VSS110 @T6G_MB_LIB.T6G(SCH_1):GND
 255    GND VSS111 @T6G_MB_LIB.T6G(SCH_1):GND
 257    GND VSS112 @T6G_MB_LIB.T6G(SCH_1):GND
 259    GND VSS113 @T6G_MB_LIB.T6G(SCH_1):GND
 262    GND VSS114 @T6G_MB_LIB.T6G(SCH_1):GND
 264    GND VSS115 @T6G_MB_LIB.T6G(SCH_1):GND
 266    GND VSS116 @T6G_MB_LIB.T6G(SCH_1):GND
 268    GND VSS117 @T6G_MB_LIB.T6G(SCH_1):GND
 270    GND VSS118 @T6G_MB_LIB.T6G(SCH_1):GND
 273    GND VSS119 @T6G_MB_LIB.T6G(SCH_1):GND
 275    GND VSS120 @T6G_MB_LIB.T6G(SCH_1):GND
 277    GND VSS121 @T6G_MB_LIB.T6G(SCH_1):GND
 279    GND VSS122 @T6G_MB_LIB.T6G(SCH_1):GND
 281    GND VSS123 @T6G_MB_LIB.T6G(SCH_1):GND
 284    GND VSS124 @T6G_MB_LIB.T6G(SCH_1):GND
 286    GND VSS125 @T6G_MB_LIB.T6G(SCH_1):GND
 288    GND VSS126 @T6G_MB_LIB.T6G(SCH_1):GND
   1 P12V_MEM_CPU1 VIN_BULK0 @T6G_MB_LIB.T6G(SCH_1):P12V_MEM_CPU1
 145 P12V_MEM_CPU1 VIN_BULK1 @T6G_MB_LIB.T6G(SCH_1):P12V_MEM_CPU1
 146 P12V_MEM_CPU1 VIN_BULK2 @T6G_MB_LIB.T6G(SCH_1):P12V_MEM_CPU1
 230    GND VSS100 @T6G_MB_LIB.T6G(SCH_1):GND
 235    GND VSS102 @T6G_MB_LIB.T6G(SCH_1):GND
 240    GND VSS104 @T6G_MB_LIB.T6G(SCH_1):GND
 132    GND  VSS58 @T6G_MB_LIB.T6G(SCH_1):GND
 136    GND  VSS60 @T6G_MB_LIB.T6G(SCH_1):GND
 139    GND  VSS61 @T6G_MB_LIB.T6G(SCH_1):GND
 141    GND  VSS62 @T6G_MB_LIB.T6G(SCH_1):GND
  G1    GND     G1 @T6G_MB_LIB.T6G(SCH_1):GND
  G2    GND     G2 @T6G_MB_LIB.T6G(SCH_1):GND
  G3    GND     G3 @T6G_MB_LIB.T6G(SCH_1):GND

Q_CAP_0402-0.1UF,25V,10%,X7R,CH4104K1B00  I185  C160
   1 P3V3_AUX      A @T6G_MB_LIB.T6G(SCH_1):P3V3_AUX
   2    GND      B @T6G_MB_LIB.T6G(SCH_1):GND

Q_RES_0402LF-1K,1%,1/16W,CHIP,CS21002FB06  I188  R1184
   1 PWRGD_CHG_CPU1_DIMM0      A @T6G_MB_LIB.T6G(SCH_1):PWRGD_CHG_CPU1_DIMM0
   2 PWRGD_CHGL_CPU1      B @T6G_MB_LIB.T6G(SCH_1):PWRGD_CHGL_CPU1

Q_RES_0402LF-1K,1%,1/16W,EMPTY,CS21002FB06  I189  R109
   1   P3V3      A @T6G_MB_LIB.T6G(SCH_1):P3V3
   2 PWRGD_CHGL_CPU1      B @T6G_MB_LIB.T6G(SCH_1):PWRGD_CHGL_CPU1

Q_RES_0402LF-1K,1%,1/16W,EMPTY,CS21002FB06  I192  R110
   1   P3V3      A @T6G_MB_LIB.T6G(SCH_1):P3V3
   2 PWRGD_CHG_CPU1_DIMM0      B @T6G_MB_LIB.T6G(SCH_1):PWRGD_CHG_CPU1_DIMM0

SCONN288_DDR506112002KQ-SCONN288_DDR506112002KQ,SMA  I238  J102
  93 M_G_CPU1_SB_DQS_DP<9> DQS9_B_T||TDQS9_B_T||DBI4_B_N @T6G_MB_LIB.T6G(SCH_1):M_G_CPU1_SB_DQS_DP(9)
  94 M_G_CPU1_SB_DQS_DN<9> DQS9_B_C||TDQS9_B_C @T6G_MB_LIB.T6G(SCH_1):M_G_CPU1_SB_DQS_DN(9)
 201 M_G_CPU1_SA_DQS_DP<9> DQS9_A_T||TDQS9_A_T @T6G_MB_LIB.T6G(SCH_1):M_G_CPU1_SA_DQS_DP(9)
 200 M_G_CPU1_SA_DQS_DN<9> DQS9_A_C||TDQS9_A_C @T6G_MB_LIB.T6G(SCH_1):M_G_CPU1_SA_DQS_DN(9)
 190 M_G_CPU1_SA_DQS_DP<8> DQS8_A_T||TDQS8_A_T @T6G_MB_LIB.T6G(SCH_1):M_G_CPU1_SA_DQS_DP(8)
 189 M_G_CPU1_SA_DQS_DN<8> DQS8_A_C||TDQS8_A_C @T6G_MB_LIB.T6G(SCH_1):M_G_CPU1_SA_DQS_DN(8)
 271 M_G_CPU1_SB_DQS_DN<7> DQS7_B_C||TDQS7_B_C @T6G_MB_LIB.T6G(SCH_1):M_G_CPU1_SB_DQS_DN(7)
 179 M_G_CPU1_SA_DQS_DP<7> DQS7_A_T||TDQS7_A_T @T6G_MB_LIB.T6G(SCH_1):M_G_CPU1_SA_DQS_DP(7)
 261 M_G_CPU1_SB_DQS_DP<6> DQS6_B_T||TDQS6_B_T @T6G_MB_LIB.T6G(SCH_1):M_G_CPU1_SB_DQS_DP(6)
 260 M_G_CPU1_SB_DQS_DN<6> DQS6_B_C||TDQS6_B_C @T6G_MB_LIB.T6G(SCH_1):M_G_CPU1_SB_DQS_DN(6)
 167 M_G_CPU1_SA_DQS_DN<6> DQS6_A_C||TDQS6_A_C||DQS6_A_T||TDQS6_A_T @T6G_MB_LIB.T6G(SCH_1):M_G_CPU1_SA_DQS_DN(6)
 250 M_G_CPU1_SB_DQS_DP<5> DQS5_B_T||TDQS5_B_T @T6G_MB_LIB.T6G(SCH_1):M_G_CPU1_SB_DQS_DP(5)
 249 M_G_CPU1_SB_DQS_DN<5> DQS5_B_C||TDQS5_B_C @T6G_MB_LIB.T6G(SCH_1):M_G_CPU1_SB_DQS_DN(5)
 157 M_G_CPU1_SA_DQS_DP<5> DQS5_A_T||TDQS5_A_T @T6G_MB_LIB.T6G(SCH_1):M_G_CPU1_SA_DQS_DP(5)
 156 M_G_CPU1_SA_DQS_DN<5> DQS5_A_C||TDQS5_A_C||DQS5_A_T||TDQS5_A_T @T6G_MB_LIB.T6G(SCH_1):M_G_CPU1_SA_DQS_DN(5)
 239 M_G_CPU1_SB_DQS_DP<4> DQS4_B_T @T6G_MB_LIB.T6G(SCH_1):M_G_CPU1_SB_DQS_DP(4)
 238 M_G_CPU1_SB_DQS_DN<4> DQS4_B_C @T6G_MB_LIB.T6G(SCH_1):M_G_CPU1_SB_DQS_DN(4)
  55 M_G_CPU1_SA_DQS_DP<4> DQS4_A_T @T6G_MB_LIB.T6G(SCH_1):M_G_CPU1_SA_DQS_DP(4)
  56 M_G_CPU1_SA_DQS_DN<4> DQS4_A_C @T6G_MB_LIB.T6G(SCH_1):M_G_CPU1_SA_DQS_DN(4)
 137 M_G_CPU1_SB_DQS_DP<3> DQS3_B_T @T6G_MB_LIB.T6G(SCH_1):M_G_CPU1_SB_DQS_DP(3)
 138 M_G_CPU1_SB_DQS_DN<3> DQS3_B_C @T6G_MB_LIB.T6G(SCH_1):M_G_CPU1_SB_DQS_DN(3)
  44 M_G_CPU1_SA_DQS_DP<3> DQS3_A_T @T6G_MB_LIB.T6G(SCH_1):M_G_CPU1_SA_DQS_DP(3)
  45 M_G_CPU1_SA_DQS_DN<3> DQS3_A_C @T6G_MB_LIB.T6G(SCH_1):M_G_CPU1_SA_DQS_DN(3)
 126 M_G_CPU1_SB_DQS_DP<2> DQS2_B_T @T6G_MB_LIB.T6G(SCH_1):M_G_CPU1_SB_DQS_DP(2)
 127 M_G_CPU1_SB_DQS_DN<2> DQS2_B_C @T6G_MB_LIB.T6G(SCH_1):M_G_CPU1_SB_DQS_DN(2)
  33 M_G_CPU1_SA_DQS_DP<2> DQS2_A_T @T6G_MB_LIB.T6G(SCH_1):M_G_CPU1_SA_DQS_DP(2)
  34 M_G_CPU1_SA_DQS_DN<2> DQS2_A_C @T6G_MB_LIB.T6G(SCH_1):M_G_CPU1_SA_DQS_DN(2)
 115 M_G_CPU1_SB_DQS_DP<1> DQS1_B_T @T6G_MB_LIB.T6G(SCH_1):M_G_CPU1_SB_DQS_DP(1)
 116 M_G_CPU1_SB_DQS_DN<1> DQS1_B_C @T6G_MB_LIB.T6G(SCH_1):M_G_CPU1_SB_DQS_DN(1)
  22 M_G_CPU1_SA_DQS_DP<1> DQS1_A_T @T6G_MB_LIB.T6G(SCH_1):M_G_CPU1_SA_DQS_DP(1)
  23 M_G_CPU1_SA_DQS_DN<1> DQS1_A_C @T6G_MB_LIB.T6G(SCH_1):M_G_CPU1_SA_DQS_DN(1)
 104 M_G_CPU1_SB_DQS_DP<0> DQS0_B_T @T6G_MB_LIB.T6G(SCH_1):M_G_CPU1_SB_DQS_DP(0)
 105 M_G_CPU1_SB_DQS_DN<0> DQS0_B_C @T6G_MB_LIB.T6G(SCH_1):M_G_CPU1_SB_DQS_DN(0)
  11 M_G_CPU1_SA_DQS_DP<0> DQS0_A_T @T6G_MB_LIB.T6G(SCH_1):M_G_CPU1_SA_DQS_DP(0)
  12 M_G_CPU1_SA_DQS_DN<0> DQS0_A_C @T6G_MB_LIB.T6G(SCH_1):M_G_CPU1_SA_DQS_DN(0)
 272 M_G_CPU1_SB_DQS_DP<7> DQS7_B_T||TDQS7_B_T @T6G_MB_LIB.T6G(SCH_1):M_G_CPU1_SB_DQS_DP(7)
 282 M_G_CPU1_SB_DQS_DN<8> DQS8_B_C||TDQS8_B_C @T6G_MB_LIB.T6G(SCH_1):M_G_CPU1_SB_DQS_DN(8)
 283 M_G_CPU1_SB_DQS_DP<8> DQS8_B_T||TDQS8_B_T @T6G_MB_LIB.T6G(SCH_1):M_G_CPU1_SB_DQS_DP(8)
 168 M_G_CPU1_SA_DQS_DP<6> DQS6_A_T||TDQS6_A_T @T6G_MB_LIB.T6G(SCH_1):M_G_CPU1_SA_DQS_DP(6)
 178 M_G_CPU1_SA_DQS_DN<7> DQS7_A_C||TDQS7_A_C @T6G_MB_LIB.T6G(SCH_1):M_G_CPU1_SA_DQS_DN(7)

Q_CAP_C0805-10UF,25V,10%,X6S,CH6104KEA00  I240  C530
   1 P12V_MEM_CPU1      A @T6G_MB_LIB.T6G(SCH_1):P12V_MEM_CPU1
   2    GND      B @T6G_MB_LIB.T6G(SCH_1):GND

Q_CAP_C0805-10UF,25V,10%,X6S,CH6104KEA00  I241  C531
   1 P12V_MEM_CPU1      A @T6G_MB_LIB.T6G(SCH_1):P12V_MEM_CPU1
   2    GND      B @T6G_MB_LIB.T6G(SCH_1):GND

Q_RES_0402LF-49.9,1%,1/16W,CHIP,CS04992FB07  I244  R1586
   1 I3C_SPD_DDRGL_CPU1_SCL      A @T6G_MB_LIB.T6G(SCH_1):I3C_SPD_DDRGL_CPU1_SCL
   2 I3C_SPD_DDRG_CPU1_SCL      B @T6G_MB_LIB.T6G(SCH_1):I3C_SPD_DDRG_CPU1_SCL

Q_RES_0402LF-10K,1%,1/16W,CHIP,CS31002FB08  I245  R8040
   1 P3V3_AUX      A @T6G_MB_LIB.T6G(SCH_1):P3V3_AUX
   2 PWRGD_CHGL_CPU1      B @T6G_MB_LIB.T6G(SCH_1):PWRGD_CHGL_CPU1

Q_RES_0402LF-0,5%,1/16W,CHIP,CS00002JB13  I249  R8089
   1 PWRGD_CHGL_CPU1      A @T6G_MB_LIB.T6G(SCH_1):PWRGD_CHGL_CPU1
   2 PWRGD_CHGL_CPU1_R1      B @T6G_MB_LIB.T6G(SCH_1):PWRGD_CHGL_CPU1_R1

Q_RES_0402LF-10K,1%,1/16W,EMPTY,CS31002FB08  I251  R8091
   1 P3V3_AUX      A @T6G_MB_LIB.T6G(SCH_1):P3V3_AUX
   2 PWRGD_CHGL_CPU1_R1      B @T6G_MB_LIB.T6G(SCH_1):PWRGD_CHGL_CPU1_R1

Q_RES_0402LF-0,5%,1/16W,CHIP,CS00002JB13  I252  R8090
   1 PWRGD_CHGL_CPU1_R1      A @T6G_MB_LIB.T6G(SCH_1):PWRGD_CHGL_CPU1_R1
   2 PWRGD_CHGL_CPU1_R2      B @T6G_MB_LIB.T6G(SCH_1):PWRGD_CHGL_CPU1_R2

SCHOTTKY_12-B0530WS7F,SMLF,EMPTY,BC000530Z41  I253  D8006
   1 PWRGD_CHGL_CPU1_R1      A @T6G_MB_LIB.T6G(SCH_1):PWRGD_CHGL_CPU1_R1
   2 P3V3_AUX      C @T6G_MB_LIB.T6G(SCH_1):P3V3_AUX

Q_RES_0402LF-10,1%,1/16W,CHIP,CS01002FB07  I256  R1705
   1 I3C_SPD_DDRGL_CPU1_SDA      A @T6G_MB_LIB.T6G(SCH_1):I3C_SPD_DDRGL_CPU1_SDA
   2 I3C_SPD_DDRG_CPU1_SDA      B @T6G_MB_LIB.T6G(SCH_1):I3C_SPD_DDRG_CPU1_SDA


DRAWING: @T6G_MB_LIB.T6G(SCH_1):PAGE104 

SCONN288_DDR506112002KQ-SCONN288_DDR506112002KQ,SMA  I22  J27
   3 P3V3_AUX VIN_MGMT @T6G_MB_LIB.T6G(SCH_1):P3V3_AUX
   2     NC   RFU0     NC
 144     NC   RFU1     NC
 149     NC   RFU2     NC
 150     NC   RFU3     NC
 220     NC   RFU4     NC
 231     NC   RFU5     NC
 232     NC   RFU6     NC
 207 M_H_CPU1_RESET_N RESET_N @T6G_MB_LIB.T6G(SCH_1):M_H_CPU1_RESET_N
 147 PWRGD_CHH_CPU1_DIMM PWR_GOOD||FAIL_N @T6G_MB_LIB.T6G(SCH_1):PWRGD_CHH_CPU1_DIMM
 227 M_H_CPU1_SB_PAR  PAR_B @T6G_MB_LIB.T6G(SCH_1):M_H_CPU1_SB_PAR
  74 M_H_CPU1_SA_PAR  PAR_A @T6G_MB_LIB.T6G(SCH_1):M_H_CPU1_SA_PAR
  87 M_H_CPU1_SB_RSP<0> LBS||RSP_B_N @T6G_MB_LIB.T6G(SCH_1):M_H_CPU1_SB_RSP(0)
  86 M_H_CPU1_SA_RSP<0> LBD||RSP_A_N @T6G_MB_LIB.T6G(SCH_1):M_H_CPU1_SA_RSP(0)
   5 I3C_SPD_DDRH_CPU1_SDA   HSDA @T6G_MB_LIB.T6G(SCH_1):I3C_SPD_DDRH_CPU1_SDA
   4 I3C_SPD_DDRH_CPU1_SCL   HSCL @T6G_MB_LIB.T6G(SCH_1):I3C_SPD_DDRH_CPU1_SCL
 148 PD_CHH_CPU1_DIMM_SAA    HAS @T6G_MB_LIB.T6G(SCH_1):PD_CHH_CPU1_DIMM_SAA
 100 M_H_CPU1_SB_DQ<0>  DQ0_B @T6G_MB_LIB.T6G(SCH_1):M_H_CPU1_SB_DQ(0)
 102 M_H_CPU1_SB_DQ<1>  DQ1_B @T6G_MB_LIB.T6G(SCH_1):M_H_CPU1_SB_DQ(1)
 245 M_H_CPU1_SB_DQ<2>  DQ2_B @T6G_MB_LIB.T6G(SCH_1):M_H_CPU1_SB_DQ(2)
 247 M_H_CPU1_SB_DQ<3>  DQ3_B @T6G_MB_LIB.T6G(SCH_1):M_H_CPU1_SB_DQ(3)
 107 M_H_CPU1_SB_DQ<4>  DQ4_B @T6G_MB_LIB.T6G(SCH_1):M_H_CPU1_SB_DQ(4)
 109 M_H_CPU1_SB_DQ<5>  DQ5_B @T6G_MB_LIB.T6G(SCH_1):M_H_CPU1_SB_DQ(5)
 252 M_H_CPU1_SB_DQ<6>  DQ6_B @T6G_MB_LIB.T6G(SCH_1):M_H_CPU1_SB_DQ(6)
 254 M_H_CPU1_SB_DQ<7>  DQ7_B @T6G_MB_LIB.T6G(SCH_1):M_H_CPU1_SB_DQ(7)
 111 M_H_CPU1_SB_DQ<8>  DQ8_B @T6G_MB_LIB.T6G(SCH_1):M_H_CPU1_SB_DQ(8)
 113 M_H_CPU1_SB_DQ<9>  DQ9_B @T6G_MB_LIB.T6G(SCH_1):M_H_CPU1_SB_DQ(9)
 256 M_H_CPU1_SB_DQ<10> DQ10_B @T6G_MB_LIB.T6G(SCH_1):M_H_CPU1_SB_DQ(10)
 258 M_H_CPU1_SB_DQ<11> DQ11_B @T6G_MB_LIB.T6G(SCH_1):M_H_CPU1_SB_DQ(11)
 118 M_H_CPU1_SB_DQ<12> DQ12_B @T6G_MB_LIB.T6G(SCH_1):M_H_CPU1_SB_DQ(12)
 120 M_H_CPU1_SB_DQ<13> DQ13_B @T6G_MB_LIB.T6G(SCH_1):M_H_CPU1_SB_DQ(13)
 263 M_H_CPU1_SB_DQ<14> DQ14_B @T6G_MB_LIB.T6G(SCH_1):M_H_CPU1_SB_DQ(14)
 265 M_H_CPU1_SB_DQ<15> DQ15_B @T6G_MB_LIB.T6G(SCH_1):M_H_CPU1_SB_DQ(15)
 122 M_H_CPU1_SB_DQ<16> DQ16_B @T6G_MB_LIB.T6G(SCH_1):M_H_CPU1_SB_DQ(16)
 124 M_H_CPU1_SB_DQ<17> DQ17_B @T6G_MB_LIB.T6G(SCH_1):M_H_CPU1_SB_DQ(17)
 267 M_H_CPU1_SB_DQ<18> DQ18_B @T6G_MB_LIB.T6G(SCH_1):M_H_CPU1_SB_DQ(18)
 269 M_H_CPU1_SB_DQ<19> DQ19_B @T6G_MB_LIB.T6G(SCH_1):M_H_CPU1_SB_DQ(19)
 129 M_H_CPU1_SB_DQ<20> DQ20_B @T6G_MB_LIB.T6G(SCH_1):M_H_CPU1_SB_DQ(20)
 131 M_H_CPU1_SB_DQ<21> DQ21_B @T6G_MB_LIB.T6G(SCH_1):M_H_CPU1_SB_DQ(21)
 274 M_H_CPU1_SB_DQ<22> DQ22_B @T6G_MB_LIB.T6G(SCH_1):M_H_CPU1_SB_DQ(22)
 276 M_H_CPU1_SB_DQ<23> DQ23_B @T6G_MB_LIB.T6G(SCH_1):M_H_CPU1_SB_DQ(23)
 133 M_H_CPU1_SB_DQ<24> DQ24_B @T6G_MB_LIB.T6G(SCH_1):M_H_CPU1_SB_DQ(24)
 135 M_H_CPU1_SB_DQ<25> DQ25_B @T6G_MB_LIB.T6G(SCH_1):M_H_CPU1_SB_DQ(25)
 278 M_H_CPU1_SB_DQ<26> DQ26_B @T6G_MB_LIB.T6G(SCH_1):M_H_CPU1_SB_DQ(26)
 280 M_H_CPU1_SB_DQ<27> DQ27_B @T6G_MB_LIB.T6G(SCH_1):M_H_CPU1_SB_DQ(27)
 140 M_H_CPU1_SB_DQ<28> DQ28_B @T6G_MB_LIB.T6G(SCH_1):M_H_CPU1_SB_DQ(28)
 142 M_H_CPU1_SB_DQ<29> DQ29_B @T6G_MB_LIB.T6G(SCH_1):M_H_CPU1_SB_DQ(29)
 285 M_H_CPU1_SB_DQ<30> DQ30_B @T6G_MB_LIB.T6G(SCH_1):M_H_CPU1_SB_DQ(30)
 287 M_H_CPU1_SB_DQ<31> DQ31_B @T6G_MB_LIB.T6G(SCH_1):M_H_CPU1_SB_DQ(31)
   7 M_H_CPU1_SA_DQ<0>  DQ0_A @T6G_MB_LIB.T6G(SCH_1):M_H_CPU1_SA_DQ(0)
   9 M_H_CPU1_SA_DQ<1>  DQ1_A @T6G_MB_LIB.T6G(SCH_1):M_H_CPU1_SA_DQ(1)
 152 M_H_CPU1_SA_DQ<2>  DQ2_A @T6G_MB_LIB.T6G(SCH_1):M_H_CPU1_SA_DQ(2)
 154 M_H_CPU1_SA_DQ<3>  DQ3_A @T6G_MB_LIB.T6G(SCH_1):M_H_CPU1_SA_DQ(3)
  14 M_H_CPU1_SA_DQ<4>  DQ4_A @T6G_MB_LIB.T6G(SCH_1):M_H_CPU1_SA_DQ(4)
  16 M_H_CPU1_SA_DQ<5>  DQ5_A @T6G_MB_LIB.T6G(SCH_1):M_H_CPU1_SA_DQ(5)
 159 M_H_CPU1_SA_DQ<6>  DQ6_A @T6G_MB_LIB.T6G(SCH_1):M_H_CPU1_SA_DQ(6)
 161 M_H_CPU1_SA_DQ<7>  DQ7_A @T6G_MB_LIB.T6G(SCH_1):M_H_CPU1_SA_DQ(7)
  18 M_H_CPU1_SA_DQ<8>  DQ8_A @T6G_MB_LIB.T6G(SCH_1):M_H_CPU1_SA_DQ(8)
  20 M_H_CPU1_SA_DQ<9>  DQ9_A @T6G_MB_LIB.T6G(SCH_1):M_H_CPU1_SA_DQ(9)
 163 M_H_CPU1_SA_DQ<10> DQ10_A @T6G_MB_LIB.T6G(SCH_1):M_H_CPU1_SA_DQ(10)
 165 M_H_CPU1_SA_DQ<11> DQ11_A @T6G_MB_LIB.T6G(SCH_1):M_H_CPU1_SA_DQ(11)
  25 M_H_CPU1_SA_DQ<12> DQ12_A @T6G_MB_LIB.T6G(SCH_1):M_H_CPU1_SA_DQ(12)
  27 M_H_CPU1_SA_DQ<13> DQ13_A @T6G_MB_LIB.T6G(SCH_1):M_H_CPU1_SA_DQ(13)
 170 M_H_CPU1_SA_DQ<14> DQ14_A @T6G_MB_LIB.T6G(SCH_1):M_H_CPU1_SA_DQ(14)
 172 M_H_CPU1_SA_DQ<15> DQ15_A @T6G_MB_LIB.T6G(SCH_1):M_H_CPU1_SA_DQ(15)
  29 M_H_CPU1_SA_DQ<16> DQ16_A @T6G_MB_LIB.T6G(SCH_1):M_H_CPU1_SA_DQ(16)
  31 M_H_CPU1_SA_DQ<17> DQ17_A @T6G_MB_LIB.T6G(SCH_1):M_H_CPU1_SA_DQ(17)
 174 M_H_CPU1_SA_DQ<18> DQ18_A @T6G_MB_LIB.T6G(SCH_1):M_H_CPU1_SA_DQ(18)
 176 M_H_CPU1_SA_DQ<19> DQ19_A @T6G_MB_LIB.T6G(SCH_1):M_H_CPU1_SA_DQ(19)
  36 M_H_CPU1_SA_DQ<20> DQ20_A @T6G_MB_LIB.T6G(SCH_1):M_H_CPU1_SA_DQ(20)
  38 M_H_CPU1_SA_DQ<21> DQ21_A @T6G_MB_LIB.T6G(SCH_1):M_H_CPU1_SA_DQ(21)
 181 M_H_CPU1_SA_DQ<22> DQ22_A @T6G_MB_LIB.T6G(SCH_1):M_H_CPU1_SA_DQ(22)
 183 M_H_CPU1_SA_DQ<23> DQ23_A @T6G_MB_LIB.T6G(SCH_1):M_H_CPU1_SA_DQ(23)
  40 M_H_CPU1_SA_DQ<24> DQ24_A @T6G_MB_LIB.T6G(SCH_1):M_H_CPU1_SA_DQ(24)
  42 M_H_CPU1_SA_DQ<25> DQ25_A @T6G_MB_LIB.T6G(SCH_1):M_H_CPU1_SA_DQ(25)
 185 M_H_CPU1_SA_DQ<26> DQ26_A @T6G_MB_LIB.T6G(SCH_1):M_H_CPU1_SA_DQ(26)
 187 M_H_CPU1_SA_DQ<27> DQ27_A @T6G_MB_LIB.T6G(SCH_1):M_H_CPU1_SA_DQ(27)
  47 M_H_CPU1_SA_DQ<28> DQ28_A @T6G_MB_LIB.T6G(SCH_1):M_H_CPU1_SA_DQ(28)
  49 M_H_CPU1_SA_DQ<29> DQ29_A @T6G_MB_LIB.T6G(SCH_1):M_H_CPU1_SA_DQ(29)
 192 M_H_CPU1_SA_DQ<30> DQ30_A @T6G_MB_LIB.T6G(SCH_1):M_H_CPU1_SA_DQ(30)
 229 M_H_CPU1_SB_CS_N<1> CS1_B_N @T6G_MB_LIB.T6G(SCH_1):M_H_CPU1_SB_CS_N(1)
 209 M_H_CPU1_SA_CS_N<1> CS1_A_N @T6G_MB_LIB.T6G(SCH_1):M_H_CPU1_SA_CS_N(1)
  84 M_H_CPU1_SB_CS_N<0> CS0_B_N @T6G_MB_LIB.T6G(SCH_1):M_H_CPU1_SB_CS_N(0)
  64 M_H_CPU1_SA_CS_N<0> CS0_A_N @T6G_MB_LIB.T6G(SCH_1):M_H_CPU1_SA_CS_N(0)
 217 M_H_CPU1_CLK_DP<0>   CK_T @T6G_MB_LIB.T6G(SCH_1):M_H_CPU1_CLK_DP(0)
 218 M_H_CPU1_CLK_DN<0>   CK_C @T6G_MB_LIB.T6G(SCH_1):M_H_CPU1_CLK_DN(0)
  96 M_H_CPU1_SB_CB<0>  CB0_B @T6G_MB_LIB.T6G(SCH_1):M_H_CPU1_SB_CB(0)
  98 M_H_CPU1_SB_CB<1>  CB1_B @T6G_MB_LIB.T6G(SCH_1):M_H_CPU1_SB_CB(1)
 241 M_H_CPU1_SB_CB<2>  CB2_B @T6G_MB_LIB.T6G(SCH_1):M_H_CPU1_SB_CB(2)
 243 M_H_CPU1_SB_CB<3>  CB3_B @T6G_MB_LIB.T6G(SCH_1):M_H_CPU1_SB_CB(3)
  89 M_H_CPU1_SB_CB<4>  CB4_B @T6G_MB_LIB.T6G(SCH_1):M_H_CPU1_SB_CB(4)
  91 M_H_CPU1_SB_CB<5>  CB5_B @T6G_MB_LIB.T6G(SCH_1):M_H_CPU1_SB_CB(5)
 234 M_H_CPU1_SB_CB<6>  CB6_B @T6G_MB_LIB.T6G(SCH_1):M_H_CPU1_SB_CB(6)
  51 M_H_CPU1_SA_CB<0>  CB0_A @T6G_MB_LIB.T6G(SCH_1):M_H_CPU1_SA_CB(0)
 196 M_H_CPU1_SA_CB<2>  CB2_A @T6G_MB_LIB.T6G(SCH_1):M_H_CPU1_SA_CB(2)
 198 M_H_CPU1_SA_CB<3>  CB3_A @T6G_MB_LIB.T6G(SCH_1):M_H_CPU1_SA_CB(3)
  60 M_H_CPU1_SA_CB<5>  CB5_A @T6G_MB_LIB.T6G(SCH_1):M_H_CPU1_SA_CB(5)
 203 M_H_CPU1_SA_CB<6>  CB6_A @T6G_MB_LIB.T6G(SCH_1):M_H_CPU1_SA_CB(6)
  82 M_H_CPU1_SB_CA<6>  CA6_B @T6G_MB_LIB.T6G(SCH_1):M_H_CPU1_SB_CA(6)
  72 M_H_CPU1_SA_CA<6>  CA6_A @T6G_MB_LIB.T6G(SCH_1):M_H_CPU1_SA_CA(6)
 225 M_H_CPU1_SB_CA<5>  CA5_B @T6G_MB_LIB.T6G(SCH_1):M_H_CPU1_SB_CA(5)
 215 M_H_CPU1_SA_CA<5>  CA5_A @T6G_MB_LIB.T6G(SCH_1):M_H_CPU1_SA_CA(5)
  80 M_H_CPU1_SB_CA<4>  CA4_B @T6G_MB_LIB.T6G(SCH_1):M_H_CPU1_SB_CA(4)
  70 M_H_CPU1_SA_CA<4>  CA4_A @T6G_MB_LIB.T6G(SCH_1):M_H_CPU1_SA_CA(4)
 223 M_H_CPU1_SB_CA<3>  CA3_B @T6G_MB_LIB.T6G(SCH_1):M_H_CPU1_SB_CA(3)
 213 M_H_CPU1_SA_CA<3>  CA3_A @T6G_MB_LIB.T6G(SCH_1):M_H_CPU1_SA_CA(3)
  78 M_H_CPU1_SB_CA<2>  CA2_B @T6G_MB_LIB.T6G(SCH_1):M_H_CPU1_SB_CA(2)
  68 M_H_CPU1_SA_CA<2>  CA2_A @T6G_MB_LIB.T6G(SCH_1):M_H_CPU1_SA_CA(2)
 221 M_H_CPU1_SB_CA<1>  CA1_B @T6G_MB_LIB.T6G(SCH_1):M_H_CPU1_SB_CA(1)
 211 M_H_CPU1_SA_CA<1>  CA1_A @T6G_MB_LIB.T6G(SCH_1):M_H_CPU1_SA_CA(1)
  76 M_H_CPU1_SB_CA<0>  CA0_B @T6G_MB_LIB.T6G(SCH_1):M_H_CPU1_SB_CA(0)
  66 M_H_CPU1_SA_CA<0>  CA0_A @T6G_MB_LIB.T6G(SCH_1):M_H_CPU1_SA_CA(0)
  62 M_H_CPU1_ALERT_N ALERT_N @T6G_MB_LIB.T6G(SCH_1):M_H_CPU1_ALERT_N
 236 M_H_CPU1_SB_CB<7>  CB7_B @T6G_MB_LIB.T6G(SCH_1):M_H_CPU1_SB_CB(7)
  53 M_H_CPU1_SA_CB<1>  CB1_A @T6G_MB_LIB.T6G(SCH_1):M_H_CPU1_SA_CB(1)
  58 M_H_CPU1_SA_CB<4>  CB4_A @T6G_MB_LIB.T6G(SCH_1):M_H_CPU1_SA_CB(4)
 205 M_H_CPU1_SA_CB<7>  CB7_A @T6G_MB_LIB.T6G(SCH_1):M_H_CPU1_SA_CB(7)
 194 M_H_CPU1_SA_DQ<31> DQ31_A @T6G_MB_LIB.T6G(SCH_1):M_H_CPU1_SA_DQ(31)

Q_RES_0402LF-15.4K,1%,1/16W,CHIP,CS31542FB02  I128  R774
   1 PD_CHH_CPU1_DIMM_SAA      A @T6G_MB_LIB.T6G(SCH_1):PD_CHH_CPU1_DIMM_SAA
   2    GND      B @T6G_MB_LIB.T6G(SCH_1):GND

SCONN288_DDR506112002KQ-SCONN288_DDR506112002KQ,SMA  I174  J27
   6    GND   VSS0 @T6G_MB_LIB.T6G(SCH_1):GND
   8    GND   VSS1 @T6G_MB_LIB.T6G(SCH_1):GND
  10    GND   VSS2 @T6G_MB_LIB.T6G(SCH_1):GND
  13    GND   VSS3 @T6G_MB_LIB.T6G(SCH_1):GND
  15    GND   VSS4 @T6G_MB_LIB.T6G(SCH_1):GND
  17    GND   VSS5 @T6G_MB_LIB.T6G(SCH_1):GND
  19    GND   VSS6 @T6G_MB_LIB.T6G(SCH_1):GND
  21    GND   VSS7 @T6G_MB_LIB.T6G(SCH_1):GND
  24    GND   VSS8 @T6G_MB_LIB.T6G(SCH_1):GND
  26    GND   VSS9 @T6G_MB_LIB.T6G(SCH_1):GND
  28    GND  VSS10 @T6G_MB_LIB.T6G(SCH_1):GND
  30    GND  VSS11 @T6G_MB_LIB.T6G(SCH_1):GND
  32    GND  VSS12 @T6G_MB_LIB.T6G(SCH_1):GND
  35    GND  VSS13 @T6G_MB_LIB.T6G(SCH_1):GND
  37    GND  VSS14 @T6G_MB_LIB.T6G(SCH_1):GND
  39    GND  VSS15 @T6G_MB_LIB.T6G(SCH_1):GND
  41    GND  VSS16 @T6G_MB_LIB.T6G(SCH_1):GND
  43    GND  VSS17 @T6G_MB_LIB.T6G(SCH_1):GND
  46    GND  VSS18 @T6G_MB_LIB.T6G(SCH_1):GND
  48    GND  VSS19 @T6G_MB_LIB.T6G(SCH_1):GND
  50    GND  VSS20 @T6G_MB_LIB.T6G(SCH_1):GND
  52    GND  VSS21 @T6G_MB_LIB.T6G(SCH_1):GND
  54    GND  VSS22 @T6G_MB_LIB.T6G(SCH_1):GND
  57    GND  VSS23 @T6G_MB_LIB.T6G(SCH_1):GND
  59    GND  VSS24 @T6G_MB_LIB.T6G(SCH_1):GND
  61    GND  VSS25 @T6G_MB_LIB.T6G(SCH_1):GND
  63    GND  VSS26 @T6G_MB_LIB.T6G(SCH_1):GND
  65    GND  VSS27 @T6G_MB_LIB.T6G(SCH_1):GND
  67    GND  VSS28 @T6G_MB_LIB.T6G(SCH_1):GND
  69    GND  VSS29 @T6G_MB_LIB.T6G(SCH_1):GND
  71    GND  VSS30 @T6G_MB_LIB.T6G(SCH_1):GND
  73    GND  VSS31 @T6G_MB_LIB.T6G(SCH_1):GND
  75    GND  VSS32 @T6G_MB_LIB.T6G(SCH_1):GND
  77    GND  VSS33 @T6G_MB_LIB.T6G(SCH_1):GND
  79    GND  VSS34 @T6G_MB_LIB.T6G(SCH_1):GND
  81    GND  VSS35 @T6G_MB_LIB.T6G(SCH_1):GND
  83    GND  VSS36 @T6G_MB_LIB.T6G(SCH_1):GND
  85    GND  VSS37 @T6G_MB_LIB.T6G(SCH_1):GND
  88    GND  VSS38 @T6G_MB_LIB.T6G(SCH_1):GND
  90    GND  VSS39 @T6G_MB_LIB.T6G(SCH_1):GND
  92    GND  VSS40 @T6G_MB_LIB.T6G(SCH_1):GND
  95    GND  VSS41 @T6G_MB_LIB.T6G(SCH_1):GND
  97    GND  VSS42 @T6G_MB_LIB.T6G(SCH_1):GND
  99    GND  VSS43 @T6G_MB_LIB.T6G(SCH_1):GND
 101    GND  VSS44 @T6G_MB_LIB.T6G(SCH_1):GND
 103    GND  VSS45 @T6G_MB_LIB.T6G(SCH_1):GND
 106    GND  VSS46 @T6G_MB_LIB.T6G(SCH_1):GND
 108    GND  VSS47 @T6G_MB_LIB.T6G(SCH_1):GND
 110    GND  VSS48 @T6G_MB_LIB.T6G(SCH_1):GND
 112    GND  VSS49 @T6G_MB_LIB.T6G(SCH_1):GND
 114    GND  VSS50 @T6G_MB_LIB.T6G(SCH_1):GND
 117    GND  VSS51 @T6G_MB_LIB.T6G(SCH_1):GND
 119    GND  VSS52 @T6G_MB_LIB.T6G(SCH_1):GND
 121    GND  VSS53 @T6G_MB_LIB.T6G(SCH_1):GND
 123    GND  VSS54 @T6G_MB_LIB.T6G(SCH_1):GND
 125    GND  VSS55 @T6G_MB_LIB.T6G(SCH_1):GND
 128    GND  VSS56 @T6G_MB_LIB.T6G(SCH_1):GND
 130    GND  VSS57 @T6G_MB_LIB.T6G(SCH_1):GND
 134    GND  VSS59 @T6G_MB_LIB.T6G(SCH_1):GND
 143    GND  VSS63 @T6G_MB_LIB.T6G(SCH_1):GND
 151    GND  VSS64 @T6G_MB_LIB.T6G(SCH_1):GND
 153    GND  VSS65 @T6G_MB_LIB.T6G(SCH_1):GND
 155    GND  VSS66 @T6G_MB_LIB.T6G(SCH_1):GND
 158    GND  VSS67 @T6G_MB_LIB.T6G(SCH_1):GND
 160    GND  VSS68 @T6G_MB_LIB.T6G(SCH_1):GND
 162    GND  VSS69 @T6G_MB_LIB.T6G(SCH_1):GND
 164    GND  VSS70 @T6G_MB_LIB.T6G(SCH_1):GND
 166    GND  VSS71 @T6G_MB_LIB.T6G(SCH_1):GND
 169    GND  VSS72 @T6G_MB_LIB.T6G(SCH_1):GND
 171    GND  VSS73 @T6G_MB_LIB.T6G(SCH_1):GND
 173    GND  VSS74 @T6G_MB_LIB.T6G(SCH_1):GND
 175    GND  VSS75 @T6G_MB_LIB.T6G(SCH_1):GND
 177    GND  VSS76 @T6G_MB_LIB.T6G(SCH_1):GND
 180    GND  VSS77 @T6G_MB_LIB.T6G(SCH_1):GND
 182    GND  VSS78 @T6G_MB_LIB.T6G(SCH_1):GND
 184    GND  VSS79 @T6G_MB_LIB.T6G(SCH_1):GND
 186    GND  VSS80 @T6G_MB_LIB.T6G(SCH_1):GND
 188    GND  VSS81 @T6G_MB_LIB.T6G(SCH_1):GND
 191    GND  VSS82 @T6G_MB_LIB.T6G(SCH_1):GND
 193    GND  VSS83 @T6G_MB_LIB.T6G(SCH_1):GND
 195    GND  VSS84 @T6G_MB_LIB.T6G(SCH_1):GND
 197    GND  VSS85 @T6G_MB_LIB.T6G(SCH_1):GND
 199    GND  VSS86 @T6G_MB_LIB.T6G(SCH_1):GND
 202    GND  VSS87 @T6G_MB_LIB.T6G(SCH_1):GND
 204    GND  VSS88 @T6G_MB_LIB.T6G(SCH_1):GND
 206    GND  VSS89 @T6G_MB_LIB.T6G(SCH_1):GND
 208    GND  VSS90 @T6G_MB_LIB.T6G(SCH_1):GND
 210    GND  VSS91 @T6G_MB_LIB.T6G(SCH_1):GND
 212    GND  VSS92 @T6G_MB_LIB.T6G(SCH_1):GND
 214    GND  VSS93 @T6G_MB_LIB.T6G(SCH_1):GND
 216    GND  VSS94 @T6G_MB_LIB.T6G(SCH_1):GND
 219    GND  VSS95 @T6G_MB_LIB.T6G(SCH_1):GND
 222    GND  VSS96 @T6G_MB_LIB.T6G(SCH_1):GND
 224    GND  VSS97 @T6G_MB_LIB.T6G(SCH_1):GND
 226    GND  VSS98 @T6G_MB_LIB.T6G(SCH_1):GND
 228    GND  VSS99 @T6G_MB_LIB.T6G(SCH_1):GND
 233    GND VSS101 @T6G_MB_LIB.T6G(SCH_1):GND
 237    GND VSS103 @T6G_MB_LIB.T6G(SCH_1):GND
 242    GND VSS105 @T6G_MB_LIB.T6G(SCH_1):GND
 244    GND VSS106 @T6G_MB_LIB.T6G(SCH_1):GND
 246    GND VSS107 @T6G_MB_LIB.T6G(SCH_1):GND
 248    GND VSS108 @T6G_MB_LIB.T6G(SCH_1):GND
 251    GND VSS109 @T6G_MB_LIB.T6G(SCH_1):GND
 253    GND VSS110 @T6G_MB_LIB.T6G(SCH_1):GND
 255    GND VSS111 @T6G_MB_LIB.T6G(SCH_1):GND
 257    GND VSS112 @T6G_MB_LIB.T6G(SCH_1):GND
 259    GND VSS113 @T6G_MB_LIB.T6G(SCH_1):GND
 262    GND VSS114 @T6G_MB_LIB.T6G(SCH_1):GND
 264    GND VSS115 @T6G_MB_LIB.T6G(SCH_1):GND
 266    GND VSS116 @T6G_MB_LIB.T6G(SCH_1):GND
 268    GND VSS117 @T6G_MB_LIB.T6G(SCH_1):GND
 270    GND VSS118 @T6G_MB_LIB.T6G(SCH_1):GND
 273    GND VSS119 @T6G_MB_LIB.T6G(SCH_1):GND
 275    GND VSS120 @T6G_MB_LIB.T6G(SCH_1):GND
 277    GND VSS121 @T6G_MB_LIB.T6G(SCH_1):GND
 279    GND VSS122 @T6G_MB_LIB.T6G(SCH_1):GND
 281    GND VSS123 @T6G_MB_LIB.T6G(SCH_1):GND
 284    GND VSS124 @T6G_MB_LIB.T6G(SCH_1):GND
 286    GND VSS125 @T6G_MB_LIB.T6G(SCH_1):GND
 288    GND VSS126 @T6G_MB_LIB.T6G(SCH_1):GND
   1 P12V_MEM_CPU1 VIN_BULK0 @T6G_MB_LIB.T6G(SCH_1):P12V_MEM_CPU1
 145 P12V_MEM_CPU1 VIN_BULK1 @T6G_MB_LIB.T6G(SCH_1):P12V_MEM_CPU1
 146 P12V_MEM_CPU1 VIN_BULK2 @T6G_MB_LIB.T6G(SCH_1):P12V_MEM_CPU1
 230    GND VSS100 @T6G_MB_LIB.T6G(SCH_1):GND
 235    GND VSS102 @T6G_MB_LIB.T6G(SCH_1):GND
 240    GND VSS104 @T6G_MB_LIB.T6G(SCH_1):GND
 132    GND  VSS58 @T6G_MB_LIB.T6G(SCH_1):GND
 136    GND  VSS60 @T6G_MB_LIB.T6G(SCH_1):GND
 139    GND  VSS61 @T6G_MB_LIB.T6G(SCH_1):GND
 141    GND  VSS62 @T6G_MB_LIB.T6G(SCH_1):GND
  G1    GND     G1 @T6G_MB_LIB.T6G(SCH_1):GND
  G2    GND     G2 @T6G_MB_LIB.T6G(SCH_1):GND
  G3    GND     G3 @T6G_MB_LIB.T6G(SCH_1):GND

Q_CAP_0402-0.1UF,25V,10%,X7R,CH4104K1B00  I185  C164
   1 P3V3_AUX      A @T6G_MB_LIB.T6G(SCH_1):P3V3_AUX
   2    GND      B @T6G_MB_LIB.T6G(SCH_1):GND

Q_RES_0402LF-1K,1%,1/16W,CHIP,CS21002FB06  I189  R310
   1 PWRGD_CHH_CPU1_DIMM      A @T6G_MB_LIB.T6G(SCH_1):PWRGD_CHH_CPU1_DIMM
   2 PWRGD_CHGL_CPU1      B @T6G_MB_LIB.T6G(SCH_1):PWRGD_CHGL_CPU1

Q_RES_0402LF-1K,1%,1/16W,EMPTY,CS21002FB06  I190  R111
   1   P3V3      A @T6G_MB_LIB.T6G(SCH_1):P3V3
   2 PWRGD_CHH_CPU1_DIMM      B @T6G_MB_LIB.T6G(SCH_1):PWRGD_CHH_CPU1_DIMM

SCONN288_DDR506112002KQ-SCONN288_DDR506112002KQ,SMA  I238  J27
  93 M_H_CPU1_SB_DQS_DP<9> DQS9_B_T||TDQS9_B_T||DBI4_B_N @T6G_MB_LIB.T6G(SCH_1):M_H_CPU1_SB_DQS_DP(9)
  94 M_H_CPU1_SB_DQS_DN<9> DQS9_B_C||TDQS9_B_C @T6G_MB_LIB.T6G(SCH_1):M_H_CPU1_SB_DQS_DN(9)
 201 M_H_CPU1_SA_DQS_DP<9> DQS9_A_T||TDQS9_A_T @T6G_MB_LIB.T6G(SCH_1):M_H_CPU1_SA_DQS_DP(9)
 200 M_H_CPU1_SA_DQS_DN<9> DQS9_A_C||TDQS9_A_C @T6G_MB_LIB.T6G(SCH_1):M_H_CPU1_SA_DQS_DN(9)
 190 M_H_CPU1_SA_DQS_DP<8> DQS8_A_T||TDQS8_A_T @T6G_MB_LIB.T6G(SCH_1):M_H_CPU1_SA_DQS_DP(8)
 189 M_H_CPU1_SA_DQS_DN<8> DQS8_A_C||TDQS8_A_C @T6G_MB_LIB.T6G(SCH_1):M_H_CPU1_SA_DQS_DN(8)
 271 M_H_CPU1_SB_DQS_DN<7> DQS7_B_C||TDQS7_B_C @T6G_MB_LIB.T6G(SCH_1):M_H_CPU1_SB_DQS_DN(7)
 179 M_H_CPU1_SA_DQS_DP<7> DQS7_A_T||TDQS7_A_T @T6G_MB_LIB.T6G(SCH_1):M_H_CPU1_SA_DQS_DP(7)
 261 M_H_CPU1_SB_DQS_DP<6> DQS6_B_T||TDQS6_B_T @T6G_MB_LIB.T6G(SCH_1):M_H_CPU1_SB_DQS_DP(6)
 260 M_H_CPU1_SB_DQS_DN<6> DQS6_B_C||TDQS6_B_C @T6G_MB_LIB.T6G(SCH_1):M_H_CPU1_SB_DQS_DN(6)
 167 M_H_CPU1_SA_DQS_DN<6> DQS6_A_C||TDQS6_A_C||DQS6_A_T||TDQS6_A_T @T6G_MB_LIB.T6G(SCH_1):M_H_CPU1_SA_DQS_DN(6)
 250 M_H_CPU1_SB_DQS_DP<5> DQS5_B_T||TDQS5_B_T @T6G_MB_LIB.T6G(SCH_1):M_H_CPU1_SB_DQS_DP(5)
 249 M_H_CPU1_SB_DQS_DN<5> DQS5_B_C||TDQS5_B_C @T6G_MB_LIB.T6G(SCH_1):M_H_CPU1_SB_DQS_DN(5)
 157 M_H_CPU1_SA_DQS_DP<5> DQS5_A_T||TDQS5_A_T @T6G_MB_LIB.T6G(SCH_1):M_H_CPU1_SA_DQS_DP(5)
 156 M_H_CPU1_SA_DQS_DN<5> DQS5_A_C||TDQS5_A_C||DQS5_A_T||TDQS5_A_T @T6G_MB_LIB.T6G(SCH_1):M_H_CPU1_SA_DQS_DN(5)
 239 M_H_CPU1_SB_DQS_DP<4> DQS4_B_T @T6G_MB_LIB.T6G(SCH_1):M_H_CPU1_SB_DQS_DP(4)
 238 M_H_CPU1_SB_DQS_DN<4> DQS4_B_C @T6G_MB_LIB.T6G(SCH_1):M_H_CPU1_SB_DQS_DN(4)
  55 M_H_CPU1_SA_DQS_DP<4> DQS4_A_T @T6G_MB_LIB.T6G(SCH_1):M_H_CPU1_SA_DQS_DP(4)
  56 M_H_CPU1_SA_DQS_DN<4> DQS4_A_C @T6G_MB_LIB.T6G(SCH_1):M_H_CPU1_SA_DQS_DN(4)
 137 M_H_CPU1_SB_DQS_DP<3> DQS3_B_T @T6G_MB_LIB.T6G(SCH_1):M_H_CPU1_SB_DQS_DP(3)
 138 M_H_CPU1_SB_DQS_DN<3> DQS3_B_C @T6G_MB_LIB.T6G(SCH_1):M_H_CPU1_SB_DQS_DN(3)
  44 M_H_CPU1_SA_DQS_DP<3> DQS3_A_T @T6G_MB_LIB.T6G(SCH_1):M_H_CPU1_SA_DQS_DP(3)
  45 M_H_CPU1_SA_DQS_DN<3> DQS3_A_C @T6G_MB_LIB.T6G(SCH_1):M_H_CPU1_SA_DQS_DN(3)
 126 M_H_CPU1_SB_DQS_DP<2> DQS2_B_T @T6G_MB_LIB.T6G(SCH_1):M_H_CPU1_SB_DQS_DP(2)
 127 M_H_CPU1_SB_DQS_DN<2> DQS2_B_C @T6G_MB_LIB.T6G(SCH_1):M_H_CPU1_SB_DQS_DN(2)
  33 M_H_CPU1_SA_DQS_DP<2> DQS2_A_T @T6G_MB_LIB.T6G(SCH_1):M_H_CPU1_SA_DQS_DP(2)
  34 M_H_CPU1_SA_DQS_DN<2> DQS2_A_C @T6G_MB_LIB.T6G(SCH_1):M_H_CPU1_SA_DQS_DN(2)
 115 M_H_CPU1_SB_DQS_DP<1> DQS1_B_T @T6G_MB_LIB.T6G(SCH_1):M_H_CPU1_SB_DQS_DP(1)
 116 M_H_CPU1_SB_DQS_DN<1> DQS1_B_C @T6G_MB_LIB.T6G(SCH_1):M_H_CPU1_SB_DQS_DN(1)
  22 M_H_CPU1_SA_DQS_DP<1> DQS1_A_T @T6G_MB_LIB.T6G(SCH_1):M_H_CPU1_SA_DQS_DP(1)
  23 M_H_CPU1_SA_DQS_DN<1> DQS1_A_C @T6G_MB_LIB.T6G(SCH_1):M_H_CPU1_SA_DQS_DN(1)
 104 M_H_CPU1_SB_DQS_DP<0> DQS0_B_T @T6G_MB_LIB.T6G(SCH_1):M_H_CPU1_SB_DQS_DP(0)
 105 M_H_CPU1_SB_DQS_DN<0> DQS0_B_C @T6G_MB_LIB.T6G(SCH_1):M_H_CPU1_SB_DQS_DN(0)
  11 M_H_CPU1_SA_DQS_DP<0> DQS0_A_T @T6G_MB_LIB.T6G(SCH_1):M_H_CPU1_SA_DQS_DP(0)
  12 M_H_CPU1_SA_DQS_DN<0> DQS0_A_C @T6G_MB_LIB.T6G(SCH_1):M_H_CPU1_SA_DQS_DN(0)
 272 M_H_CPU1_SB_DQS_DP<7> DQS7_B_T||TDQS7_B_T @T6G_MB_LIB.T6G(SCH_1):M_H_CPU1_SB_DQS_DP(7)
 282 M_H_CPU1_SB_DQS_DN<8> DQS8_B_C||TDQS8_B_C @T6G_MB_LIB.T6G(SCH_1):M_H_CPU1_SB_DQS_DN(8)
 283 M_H_CPU1_SB_DQS_DP<8> DQS8_B_T||TDQS8_B_T @T6G_MB_LIB.T6G(SCH_1):M_H_CPU1_SB_DQS_DP(8)
 168 M_H_CPU1_SA_DQS_DP<6> DQS6_A_T||TDQS6_A_T @T6G_MB_LIB.T6G(SCH_1):M_H_CPU1_SA_DQS_DP(6)
 178 M_H_CPU1_SA_DQS_DN<7> DQS7_A_C||TDQS7_A_C @T6G_MB_LIB.T6G(SCH_1):M_H_CPU1_SA_DQS_DN(7)

Q_CAP_C0805-10UF,25V,10%,X6S,CH6104KEA00  I240  C532
   1 P12V_MEM_CPU1      A @T6G_MB_LIB.T6G(SCH_1):P12V_MEM_CPU1
   2    GND      B @T6G_MB_LIB.T6G(SCH_1):GND

Q_CAP_C0805-10UF,25V,10%,X6S,CH6104KEA00  I241  C533
   1 P12V_MEM_CPU1      A @T6G_MB_LIB.T6G(SCH_1):P12V_MEM_CPU1
   2    GND      B @T6G_MB_LIB.T6G(SCH_1):GND

Q_RES_0402LF-49.9,1%,1/16W,CHIP,CS04992FB07  I244  R1587
   1 I3C_SPD_DDRGL_CPU1_SCL      A @T6G_MB_LIB.T6G(SCH_1):I3C_SPD_DDRGL_CPU1_SCL
   2 I3C_SPD_DDRH_CPU1_SCL      B @T6G_MB_LIB.T6G(SCH_1):I3C_SPD_DDRH_CPU1_SCL

Q_RES_0402LF-10,1%,1/16W,CHIP,CS01002FB07  I245  R1707
   1 I3C_SPD_DDRGL_CPU1_SDA      A @T6G_MB_LIB.T6G(SCH_1):I3C_SPD_DDRGL_CPU1_SDA
   2 I3C_SPD_DDRH_CPU1_SDA      B @T6G_MB_LIB.T6G(SCH_1):I3C_SPD_DDRH_CPU1_SDA


DRAWING: @T6G_MB_LIB.T6G(SCH_1):PAGE105 

SCONN288_DDR506112002KQ-SCONN288_DDR506112002KQ,SMA  I22  J100
   3 P3V3_AUX VIN_MGMT @T6G_MB_LIB.T6G(SCH_1):P3V3_AUX
   2     NC   RFU0     NC
 144     NC   RFU1     NC
 149     NC   RFU2     NC
 150     NC   RFU3     NC
 220     NC   RFU4     NC
 231     NC   RFU5     NC
 232     NC   RFU6     NC
 207 M_I_CPU1_RESET_N RESET_N @T6G_MB_LIB.T6G(SCH_1):M_I_CPU1_RESET_N
 147 PWRGD_CHI_CPU1_DIMM PWR_GOOD||FAIL_N @T6G_MB_LIB.T6G(SCH_1):PWRGD_CHI_CPU1_DIMM
 227 M_I_CPU1_SB_PAR  PAR_B @T6G_MB_LIB.T6G(SCH_1):M_I_CPU1_SB_PAR
  74 M_I_CPU1_SA_PAR  PAR_A @T6G_MB_LIB.T6G(SCH_1):M_I_CPU1_SA_PAR
  87 M_I_CPU1_SB_RSP<0> LBS||RSP_B_N @T6G_MB_LIB.T6G(SCH_1):M_I_CPU1_SB_RSP(0)
  86 M_I_CPU1_SA_RSP<0> LBD||RSP_A_N @T6G_MB_LIB.T6G(SCH_1):M_I_CPU1_SA_RSP(0)
   5 I3C_SPD_DDRI_CPU1_SDA   HSDA @T6G_MB_LIB.T6G(SCH_1):I3C_SPD_DDRI_CPU1_SDA
   4 I3C_SPD_DDRI_CPU1_SCL   HSCL @T6G_MB_LIB.T6G(SCH_1):I3C_SPD_DDRI_CPU1_SCL
 148 PD_CHI_CPU1_DIMM_SAA    HAS @T6G_MB_LIB.T6G(SCH_1):PD_CHI_CPU1_DIMM_SAA
 100 M_I_CPU1_SB_DQ<0>  DQ0_B @T6G_MB_LIB.T6G(SCH_1):M_I_CPU1_SB_DQ(0)
 102 M_I_CPU1_SB_DQ<1>  DQ1_B @T6G_MB_LIB.T6G(SCH_1):M_I_CPU1_SB_DQ(1)
 245 M_I_CPU1_SB_DQ<2>  DQ2_B @T6G_MB_LIB.T6G(SCH_1):M_I_CPU1_SB_DQ(2)
 247 M_I_CPU1_SB_DQ<3>  DQ3_B @T6G_MB_LIB.T6G(SCH_1):M_I_CPU1_SB_DQ(3)
 107 M_I_CPU1_SB_DQ<4>  DQ4_B @T6G_MB_LIB.T6G(SCH_1):M_I_CPU1_SB_DQ(4)
 109 M_I_CPU1_SB_DQ<5>  DQ5_B @T6G_MB_LIB.T6G(SCH_1):M_I_CPU1_SB_DQ(5)
 252 M_I_CPU1_SB_DQ<6>  DQ6_B @T6G_MB_LIB.T6G(SCH_1):M_I_CPU1_SB_DQ(6)
 254 M_I_CPU1_SB_DQ<7>  DQ7_B @T6G_MB_LIB.T6G(SCH_1):M_I_CPU1_SB_DQ(7)
 111 M_I_CPU1_SB_DQ<8>  DQ8_B @T6G_MB_LIB.T6G(SCH_1):M_I_CPU1_SB_DQ(8)
 113 M_I_CPU1_SB_DQ<9>  DQ9_B @T6G_MB_LIB.T6G(SCH_1):M_I_CPU1_SB_DQ(9)
 256 M_I_CPU1_SB_DQ<10> DQ10_B @T6G_MB_LIB.T6G(SCH_1):M_I_CPU1_SB_DQ(10)
 258 M_I_CPU1_SB_DQ<11> DQ11_B @T6G_MB_LIB.T6G(SCH_1):M_I_CPU1_SB_DQ(11)
 118 M_I_CPU1_SB_DQ<12> DQ12_B @T6G_MB_LIB.T6G(SCH_1):M_I_CPU1_SB_DQ(12)
 120 M_I_CPU1_SB_DQ<13> DQ13_B @T6G_MB_LIB.T6G(SCH_1):M_I_CPU1_SB_DQ(13)
 263 M_I_CPU1_SB_DQ<14> DQ14_B @T6G_MB_LIB.T6G(SCH_1):M_I_CPU1_SB_DQ(14)
 265 M_I_CPU1_SB_DQ<15> DQ15_B @T6G_MB_LIB.T6G(SCH_1):M_I_CPU1_SB_DQ(15)
 122 M_I_CPU1_SB_DQ<16> DQ16_B @T6G_MB_LIB.T6G(SCH_1):M_I_CPU1_SB_DQ(16)
 124 M_I_CPU1_SB_DQ<17> DQ17_B @T6G_MB_LIB.T6G(SCH_1):M_I_CPU1_SB_DQ(17)
 267 M_I_CPU1_SB_DQ<18> DQ18_B @T6G_MB_LIB.T6G(SCH_1):M_I_CPU1_SB_DQ(18)
 269 M_I_CPU1_SB_DQ<19> DQ19_B @T6G_MB_LIB.T6G(SCH_1):M_I_CPU1_SB_DQ(19)
 129 M_I_CPU1_SB_DQ<20> DQ20_B @T6G_MB_LIB.T6G(SCH_1):M_I_CPU1_SB_DQ(20)
 131 M_I_CPU1_SB_DQ<21> DQ21_B @T6G_MB_LIB.T6G(SCH_1):M_I_CPU1_SB_DQ(21)
 274 M_I_CPU1_SB_DQ<22> DQ22_B @T6G_MB_LIB.T6G(SCH_1):M_I_CPU1_SB_DQ(22)
 276 M_I_CPU1_SB_DQ<23> DQ23_B @T6G_MB_LIB.T6G(SCH_1):M_I_CPU1_SB_DQ(23)
 133 M_I_CPU1_SB_DQ<24> DQ24_B @T6G_MB_LIB.T6G(SCH_1):M_I_CPU1_SB_DQ(24)
 135 M_I_CPU1_SB_DQ<25> DQ25_B @T6G_MB_LIB.T6G(SCH_1):M_I_CPU1_SB_DQ(25)
 278 M_I_CPU1_SB_DQ<26> DQ26_B @T6G_MB_LIB.T6G(SCH_1):M_I_CPU1_SB_DQ(26)
 280 M_I_CPU1_SB_DQ<27> DQ27_B @T6G_MB_LIB.T6G(SCH_1):M_I_CPU1_SB_DQ(27)
 140 M_I_CPU1_SB_DQ<28> DQ28_B @T6G_MB_LIB.T6G(SCH_1):M_I_CPU1_SB_DQ(28)
 142 M_I_CPU1_SB_DQ<29> DQ29_B @T6G_MB_LIB.T6G(SCH_1):M_I_CPU1_SB_DQ(29)
 285 M_I_CPU1_SB_DQ<30> DQ30_B @T6G_MB_LIB.T6G(SCH_1):M_I_CPU1_SB_DQ(30)
 287 M_I_CPU1_SB_DQ<31> DQ31_B @T6G_MB_LIB.T6G(SCH_1):M_I_CPU1_SB_DQ(31)
   7 M_I_CPU1_SA_DQ<0>  DQ0_A @T6G_MB_LIB.T6G(SCH_1):M_I_CPU1_SA_DQ(0)
   9 M_I_CPU1_SA_DQ<1>  DQ1_A @T6G_MB_LIB.T6G(SCH_1):M_I_CPU1_SA_DQ(1)
 152 M_I_CPU1_SA_DQ<2>  DQ2_A @T6G_MB_LIB.T6G(SCH_1):M_I_CPU1_SA_DQ(2)
 154 M_I_CPU1_SA_DQ<3>  DQ3_A @T6G_MB_LIB.T6G(SCH_1):M_I_CPU1_SA_DQ(3)
  14 M_I_CPU1_SA_DQ<4>  DQ4_A @T6G_MB_LIB.T6G(SCH_1):M_I_CPU1_SA_DQ(4)
  16 M_I_CPU1_SA_DQ<5>  DQ5_A @T6G_MB_LIB.T6G(SCH_1):M_I_CPU1_SA_DQ(5)
 159 M_I_CPU1_SA_DQ<6>  DQ6_A @T6G_MB_LIB.T6G(SCH_1):M_I_CPU1_SA_DQ(6)
 161 M_I_CPU1_SA_DQ<7>  DQ7_A @T6G_MB_LIB.T6G(SCH_1):M_I_CPU1_SA_DQ(7)
  18 M_I_CPU1_SA_DQ<8>  DQ8_A @T6G_MB_LIB.T6G(SCH_1):M_I_CPU1_SA_DQ(8)
  20 M_I_CPU1_SA_DQ<9>  DQ9_A @T6G_MB_LIB.T6G(SCH_1):M_I_CPU1_SA_DQ(9)
 163 M_I_CPU1_SA_DQ<10> DQ10_A @T6G_MB_LIB.T6G(SCH_1):M_I_CPU1_SA_DQ(10)
 165 M_I_CPU1_SA_DQ<11> DQ11_A @T6G_MB_LIB.T6G(SCH_1):M_I_CPU1_SA_DQ(11)
  25 M_I_CPU1_SA_DQ<12> DQ12_A @T6G_MB_LIB.T6G(SCH_1):M_I_CPU1_SA_DQ(12)
  27 M_I_CPU1_SA_DQ<13> DQ13_A @T6G_MB_LIB.T6G(SCH_1):M_I_CPU1_SA_DQ(13)
 170 M_I_CPU1_SA_DQ<14> DQ14_A @T6G_MB_LIB.T6G(SCH_1):M_I_CPU1_SA_DQ(14)
 172 M_I_CPU1_SA_DQ<15> DQ15_A @T6G_MB_LIB.T6G(SCH_1):M_I_CPU1_SA_DQ(15)
  29 M_I_CPU1_SA_DQ<16> DQ16_A @T6G_MB_LIB.T6G(SCH_1):M_I_CPU1_SA_DQ(16)
  31 M_I_CPU1_SA_DQ<17> DQ17_A @T6G_MB_LIB.T6G(SCH_1):M_I_CPU1_SA_DQ(17)
 174 M_I_CPU1_SA_DQ<18> DQ18_A @T6G_MB_LIB.T6G(SCH_1):M_I_CPU1_SA_DQ(18)
 176 M_I_CPU1_SA_DQ<19> DQ19_A @T6G_MB_LIB.T6G(SCH_1):M_I_CPU1_SA_DQ(19)
  36 M_I_CPU1_SA_DQ<20> DQ20_A @T6G_MB_LIB.T6G(SCH_1):M_I_CPU1_SA_DQ(20)
  38 M_I_CPU1_SA_DQ<21> DQ21_A @T6G_MB_LIB.T6G(SCH_1):M_I_CPU1_SA_DQ(21)
 181 M_I_CPU1_SA_DQ<22> DQ22_A @T6G_MB_LIB.T6G(SCH_1):M_I_CPU1_SA_DQ(22)
 183 M_I_CPU1_SA_DQ<23> DQ23_A @T6G_MB_LIB.T6G(SCH_1):M_I_CPU1_SA_DQ(23)
  40 M_I_CPU1_SA_DQ<24> DQ24_A @T6G_MB_LIB.T6G(SCH_1):M_I_CPU1_SA_DQ(24)
  42 M_I_CPU1_SA_DQ<25> DQ25_A @T6G_MB_LIB.T6G(SCH_1):M_I_CPU1_SA_DQ(25)
 185 M_I_CPU1_SA_DQ<26> DQ26_A @T6G_MB_LIB.T6G(SCH_1):M_I_CPU1_SA_DQ(26)
 187 M_I_CPU1_SA_DQ<27> DQ27_A @T6G_MB_LIB.T6G(SCH_1):M_I_CPU1_SA_DQ(27)
  47 M_I_CPU1_SA_DQ<28> DQ28_A @T6G_MB_LIB.T6G(SCH_1):M_I_CPU1_SA_DQ(28)
  49 M_I_CPU1_SA_DQ<29> DQ29_A @T6G_MB_LIB.T6G(SCH_1):M_I_CPU1_SA_DQ(29)
 192 M_I_CPU1_SA_DQ<30> DQ30_A @T6G_MB_LIB.T6G(SCH_1):M_I_CPU1_SA_DQ(30)
 229 M_I_CPU1_SB_CS_N<1> CS1_B_N @T6G_MB_LIB.T6G(SCH_1):M_I_CPU1_SB_CS_N(1)
 209 M_I_CPU1_SA_CS_N<1> CS1_A_N @T6G_MB_LIB.T6G(SCH_1):M_I_CPU1_SA_CS_N(1)
  84 M_I_CPU1_SB_CS_N<0> CS0_B_N @T6G_MB_LIB.T6G(SCH_1):M_I_CPU1_SB_CS_N(0)
  64 M_I_CPU1_SA_CS_N<0> CS0_A_N @T6G_MB_LIB.T6G(SCH_1):M_I_CPU1_SA_CS_N(0)
 217 M_I_CPU1_CLK_DP<0>   CK_T @T6G_MB_LIB.T6G(SCH_1):M_I_CPU1_CLK_DP(0)
 218 M_I_CPU1_CLK_DN<0>   CK_C @T6G_MB_LIB.T6G(SCH_1):M_I_CPU1_CLK_DN(0)
  96 M_I_CPU1_SB_CB<0>  CB0_B @T6G_MB_LIB.T6G(SCH_1):M_I_CPU1_SB_CB(0)
  98 M_I_CPU1_SB_CB<1>  CB1_B @T6G_MB_LIB.T6G(SCH_1):M_I_CPU1_SB_CB(1)
 241 M_I_CPU1_SB_CB<2>  CB2_B @T6G_MB_LIB.T6G(SCH_1):M_I_CPU1_SB_CB(2)
 243 M_I_CPU1_SB_CB<3>  CB3_B @T6G_MB_LIB.T6G(SCH_1):M_I_CPU1_SB_CB(3)
  89 M_I_CPU1_SB_CB<4>  CB4_B @T6G_MB_LIB.T6G(SCH_1):M_I_CPU1_SB_CB(4)
  91 M_I_CPU1_SB_CB<5>  CB5_B @T6G_MB_LIB.T6G(SCH_1):M_I_CPU1_SB_CB(5)
 234 M_I_CPU1_SB_CB<6>  CB6_B @T6G_MB_LIB.T6G(SCH_1):M_I_CPU1_SB_CB(6)
  51 M_I_CPU1_SA_CB<0>  CB0_A @T6G_MB_LIB.T6G(SCH_1):M_I_CPU1_SA_CB(0)
 196 M_I_CPU1_SA_CB<2>  CB2_A @T6G_MB_LIB.T6G(SCH_1):M_I_CPU1_SA_CB(2)
 198 M_I_CPU1_SA_CB<3>  CB3_A @T6G_MB_LIB.T6G(SCH_1):M_I_CPU1_SA_CB(3)
  60 M_I_CPU1_SA_CB<5>  CB5_A @T6G_MB_LIB.T6G(SCH_1):M_I_CPU1_SA_CB(5)
 203 M_I_CPU1_SA_CB<6>  CB6_A @T6G_MB_LIB.T6G(SCH_1):M_I_CPU1_SA_CB(6)
  82 M_I_CPU1_SB_CA<6>  CA6_B @T6G_MB_LIB.T6G(SCH_1):M_I_CPU1_SB_CA(6)
  72 M_I_CPU1_SA_CA<6>  CA6_A @T6G_MB_LIB.T6G(SCH_1):M_I_CPU1_SA_CA(6)
 225 M_I_CPU1_SB_CA<5>  CA5_B @T6G_MB_LIB.T6G(SCH_1):M_I_CPU1_SB_CA(5)
 215 M_I_CPU1_SA_CA<5>  CA5_A @T6G_MB_LIB.T6G(SCH_1):M_I_CPU1_SA_CA(5)
  80 M_I_CPU1_SB_CA<4>  CA4_B @T6G_MB_LIB.T6G(SCH_1):M_I_CPU1_SB_CA(4)
  70 M_I_CPU1_SA_CA<4>  CA4_A @T6G_MB_LIB.T6G(SCH_1):M_I_CPU1_SA_CA(4)
 223 M_I_CPU1_SB_CA<3>  CA3_B @T6G_MB_LIB.T6G(SCH_1):M_I_CPU1_SB_CA(3)
 213 M_I_CPU1_SA_CA<3>  CA3_A @T6G_MB_LIB.T6G(SCH_1):M_I_CPU1_SA_CA(3)
  78 M_I_CPU1_SB_CA<2>  CA2_B @T6G_MB_LIB.T6G(SCH_1):M_I_CPU1_SB_CA(2)
  68 M_I_CPU1_SA_CA<2>  CA2_A @T6G_MB_LIB.T6G(SCH_1):M_I_CPU1_SA_CA(2)
 221 M_I_CPU1_SB_CA<1>  CA1_B @T6G_MB_LIB.T6G(SCH_1):M_I_CPU1_SB_CA(1)
 211 M_I_CPU1_SA_CA<1>  CA1_A @T6G_MB_LIB.T6G(SCH_1):M_I_CPU1_SA_CA(1)
  76 M_I_CPU1_SB_CA<0>  CA0_B @T6G_MB_LIB.T6G(SCH_1):M_I_CPU1_SB_CA(0)
  66 M_I_CPU1_SA_CA<0>  CA0_A @T6G_MB_LIB.T6G(SCH_1):M_I_CPU1_SA_CA(0)
  62 M_I_CPU1_ALERT_N ALERT_N @T6G_MB_LIB.T6G(SCH_1):M_I_CPU1_ALERT_N
 236 M_I_CPU1_SB_CB<7>  CB7_B @T6G_MB_LIB.T6G(SCH_1):M_I_CPU1_SB_CB(7)
  53 M_I_CPU1_SA_CB<1>  CB1_A @T6G_MB_LIB.T6G(SCH_1):M_I_CPU1_SA_CB(1)
  58 M_I_CPU1_SA_CB<4>  CB4_A @T6G_MB_LIB.T6G(SCH_1):M_I_CPU1_SA_CB(4)
 205 M_I_CPU1_SA_CB<7>  CB7_A @T6G_MB_LIB.T6G(SCH_1):M_I_CPU1_SA_CB(7)
 194 M_I_CPU1_SA_DQ<31> DQ31_A @T6G_MB_LIB.T6G(SCH_1):M_I_CPU1_SA_DQ(31)

Q_RES_0402LF-23.2K,1%,1/16W,CHIP,CS32322FB03  I128  R775
   1 PD_CHI_CPU1_DIMM_SAA      A @T6G_MB_LIB.T6G(SCH_1):PD_CHI_CPU1_DIMM_SAA
   2    GND      B @T6G_MB_LIB.T6G(SCH_1):GND

SCONN288_DDR506112002KQ-SCONN288_DDR506112002KQ,SMA  I176  J100
   6    GND   VSS0 @T6G_MB_LIB.T6G(SCH_1):GND
   8    GND   VSS1 @T6G_MB_LIB.T6G(SCH_1):GND
  10    GND   VSS2 @T6G_MB_LIB.T6G(SCH_1):GND
  13    GND   VSS3 @T6G_MB_LIB.T6G(SCH_1):GND
  15    GND   VSS4 @T6G_MB_LIB.T6G(SCH_1):GND
  17    GND   VSS5 @T6G_MB_LIB.T6G(SCH_1):GND
  19    GND   VSS6 @T6G_MB_LIB.T6G(SCH_1):GND
  21    GND   VSS7 @T6G_MB_LIB.T6G(SCH_1):GND
  24    GND   VSS8 @T6G_MB_LIB.T6G(SCH_1):GND
  26    GND   VSS9 @T6G_MB_LIB.T6G(SCH_1):GND
  28    GND  VSS10 @T6G_MB_LIB.T6G(SCH_1):GND
  30    GND  VSS11 @T6G_MB_LIB.T6G(SCH_1):GND
  32    GND  VSS12 @T6G_MB_LIB.T6G(SCH_1):GND
  35    GND  VSS13 @T6G_MB_LIB.T6G(SCH_1):GND
  37    GND  VSS14 @T6G_MB_LIB.T6G(SCH_1):GND
  39    GND  VSS15 @T6G_MB_LIB.T6G(SCH_1):GND
  41    GND  VSS16 @T6G_MB_LIB.T6G(SCH_1):GND
  43    GND  VSS17 @T6G_MB_LIB.T6G(SCH_1):GND
  46    GND  VSS18 @T6G_MB_LIB.T6G(SCH_1):GND
  48    GND  VSS19 @T6G_MB_LIB.T6G(SCH_1):GND
  50    GND  VSS20 @T6G_MB_LIB.T6G(SCH_1):GND
  52    GND  VSS21 @T6G_MB_LIB.T6G(SCH_1):GND
  54    GND  VSS22 @T6G_MB_LIB.T6G(SCH_1):GND
  57    GND  VSS23 @T6G_MB_LIB.T6G(SCH_1):GND
  59    GND  VSS24 @T6G_MB_LIB.T6G(SCH_1):GND
  61    GND  VSS25 @T6G_MB_LIB.T6G(SCH_1):GND
  63    GND  VSS26 @T6G_MB_LIB.T6G(SCH_1):GND
  65    GND  VSS27 @T6G_MB_LIB.T6G(SCH_1):GND
  67    GND  VSS28 @T6G_MB_LIB.T6G(SCH_1):GND
  69    GND  VSS29 @T6G_MB_LIB.T6G(SCH_1):GND
  71    GND  VSS30 @T6G_MB_LIB.T6G(SCH_1):GND
  73    GND  VSS31 @T6G_MB_LIB.T6G(SCH_1):GND
  75    GND  VSS32 @T6G_MB_LIB.T6G(SCH_1):GND
  77    GND  VSS33 @T6G_MB_LIB.T6G(SCH_1):GND
  79    GND  VSS34 @T6G_MB_LIB.T6G(SCH_1):GND
  81    GND  VSS35 @T6G_MB_LIB.T6G(SCH_1):GND
  83    GND  VSS36 @T6G_MB_LIB.T6G(SCH_1):GND
  85    GND  VSS37 @T6G_MB_LIB.T6G(SCH_1):GND
  88    GND  VSS38 @T6G_MB_LIB.T6G(SCH_1):GND
  90    GND  VSS39 @T6G_MB_LIB.T6G(SCH_1):GND
  92    GND  VSS40 @T6G_MB_LIB.T6G(SCH_1):GND
  95    GND  VSS41 @T6G_MB_LIB.T6G(SCH_1):GND
  97    GND  VSS42 @T6G_MB_LIB.T6G(SCH_1):GND
  99    GND  VSS43 @T6G_MB_LIB.T6G(SCH_1):GND
 101    GND  VSS44 @T6G_MB_LIB.T6G(SCH_1):GND
 103    GND  VSS45 @T6G_MB_LIB.T6G(SCH_1):GND
 106    GND  VSS46 @T6G_MB_LIB.T6G(SCH_1):GND
 108    GND  VSS47 @T6G_MB_LIB.T6G(SCH_1):GND
 110    GND  VSS48 @T6G_MB_LIB.T6G(SCH_1):GND
 112    GND  VSS49 @T6G_MB_LIB.T6G(SCH_1):GND
 114    GND  VSS50 @T6G_MB_LIB.T6G(SCH_1):GND
 117    GND  VSS51 @T6G_MB_LIB.T6G(SCH_1):GND
 119    GND  VSS52 @T6G_MB_LIB.T6G(SCH_1):GND
 121    GND  VSS53 @T6G_MB_LIB.T6G(SCH_1):GND
 123    GND  VSS54 @T6G_MB_LIB.T6G(SCH_1):GND
 125    GND  VSS55 @T6G_MB_LIB.T6G(SCH_1):GND
 128    GND  VSS56 @T6G_MB_LIB.T6G(SCH_1):GND
 130    GND  VSS57 @T6G_MB_LIB.T6G(SCH_1):GND
 134    GND  VSS59 @T6G_MB_LIB.T6G(SCH_1):GND
 143    GND  VSS63 @T6G_MB_LIB.T6G(SCH_1):GND
 151    GND  VSS64 @T6G_MB_LIB.T6G(SCH_1):GND
 153    GND  VSS65 @T6G_MB_LIB.T6G(SCH_1):GND
 155    GND  VSS66 @T6G_MB_LIB.T6G(SCH_1):GND
 158    GND  VSS67 @T6G_MB_LIB.T6G(SCH_1):GND
 160    GND  VSS68 @T6G_MB_LIB.T6G(SCH_1):GND
 162    GND  VSS69 @T6G_MB_LIB.T6G(SCH_1):GND
 164    GND  VSS70 @T6G_MB_LIB.T6G(SCH_1):GND
 166    GND  VSS71 @T6G_MB_LIB.T6G(SCH_1):GND
 169    GND  VSS72 @T6G_MB_LIB.T6G(SCH_1):GND
 171    GND  VSS73 @T6G_MB_LIB.T6G(SCH_1):GND
 173    GND  VSS74 @T6G_MB_LIB.T6G(SCH_1):GND
 175    GND  VSS75 @T6G_MB_LIB.T6G(SCH_1):GND
 177    GND  VSS76 @T6G_MB_LIB.T6G(SCH_1):GND
 180    GND  VSS77 @T6G_MB_LIB.T6G(SCH_1):GND
 182    GND  VSS78 @T6G_MB_LIB.T6G(SCH_1):GND
 184    GND  VSS79 @T6G_MB_LIB.T6G(SCH_1):GND
 186    GND  VSS80 @T6G_MB_LIB.T6G(SCH_1):GND
 188    GND  VSS81 @T6G_MB_LIB.T6G(SCH_1):GND
 191    GND  VSS82 @T6G_MB_LIB.T6G(SCH_1):GND
 193    GND  VSS83 @T6G_MB_LIB.T6G(SCH_1):GND
 195    GND  VSS84 @T6G_MB_LIB.T6G(SCH_1):GND
 197    GND  VSS85 @T6G_MB_LIB.T6G(SCH_1):GND
 199    GND  VSS86 @T6G_MB_LIB.T6G(SCH_1):GND
 202    GND  VSS87 @T6G_MB_LIB.T6G(SCH_1):GND
 204    GND  VSS88 @T6G_MB_LIB.T6G(SCH_1):GND
 206    GND  VSS89 @T6G_MB_LIB.T6G(SCH_1):GND
 208    GND  VSS90 @T6G_MB_LIB.T6G(SCH_1):GND
 210    GND  VSS91 @T6G_MB_LIB.T6G(SCH_1):GND
 212    GND  VSS92 @T6G_MB_LIB.T6G(SCH_1):GND
 214    GND  VSS93 @T6G_MB_LIB.T6G(SCH_1):GND
 216    GND  VSS94 @T6G_MB_LIB.T6G(SCH_1):GND
 219    GND  VSS95 @T6G_MB_LIB.T6G(SCH_1):GND
 222    GND  VSS96 @T6G_MB_LIB.T6G(SCH_1):GND
 224    GND  VSS97 @T6G_MB_LIB.T6G(SCH_1):GND
 226    GND  VSS98 @T6G_MB_LIB.T6G(SCH_1):GND
 228    GND  VSS99 @T6G_MB_LIB.T6G(SCH_1):GND
 233    GND VSS101 @T6G_MB_LIB.T6G(SCH_1):GND
 237    GND VSS103 @T6G_MB_LIB.T6G(SCH_1):GND
 242    GND VSS105 @T6G_MB_LIB.T6G(SCH_1):GND
 244    GND VSS106 @T6G_MB_LIB.T6G(SCH_1):GND
 246    GND VSS107 @T6G_MB_LIB.T6G(SCH_1):GND
 248    GND VSS108 @T6G_MB_LIB.T6G(SCH_1):GND
 251    GND VSS109 @T6G_MB_LIB.T6G(SCH_1):GND
 253    GND VSS110 @T6G_MB_LIB.T6G(SCH_1):GND
 255    GND VSS111 @T6G_MB_LIB.T6G(SCH_1):GND
 257    GND VSS112 @T6G_MB_LIB.T6G(SCH_1):GND
 259    GND VSS113 @T6G_MB_LIB.T6G(SCH_1):GND
 262    GND VSS114 @T6G_MB_LIB.T6G(SCH_1):GND
 264    GND VSS115 @T6G_MB_LIB.T6G(SCH_1):GND
 266    GND VSS116 @T6G_MB_LIB.T6G(SCH_1):GND
 268    GND VSS117 @T6G_MB_LIB.T6G(SCH_1):GND
 270    GND VSS118 @T6G_MB_LIB.T6G(SCH_1):GND
 273    GND VSS119 @T6G_MB_LIB.T6G(SCH_1):GND
 275    GND VSS120 @T6G_MB_LIB.T6G(SCH_1):GND
 277    GND VSS121 @T6G_MB_LIB.T6G(SCH_1):GND
 279    GND VSS122 @T6G_MB_LIB.T6G(SCH_1):GND
 281    GND VSS123 @T6G_MB_LIB.T6G(SCH_1):GND
 284    GND VSS124 @T6G_MB_LIB.T6G(SCH_1):GND
 286    GND VSS125 @T6G_MB_LIB.T6G(SCH_1):GND
 288    GND VSS126 @T6G_MB_LIB.T6G(SCH_1):GND
   1 P12V_MEM_CPU1 VIN_BULK0 @T6G_MB_LIB.T6G(SCH_1):P12V_MEM_CPU1
 145 P12V_MEM_CPU1 VIN_BULK1 @T6G_MB_LIB.T6G(SCH_1):P12V_MEM_CPU1
 146 P12V_MEM_CPU1 VIN_BULK2 @T6G_MB_LIB.T6G(SCH_1):P12V_MEM_CPU1
 230    GND VSS100 @T6G_MB_LIB.T6G(SCH_1):GND
 235    GND VSS102 @T6G_MB_LIB.T6G(SCH_1):GND
 240    GND VSS104 @T6G_MB_LIB.T6G(SCH_1):GND
 132    GND  VSS58 @T6G_MB_LIB.T6G(SCH_1):GND
 136    GND  VSS60 @T6G_MB_LIB.T6G(SCH_1):GND
 139    GND  VSS61 @T6G_MB_LIB.T6G(SCH_1):GND
 141    GND  VSS62 @T6G_MB_LIB.T6G(SCH_1):GND
  G1    GND     G1 @T6G_MB_LIB.T6G(SCH_1):GND
  G2    GND     G2 @T6G_MB_LIB.T6G(SCH_1):GND
  G3    GND     G3 @T6G_MB_LIB.T6G(SCH_1):GND

Q_CAP_0402-0.1UF,25V,10%,X7R,CH4104K1B00  I185  C168
   1 P3V3_AUX      A @T6G_MB_LIB.T6G(SCH_1):P3V3_AUX
   2    GND      B @T6G_MB_LIB.T6G(SCH_1):GND

Q_RES_0402LF-1K,1%,1/16W,CHIP,CS21002FB06  I188  R311
   1 PWRGD_CHI_CPU1_DIMM      A @T6G_MB_LIB.T6G(SCH_1):PWRGD_CHI_CPU1_DIMM
   2 PWRGD_CHGL_CPU1      B @T6G_MB_LIB.T6G(SCH_1):PWRGD_CHGL_CPU1

Q_RES_0402LF-1K,1%,1/16W,EMPTY,CS21002FB06  I190  R112
   1   P3V3      A @T6G_MB_LIB.T6G(SCH_1):P3V3
   2 PWRGD_CHI_CPU1_DIMM      B @T6G_MB_LIB.T6G(SCH_1):PWRGD_CHI_CPU1_DIMM

SCONN288_DDR506112002KQ-SCONN288_DDR506112002KQ,SMA  I236  J100
  93 M_I_CPU1_SB_DQS_DP<9> DQS9_B_T||TDQS9_B_T||DBI4_B_N @T6G_MB_LIB.T6G(SCH_1):M_I_CPU1_SB_DQS_DP(9)
  94 M_I_CPU1_SB_DQS_DN<9> DQS9_B_C||TDQS9_B_C @T6G_MB_LIB.T6G(SCH_1):M_I_CPU1_SB_DQS_DN(9)
 201 M_I_CPU1_SA_DQS_DP<9> DQS9_A_T||TDQS9_A_T @T6G_MB_LIB.T6G(SCH_1):M_I_CPU1_SA_DQS_DP(9)
 200 M_I_CPU1_SA_DQS_DN<9> DQS9_A_C||TDQS9_A_C @T6G_MB_LIB.T6G(SCH_1):M_I_CPU1_SA_DQS_DN(9)
 190 M_I_CPU1_SA_DQS_DP<8> DQS8_A_T||TDQS8_A_T @T6G_MB_LIB.T6G(SCH_1):M_I_CPU1_SA_DQS_DP(8)
 189 M_I_CPU1_SA_DQS_DN<8> DQS8_A_C||TDQS8_A_C @T6G_MB_LIB.T6G(SCH_1):M_I_CPU1_SA_DQS_DN(8)
 271 M_I_CPU1_SB_DQS_DN<7> DQS7_B_C||TDQS7_B_C @T6G_MB_LIB.T6G(SCH_1):M_I_CPU1_SB_DQS_DN(7)
 179 M_I_CPU1_SA_DQS_DP<7> DQS7_A_T||TDQS7_A_T @T6G_MB_LIB.T6G(SCH_1):M_I_CPU1_SA_DQS_DP(7)
 261 M_I_CPU1_SB_DQS_DP<6> DQS6_B_T||TDQS6_B_T @T6G_MB_LIB.T6G(SCH_1):M_I_CPU1_SB_DQS_DP(6)
 260 M_I_CPU1_SB_DQS_DN<6> DQS6_B_C||TDQS6_B_C @T6G_MB_LIB.T6G(SCH_1):M_I_CPU1_SB_DQS_DN(6)
 167 M_I_CPU1_SA_DQS_DN<6> DQS6_A_C||TDQS6_A_C||DQS6_A_T||TDQS6_A_T @T6G_MB_LIB.T6G(SCH_1):M_I_CPU1_SA_DQS_DN(6)
 250 M_I_CPU1_SB_DQS_DP<5> DQS5_B_T||TDQS5_B_T @T6G_MB_LIB.T6G(SCH_1):M_I_CPU1_SB_DQS_DP(5)
 249 M_I_CPU1_SB_DQS_DN<5> DQS5_B_C||TDQS5_B_C @T6G_MB_LIB.T6G(SCH_1):M_I_CPU1_SB_DQS_DN(5)
 157 M_I_CPU1_SA_DQS_DP<5> DQS5_A_T||TDQS5_A_T @T6G_MB_LIB.T6G(SCH_1):M_I_CPU1_SA_DQS_DP(5)
 156 M_I_CPU1_SA_DQS_DN<5> DQS5_A_C||TDQS5_A_C||DQS5_A_T||TDQS5_A_T @T6G_MB_LIB.T6G(SCH_1):M_I_CPU1_SA_DQS_DN(5)
 239 M_I_CPU1_SB_DQS_DP<4> DQS4_B_T @T6G_MB_LIB.T6G(SCH_1):M_I_CPU1_SB_DQS_DP(4)
 238 M_I_CPU1_SB_DQS_DN<4> DQS4_B_C @T6G_MB_LIB.T6G(SCH_1):M_I_CPU1_SB_DQS_DN(4)
  55 M_I_CPU1_SA_DQS_DP<4> DQS4_A_T @T6G_MB_LIB.T6G(SCH_1):M_I_CPU1_SA_DQS_DP(4)
  56 M_I_CPU1_SA_DQS_DN<4> DQS4_A_C @T6G_MB_LIB.T6G(SCH_1):M_I_CPU1_SA_DQS_DN(4)
 137 M_I_CPU1_SB_DQS_DP<3> DQS3_B_T @T6G_MB_LIB.T6G(SCH_1):M_I_CPU1_SB_DQS_DP(3)
 138 M_I_CPU1_SB_DQS_DN<3> DQS3_B_C @T6G_MB_LIB.T6G(SCH_1):M_I_CPU1_SB_DQS_DN(3)
  44 M_I_CPU1_SA_DQS_DP<3> DQS3_A_T @T6G_MB_LIB.T6G(SCH_1):M_I_CPU1_SA_DQS_DP(3)
  45 M_I_CPU1_SA_DQS_DN<3> DQS3_A_C @T6G_MB_LIB.T6G(SCH_1):M_I_CPU1_SA_DQS_DN(3)
 126 M_I_CPU1_SB_DQS_DP<2> DQS2_B_T @T6G_MB_LIB.T6G(SCH_1):M_I_CPU1_SB_DQS_DP(2)
 127 M_I_CPU1_SB_DQS_DN<2> DQS2_B_C @T6G_MB_LIB.T6G(SCH_1):M_I_CPU1_SB_DQS_DN(2)
  33 M_I_CPU1_SA_DQS_DP<2> DQS2_A_T @T6G_MB_LIB.T6G(SCH_1):M_I_CPU1_SA_DQS_DP(2)
  34 M_I_CPU1_SA_DQS_DN<2> DQS2_A_C @T6G_MB_LIB.T6G(SCH_1):M_I_CPU1_SA_DQS_DN(2)
 115 M_I_CPU1_SB_DQS_DP<1> DQS1_B_T @T6G_MB_LIB.T6G(SCH_1):M_I_CPU1_SB_DQS_DP(1)
 116 M_I_CPU1_SB_DQS_DN<1> DQS1_B_C @T6G_MB_LIB.T6G(SCH_1):M_I_CPU1_SB_DQS_DN(1)
  22 M_I_CPU1_SA_DQS_DP<1> DQS1_A_T @T6G_MB_LIB.T6G(SCH_1):M_I_CPU1_SA_DQS_DP(1)
  23 M_I_CPU1_SA_DQS_DN<1> DQS1_A_C @T6G_MB_LIB.T6G(SCH_1):M_I_CPU1_SA_DQS_DN(1)
 104 M_I_CPU1_SB_DQS_DP<0> DQS0_B_T @T6G_MB_LIB.T6G(SCH_1):M_I_CPU1_SB_DQS_DP(0)
 105 M_I_CPU1_SB_DQS_DN<0> DQS0_B_C @T6G_MB_LIB.T6G(SCH_1):M_I_CPU1_SB_DQS_DN(0)
  11 M_I_CPU1_SA_DQS_DP<0> DQS0_A_T @T6G_MB_LIB.T6G(SCH_1):M_I_CPU1_SA_DQS_DP(0)
  12 M_I_CPU1_SA_DQS_DN<0> DQS0_A_C @T6G_MB_LIB.T6G(SCH_1):M_I_CPU1_SA_DQS_DN(0)
 272 M_I_CPU1_SB_DQS_DP<7> DQS7_B_T||TDQS7_B_T @T6G_MB_LIB.T6G(SCH_1):M_I_CPU1_SB_DQS_DP(7)
 282 M_I_CPU1_SB_DQS_DN<8> DQS8_B_C||TDQS8_B_C @T6G_MB_LIB.T6G(SCH_1):M_I_CPU1_SB_DQS_DN(8)
 283 M_I_CPU1_SB_DQS_DP<8> DQS8_B_T||TDQS8_B_T @T6G_MB_LIB.T6G(SCH_1):M_I_CPU1_SB_DQS_DP(8)
 168 M_I_CPU1_SA_DQS_DP<6> DQS6_A_T||TDQS6_A_T @T6G_MB_LIB.T6G(SCH_1):M_I_CPU1_SA_DQS_DP(6)
 178 M_I_CPU1_SA_DQS_DN<7> DQS7_A_C||TDQS7_A_C @T6G_MB_LIB.T6G(SCH_1):M_I_CPU1_SA_DQS_DN(7)

Q_CAP_C0805-10UF,25V,10%,X6S,CH6104KEA00  I238  C534
   1 P12V_MEM_CPU1      A @T6G_MB_LIB.T6G(SCH_1):P12V_MEM_CPU1
   2    GND      B @T6G_MB_LIB.T6G(SCH_1):GND

Q_CAP_C0805-10UF,25V,10%,X6S,CH6104KEA00  I239  C535
   1 P12V_MEM_CPU1      A @T6G_MB_LIB.T6G(SCH_1):P12V_MEM_CPU1
   2    GND      B @T6G_MB_LIB.T6G(SCH_1):GND

Q_RES_0402LF-49.9,1%,1/16W,CHIP,CS04992FB07  I242  R1588
   1 I3C_SPD_DDRGL_CPU1_SCL      A @T6G_MB_LIB.T6G(SCH_1):I3C_SPD_DDRGL_CPU1_SCL
   2 I3C_SPD_DDRI_CPU1_SCL      B @T6G_MB_LIB.T6G(SCH_1):I3C_SPD_DDRI_CPU1_SCL

Q_RES_0402LF-10,1%,1/16W,CHIP,CS01002FB07  I243  R1708
   1 I3C_SPD_DDRGL_CPU1_SDA      A @T6G_MB_LIB.T6G(SCH_1):I3C_SPD_DDRGL_CPU1_SDA
   2 I3C_SPD_DDRI_CPU1_SDA      B @T6G_MB_LIB.T6G(SCH_1):I3C_SPD_DDRI_CPU1_SDA


DRAWING: @T6G_MB_LIB.T6G(SCH_1):PAGE106 

SCONN288_DDR506112002KQ-SCONN288_DDR506112002KQ,SMA  I22  J29
   3 P3V3_AUX VIN_MGMT @T6G_MB_LIB.T6G(SCH_1):P3V3_AUX
   2     NC   RFU0     NC
 144     NC   RFU1     NC
 149     NC   RFU2     NC
 150     NC   RFU3     NC
 220     NC   RFU4     NC
 231     NC   RFU5     NC
 232     NC   RFU6     NC
 207 M_J_CPU1_RESET_N RESET_N @T6G_MB_LIB.T6G(SCH_1):M_J_CPU1_RESET_N
 147 PWRGD_CHJ_CPU1_DIMM PWR_GOOD||FAIL_N @T6G_MB_LIB.T6G(SCH_1):PWRGD_CHJ_CPU1_DIMM
 227 M_J_CPU1_SB_PAR  PAR_B @T6G_MB_LIB.T6G(SCH_1):M_J_CPU1_SB_PAR
  74 M_J_CPU1_SA_PAR  PAR_A @T6G_MB_LIB.T6G(SCH_1):M_J_CPU1_SA_PAR
  87 M_J_CPU1_SB_RSP<0> LBS||RSP_B_N @T6G_MB_LIB.T6G(SCH_1):M_J_CPU1_SB_RSP(0)
  86 M_J_CPU1_SA_RSP<0> LBD||RSP_A_N @T6G_MB_LIB.T6G(SCH_1):M_J_CPU1_SA_RSP(0)
   5 I3C_SPD_DDRJ_CPU1_SDA   HSDA @T6G_MB_LIB.T6G(SCH_1):I3C_SPD_DDRJ_CPU1_SDA
   4 I3C_SPD_DDRJ_CPU1_SCL   HSCL @T6G_MB_LIB.T6G(SCH_1):I3C_SPD_DDRJ_CPU1_SCL
 148 PD_CHJ_CPU1_DIMM_SAA    HAS @T6G_MB_LIB.T6G(SCH_1):PD_CHJ_CPU1_DIMM_SAA
 100 M_J_CPU1_SB_DQ<0>  DQ0_B @T6G_MB_LIB.T6G(SCH_1):M_J_CPU1_SB_DQ(0)
 102 M_J_CPU1_SB_DQ<1>  DQ1_B @T6G_MB_LIB.T6G(SCH_1):M_J_CPU1_SB_DQ(1)
 245 M_J_CPU1_SB_DQ<2>  DQ2_B @T6G_MB_LIB.T6G(SCH_1):M_J_CPU1_SB_DQ(2)
 247 M_J_CPU1_SB_DQ<3>  DQ3_B @T6G_MB_LIB.T6G(SCH_1):M_J_CPU1_SB_DQ(3)
 107 M_J_CPU1_SB_DQ<4>  DQ4_B @T6G_MB_LIB.T6G(SCH_1):M_J_CPU1_SB_DQ(4)
 109 M_J_CPU1_SB_DQ<5>  DQ5_B @T6G_MB_LIB.T6G(SCH_1):M_J_CPU1_SB_DQ(5)
 252 M_J_CPU1_SB_DQ<6>  DQ6_B @T6G_MB_LIB.T6G(SCH_1):M_J_CPU1_SB_DQ(6)
 254 M_J_CPU1_SB_DQ<7>  DQ7_B @T6G_MB_LIB.T6G(SCH_1):M_J_CPU1_SB_DQ(7)
 111 M_J_CPU1_SB_DQ<8>  DQ8_B @T6G_MB_LIB.T6G(SCH_1):M_J_CPU1_SB_DQ(8)
 113 M_J_CPU1_SB_DQ<9>  DQ9_B @T6G_MB_LIB.T6G(SCH_1):M_J_CPU1_SB_DQ(9)
 256 M_J_CPU1_SB_DQ<10> DQ10_B @T6G_MB_LIB.T6G(SCH_1):M_J_CPU1_SB_DQ(10)
 258 M_J_CPU1_SB_DQ<11> DQ11_B @T6G_MB_LIB.T6G(SCH_1):M_J_CPU1_SB_DQ(11)
 118 M_J_CPU1_SB_DQ<12> DQ12_B @T6G_MB_LIB.T6G(SCH_1):M_J_CPU1_SB_DQ(12)
 120 M_J_CPU1_SB_DQ<13> DQ13_B @T6G_MB_LIB.T6G(SCH_1):M_J_CPU1_SB_DQ(13)
 263 M_J_CPU1_SB_DQ<14> DQ14_B @T6G_MB_LIB.T6G(SCH_1):M_J_CPU1_SB_DQ(14)
 265 M_J_CPU1_SB_DQ<15> DQ15_B @T6G_MB_LIB.T6G(SCH_1):M_J_CPU1_SB_DQ(15)
 122 M_J_CPU1_SB_DQ<16> DQ16_B @T6G_MB_LIB.T6G(SCH_1):M_J_CPU1_SB_DQ(16)
 124 M_J_CPU1_SB_DQ<17> DQ17_B @T6G_MB_LIB.T6G(SCH_1):M_J_CPU1_SB_DQ(17)
 267 M_J_CPU1_SB_DQ<18> DQ18_B @T6G_MB_LIB.T6G(SCH_1):M_J_CPU1_SB_DQ(18)
 269 M_J_CPU1_SB_DQ<19> DQ19_B @T6G_MB_LIB.T6G(SCH_1):M_J_CPU1_SB_DQ(19)
 129 M_J_CPU1_SB_DQ<20> DQ20_B @T6G_MB_LIB.T6G(SCH_1):M_J_CPU1_SB_DQ(20)
 131 M_J_CPU1_SB_DQ<21> DQ21_B @T6G_MB_LIB.T6G(SCH_1):M_J_CPU1_SB_DQ(21)
 274 M_J_CPU1_SB_DQ<22> DQ22_B @T6G_MB_LIB.T6G(SCH_1):M_J_CPU1_SB_DQ(22)
 276 M_J_CPU1_SB_DQ<23> DQ23_B @T6G_MB_LIB.T6G(SCH_1):M_J_CPU1_SB_DQ(23)
 133 M_J_CPU1_SB_DQ<24> DQ24_B @T6G_MB_LIB.T6G(SCH_1):M_J_CPU1_SB_DQ(24)
 135 M_J_CPU1_SB_DQ<25> DQ25_B @T6G_MB_LIB.T6G(SCH_1):M_J_CPU1_SB_DQ(25)
 278 M_J_CPU1_SB_DQ<26> DQ26_B @T6G_MB_LIB.T6G(SCH_1):M_J_CPU1_SB_DQ(26)
 280 M_J_CPU1_SB_DQ<27> DQ27_B @T6G_MB_LIB.T6G(SCH_1):M_J_CPU1_SB_DQ(27)
 140 M_J_CPU1_SB_DQ<28> DQ28_B @T6G_MB_LIB.T6G(SCH_1):M_J_CPU1_SB_DQ(28)
 142 M_J_CPU1_SB_DQ<29> DQ29_B @T6G_MB_LIB.T6G(SCH_1):M_J_CPU1_SB_DQ(29)
 285 M_J_CPU1_SB_DQ<30> DQ30_B @T6G_MB_LIB.T6G(SCH_1):M_J_CPU1_SB_DQ(30)
 287 M_J_CPU1_SB_DQ<31> DQ31_B @T6G_MB_LIB.T6G(SCH_1):M_J_CPU1_SB_DQ(31)
   7 M_J_CPU1_SA_DQ<0>  DQ0_A @T6G_MB_LIB.T6G(SCH_1):M_J_CPU1_SA_DQ(0)
   9 M_J_CPU1_SA_DQ<1>  DQ1_A @T6G_MB_LIB.T6G(SCH_1):M_J_CPU1_SA_DQ(1)
 152 M_J_CPU1_SA_DQ<2>  DQ2_A @T6G_MB_LIB.T6G(SCH_1):M_J_CPU1_SA_DQ(2)
 154 M_J_CPU1_SA_DQ<3>  DQ3_A @T6G_MB_LIB.T6G(SCH_1):M_J_CPU1_SA_DQ(3)
  14 M_J_CPU1_SA_DQ<4>  DQ4_A @T6G_MB_LIB.T6G(SCH_1):M_J_CPU1_SA_DQ(4)
  16 M_J_CPU1_SA_DQ<5>  DQ5_A @T6G_MB_LIB.T6G(SCH_1):M_J_CPU1_SA_DQ(5)
 159 M_J_CPU1_SA_DQ<6>  DQ6_A @T6G_MB_LIB.T6G(SCH_1):M_J_CPU1_SA_DQ(6)
 161 M_J_CPU1_SA_DQ<7>  DQ7_A @T6G_MB_LIB.T6G(SCH_1):M_J_CPU1_SA_DQ(7)
  18 M_J_CPU1_SA_DQ<8>  DQ8_A @T6G_MB_LIB.T6G(SCH_1):M_J_CPU1_SA_DQ(8)
  20 M_J_CPU1_SA_DQ<9>  DQ9_A @T6G_MB_LIB.T6G(SCH_1):M_J_CPU1_SA_DQ(9)
 163 M_J_CPU1_SA_DQ<10> DQ10_A @T6G_MB_LIB.T6G(SCH_1):M_J_CPU1_SA_DQ(10)
 165 M_J_CPU1_SA_DQ<11> DQ11_A @T6G_MB_LIB.T6G(SCH_1):M_J_CPU1_SA_DQ(11)
  25 M_J_CPU1_SA_DQ<12> DQ12_A @T6G_MB_LIB.T6G(SCH_1):M_J_CPU1_SA_DQ(12)
  27 M_J_CPU1_SA_DQ<13> DQ13_A @T6G_MB_LIB.T6G(SCH_1):M_J_CPU1_SA_DQ(13)
 170 M_J_CPU1_SA_DQ<14> DQ14_A @T6G_MB_LIB.T6G(SCH_1):M_J_CPU1_SA_DQ(14)
 172 M_J_CPU1_SA_DQ<15> DQ15_A @T6G_MB_LIB.T6G(SCH_1):M_J_CPU1_SA_DQ(15)
  29 M_J_CPU1_SA_DQ<16> DQ16_A @T6G_MB_LIB.T6G(SCH_1):M_J_CPU1_SA_DQ(16)
  31 M_J_CPU1_SA_DQ<17> DQ17_A @T6G_MB_LIB.T6G(SCH_1):M_J_CPU1_SA_DQ(17)
 174 M_J_CPU1_SA_DQ<18> DQ18_A @T6G_MB_LIB.T6G(SCH_1):M_J_CPU1_SA_DQ(18)
 176 M_J_CPU1_SA_DQ<19> DQ19_A @T6G_MB_LIB.T6G(SCH_1):M_J_CPU1_SA_DQ(19)
  36 M_J_CPU1_SA_DQ<20> DQ20_A @T6G_MB_LIB.T6G(SCH_1):M_J_CPU1_SA_DQ(20)
  38 M_J_CPU1_SA_DQ<21> DQ21_A @T6G_MB_LIB.T6G(SCH_1):M_J_CPU1_SA_DQ(21)
 181 M_J_CPU1_SA_DQ<22> DQ22_A @T6G_MB_LIB.T6G(SCH_1):M_J_CPU1_SA_DQ(22)
 183 M_J_CPU1_SA_DQ<23> DQ23_A @T6G_MB_LIB.T6G(SCH_1):M_J_CPU1_SA_DQ(23)
  40 M_J_CPU1_SA_DQ<24> DQ24_A @T6G_MB_LIB.T6G(SCH_1):M_J_CPU1_SA_DQ(24)
  42 M_J_CPU1_SA_DQ<25> DQ25_A @T6G_MB_LIB.T6G(SCH_1):M_J_CPU1_SA_DQ(25)
 185 M_J_CPU1_SA_DQ<26> DQ26_A @T6G_MB_LIB.T6G(SCH_1):M_J_CPU1_SA_DQ(26)
 187 M_J_CPU1_SA_DQ<27> DQ27_A @T6G_MB_LIB.T6G(SCH_1):M_J_CPU1_SA_DQ(27)
  47 M_J_CPU1_SA_DQ<28> DQ28_A @T6G_MB_LIB.T6G(SCH_1):M_J_CPU1_SA_DQ(28)
  49 M_J_CPU1_SA_DQ<29> DQ29_A @T6G_MB_LIB.T6G(SCH_1):M_J_CPU1_SA_DQ(29)
 192 M_J_CPU1_SA_DQ<30> DQ30_A @T6G_MB_LIB.T6G(SCH_1):M_J_CPU1_SA_DQ(30)
 229 M_J_CPU1_SB_CS_N<1> CS1_B_N @T6G_MB_LIB.T6G(SCH_1):M_J_CPU1_SB_CS_N(1)
 209 M_J_CPU1_SA_CS_N<1> CS1_A_N @T6G_MB_LIB.T6G(SCH_1):M_J_CPU1_SA_CS_N(1)
  84 M_J_CPU1_SB_CS_N<0> CS0_B_N @T6G_MB_LIB.T6G(SCH_1):M_J_CPU1_SB_CS_N(0)
  64 M_J_CPU1_SA_CS_N<0> CS0_A_N @T6G_MB_LIB.T6G(SCH_1):M_J_CPU1_SA_CS_N(0)
 217 M_J_CPU1_CLK_DP<0>   CK_T @T6G_MB_LIB.T6G(SCH_1):M_J_CPU1_CLK_DP(0)
 218 M_J_CPU1_CLK_DN<0>   CK_C @T6G_MB_LIB.T6G(SCH_1):M_J_CPU1_CLK_DN(0)
  96 M_J_CPU1_SB_CB<0>  CB0_B @T6G_MB_LIB.T6G(SCH_1):M_J_CPU1_SB_CB(0)
  98 M_J_CPU1_SB_CB<1>  CB1_B @T6G_MB_LIB.T6G(SCH_1):M_J_CPU1_SB_CB(1)
 241 M_J_CPU1_SB_CB<2>  CB2_B @T6G_MB_LIB.T6G(SCH_1):M_J_CPU1_SB_CB(2)
 243 M_J_CPU1_SB_CB<3>  CB3_B @T6G_MB_LIB.T6G(SCH_1):M_J_CPU1_SB_CB(3)
  89 M_J_CPU1_SB_CB<4>  CB4_B @T6G_MB_LIB.T6G(SCH_1):M_J_CPU1_SB_CB(4)
  91 M_J_CPU1_SB_CB<5>  CB5_B @T6G_MB_LIB.T6G(SCH_1):M_J_CPU1_SB_CB(5)
 234 M_J_CPU1_SB_CB<6>  CB6_B @T6G_MB_LIB.T6G(SCH_1):M_J_CPU1_SB_CB(6)
  51 M_J_CPU1_SA_CB<0>  CB0_A @T6G_MB_LIB.T6G(SCH_1):M_J_CPU1_SA_CB(0)
 196 M_J_CPU1_SA_CB<2>  CB2_A @T6G_MB_LIB.T6G(SCH_1):M_J_CPU1_SA_CB(2)
 198 M_J_CPU1_SA_CB<3>  CB3_A @T6G_MB_LIB.T6G(SCH_1):M_J_CPU1_SA_CB(3)
  60 M_J_CPU1_SA_CB<5>  CB5_A @T6G_MB_LIB.T6G(SCH_1):M_J_CPU1_SA_CB(5)
 203 M_J_CPU1_SA_CB<6>  CB6_A @T6G_MB_LIB.T6G(SCH_1):M_J_CPU1_SA_CB(6)
  82 M_J_CPU1_SB_CA<6>  CA6_B @T6G_MB_LIB.T6G(SCH_1):M_J_CPU1_SB_CA(6)
  72 M_J_CPU1_SA_CA<6>  CA6_A @T6G_MB_LIB.T6G(SCH_1):M_J_CPU1_SA_CA(6)
 225 M_J_CPU1_SB_CA<5>  CA5_B @T6G_MB_LIB.T6G(SCH_1):M_J_CPU1_SB_CA(5)
 215 M_J_CPU1_SA_CA<5>  CA5_A @T6G_MB_LIB.T6G(SCH_1):M_J_CPU1_SA_CA(5)
  80 M_J_CPU1_SB_CA<4>  CA4_B @T6G_MB_LIB.T6G(SCH_1):M_J_CPU1_SB_CA(4)
  70 M_J_CPU1_SA_CA<4>  CA4_A @T6G_MB_LIB.T6G(SCH_1):M_J_CPU1_SA_CA(4)
 223 M_J_CPU1_SB_CA<3>  CA3_B @T6G_MB_LIB.T6G(SCH_1):M_J_CPU1_SB_CA(3)
 213 M_J_CPU1_SA_CA<3>  CA3_A @T6G_MB_LIB.T6G(SCH_1):M_J_CPU1_SA_CA(3)
  78 M_J_CPU1_SB_CA<2>  CA2_B @T6G_MB_LIB.T6G(SCH_1):M_J_CPU1_SB_CA(2)
  68 M_J_CPU1_SA_CA<2>  CA2_A @T6G_MB_LIB.T6G(SCH_1):M_J_CPU1_SA_CA(2)
 221 M_J_CPU1_SB_CA<1>  CA1_B @T6G_MB_LIB.T6G(SCH_1):M_J_CPU1_SB_CA(1)
 211 M_J_CPU1_SA_CA<1>  CA1_A @T6G_MB_LIB.T6G(SCH_1):M_J_CPU1_SA_CA(1)
  76 M_J_CPU1_SB_CA<0>  CA0_B @T6G_MB_LIB.T6G(SCH_1):M_J_CPU1_SB_CA(0)
  66 M_J_CPU1_SA_CA<0>  CA0_A @T6G_MB_LIB.T6G(SCH_1):M_J_CPU1_SA_CA(0)
  62 M_J_CPU1_ALERT_N ALERT_N @T6G_MB_LIB.T6G(SCH_1):M_J_CPU1_ALERT_N
 236 M_J_CPU1_SB_CB<7>  CB7_B @T6G_MB_LIB.T6G(SCH_1):M_J_CPU1_SB_CB(7)
  53 M_J_CPU1_SA_CB<1>  CB1_A @T6G_MB_LIB.T6G(SCH_1):M_J_CPU1_SA_CB(1)
  58 M_J_CPU1_SA_CB<4>  CB4_A @T6G_MB_LIB.T6G(SCH_1):M_J_CPU1_SA_CB(4)
 205 M_J_CPU1_SA_CB<7>  CB7_A @T6G_MB_LIB.T6G(SCH_1):M_J_CPU1_SA_CB(7)
 194 M_J_CPU1_SA_DQ<31> DQ31_A @T6G_MB_LIB.T6G(SCH_1):M_J_CPU1_SA_DQ(31)

Q_RES_0402LF-35.7K,1%,1/16W,CHIP,CS33572FB01  I127  R776
   1 PD_CHJ_CPU1_DIMM_SAA      A @T6G_MB_LIB.T6G(SCH_1):PD_CHJ_CPU1_DIMM_SAA
   2    GND      B @T6G_MB_LIB.T6G(SCH_1):GND

SCONN288_DDR506112002KQ-SCONN288_DDR506112002KQ,SMA  I143  J29
   6    GND   VSS0 @T6G_MB_LIB.T6G(SCH_1):GND
   8    GND   VSS1 @T6G_MB_LIB.T6G(SCH_1):GND
  10    GND   VSS2 @T6G_MB_LIB.T6G(SCH_1):GND
  13    GND   VSS3 @T6G_MB_LIB.T6G(SCH_1):GND
  15    GND   VSS4 @T6G_MB_LIB.T6G(SCH_1):GND
  17    GND   VSS5 @T6G_MB_LIB.T6G(SCH_1):GND
  19    GND   VSS6 @T6G_MB_LIB.T6G(SCH_1):GND
  21    GND   VSS7 @T6G_MB_LIB.T6G(SCH_1):GND
  24    GND   VSS8 @T6G_MB_LIB.T6G(SCH_1):GND
  26    GND   VSS9 @T6G_MB_LIB.T6G(SCH_1):GND
  28    GND  VSS10 @T6G_MB_LIB.T6G(SCH_1):GND
  30    GND  VSS11 @T6G_MB_LIB.T6G(SCH_1):GND
  32    GND  VSS12 @T6G_MB_LIB.T6G(SCH_1):GND
  35    GND  VSS13 @T6G_MB_LIB.T6G(SCH_1):GND
  37    GND  VSS14 @T6G_MB_LIB.T6G(SCH_1):GND
  39    GND  VSS15 @T6G_MB_LIB.T6G(SCH_1):GND
  41    GND  VSS16 @T6G_MB_LIB.T6G(SCH_1):GND
  43    GND  VSS17 @T6G_MB_LIB.T6G(SCH_1):GND
  46    GND  VSS18 @T6G_MB_LIB.T6G(SCH_1):GND
  48    GND  VSS19 @T6G_MB_LIB.T6G(SCH_1):GND
  50    GND  VSS20 @T6G_MB_LIB.T6G(SCH_1):GND
  52    GND  VSS21 @T6G_MB_LIB.T6G(SCH_1):GND
  54    GND  VSS22 @T6G_MB_LIB.T6G(SCH_1):GND
  57    GND  VSS23 @T6G_MB_LIB.T6G(SCH_1):GND
  59    GND  VSS24 @T6G_MB_LIB.T6G(SCH_1):GND
  61    GND  VSS25 @T6G_MB_LIB.T6G(SCH_1):GND
  63    GND  VSS26 @T6G_MB_LIB.T6G(SCH_1):GND
  65    GND  VSS27 @T6G_MB_LIB.T6G(SCH_1):GND
  67    GND  VSS28 @T6G_MB_LIB.T6G(SCH_1):GND
  69    GND  VSS29 @T6G_MB_LIB.T6G(SCH_1):GND
  71    GND  VSS30 @T6G_MB_LIB.T6G(SCH_1):GND
  73    GND  VSS31 @T6G_MB_LIB.T6G(SCH_1):GND
  75    GND  VSS32 @T6G_MB_LIB.T6G(SCH_1):GND
  77    GND  VSS33 @T6G_MB_LIB.T6G(SCH_1):GND
  79    GND  VSS34 @T6G_MB_LIB.T6G(SCH_1):GND
  81    GND  VSS35 @T6G_MB_LIB.T6G(SCH_1):GND
  83    GND  VSS36 @T6G_MB_LIB.T6G(SCH_1):GND
  85    GND  VSS37 @T6G_MB_LIB.T6G(SCH_1):GND
  88    GND  VSS38 @T6G_MB_LIB.T6G(SCH_1):GND
  90    GND  VSS39 @T6G_MB_LIB.T6G(SCH_1):GND
  92    GND  VSS40 @T6G_MB_LIB.T6G(SCH_1):GND
  95    GND  VSS41 @T6G_MB_LIB.T6G(SCH_1):GND
  97    GND  VSS42 @T6G_MB_LIB.T6G(SCH_1):GND
  99    GND  VSS43 @T6G_MB_LIB.T6G(SCH_1):GND
 101    GND  VSS44 @T6G_MB_LIB.T6G(SCH_1):GND
 103    GND  VSS45 @T6G_MB_LIB.T6G(SCH_1):GND
 106    GND  VSS46 @T6G_MB_LIB.T6G(SCH_1):GND
 108    GND  VSS47 @T6G_MB_LIB.T6G(SCH_1):GND
 110    GND  VSS48 @T6G_MB_LIB.T6G(SCH_1):GND
 112    GND  VSS49 @T6G_MB_LIB.T6G(SCH_1):GND
 114    GND  VSS50 @T6G_MB_LIB.T6G(SCH_1):GND
 117    GND  VSS51 @T6G_MB_LIB.T6G(SCH_1):GND
 119    GND  VSS52 @T6G_MB_LIB.T6G(SCH_1):GND
 121    GND  VSS53 @T6G_MB_LIB.T6G(SCH_1):GND
 123    GND  VSS54 @T6G_MB_LIB.T6G(SCH_1):GND
 125    GND  VSS55 @T6G_MB_LIB.T6G(SCH_1):GND
 128    GND  VSS56 @T6G_MB_LIB.T6G(SCH_1):GND
 130    GND  VSS57 @T6G_MB_LIB.T6G(SCH_1):GND
 134    GND  VSS59 @T6G_MB_LIB.T6G(SCH_1):GND
 143    GND  VSS63 @T6G_MB_LIB.T6G(SCH_1):GND
 151    GND  VSS64 @T6G_MB_LIB.T6G(SCH_1):GND
 153    GND  VSS65 @T6G_MB_LIB.T6G(SCH_1):GND
 155    GND  VSS66 @T6G_MB_LIB.T6G(SCH_1):GND
 158    GND  VSS67 @T6G_MB_LIB.T6G(SCH_1):GND
 160    GND  VSS68 @T6G_MB_LIB.T6G(SCH_1):GND
 162    GND  VSS69 @T6G_MB_LIB.T6G(SCH_1):GND
 164    GND  VSS70 @T6G_MB_LIB.T6G(SCH_1):GND
 166    GND  VSS71 @T6G_MB_LIB.T6G(SCH_1):GND
 169    GND  VSS72 @T6G_MB_LIB.T6G(SCH_1):GND
 171    GND  VSS73 @T6G_MB_LIB.T6G(SCH_1):GND
 173    GND  VSS74 @T6G_MB_LIB.T6G(SCH_1):GND
 175    GND  VSS75 @T6G_MB_LIB.T6G(SCH_1):GND
 177    GND  VSS76 @T6G_MB_LIB.T6G(SCH_1):GND
 180    GND  VSS77 @T6G_MB_LIB.T6G(SCH_1):GND
 182    GND  VSS78 @T6G_MB_LIB.T6G(SCH_1):GND
 184    GND  VSS79 @T6G_MB_LIB.T6G(SCH_1):GND
 186    GND  VSS80 @T6G_MB_LIB.T6G(SCH_1):GND
 188    GND  VSS81 @T6G_MB_LIB.T6G(SCH_1):GND
 191    GND  VSS82 @T6G_MB_LIB.T6G(SCH_1):GND
 193    GND  VSS83 @T6G_MB_LIB.T6G(SCH_1):GND
 195    GND  VSS84 @T6G_MB_LIB.T6G(SCH_1):GND
 197    GND  VSS85 @T6G_MB_LIB.T6G(SCH_1):GND
 199    GND  VSS86 @T6G_MB_LIB.T6G(SCH_1):GND
 202    GND  VSS87 @T6G_MB_LIB.T6G(SCH_1):GND
 204    GND  VSS88 @T6G_MB_LIB.T6G(SCH_1):GND
 206    GND  VSS89 @T6G_MB_LIB.T6G(SCH_1):GND
 208    GND  VSS90 @T6G_MB_LIB.T6G(SCH_1):GND
 210    GND  VSS91 @T6G_MB_LIB.T6G(SCH_1):GND
 212    GND  VSS92 @T6G_MB_LIB.T6G(SCH_1):GND
 214    GND  VSS93 @T6G_MB_LIB.T6G(SCH_1):GND
 216    GND  VSS94 @T6G_MB_LIB.T6G(SCH_1):GND
 219    GND  VSS95 @T6G_MB_LIB.T6G(SCH_1):GND
 222    GND  VSS96 @T6G_MB_LIB.T6G(SCH_1):GND
 224    GND  VSS97 @T6G_MB_LIB.T6G(SCH_1):GND
 226    GND  VSS98 @T6G_MB_LIB.T6G(SCH_1):GND
 228    GND  VSS99 @T6G_MB_LIB.T6G(SCH_1):GND
 233    GND VSS101 @T6G_MB_LIB.T6G(SCH_1):GND
 237    GND VSS103 @T6G_MB_LIB.T6G(SCH_1):GND
 242    GND VSS105 @T6G_MB_LIB.T6G(SCH_1):GND
 244    GND VSS106 @T6G_MB_LIB.T6G(SCH_1):GND
 246    GND VSS107 @T6G_MB_LIB.T6G(SCH_1):GND
 248    GND VSS108 @T6G_MB_LIB.T6G(SCH_1):GND
 251    GND VSS109 @T6G_MB_LIB.T6G(SCH_1):GND
 253    GND VSS110 @T6G_MB_LIB.T6G(SCH_1):GND
 255    GND VSS111 @T6G_MB_LIB.T6G(SCH_1):GND
 257    GND VSS112 @T6G_MB_LIB.T6G(SCH_1):GND
 259    GND VSS113 @T6G_MB_LIB.T6G(SCH_1):GND
 262    GND VSS114 @T6G_MB_LIB.T6G(SCH_1):GND
 264    GND VSS115 @T6G_MB_LIB.T6G(SCH_1):GND
 266    GND VSS116 @T6G_MB_LIB.T6G(SCH_1):GND
 268    GND VSS117 @T6G_MB_LIB.T6G(SCH_1):GND
 270    GND VSS118 @T6G_MB_LIB.T6G(SCH_1):GND
 273    GND VSS119 @T6G_MB_LIB.T6G(SCH_1):GND
 275    GND VSS120 @T6G_MB_LIB.T6G(SCH_1):GND
 277    GND VSS121 @T6G_MB_LIB.T6G(SCH_1):GND
 279    GND VSS122 @T6G_MB_LIB.T6G(SCH_1):GND
 281    GND VSS123 @T6G_MB_LIB.T6G(SCH_1):GND
 284    GND VSS124 @T6G_MB_LIB.T6G(SCH_1):GND
 286    GND VSS125 @T6G_MB_LIB.T6G(SCH_1):GND
 288    GND VSS126 @T6G_MB_LIB.T6G(SCH_1):GND
   1 P12V_MEM_CPU1 VIN_BULK0 @T6G_MB_LIB.T6G(SCH_1):P12V_MEM_CPU1
 145 P12V_MEM_CPU1 VIN_BULK1 @T6G_MB_LIB.T6G(SCH_1):P12V_MEM_CPU1
 146 P12V_MEM_CPU1 VIN_BULK2 @T6G_MB_LIB.T6G(SCH_1):P12V_MEM_CPU1
 230    GND VSS100 @T6G_MB_LIB.T6G(SCH_1):GND
 235    GND VSS102 @T6G_MB_LIB.T6G(SCH_1):GND
 240    GND VSS104 @T6G_MB_LIB.T6G(SCH_1):GND
 132    GND  VSS58 @T6G_MB_LIB.T6G(SCH_1):GND
 136    GND  VSS60 @T6G_MB_LIB.T6G(SCH_1):GND
 139    GND  VSS61 @T6G_MB_LIB.T6G(SCH_1):GND
 141    GND  VSS62 @T6G_MB_LIB.T6G(SCH_1):GND
  G1    GND     G1 @T6G_MB_LIB.T6G(SCH_1):GND
  G2    GND     G2 @T6G_MB_LIB.T6G(SCH_1):GND
  G3    GND     G3 @T6G_MB_LIB.T6G(SCH_1):GND

Q_CAP_0402-0.1UF,25V,10%,X7R,CH4104K1B00  I185  C172
   1 P3V3_AUX      A @T6G_MB_LIB.T6G(SCH_1):P3V3_AUX
   2    GND      B @T6G_MB_LIB.T6G(SCH_1):GND

Q_RES_0402LF-1K,1%,1/16W,CHIP,CS21002FB06  I188  R312
   1 PWRGD_CHJ_CPU1_DIMM      A @T6G_MB_LIB.T6G(SCH_1):PWRGD_CHJ_CPU1_DIMM
   2 PWRGD_CHGL_CPU1      B @T6G_MB_LIB.T6G(SCH_1):PWRGD_CHGL_CPU1

Q_RES_0402LF-1K,1%,1/16W,EMPTY,CS21002FB06  I190  R113
   1   P3V3      A @T6G_MB_LIB.T6G(SCH_1):P3V3
   2 PWRGD_CHJ_CPU1_DIMM      B @T6G_MB_LIB.T6G(SCH_1):PWRGD_CHJ_CPU1_DIMM

SCONN288_DDR506112002KQ-SCONN288_DDR506112002KQ,SMA  I236  J29
  93 M_J_CPU1_SB_DQS_DP<9> DQS9_B_T||TDQS9_B_T||DBI4_B_N @T6G_MB_LIB.T6G(SCH_1):M_J_CPU1_SB_DQS_DP(9)
  94 M_J_CPU1_SB_DQS_DN<9> DQS9_B_C||TDQS9_B_C @T6G_MB_LIB.T6G(SCH_1):M_J_CPU1_SB_DQS_DN(9)
 201 M_J_CPU1_SA_DQS_DP<9> DQS9_A_T||TDQS9_A_T @T6G_MB_LIB.T6G(SCH_1):M_J_CPU1_SA_DQS_DP(9)
 200 M_J_CPU1_SA_DQS_DN<9> DQS9_A_C||TDQS9_A_C @T6G_MB_LIB.T6G(SCH_1):M_J_CPU1_SA_DQS_DN(9)
 190 M_J_CPU1_SA_DQS_DP<8> DQS8_A_T||TDQS8_A_T @T6G_MB_LIB.T6G(SCH_1):M_J_CPU1_SA_DQS_DP(8)
 189 M_J_CPU1_SA_DQS_DN<8> DQS8_A_C||TDQS8_A_C @T6G_MB_LIB.T6G(SCH_1):M_J_CPU1_SA_DQS_DN(8)
 271 M_J_CPU1_SB_DQS_DN<7> DQS7_B_C||TDQS7_B_C @T6G_MB_LIB.T6G(SCH_1):M_J_CPU1_SB_DQS_DN(7)
 179 M_J_CPU1_SA_DQS_DP<7> DQS7_A_T||TDQS7_A_T @T6G_MB_LIB.T6G(SCH_1):M_J_CPU1_SA_DQS_DP(7)
 261 M_J_CPU1_SB_DQS_DP<6> DQS6_B_T||TDQS6_B_T @T6G_MB_LIB.T6G(SCH_1):M_J_CPU1_SB_DQS_DP(6)
 260 M_J_CPU1_SB_DQS_DN<6> DQS6_B_C||TDQS6_B_C @T6G_MB_LIB.T6G(SCH_1):M_J_CPU1_SB_DQS_DN(6)
 167 M_J_CPU1_SA_DQS_DN<6> DQS6_A_C||TDQS6_A_C||DQS6_A_T||TDQS6_A_T @T6G_MB_LIB.T6G(SCH_1):M_J_CPU1_SA_DQS_DN(6)
 250 M_J_CPU1_SB_DQS_DP<5> DQS5_B_T||TDQS5_B_T @T6G_MB_LIB.T6G(SCH_1):M_J_CPU1_SB_DQS_DP(5)
 249 M_J_CPU1_SB_DQS_DN<5> DQS5_B_C||TDQS5_B_C @T6G_MB_LIB.T6G(SCH_1):M_J_CPU1_SB_DQS_DN(5)
 157 M_J_CPU1_SA_DQS_DP<5> DQS5_A_T||TDQS5_A_T @T6G_MB_LIB.T6G(SCH_1):M_J_CPU1_SA_DQS_DP(5)
 156 M_J_CPU1_SA_DQS_DN<5> DQS5_A_C||TDQS5_A_C||DQS5_A_T||TDQS5_A_T @T6G_MB_LIB.T6G(SCH_1):M_J_CPU1_SA_DQS_DN(5)
 239 M_J_CPU1_SB_DQS_DP<4> DQS4_B_T @T6G_MB_LIB.T6G(SCH_1):M_J_CPU1_SB_DQS_DP(4)
 238 M_J_CPU1_SB_DQS_DN<4> DQS4_B_C @T6G_MB_LIB.T6G(SCH_1):M_J_CPU1_SB_DQS_DN(4)
  55 M_J_CPU1_SA_DQS_DP<4> DQS4_A_T @T6G_MB_LIB.T6G(SCH_1):M_J_CPU1_SA_DQS_DP(4)
  56 M_J_CPU1_SA_DQS_DN<4> DQS4_A_C @T6G_MB_LIB.T6G(SCH_1):M_J_CPU1_SA_DQS_DN(4)
 137 M_J_CPU1_SB_DQS_DP<3> DQS3_B_T @T6G_MB_LIB.T6G(SCH_1):M_J_CPU1_SB_DQS_DP(3)
 138 M_J_CPU1_SB_DQS_DN<3> DQS3_B_C @T6G_MB_LIB.T6G(SCH_1):M_J_CPU1_SB_DQS_DN(3)
  44 M_J_CPU1_SA_DQS_DP<3> DQS3_A_T @T6G_MB_LIB.T6G(SCH_1):M_J_CPU1_SA_DQS_DP(3)
  45 M_J_CPU1_SA_DQS_DN<3> DQS3_A_C @T6G_MB_LIB.T6G(SCH_1):M_J_CPU1_SA_DQS_DN(3)
 126 M_J_CPU1_SB_DQS_DP<2> DQS2_B_T @T6G_MB_LIB.T6G(SCH_1):M_J_CPU1_SB_DQS_DP(2)
 127 M_J_CPU1_SB_DQS_DN<2> DQS2_B_C @T6G_MB_LIB.T6G(SCH_1):M_J_CPU1_SB_DQS_DN(2)
  33 M_J_CPU1_SA_DQS_DP<2> DQS2_A_T @T6G_MB_LIB.T6G(SCH_1):M_J_CPU1_SA_DQS_DP(2)
  34 M_J_CPU1_SA_DQS_DN<2> DQS2_A_C @T6G_MB_LIB.T6G(SCH_1):M_J_CPU1_SA_DQS_DN(2)
 115 M_J_CPU1_SB_DQS_DP<1> DQS1_B_T @T6G_MB_LIB.T6G(SCH_1):M_J_CPU1_SB_DQS_DP(1)
 116 M_J_CPU1_SB_DQS_DN<1> DQS1_B_C @T6G_MB_LIB.T6G(SCH_1):M_J_CPU1_SB_DQS_DN(1)
  22 M_J_CPU1_SA_DQS_DP<1> DQS1_A_T @T6G_MB_LIB.T6G(SCH_1):M_J_CPU1_SA_DQS_DP(1)
  23 M_J_CPU1_SA_DQS_DN<1> DQS1_A_C @T6G_MB_LIB.T6G(SCH_1):M_J_CPU1_SA_DQS_DN(1)
 104 M_J_CPU1_SB_DQS_DP<0> DQS0_B_T @T6G_MB_LIB.T6G(SCH_1):M_J_CPU1_SB_DQS_DP(0)
 105 M_J_CPU1_SB_DQS_DN<0> DQS0_B_C @T6G_MB_LIB.T6G(SCH_1):M_J_CPU1_SB_DQS_DN(0)
  11 M_J_CPU1_SA_DQS_DP<0> DQS0_A_T @T6G_MB_LIB.T6G(SCH_1):M_J_CPU1_SA_DQS_DP(0)
  12 M_J_CPU1_SA_DQS_DN<0> DQS0_A_C @T6G_MB_LIB.T6G(SCH_1):M_J_CPU1_SA_DQS_DN(0)
 272 M_J_CPU1_SB_DQS_DP<7> DQS7_B_T||TDQS7_B_T @T6G_MB_LIB.T6G(SCH_1):M_J_CPU1_SB_DQS_DP(7)
 282 M_J_CPU1_SB_DQS_DN<8> DQS8_B_C||TDQS8_B_C @T6G_MB_LIB.T6G(SCH_1):M_J_CPU1_SB_DQS_DN(8)
 283 M_J_CPU1_SB_DQS_DP<8> DQS8_B_T||TDQS8_B_T @T6G_MB_LIB.T6G(SCH_1):M_J_CPU1_SB_DQS_DP(8)
 168 M_J_CPU1_SA_DQS_DP<6> DQS6_A_T||TDQS6_A_T @T6G_MB_LIB.T6G(SCH_1):M_J_CPU1_SA_DQS_DP(6)
 178 M_J_CPU1_SA_DQS_DN<7> DQS7_A_C||TDQS7_A_C @T6G_MB_LIB.T6G(SCH_1):M_J_CPU1_SA_DQS_DN(7)

Q_CAP_C0805-10UF,25V,10%,X6S,CH6104KEA00  I238  C536
   1 P12V_MEM_CPU1      A @T6G_MB_LIB.T6G(SCH_1):P12V_MEM_CPU1
   2    GND      B @T6G_MB_LIB.T6G(SCH_1):GND

Q_CAP_C0805-10UF,25V,10%,X6S,CH6104KEA00  I239  C537
   1 P12V_MEM_CPU1      A @T6G_MB_LIB.T6G(SCH_1):P12V_MEM_CPU1
   2    GND      B @T6G_MB_LIB.T6G(SCH_1):GND

Q_RES_0402LF-49.9,1%,1/16W,CHIP,CS04992FB07  I242  R1589
   1 I3C_SPD_DDRGL_CPU1_SCL      A @T6G_MB_LIB.T6G(SCH_1):I3C_SPD_DDRGL_CPU1_SCL
   2 I3C_SPD_DDRJ_CPU1_SCL      B @T6G_MB_LIB.T6G(SCH_1):I3C_SPD_DDRJ_CPU1_SCL

Q_RES_0402LF-10,1%,1/16W,CHIP,CS01002FB07  I243  R1709
   1 I3C_SPD_DDRGL_CPU1_SDA      A @T6G_MB_LIB.T6G(SCH_1):I3C_SPD_DDRGL_CPU1_SDA
   2 I3C_SPD_DDRJ_CPU1_SDA      B @T6G_MB_LIB.T6G(SCH_1):I3C_SPD_DDRJ_CPU1_SDA


DRAWING: @T6G_MB_LIB.T6G(SCH_1):PAGE107 

SCONN288_DDR506112002KQ-SCONN288_DDR506112002KQ,SMA  I22  J99
   3 P3V3_AUX VIN_MGMT @T6G_MB_LIB.T6G(SCH_1):P3V3_AUX
   2     NC   RFU0     NC
 144     NC   RFU1     NC
 149     NC   RFU2     NC
 150     NC   RFU3     NC
 220     NC   RFU4     NC
 231     NC   RFU5     NC
 232     NC   RFU6     NC
 207 M_K_CPU1_RESET_N RESET_N @T6G_MB_LIB.T6G(SCH_1):M_K_CPU1_RESET_N
 147 PWRGD_CHK_CPU1_DIMM PWR_GOOD||FAIL_N @T6G_MB_LIB.T6G(SCH_1):PWRGD_CHK_CPU1_DIMM
 227 M_K_CPU1_SB_PAR  PAR_B @T6G_MB_LIB.T6G(SCH_1):M_K_CPU1_SB_PAR
  74 M_K_CPU1_SA_PAR  PAR_A @T6G_MB_LIB.T6G(SCH_1):M_K_CPU1_SA_PAR
  87 M_K_CPU1_SB_RSP<0> LBS||RSP_B_N @T6G_MB_LIB.T6G(SCH_1):M_K_CPU1_SB_RSP(0)
  86 M_K_CPU1_SA_RSP<0> LBD||RSP_A_N @T6G_MB_LIB.T6G(SCH_1):M_K_CPU1_SA_RSP(0)
   5 I3C_SPD_DDRK_CPU1_SDA   HSDA @T6G_MB_LIB.T6G(SCH_1):I3C_SPD_DDRK_CPU1_SDA
   4 I3C_SPD_DDRK_CPU1_SCL   HSCL @T6G_MB_LIB.T6G(SCH_1):I3C_SPD_DDRK_CPU1_SCL
 148 PD_CHK_CPU1_DIMM_SAA    HAS @T6G_MB_LIB.T6G(SCH_1):PD_CHK_CPU1_DIMM_SAA
 100 M_K_CPU1_SB_DQ<0>  DQ0_B @T6G_MB_LIB.T6G(SCH_1):M_K_CPU1_SB_DQ(0)
 102 M_K_CPU1_SB_DQ<1>  DQ1_B @T6G_MB_LIB.T6G(SCH_1):M_K_CPU1_SB_DQ(1)
 245 M_K_CPU1_SB_DQ<2>  DQ2_B @T6G_MB_LIB.T6G(SCH_1):M_K_CPU1_SB_DQ(2)
 247 M_K_CPU1_SB_DQ<3>  DQ3_B @T6G_MB_LIB.T6G(SCH_1):M_K_CPU1_SB_DQ(3)
 107 M_K_CPU1_SB_DQ<4>  DQ4_B @T6G_MB_LIB.T6G(SCH_1):M_K_CPU1_SB_DQ(4)
 109 M_K_CPU1_SB_DQ<5>  DQ5_B @T6G_MB_LIB.T6G(SCH_1):M_K_CPU1_SB_DQ(5)
 252 M_K_CPU1_SB_DQ<6>  DQ6_B @T6G_MB_LIB.T6G(SCH_1):M_K_CPU1_SB_DQ(6)
 254 M_K_CPU1_SB_DQ<7>  DQ7_B @T6G_MB_LIB.T6G(SCH_1):M_K_CPU1_SB_DQ(7)
 111 M_K_CPU1_SB_DQ<8>  DQ8_B @T6G_MB_LIB.T6G(SCH_1):M_K_CPU1_SB_DQ(8)
 113 M_K_CPU1_SB_DQ<9>  DQ9_B @T6G_MB_LIB.T6G(SCH_1):M_K_CPU1_SB_DQ(9)
 256 M_K_CPU1_SB_DQ<10> DQ10_B @T6G_MB_LIB.T6G(SCH_1):M_K_CPU1_SB_DQ(10)
 258 M_K_CPU1_SB_DQ<11> DQ11_B @T6G_MB_LIB.T6G(SCH_1):M_K_CPU1_SB_DQ(11)
 118 M_K_CPU1_SB_DQ<12> DQ12_B @T6G_MB_LIB.T6G(SCH_1):M_K_CPU1_SB_DQ(12)
 120 M_K_CPU1_SB_DQ<13> DQ13_B @T6G_MB_LIB.T6G(SCH_1):M_K_CPU1_SB_DQ(13)
 263 M_K_CPU1_SB_DQ<14> DQ14_B @T6G_MB_LIB.T6G(SCH_1):M_K_CPU1_SB_DQ(14)
 265 M_K_CPU1_SB_DQ<15> DQ15_B @T6G_MB_LIB.T6G(SCH_1):M_K_CPU1_SB_DQ(15)
 122 M_K_CPU1_SB_DQ<16> DQ16_B @T6G_MB_LIB.T6G(SCH_1):M_K_CPU1_SB_DQ(16)
 124 M_K_CPU1_SB_DQ<17> DQ17_B @T6G_MB_LIB.T6G(SCH_1):M_K_CPU1_SB_DQ(17)
 267 M_K_CPU1_SB_DQ<18> DQ18_B @T6G_MB_LIB.T6G(SCH_1):M_K_CPU1_SB_DQ(18)
 269 M_K_CPU1_SB_DQ<19> DQ19_B @T6G_MB_LIB.T6G(SCH_1):M_K_CPU1_SB_DQ(19)
 129 M_K_CPU1_SB_DQ<20> DQ20_B @T6G_MB_LIB.T6G(SCH_1):M_K_CPU1_SB_DQ(20)
 131 M_K_CPU1_SB_DQ<21> DQ21_B @T6G_MB_LIB.T6G(SCH_1):M_K_CPU1_SB_DQ(21)
 274 M_K_CPU1_SB_DQ<22> DQ22_B @T6G_MB_LIB.T6G(SCH_1):M_K_CPU1_SB_DQ(22)
 276 M_K_CPU1_SB_DQ<23> DQ23_B @T6G_MB_LIB.T6G(SCH_1):M_K_CPU1_SB_DQ(23)
 133 M_K_CPU1_SB_DQ<24> DQ24_B @T6G_MB_LIB.T6G(SCH_1):M_K_CPU1_SB_DQ(24)
 135 M_K_CPU1_SB_DQ<25> DQ25_B @T6G_MB_LIB.T6G(SCH_1):M_K_CPU1_SB_DQ(25)
 278 M_K_CPU1_SB_DQ<26> DQ26_B @T6G_MB_LIB.T6G(SCH_1):M_K_CPU1_SB_DQ(26)
 280 M_K_CPU1_SB_DQ<27> DQ27_B @T6G_MB_LIB.T6G(SCH_1):M_K_CPU1_SB_DQ(27)
 140 M_K_CPU1_SB_DQ<28> DQ28_B @T6G_MB_LIB.T6G(SCH_1):M_K_CPU1_SB_DQ(28)
 142 M_K_CPU1_SB_DQ<29> DQ29_B @T6G_MB_LIB.T6G(SCH_1):M_K_CPU1_SB_DQ(29)
 285 M_K_CPU1_SB_DQ<30> DQ30_B @T6G_MB_LIB.T6G(SCH_1):M_K_CPU1_SB_DQ(30)
 287 M_K_CPU1_SB_DQ<31> DQ31_B @T6G_MB_LIB.T6G(SCH_1):M_K_CPU1_SB_DQ(31)
   7 M_K_CPU1_SA_DQ<0>  DQ0_A @T6G_MB_LIB.T6G(SCH_1):M_K_CPU1_SA_DQ(0)
   9 M_K_CPU1_SA_DQ<1>  DQ1_A @T6G_MB_LIB.T6G(SCH_1):M_K_CPU1_SA_DQ(1)
 152 M_K_CPU1_SA_DQ<2>  DQ2_A @T6G_MB_LIB.T6G(SCH_1):M_K_CPU1_SA_DQ(2)
 154 M_K_CPU1_SA_DQ<3>  DQ3_A @T6G_MB_LIB.T6G(SCH_1):M_K_CPU1_SA_DQ(3)
  14 M_K_CPU1_SA_DQ<4>  DQ4_A @T6G_MB_LIB.T6G(SCH_1):M_K_CPU1_SA_DQ(4)
  16 M_K_CPU1_SA_DQ<5>  DQ5_A @T6G_MB_LIB.T6G(SCH_1):M_K_CPU1_SA_DQ(5)
 159 M_K_CPU1_SA_DQ<6>  DQ6_A @T6G_MB_LIB.T6G(SCH_1):M_K_CPU1_SA_DQ(6)
 161 M_K_CPU1_SA_DQ<7>  DQ7_A @T6G_MB_LIB.T6G(SCH_1):M_K_CPU1_SA_DQ(7)
  18 M_K_CPU1_SA_DQ<8>  DQ8_A @T6G_MB_LIB.T6G(SCH_1):M_K_CPU1_SA_DQ(8)
  20 M_K_CPU1_SA_DQ<9>  DQ9_A @T6G_MB_LIB.T6G(SCH_1):M_K_CPU1_SA_DQ(9)
 163 M_K_CPU1_SA_DQ<10> DQ10_A @T6G_MB_LIB.T6G(SCH_1):M_K_CPU1_SA_DQ(10)
 165 M_K_CPU1_SA_DQ<11> DQ11_A @T6G_MB_LIB.T6G(SCH_1):M_K_CPU1_SA_DQ(11)
  25 M_K_CPU1_SA_DQ<12> DQ12_A @T6G_MB_LIB.T6G(SCH_1):M_K_CPU1_SA_DQ(12)
  27 M_K_CPU1_SA_DQ<13> DQ13_A @T6G_MB_LIB.T6G(SCH_1):M_K_CPU1_SA_DQ(13)
 170 M_K_CPU1_SA_DQ<14> DQ14_A @T6G_MB_LIB.T6G(SCH_1):M_K_CPU1_SA_DQ(14)
 172 M_K_CPU1_SA_DQ<15> DQ15_A @T6G_MB_LIB.T6G(SCH_1):M_K_CPU1_SA_DQ(15)
  29 M_K_CPU1_SA_DQ<16> DQ16_A @T6G_MB_LIB.T6G(SCH_1):M_K_CPU1_SA_DQ(16)
  31 M_K_CPU1_SA_DQ<17> DQ17_A @T6G_MB_LIB.T6G(SCH_1):M_K_CPU1_SA_DQ(17)
 174 M_K_CPU1_SA_DQ<18> DQ18_A @T6G_MB_LIB.T6G(SCH_1):M_K_CPU1_SA_DQ(18)
 176 M_K_CPU1_SA_DQ<19> DQ19_A @T6G_MB_LIB.T6G(SCH_1):M_K_CPU1_SA_DQ(19)
  36 M_K_CPU1_SA_DQ<20> DQ20_A @T6G_MB_LIB.T6G(SCH_1):M_K_CPU1_SA_DQ(20)
  38 M_K_CPU1_SA_DQ<21> DQ21_A @T6G_MB_LIB.T6G(SCH_1):M_K_CPU1_SA_DQ(21)
 181 M_K_CPU1_SA_DQ<22> DQ22_A @T6G_MB_LIB.T6G(SCH_1):M_K_CPU1_SA_DQ(22)
 183 M_K_CPU1_SA_DQ<23> DQ23_A @T6G_MB_LIB.T6G(SCH_1):M_K_CPU1_SA_DQ(23)
  40 M_K_CPU1_SA_DQ<24> DQ24_A @T6G_MB_LIB.T6G(SCH_1):M_K_CPU1_SA_DQ(24)
  42 M_K_CPU1_SA_DQ<25> DQ25_A @T6G_MB_LIB.T6G(SCH_1):M_K_CPU1_SA_DQ(25)
 185 M_K_CPU1_SA_DQ<26> DQ26_A @T6G_MB_LIB.T6G(SCH_1):M_K_CPU1_SA_DQ(26)
 187 M_K_CPU1_SA_DQ<27> DQ27_A @T6G_MB_LIB.T6G(SCH_1):M_K_CPU1_SA_DQ(27)
  47 M_K_CPU1_SA_DQ<28> DQ28_A @T6G_MB_LIB.T6G(SCH_1):M_K_CPU1_SA_DQ(28)
  49 M_K_CPU1_SA_DQ<29> DQ29_A @T6G_MB_LIB.T6G(SCH_1):M_K_CPU1_SA_DQ(29)
 192 M_K_CPU1_SA_DQ<30> DQ30_A @T6G_MB_LIB.T6G(SCH_1):M_K_CPU1_SA_DQ(30)
 229 M_K_CPU1_SB_CS_N<1> CS1_B_N @T6G_MB_LIB.T6G(SCH_1):M_K_CPU1_SB_CS_N(1)
 209 M_K_CPU1_SA_CS_N<1> CS1_A_N @T6G_MB_LIB.T6G(SCH_1):M_K_CPU1_SA_CS_N(1)
  84 M_K_CPU1_SB_CS_N<0> CS0_B_N @T6G_MB_LIB.T6G(SCH_1):M_K_CPU1_SB_CS_N(0)
  64 M_K_CPU1_SA_CS_N<0> CS0_A_N @T6G_MB_LIB.T6G(SCH_1):M_K_CPU1_SA_CS_N(0)
 217 M_K_CPU1_CLK_DP<0>   CK_T @T6G_MB_LIB.T6G(SCH_1):M_K_CPU1_CLK_DP(0)
 218 M_K_CPU1_CLK_DN<0>   CK_C @T6G_MB_LIB.T6G(SCH_1):M_K_CPU1_CLK_DN(0)
  96 M_K_CPU1_SB_CB<0>  CB0_B @T6G_MB_LIB.T6G(SCH_1):M_K_CPU1_SB_CB(0)
  98 M_K_CPU1_SB_CB<1>  CB1_B @T6G_MB_LIB.T6G(SCH_1):M_K_CPU1_SB_CB(1)
 241 M_K_CPU1_SB_CB<2>  CB2_B @T6G_MB_LIB.T6G(SCH_1):M_K_CPU1_SB_CB(2)
 243 M_K_CPU1_SB_CB<3>  CB3_B @T6G_MB_LIB.T6G(SCH_1):M_K_CPU1_SB_CB(3)
  89 M_K_CPU1_SB_CB<4>  CB4_B @T6G_MB_LIB.T6G(SCH_1):M_K_CPU1_SB_CB(4)
  91 M_K_CPU1_SB_CB<5>  CB5_B @T6G_MB_LIB.T6G(SCH_1):M_K_CPU1_SB_CB(5)
 234 M_K_CPU1_SB_CB<6>  CB6_B @T6G_MB_LIB.T6G(SCH_1):M_K_CPU1_SB_CB(6)
  51 M_K_CPU1_SA_CB<0>  CB0_A @T6G_MB_LIB.T6G(SCH_1):M_K_CPU1_SA_CB(0)
 196 M_K_CPU1_SA_CB<2>  CB2_A @T6G_MB_LIB.T6G(SCH_1):M_K_CPU1_SA_CB(2)
 198 M_K_CPU1_SA_CB<3>  CB3_A @T6G_MB_LIB.T6G(SCH_1):M_K_CPU1_SA_CB(3)
  60 M_K_CPU1_SA_CB<5>  CB5_A @T6G_MB_LIB.T6G(SCH_1):M_K_CPU1_SA_CB(5)
 203 M_K_CPU1_SA_CB<6>  CB6_A @T6G_MB_LIB.T6G(SCH_1):M_K_CPU1_SA_CB(6)
  82 M_K_CPU1_SB_CA<6>  CA6_B @T6G_MB_LIB.T6G(SCH_1):M_K_CPU1_SB_CA(6)
  72 M_K_CPU1_SA_CA<6>  CA6_A @T6G_MB_LIB.T6G(SCH_1):M_K_CPU1_SA_CA(6)
 225 M_K_CPU1_SB_CA<5>  CA5_B @T6G_MB_LIB.T6G(SCH_1):M_K_CPU1_SB_CA(5)
 215 M_K_CPU1_SA_CA<5>  CA5_A @T6G_MB_LIB.T6G(SCH_1):M_K_CPU1_SA_CA(5)
  80 M_K_CPU1_SB_CA<4>  CA4_B @T6G_MB_LIB.T6G(SCH_1):M_K_CPU1_SB_CA(4)
  70 M_K_CPU1_SA_CA<4>  CA4_A @T6G_MB_LIB.T6G(SCH_1):M_K_CPU1_SA_CA(4)
 223 M_K_CPU1_SB_CA<3>  CA3_B @T6G_MB_LIB.T6G(SCH_1):M_K_CPU1_SB_CA(3)
 213 M_K_CPU1_SA_CA<3>  CA3_A @T6G_MB_LIB.T6G(SCH_1):M_K_CPU1_SA_CA(3)
  78 M_K_CPU1_SB_CA<2>  CA2_B @T6G_MB_LIB.T6G(SCH_1):M_K_CPU1_SB_CA(2)
  68 M_K_CPU1_SA_CA<2>  CA2_A @T6G_MB_LIB.T6G(SCH_1):M_K_CPU1_SA_CA(2)
 221 M_K_CPU1_SB_CA<1>  CA1_B @T6G_MB_LIB.T6G(SCH_1):M_K_CPU1_SB_CA(1)
 211 M_K_CPU1_SA_CA<1>  CA1_A @T6G_MB_LIB.T6G(SCH_1):M_K_CPU1_SA_CA(1)
  76 M_K_CPU1_SB_CA<0>  CA0_B @T6G_MB_LIB.T6G(SCH_1):M_K_CPU1_SB_CA(0)
  66 M_K_CPU1_SA_CA<0>  CA0_A @T6G_MB_LIB.T6G(SCH_1):M_K_CPU1_SA_CA(0)
  62 M_K_CPU1_ALERT_N ALERT_N @T6G_MB_LIB.T6G(SCH_1):M_K_CPU1_ALERT_N
 236 M_K_CPU1_SB_CB<7>  CB7_B @T6G_MB_LIB.T6G(SCH_1):M_K_CPU1_SB_CB(7)
  53 M_K_CPU1_SA_CB<1>  CB1_A @T6G_MB_LIB.T6G(SCH_1):M_K_CPU1_SA_CB(1)
  58 M_K_CPU1_SA_CB<4>  CB4_A @T6G_MB_LIB.T6G(SCH_1):M_K_CPU1_SA_CB(4)
 205 M_K_CPU1_SA_CB<7>  CB7_A @T6G_MB_LIB.T6G(SCH_1):M_K_CPU1_SA_CB(7)
 194 M_K_CPU1_SA_DQ<31> DQ31_A @T6G_MB_LIB.T6G(SCH_1):M_K_CPU1_SA_DQ(31)

Q_RES_0402LF-54.9K,1%,1/16W,CHIP,CS35492FB03  I136  R777
   1 PD_CHK_CPU1_DIMM_SAA      A @T6G_MB_LIB.T6G(SCH_1):PD_CHK_CPU1_DIMM_SAA
   2    GND      B @T6G_MB_LIB.T6G(SCH_1):GND

SCONN288_DDR506112002KQ-SCONN288_DDR506112002KQ,SMA  I139  J99
   6    GND   VSS0 @T6G_MB_LIB.T6G(SCH_1):GND
   8    GND   VSS1 @T6G_MB_LIB.T6G(SCH_1):GND
  10    GND   VSS2 @T6G_MB_LIB.T6G(SCH_1):GND
  13    GND   VSS3 @T6G_MB_LIB.T6G(SCH_1):GND
  15    GND   VSS4 @T6G_MB_LIB.T6G(SCH_1):GND
  17    GND   VSS5 @T6G_MB_LIB.T6G(SCH_1):GND
  19    GND   VSS6 @T6G_MB_LIB.T6G(SCH_1):GND
  21    GND   VSS7 @T6G_MB_LIB.T6G(SCH_1):GND
  24    GND   VSS8 @T6G_MB_LIB.T6G(SCH_1):GND
  26    GND   VSS9 @T6G_MB_LIB.T6G(SCH_1):GND
  28    GND  VSS10 @T6G_MB_LIB.T6G(SCH_1):GND
  30    GND  VSS11 @T6G_MB_LIB.T6G(SCH_1):GND
  32    GND  VSS12 @T6G_MB_LIB.T6G(SCH_1):GND
  35    GND  VSS13 @T6G_MB_LIB.T6G(SCH_1):GND
  37    GND  VSS14 @T6G_MB_LIB.T6G(SCH_1):GND
  39    GND  VSS15 @T6G_MB_LIB.T6G(SCH_1):GND
  41    GND  VSS16 @T6G_MB_LIB.T6G(SCH_1):GND
  43    GND  VSS17 @T6G_MB_LIB.T6G(SCH_1):GND
  46    GND  VSS18 @T6G_MB_LIB.T6G(SCH_1):GND
  48    GND  VSS19 @T6G_MB_LIB.T6G(SCH_1):GND
  50    GND  VSS20 @T6G_MB_LIB.T6G(SCH_1):GND
  52    GND  VSS21 @T6G_MB_LIB.T6G(SCH_1):GND
  54    GND  VSS22 @T6G_MB_LIB.T6G(SCH_1):GND
  57    GND  VSS23 @T6G_MB_LIB.T6G(SCH_1):GND
  59    GND  VSS24 @T6G_MB_LIB.T6G(SCH_1):GND
  61    GND  VSS25 @T6G_MB_LIB.T6G(SCH_1):GND
  63    GND  VSS26 @T6G_MB_LIB.T6G(SCH_1):GND
  65    GND  VSS27 @T6G_MB_LIB.T6G(SCH_1):GND
  67    GND  VSS28 @T6G_MB_LIB.T6G(SCH_1):GND
  69    GND  VSS29 @T6G_MB_LIB.T6G(SCH_1):GND
  71    GND  VSS30 @T6G_MB_LIB.T6G(SCH_1):GND
  73    GND  VSS31 @T6G_MB_LIB.T6G(SCH_1):GND
  75    GND  VSS32 @T6G_MB_LIB.T6G(SCH_1):GND
  77    GND  VSS33 @T6G_MB_LIB.T6G(SCH_1):GND
  79    GND  VSS34 @T6G_MB_LIB.T6G(SCH_1):GND
  81    GND  VSS35 @T6G_MB_LIB.T6G(SCH_1):GND
  83    GND  VSS36 @T6G_MB_LIB.T6G(SCH_1):GND
  85    GND  VSS37 @T6G_MB_LIB.T6G(SCH_1):GND
  88    GND  VSS38 @T6G_MB_LIB.T6G(SCH_1):GND
  90    GND  VSS39 @T6G_MB_LIB.T6G(SCH_1):GND
  92    GND  VSS40 @T6G_MB_LIB.T6G(SCH_1):GND
  95    GND  VSS41 @T6G_MB_LIB.T6G(SCH_1):GND
  97    GND  VSS42 @T6G_MB_LIB.T6G(SCH_1):GND
  99    GND  VSS43 @T6G_MB_LIB.T6G(SCH_1):GND
 101    GND  VSS44 @T6G_MB_LIB.T6G(SCH_1):GND
 103    GND  VSS45 @T6G_MB_LIB.T6G(SCH_1):GND
 106    GND  VSS46 @T6G_MB_LIB.T6G(SCH_1):GND
 108    GND  VSS47 @T6G_MB_LIB.T6G(SCH_1):GND
 110    GND  VSS48 @T6G_MB_LIB.T6G(SCH_1):GND
 112    GND  VSS49 @T6G_MB_LIB.T6G(SCH_1):GND
 114    GND  VSS50 @T6G_MB_LIB.T6G(SCH_1):GND
 117    GND  VSS51 @T6G_MB_LIB.T6G(SCH_1):GND
 119    GND  VSS52 @T6G_MB_LIB.T6G(SCH_1):GND
 121    GND  VSS53 @T6G_MB_LIB.T6G(SCH_1):GND
 123    GND  VSS54 @T6G_MB_LIB.T6G(SCH_1):GND
 125    GND  VSS55 @T6G_MB_LIB.T6G(SCH_1):GND
 128    GND  VSS56 @T6G_MB_LIB.T6G(SCH_1):GND
 130    GND  VSS57 @T6G_MB_LIB.T6G(SCH_1):GND
 134    GND  VSS59 @T6G_MB_LIB.T6G(SCH_1):GND
 143    GND  VSS63 @T6G_MB_LIB.T6G(SCH_1):GND
 151    GND  VSS64 @T6G_MB_LIB.T6G(SCH_1):GND
 153    GND  VSS65 @T6G_MB_LIB.T6G(SCH_1):GND
 155    GND  VSS66 @T6G_MB_LIB.T6G(SCH_1):GND
 158    GND  VSS67 @T6G_MB_LIB.T6G(SCH_1):GND
 160    GND  VSS68 @T6G_MB_LIB.T6G(SCH_1):GND
 162    GND  VSS69 @T6G_MB_LIB.T6G(SCH_1):GND
 164    GND  VSS70 @T6G_MB_LIB.T6G(SCH_1):GND
 166    GND  VSS71 @T6G_MB_LIB.T6G(SCH_1):GND
 169    GND  VSS72 @T6G_MB_LIB.T6G(SCH_1):GND
 171    GND  VSS73 @T6G_MB_LIB.T6G(SCH_1):GND
 173    GND  VSS74 @T6G_MB_LIB.T6G(SCH_1):GND
 175    GND  VSS75 @T6G_MB_LIB.T6G(SCH_1):GND
 177    GND  VSS76 @T6G_MB_LIB.T6G(SCH_1):GND
 180    GND  VSS77 @T6G_MB_LIB.T6G(SCH_1):GND
 182    GND  VSS78 @T6G_MB_LIB.T6G(SCH_1):GND
 184    GND  VSS79 @T6G_MB_LIB.T6G(SCH_1):GND
 186    GND  VSS80 @T6G_MB_LIB.T6G(SCH_1):GND
 188    GND  VSS81 @T6G_MB_LIB.T6G(SCH_1):GND
 191    GND  VSS82 @T6G_MB_LIB.T6G(SCH_1):GND
 193    GND  VSS83 @T6G_MB_LIB.T6G(SCH_1):GND
 195    GND  VSS84 @T6G_MB_LIB.T6G(SCH_1):GND
 197    GND  VSS85 @T6G_MB_LIB.T6G(SCH_1):GND
 199    GND  VSS86 @T6G_MB_LIB.T6G(SCH_1):GND
 202    GND  VSS87 @T6G_MB_LIB.T6G(SCH_1):GND
 204    GND  VSS88 @T6G_MB_LIB.T6G(SCH_1):GND
 206    GND  VSS89 @T6G_MB_LIB.T6G(SCH_1):GND
 208    GND  VSS90 @T6G_MB_LIB.T6G(SCH_1):GND
 210    GND  VSS91 @T6G_MB_LIB.T6G(SCH_1):GND
 212    GND  VSS92 @T6G_MB_LIB.T6G(SCH_1):GND
 214    GND  VSS93 @T6G_MB_LIB.T6G(SCH_1):GND
 216    GND  VSS94 @T6G_MB_LIB.T6G(SCH_1):GND
 219    GND  VSS95 @T6G_MB_LIB.T6G(SCH_1):GND
 222    GND  VSS96 @T6G_MB_LIB.T6G(SCH_1):GND
 224    GND  VSS97 @T6G_MB_LIB.T6G(SCH_1):GND
 226    GND  VSS98 @T6G_MB_LIB.T6G(SCH_1):GND
 228    GND  VSS99 @T6G_MB_LIB.T6G(SCH_1):GND
 233    GND VSS101 @T6G_MB_LIB.T6G(SCH_1):GND
 237    GND VSS103 @T6G_MB_LIB.T6G(SCH_1):GND
 242    GND VSS105 @T6G_MB_LIB.T6G(SCH_1):GND
 244    GND VSS106 @T6G_MB_LIB.T6G(SCH_1):GND
 246    GND VSS107 @T6G_MB_LIB.T6G(SCH_1):GND
 248    GND VSS108 @T6G_MB_LIB.T6G(SCH_1):GND
 251    GND VSS109 @T6G_MB_LIB.T6G(SCH_1):GND
 253    GND VSS110 @T6G_MB_LIB.T6G(SCH_1):GND
 255    GND VSS111 @T6G_MB_LIB.T6G(SCH_1):GND
 257    GND VSS112 @T6G_MB_LIB.T6G(SCH_1):GND
 259    GND VSS113 @T6G_MB_LIB.T6G(SCH_1):GND
 262    GND VSS114 @T6G_MB_LIB.T6G(SCH_1):GND
 264    GND VSS115 @T6G_MB_LIB.T6G(SCH_1):GND
 266    GND VSS116 @T6G_MB_LIB.T6G(SCH_1):GND
 268    GND VSS117 @T6G_MB_LIB.T6G(SCH_1):GND
 270    GND VSS118 @T6G_MB_LIB.T6G(SCH_1):GND
 273    GND VSS119 @T6G_MB_LIB.T6G(SCH_1):GND
 275    GND VSS120 @T6G_MB_LIB.T6G(SCH_1):GND
 277    GND VSS121 @T6G_MB_LIB.T6G(SCH_1):GND
 279    GND VSS122 @T6G_MB_LIB.T6G(SCH_1):GND
 281    GND VSS123 @T6G_MB_LIB.T6G(SCH_1):GND
 284    GND VSS124 @T6G_MB_LIB.T6G(SCH_1):GND
 286    GND VSS125 @T6G_MB_LIB.T6G(SCH_1):GND
 288    GND VSS126 @T6G_MB_LIB.T6G(SCH_1):GND
   1 P12V_MEM_CPU1 VIN_BULK0 @T6G_MB_LIB.T6G(SCH_1):P12V_MEM_CPU1
 145 P12V_MEM_CPU1 VIN_BULK1 @T6G_MB_LIB.T6G(SCH_1):P12V_MEM_CPU1
 146 P12V_MEM_CPU1 VIN_BULK2 @T6G_MB_LIB.T6G(SCH_1):P12V_MEM_CPU1
 230    GND VSS100 @T6G_MB_LIB.T6G(SCH_1):GND
 235    GND VSS102 @T6G_MB_LIB.T6G(SCH_1):GND
 240    GND VSS104 @T6G_MB_LIB.T6G(SCH_1):GND
 132    GND  VSS58 @T6G_MB_LIB.T6G(SCH_1):GND
 136    GND  VSS60 @T6G_MB_LIB.T6G(SCH_1):GND
 139    GND  VSS61 @T6G_MB_LIB.T6G(SCH_1):GND
 141    GND  VSS62 @T6G_MB_LIB.T6G(SCH_1):GND
  G1    GND     G1 @T6G_MB_LIB.T6G(SCH_1):GND
  G2    GND     G2 @T6G_MB_LIB.T6G(SCH_1):GND
  G3    GND     G3 @T6G_MB_LIB.T6G(SCH_1):GND

Q_CAP_0402-0.1UF,25V,10%,X7R,CH4104K1B00  I185  C176
   1 P3V3_AUX      A @T6G_MB_LIB.T6G(SCH_1):P3V3_AUX
   2    GND      B @T6G_MB_LIB.T6G(SCH_1):GND

Q_RES_0402LF-1K,1%,1/16W,CHIP,CS21002FB06  I188  R313
   1 PWRGD_CHK_CPU1_DIMM      A @T6G_MB_LIB.T6G(SCH_1):PWRGD_CHK_CPU1_DIMM
   2 PWRGD_CHGL_CPU1      B @T6G_MB_LIB.T6G(SCH_1):PWRGD_CHGL_CPU1

Q_RES_0402LF-1K,1%,1/16W,EMPTY,CS21002FB06  I190  R114
   1   P3V3      A @T6G_MB_LIB.T6G(SCH_1):P3V3
   2 PWRGD_CHK_CPU1_DIMM      B @T6G_MB_LIB.T6G(SCH_1):PWRGD_CHK_CPU1_DIMM

SCONN288_DDR506112002KQ-SCONN288_DDR506112002KQ,SMA  I235  J99
  93 M_K_CPU1_SB_DQS_DP<9> DQS9_B_T||TDQS9_B_T||DBI4_B_N @T6G_MB_LIB.T6G(SCH_1):M_K_CPU1_SB_DQS_DP(9)
  94 M_K_CPU1_SB_DQS_DN<9> DQS9_B_C||TDQS9_B_C @T6G_MB_LIB.T6G(SCH_1):M_K_CPU1_SB_DQS_DN(9)
 201 M_K_CPU1_SA_DQS_DP<9> DQS9_A_T||TDQS9_A_T @T6G_MB_LIB.T6G(SCH_1):M_K_CPU1_SA_DQS_DP(9)
 200 M_K_CPU1_SA_DQS_DN<9> DQS9_A_C||TDQS9_A_C @T6G_MB_LIB.T6G(SCH_1):M_K_CPU1_SA_DQS_DN(9)
 190 M_K_CPU1_SA_DQS_DP<8> DQS8_A_T||TDQS8_A_T @T6G_MB_LIB.T6G(SCH_1):M_K_CPU1_SA_DQS_DP(8)
 189 M_K_CPU1_SA_DQS_DN<8> DQS8_A_C||TDQS8_A_C @T6G_MB_LIB.T6G(SCH_1):M_K_CPU1_SA_DQS_DN(8)
 271 M_K_CPU1_SB_DQS_DN<7> DQS7_B_C||TDQS7_B_C @T6G_MB_LIB.T6G(SCH_1):M_K_CPU1_SB_DQS_DN(7)
 179 M_K_CPU1_SA_DQS_DP<7> DQS7_A_T||TDQS7_A_T @T6G_MB_LIB.T6G(SCH_1):M_K_CPU1_SA_DQS_DP(7)
 261 M_K_CPU1_SB_DQS_DP<6> DQS6_B_T||TDQS6_B_T @T6G_MB_LIB.T6G(SCH_1):M_K_CPU1_SB_DQS_DP(6)
 260 M_K_CPU1_SB_DQS_DN<6> DQS6_B_C||TDQS6_B_C @T6G_MB_LIB.T6G(SCH_1):M_K_CPU1_SB_DQS_DN(6)
 167 M_K_CPU1_SA_DQS_DN<6> DQS6_A_C||TDQS6_A_C||DQS6_A_T||TDQS6_A_T @T6G_MB_LIB.T6G(SCH_1):M_K_CPU1_SA_DQS_DN(6)
 250 M_K_CPU1_SB_DQS_DP<5> DQS5_B_T||TDQS5_B_T @T6G_MB_LIB.T6G(SCH_1):M_K_CPU1_SB_DQS_DP(5)
 249 M_K_CPU1_SB_DQS_DN<5> DQS5_B_C||TDQS5_B_C @T6G_MB_LIB.T6G(SCH_1):M_K_CPU1_SB_DQS_DN(5)
 157 M_K_CPU1_SA_DQS_DP<5> DQS5_A_T||TDQS5_A_T @T6G_MB_LIB.T6G(SCH_1):M_K_CPU1_SA_DQS_DP(5)
 156 M_K_CPU1_SA_DQS_DN<5> DQS5_A_C||TDQS5_A_C||DQS5_A_T||TDQS5_A_T @T6G_MB_LIB.T6G(SCH_1):M_K_CPU1_SA_DQS_DN(5)
 239 M_K_CPU1_SB_DQS_DP<4> DQS4_B_T @T6G_MB_LIB.T6G(SCH_1):M_K_CPU1_SB_DQS_DP(4)
 238 M_K_CPU1_SB_DQS_DN<4> DQS4_B_C @T6G_MB_LIB.T6G(SCH_1):M_K_CPU1_SB_DQS_DN(4)
  55 M_K_CPU1_SA_DQS_DP<4> DQS4_A_T @T6G_MB_LIB.T6G(SCH_1):M_K_CPU1_SA_DQS_DP(4)
  56 M_K_CPU1_SA_DQS_DN<4> DQS4_A_C @T6G_MB_LIB.T6G(SCH_1):M_K_CPU1_SA_DQS_DN(4)
 137 M_K_CPU1_SB_DQS_DP<3> DQS3_B_T @T6G_MB_LIB.T6G(SCH_1):M_K_CPU1_SB_DQS_DP(3)
 138 M_K_CPU1_SB_DQS_DN<3> DQS3_B_C @T6G_MB_LIB.T6G(SCH_1):M_K_CPU1_SB_DQS_DN(3)
  44 M_K_CPU1_SA_DQS_DP<3> DQS3_A_T @T6G_MB_LIB.T6G(SCH_1):M_K_CPU1_SA_DQS_DP(3)
  45 M_K_CPU1_SA_DQS_DN<3> DQS3_A_C @T6G_MB_LIB.T6G(SCH_1):M_K_CPU1_SA_DQS_DN(3)
 126 M_K_CPU1_SB_DQS_DP<2> DQS2_B_T @T6G_MB_LIB.T6G(SCH_1):M_K_CPU1_SB_DQS_DP(2)
 127 M_K_CPU1_SB_DQS_DN<2> DQS2_B_C @T6G_MB_LIB.T6G(SCH_1):M_K_CPU1_SB_DQS_DN(2)
  33 M_K_CPU1_SA_DQS_DP<2> DQS2_A_T @T6G_MB_LIB.T6G(SCH_1):M_K_CPU1_SA_DQS_DP(2)
  34 M_K_CPU1_SA_DQS_DN<2> DQS2_A_C @T6G_MB_LIB.T6G(SCH_1):M_K_CPU1_SA_DQS_DN(2)
 115 M_K_CPU1_SB_DQS_DP<1> DQS1_B_T @T6G_MB_LIB.T6G(SCH_1):M_K_CPU1_SB_DQS_DP(1)
 116 M_K_CPU1_SB_DQS_DN<1> DQS1_B_C @T6G_MB_LIB.T6G(SCH_1):M_K_CPU1_SB_DQS_DN(1)
  22 M_K_CPU1_SA_DQS_DP<1> DQS1_A_T @T6G_MB_LIB.T6G(SCH_1):M_K_CPU1_SA_DQS_DP(1)
  23 M_K_CPU1_SA_DQS_DN<1> DQS1_A_C @T6G_MB_LIB.T6G(SCH_1):M_K_CPU1_SA_DQS_DN(1)
 104 M_K_CPU1_SB_DQS_DP<0> DQS0_B_T @T6G_MB_LIB.T6G(SCH_1):M_K_CPU1_SB_DQS_DP(0)
 105 M_K_CPU1_SB_DQS_DN<0> DQS0_B_C @T6G_MB_LIB.T6G(SCH_1):M_K_CPU1_SB_DQS_DN(0)
  11 M_K_CPU1_SA_DQS_DP<0> DQS0_A_T @T6G_MB_LIB.T6G(SCH_1):M_K_CPU1_SA_DQS_DP(0)
  12 M_K_CPU1_SA_DQS_DN<0> DQS0_A_C @T6G_MB_LIB.T6G(SCH_1):M_K_CPU1_SA_DQS_DN(0)
 272 M_K_CPU1_SB_DQS_DP<7> DQS7_B_T||TDQS7_B_T @T6G_MB_LIB.T6G(SCH_1):M_K_CPU1_SB_DQS_DP(7)
 282 M_K_CPU1_SB_DQS_DN<8> DQS8_B_C||TDQS8_B_C @T6G_MB_LIB.T6G(SCH_1):M_K_CPU1_SB_DQS_DN(8)
 283 M_K_CPU1_SB_DQS_DP<8> DQS8_B_T||TDQS8_B_T @T6G_MB_LIB.T6G(SCH_1):M_K_CPU1_SB_DQS_DP(8)
 168 M_K_CPU1_SA_DQS_DP<6> DQS6_A_T||TDQS6_A_T @T6G_MB_LIB.T6G(SCH_1):M_K_CPU1_SA_DQS_DP(6)
 178 M_K_CPU1_SA_DQS_DN<7> DQS7_A_C||TDQS7_A_C @T6G_MB_LIB.T6G(SCH_1):M_K_CPU1_SA_DQS_DN(7)

Q_CAP_C0805-10UF,25V,10%,X6S,CH6104KEA00  I237  C546
   1 P12V_MEM_CPU1      A @T6G_MB_LIB.T6G(SCH_1):P12V_MEM_CPU1
   2    GND      B @T6G_MB_LIB.T6G(SCH_1):GND

Q_CAP_C0805-10UF,25V,10%,X6S,CH6104KEA00  I238  C547
   1 P12V_MEM_CPU1      A @T6G_MB_LIB.T6G(SCH_1):P12V_MEM_CPU1
   2    GND      B @T6G_MB_LIB.T6G(SCH_1):GND

Q_RES_0402LF-49.9,1%,1/16W,CHIP,CS04992FB07  I241  R1590
   1 I3C_SPD_DDRGL_CPU1_SCL      A @T6G_MB_LIB.T6G(SCH_1):I3C_SPD_DDRGL_CPU1_SCL
   2 I3C_SPD_DDRK_CPU1_SCL      B @T6G_MB_LIB.T6G(SCH_1):I3C_SPD_DDRK_CPU1_SCL

Q_RES_0402LF-10,1%,1/16W,CHIP,CS01002FB07  I242  R1710
   1 I3C_SPD_DDRGL_CPU1_SDA      A @T6G_MB_LIB.T6G(SCH_1):I3C_SPD_DDRGL_CPU1_SDA
   2 I3C_SPD_DDRK_CPU1_SDA      B @T6G_MB_LIB.T6G(SCH_1):I3C_SPD_DDRK_CPU1_SDA


DRAWING: @T6G_MB_LIB.T6G(SCH_1):PAGE108 

SCONN288_DDR506112002KQ-SCONN288_DDR506112002KQ,SMA  I22  J37
   3 P3V3_AUX VIN_MGMT @T6G_MB_LIB.T6G(SCH_1):P3V3_AUX
   2     NC   RFU0     NC
 144     NC   RFU1     NC
 149     NC   RFU2     NC
 150     NC   RFU3     NC
 220     NC   RFU4     NC
 231     NC   RFU5     NC
 232     NC   RFU6     NC
 207 M_L_CPU1_RESET_N RESET_N @T6G_MB_LIB.T6G(SCH_1):M_L_CPU1_RESET_N
 147 PWRGD_CHL_CPU1_DIMM PWR_GOOD||FAIL_N @T6G_MB_LIB.T6G(SCH_1):PWRGD_CHL_CPU1_DIMM
 227 M_L_CPU1_SB_PAR  PAR_B @T6G_MB_LIB.T6G(SCH_1):M_L_CPU1_SB_PAR
  74 M_L_CPU1_SA_PAR  PAR_A @T6G_MB_LIB.T6G(SCH_1):M_L_CPU1_SA_PAR
  87 M_L_CPU1_SB_RSP<0> LBS||RSP_B_N @T6G_MB_LIB.T6G(SCH_1):M_L_CPU1_SB_RSP(0)
  86 M_L_CPU1_SA_RSP<0> LBD||RSP_A_N @T6G_MB_LIB.T6G(SCH_1):M_L_CPU1_SA_RSP(0)
   5 I3C_SPD_DDRL_CPU1_SDA   HSDA @T6G_MB_LIB.T6G(SCH_1):I3C_SPD_DDRL_CPU1_SDA
   4 I3C_SPD_DDRL_CPU1_SCL   HSCL @T6G_MB_LIB.T6G(SCH_1):I3C_SPD_DDRL_CPU1_SCL
 148 PD_CHL_CPU1_DIMM_SAA    HAS @T6G_MB_LIB.T6G(SCH_1):PD_CHL_CPU1_DIMM_SAA
 100 M_L_CPU1_SB_DQ<0>  DQ0_B @T6G_MB_LIB.T6G(SCH_1):M_L_CPU1_SB_DQ(0)
 102 M_L_CPU1_SB_DQ<1>  DQ1_B @T6G_MB_LIB.T6G(SCH_1):M_L_CPU1_SB_DQ(1)
 245 M_L_CPU1_SB_DQ<2>  DQ2_B @T6G_MB_LIB.T6G(SCH_1):M_L_CPU1_SB_DQ(2)
 247 M_L_CPU1_SB_DQ<3>  DQ3_B @T6G_MB_LIB.T6G(SCH_1):M_L_CPU1_SB_DQ(3)
 107 M_L_CPU1_SB_DQ<4>  DQ4_B @T6G_MB_LIB.T6G(SCH_1):M_L_CPU1_SB_DQ(4)
 109 M_L_CPU1_SB_DQ<5>  DQ5_B @T6G_MB_LIB.T6G(SCH_1):M_L_CPU1_SB_DQ(5)
 252 M_L_CPU1_SB_DQ<6>  DQ6_B @T6G_MB_LIB.T6G(SCH_1):M_L_CPU1_SB_DQ(6)
 254 M_L_CPU1_SB_DQ<7>  DQ7_B @T6G_MB_LIB.T6G(SCH_1):M_L_CPU1_SB_DQ(7)
 111 M_L_CPU1_SB_DQ<8>  DQ8_B @T6G_MB_LIB.T6G(SCH_1):M_L_CPU1_SB_DQ(8)
 113 M_L_CPU1_SB_DQ<9>  DQ9_B @T6G_MB_LIB.T6G(SCH_1):M_L_CPU1_SB_DQ(9)
 256 M_L_CPU1_SB_DQ<10> DQ10_B @T6G_MB_LIB.T6G(SCH_1):M_L_CPU1_SB_DQ(10)
 258 M_L_CPU1_SB_DQ<11> DQ11_B @T6G_MB_LIB.T6G(SCH_1):M_L_CPU1_SB_DQ(11)
 118 M_L_CPU1_SB_DQ<12> DQ12_B @T6G_MB_LIB.T6G(SCH_1):M_L_CPU1_SB_DQ(12)
 120 M_L_CPU1_SB_DQ<13> DQ13_B @T6G_MB_LIB.T6G(SCH_1):M_L_CPU1_SB_DQ(13)
 263 M_L_CPU1_SB_DQ<14> DQ14_B @T6G_MB_LIB.T6G(SCH_1):M_L_CPU1_SB_DQ(14)
 265 M_L_CPU1_SB_DQ<15> DQ15_B @T6G_MB_LIB.T6G(SCH_1):M_L_CPU1_SB_DQ(15)
 122 M_L_CPU1_SB_DQ<16> DQ16_B @T6G_MB_LIB.T6G(SCH_1):M_L_CPU1_SB_DQ(16)
 124 M_L_CPU1_SB_DQ<17> DQ17_B @T6G_MB_LIB.T6G(SCH_1):M_L_CPU1_SB_DQ(17)
 267 M_L_CPU1_SB_DQ<18> DQ18_B @T6G_MB_LIB.T6G(SCH_1):M_L_CPU1_SB_DQ(18)
 269 M_L_CPU1_SB_DQ<19> DQ19_B @T6G_MB_LIB.T6G(SCH_1):M_L_CPU1_SB_DQ(19)
 129 M_L_CPU1_SB_DQ<20> DQ20_B @T6G_MB_LIB.T6G(SCH_1):M_L_CPU1_SB_DQ(20)
 131 M_L_CPU1_SB_DQ<21> DQ21_B @T6G_MB_LIB.T6G(SCH_1):M_L_CPU1_SB_DQ(21)
 274 M_L_CPU1_SB_DQ<22> DQ22_B @T6G_MB_LIB.T6G(SCH_1):M_L_CPU1_SB_DQ(22)
 276 M_L_CPU1_SB_DQ<23> DQ23_B @T6G_MB_LIB.T6G(SCH_1):M_L_CPU1_SB_DQ(23)
 133 M_L_CPU1_SB_DQ<24> DQ24_B @T6G_MB_LIB.T6G(SCH_1):M_L_CPU1_SB_DQ(24)
 135 M_L_CPU1_SB_DQ<25> DQ25_B @T6G_MB_LIB.T6G(SCH_1):M_L_CPU1_SB_DQ(25)
 278 M_L_CPU1_SB_DQ<26> DQ26_B @T6G_MB_LIB.T6G(SCH_1):M_L_CPU1_SB_DQ(26)
 280 M_L_CPU1_SB_DQ<27> DQ27_B @T6G_MB_LIB.T6G(SCH_1):M_L_CPU1_SB_DQ(27)
 140 M_L_CPU1_SB_DQ<28> DQ28_B @T6G_MB_LIB.T6G(SCH_1):M_L_CPU1_SB_DQ(28)
 142 M_L_CPU1_SB_DQ<29> DQ29_B @T6G_MB_LIB.T6G(SCH_1):M_L_CPU1_SB_DQ(29)
 285 M_L_CPU1_SB_DQ<30> DQ30_B @T6G_MB_LIB.T6G(SCH_1):M_L_CPU1_SB_DQ(30)
 287 M_L_CPU1_SB_DQ<31> DQ31_B @T6G_MB_LIB.T6G(SCH_1):M_L_CPU1_SB_DQ(31)
   7 M_L_CPU1_SA_DQ<0>  DQ0_A @T6G_MB_LIB.T6G(SCH_1):M_L_CPU1_SA_DQ(0)
   9 M_L_CPU1_SA_DQ<1>  DQ1_A @T6G_MB_LIB.T6G(SCH_1):M_L_CPU1_SA_DQ(1)
 152 M_L_CPU1_SA_DQ<2>  DQ2_A @T6G_MB_LIB.T6G(SCH_1):M_L_CPU1_SA_DQ(2)
 154 M_L_CPU1_SA_DQ<3>  DQ3_A @T6G_MB_LIB.T6G(SCH_1):M_L_CPU1_SA_DQ(3)
  14 M_L_CPU1_SA_DQ<4>  DQ4_A @T6G_MB_LIB.T6G(SCH_1):M_L_CPU1_SA_DQ(4)
  16 M_L_CPU1_SA_DQ<5>  DQ5_A @T6G_MB_LIB.T6G(SCH_1):M_L_CPU1_SA_DQ(5)
 159 M_L_CPU1_SA_DQ<6>  DQ6_A @T6G_MB_LIB.T6G(SCH_1):M_L_CPU1_SA_DQ(6)
 161 M_L_CPU1_SA_DQ<7>  DQ7_A @T6G_MB_LIB.T6G(SCH_1):M_L_CPU1_SA_DQ(7)
  18 M_L_CPU1_SA_DQ<8>  DQ8_A @T6G_MB_LIB.T6G(SCH_1):M_L_CPU1_SA_DQ(8)
  20 M_L_CPU1_SA_DQ<9>  DQ9_A @T6G_MB_LIB.T6G(SCH_1):M_L_CPU1_SA_DQ(9)
 163 M_L_CPU1_SA_DQ<10> DQ10_A @T6G_MB_LIB.T6G(SCH_1):M_L_CPU1_SA_DQ(10)
 165 M_L_CPU1_SA_DQ<11> DQ11_A @T6G_MB_LIB.T6G(SCH_1):M_L_CPU1_SA_DQ(11)
  25 M_L_CPU1_SA_DQ<12> DQ12_A @T6G_MB_LIB.T6G(SCH_1):M_L_CPU1_SA_DQ(12)
  27 M_L_CPU1_SA_DQ<13> DQ13_A @T6G_MB_LIB.T6G(SCH_1):M_L_CPU1_SA_DQ(13)
 170 M_L_CPU1_SA_DQ<14> DQ14_A @T6G_MB_LIB.T6G(SCH_1):M_L_CPU1_SA_DQ(14)
 172 M_L_CPU1_SA_DQ<15> DQ15_A @T6G_MB_LIB.T6G(SCH_1):M_L_CPU1_SA_DQ(15)
  29 M_L_CPU1_SA_DQ<16> DQ16_A @T6G_MB_LIB.T6G(SCH_1):M_L_CPU1_SA_DQ(16)
  31 M_L_CPU1_SA_DQ<17> DQ17_A @T6G_MB_LIB.T6G(SCH_1):M_L_CPU1_SA_DQ(17)
 174 M_L_CPU1_SA_DQ<18> DQ18_A @T6G_MB_LIB.T6G(SCH_1):M_L_CPU1_SA_DQ(18)
 176 M_L_CPU1_SA_DQ<19> DQ19_A @T6G_MB_LIB.T6G(SCH_1):M_L_CPU1_SA_DQ(19)
  36 M_L_CPU1_SA_DQ<20> DQ20_A @T6G_MB_LIB.T6G(SCH_1):M_L_CPU1_SA_DQ(20)
  38 M_L_CPU1_SA_DQ<21> DQ21_A @T6G_MB_LIB.T6G(SCH_1):M_L_CPU1_SA_DQ(21)
 181 M_L_CPU1_SA_DQ<22> DQ22_A @T6G_MB_LIB.T6G(SCH_1):M_L_CPU1_SA_DQ(22)
 183 M_L_CPU1_SA_DQ<23> DQ23_A @T6G_MB_LIB.T6G(SCH_1):M_L_CPU1_SA_DQ(23)
  40 M_L_CPU1_SA_DQ<24> DQ24_A @T6G_MB_LIB.T6G(SCH_1):M_L_CPU1_SA_DQ(24)
  42 M_L_CPU1_SA_DQ<25> DQ25_A @T6G_MB_LIB.T6G(SCH_1):M_L_CPU1_SA_DQ(25)
 185 M_L_CPU1_SA_DQ<26> DQ26_A @T6G_MB_LIB.T6G(SCH_1):M_L_CPU1_SA_DQ(26)
 187 M_L_CPU1_SA_DQ<27> DQ27_A @T6G_MB_LIB.T6G(SCH_1):M_L_CPU1_SA_DQ(27)
  47 M_L_CPU1_SA_DQ<28> DQ28_A @T6G_MB_LIB.T6G(SCH_1):M_L_CPU1_SA_DQ(28)
  49 M_L_CPU1_SA_DQ<29> DQ29_A @T6G_MB_LIB.T6G(SCH_1):M_L_CPU1_SA_DQ(29)
 192 M_L_CPU1_SA_DQ<30> DQ30_A @T6G_MB_LIB.T6G(SCH_1):M_L_CPU1_SA_DQ(30)
 229 M_L_CPU1_SB_CS_N<1> CS1_B_N @T6G_MB_LIB.T6G(SCH_1):M_L_CPU1_SB_CS_N(1)
 209 M_L_CPU1_SA_CS_N<1> CS1_A_N @T6G_MB_LIB.T6G(SCH_1):M_L_CPU1_SA_CS_N(1)
  84 M_L_CPU1_SB_CS_N<0> CS0_B_N @T6G_MB_LIB.T6G(SCH_1):M_L_CPU1_SB_CS_N(0)
  64 M_L_CPU1_SA_CS_N<0> CS0_A_N @T6G_MB_LIB.T6G(SCH_1):M_L_CPU1_SA_CS_N(0)
 217 M_L_CPU1_CLK_DP<0>   CK_T @T6G_MB_LIB.T6G(SCH_1):M_L_CPU1_CLK_DP(0)
 218 M_L_CPU1_CLK_DN<0>   CK_C @T6G_MB_LIB.T6G(SCH_1):M_L_CPU1_CLK_DN(0)
  96 M_L_CPU1_SB_CB<0>  CB0_B @T6G_MB_LIB.T6G(SCH_1):M_L_CPU1_SB_CB(0)
  98 M_L_CPU1_SB_CB<1>  CB1_B @T6G_MB_LIB.T6G(SCH_1):M_L_CPU1_SB_CB(1)
 241 M_L_CPU1_SB_CB<2>  CB2_B @T6G_MB_LIB.T6G(SCH_1):M_L_CPU1_SB_CB(2)
 243 M_L_CPU1_SB_CB<3>  CB3_B @T6G_MB_LIB.T6G(SCH_1):M_L_CPU1_SB_CB(3)
  89 M_L_CPU1_SB_CB<4>  CB4_B @T6G_MB_LIB.T6G(SCH_1):M_L_CPU1_SB_CB(4)
  91 M_L_CPU1_SB_CB<5>  CB5_B @T6G_MB_LIB.T6G(SCH_1):M_L_CPU1_SB_CB(5)
 234 M_L_CPU1_SB_CB<6>  CB6_B @T6G_MB_LIB.T6G(SCH_1):M_L_CPU1_SB_CB(6)
  51 M_L_CPU1_SA_CB<0>  CB0_A @T6G_MB_LIB.T6G(SCH_1):M_L_CPU1_SA_CB(0)
 196 M_L_CPU1_SA_CB<2>  CB2_A @T6G_MB_LIB.T6G(SCH_1):M_L_CPU1_SA_CB(2)
 198 M_L_CPU1_SA_CB<3>  CB3_A @T6G_MB_LIB.T6G(SCH_1):M_L_CPU1_SA_CB(3)
  60 M_L_CPU1_SA_CB<5>  CB5_A @T6G_MB_LIB.T6G(SCH_1):M_L_CPU1_SA_CB(5)
 203 M_L_CPU1_SA_CB<6>  CB6_A @T6G_MB_LIB.T6G(SCH_1):M_L_CPU1_SA_CB(6)
  82 M_L_CPU1_SB_CA<6>  CA6_B @T6G_MB_LIB.T6G(SCH_1):M_L_CPU1_SB_CA(6)
  72 M_L_CPU1_SA_CA<6>  CA6_A @T6G_MB_LIB.T6G(SCH_1):M_L_CPU1_SA_CA(6)
 225 M_L_CPU1_SB_CA<5>  CA5_B @T6G_MB_LIB.T6G(SCH_1):M_L_CPU1_SB_CA(5)
 215 M_L_CPU1_SA_CA<5>  CA5_A @T6G_MB_LIB.T6G(SCH_1):M_L_CPU1_SA_CA(5)
  80 M_L_CPU1_SB_CA<4>  CA4_B @T6G_MB_LIB.T6G(SCH_1):M_L_CPU1_SB_CA(4)
  70 M_L_CPU1_SA_CA<4>  CA4_A @T6G_MB_LIB.T6G(SCH_1):M_L_CPU1_SA_CA(4)
 223 M_L_CPU1_SB_CA<3>  CA3_B @T6G_MB_LIB.T6G(SCH_1):M_L_CPU1_SB_CA(3)
 213 M_L_CPU1_SA_CA<3>  CA3_A @T6G_MB_LIB.T6G(SCH_1):M_L_CPU1_SA_CA(3)
  78 M_L_CPU1_SB_CA<2>  CA2_B @T6G_MB_LIB.T6G(SCH_1):M_L_CPU1_SB_CA(2)
  68 M_L_CPU1_SA_CA<2>  CA2_A @T6G_MB_LIB.T6G(SCH_1):M_L_CPU1_SA_CA(2)
 221 M_L_CPU1_SB_CA<1>  CA1_B @T6G_MB_LIB.T6G(SCH_1):M_L_CPU1_SB_CA(1)
 211 M_L_CPU1_SA_CA<1>  CA1_A @T6G_MB_LIB.T6G(SCH_1):M_L_CPU1_SA_CA(1)
  76 M_L_CPU1_SB_CA<0>  CA0_B @T6G_MB_LIB.T6G(SCH_1):M_L_CPU1_SB_CA(0)
  66 M_L_CPU1_SA_CA<0>  CA0_A @T6G_MB_LIB.T6G(SCH_1):M_L_CPU1_SA_CA(0)
  62 M_L_CPU1_ALERT_N ALERT_N @T6G_MB_LIB.T6G(SCH_1):M_L_CPU1_ALERT_N
 236 M_L_CPU1_SB_CB<7>  CB7_B @T6G_MB_LIB.T6G(SCH_1):M_L_CPU1_SB_CB(7)
  53 M_L_CPU1_SA_CB<1>  CB1_A @T6G_MB_LIB.T6G(SCH_1):M_L_CPU1_SA_CB(1)
  58 M_L_CPU1_SA_CB<4>  CB4_A @T6G_MB_LIB.T6G(SCH_1):M_L_CPU1_SA_CB(4)
 205 M_L_CPU1_SA_CB<7>  CB7_A @T6G_MB_LIB.T6G(SCH_1):M_L_CPU1_SA_CB(7)
 194 M_L_CPU1_SA_DQ<31> DQ31_A @T6G_MB_LIB.T6G(SCH_1):M_L_CPU1_SA_DQ(31)

Q_RES_0402LF-84.5K,1%,1/16W,CHIP,CS38452FB05  I136  R778
   1 PD_CHL_CPU1_DIMM_SAA      A @T6G_MB_LIB.T6G(SCH_1):PD_CHL_CPU1_DIMM_SAA
   2    GND      B @T6G_MB_LIB.T6G(SCH_1):GND

SCONN288_DDR506112002KQ-SCONN288_DDR506112002KQ,SMA  I138  J37
   6    GND   VSS0 @T6G_MB_LIB.T6G(SCH_1):GND
   8    GND   VSS1 @T6G_MB_LIB.T6G(SCH_1):GND
  10    GND   VSS2 @T6G_MB_LIB.T6G(SCH_1):GND
  13    GND   VSS3 @T6G_MB_LIB.T6G(SCH_1):GND
  15    GND   VSS4 @T6G_MB_LIB.T6G(SCH_1):GND
  17    GND   VSS5 @T6G_MB_LIB.T6G(SCH_1):GND
  19    GND   VSS6 @T6G_MB_LIB.T6G(SCH_1):GND
  21    GND   VSS7 @T6G_MB_LIB.T6G(SCH_1):GND
  24    GND   VSS8 @T6G_MB_LIB.T6G(SCH_1):GND
  26    GND   VSS9 @T6G_MB_LIB.T6G(SCH_1):GND
  28    GND  VSS10 @T6G_MB_LIB.T6G(SCH_1):GND
  30    GND  VSS11 @T6G_MB_LIB.T6G(SCH_1):GND
  32    GND  VSS12 @T6G_MB_LIB.T6G(SCH_1):GND
  35    GND  VSS13 @T6G_MB_LIB.T6G(SCH_1):GND
  37    GND  VSS14 @T6G_MB_LIB.T6G(SCH_1):GND
  39    GND  VSS15 @T6G_MB_LIB.T6G(SCH_1):GND
  41    GND  VSS16 @T6G_MB_LIB.T6G(SCH_1):GND
  43    GND  VSS17 @T6G_MB_LIB.T6G(SCH_1):GND
  46    GND  VSS18 @T6G_MB_LIB.T6G(SCH_1):GND
  48    GND  VSS19 @T6G_MB_LIB.T6G(SCH_1):GND
  50    GND  VSS20 @T6G_MB_LIB.T6G(SCH_1):GND
  52    GND  VSS21 @T6G_MB_LIB.T6G(SCH_1):GND
  54    GND  VSS22 @T6G_MB_LIB.T6G(SCH_1):GND
  57    GND  VSS23 @T6G_MB_LIB.T6G(SCH_1):GND
  59    GND  VSS24 @T6G_MB_LIB.T6G(SCH_1):GND
  61    GND  VSS25 @T6G_MB_LIB.T6G(SCH_1):GND
  63    GND  VSS26 @T6G_MB_LIB.T6G(SCH_1):GND
  65    GND  VSS27 @T6G_MB_LIB.T6G(SCH_1):GND
  67    GND  VSS28 @T6G_MB_LIB.T6G(SCH_1):GND
  69    GND  VSS29 @T6G_MB_LIB.T6G(SCH_1):GND
  71    GND  VSS30 @T6G_MB_LIB.T6G(SCH_1):GND
  73    GND  VSS31 @T6G_MB_LIB.T6G(SCH_1):GND
  75    GND  VSS32 @T6G_MB_LIB.T6G(SCH_1):GND
  77    GND  VSS33 @T6G_MB_LIB.T6G(SCH_1):GND
  79    GND  VSS34 @T6G_MB_LIB.T6G(SCH_1):GND
  81    GND  VSS35 @T6G_MB_LIB.T6G(SCH_1):GND
  83    GND  VSS36 @T6G_MB_LIB.T6G(SCH_1):GND
  85    GND  VSS37 @T6G_MB_LIB.T6G(SCH_1):GND
  88    GND  VSS38 @T6G_MB_LIB.T6G(SCH_1):GND
  90    GND  VSS39 @T6G_MB_LIB.T6G(SCH_1):GND
  92    GND  VSS40 @T6G_MB_LIB.T6G(SCH_1):GND
  95    GND  VSS41 @T6G_MB_LIB.T6G(SCH_1):GND
  97    GND  VSS42 @T6G_MB_LIB.T6G(SCH_1):GND
  99    GND  VSS43 @T6G_MB_LIB.T6G(SCH_1):GND
 101    GND  VSS44 @T6G_MB_LIB.T6G(SCH_1):GND
 103    GND  VSS45 @T6G_MB_LIB.T6G(SCH_1):GND
 106    GND  VSS46 @T6G_MB_LIB.T6G(SCH_1):GND
 108    GND  VSS47 @T6G_MB_LIB.T6G(SCH_1):GND
 110    GND  VSS48 @T6G_MB_LIB.T6G(SCH_1):GND
 112    GND  VSS49 @T6G_MB_LIB.T6G(SCH_1):GND
 114    GND  VSS50 @T6G_MB_LIB.T6G(SCH_1):GND
 117    GND  VSS51 @T6G_MB_LIB.T6G(SCH_1):GND
 119    GND  VSS52 @T6G_MB_LIB.T6G(SCH_1):GND
 121    GND  VSS53 @T6G_MB_LIB.T6G(SCH_1):GND
 123    GND  VSS54 @T6G_MB_LIB.T6G(SCH_1):GND
 125    GND  VSS55 @T6G_MB_LIB.T6G(SCH_1):GND
 128    GND  VSS56 @T6G_MB_LIB.T6G(SCH_1):GND
 130    GND  VSS57 @T6G_MB_LIB.T6G(SCH_1):GND
 134    GND  VSS59 @T6G_MB_LIB.T6G(SCH_1):GND
 143    GND  VSS63 @T6G_MB_LIB.T6G(SCH_1):GND
 151    GND  VSS64 @T6G_MB_LIB.T6G(SCH_1):GND
 153    GND  VSS65 @T6G_MB_LIB.T6G(SCH_1):GND
 155    GND  VSS66 @T6G_MB_LIB.T6G(SCH_1):GND
 158    GND  VSS67 @T6G_MB_LIB.T6G(SCH_1):GND
 160    GND  VSS68 @T6G_MB_LIB.T6G(SCH_1):GND
 162    GND  VSS69 @T6G_MB_LIB.T6G(SCH_1):GND
 164    GND  VSS70 @T6G_MB_LIB.T6G(SCH_1):GND
 166    GND  VSS71 @T6G_MB_LIB.T6G(SCH_1):GND
 169    GND  VSS72 @T6G_MB_LIB.T6G(SCH_1):GND
 171    GND  VSS73 @T6G_MB_LIB.T6G(SCH_1):GND
 173    GND  VSS74 @T6G_MB_LIB.T6G(SCH_1):GND
 175    GND  VSS75 @T6G_MB_LIB.T6G(SCH_1):GND
 177    GND  VSS76 @T6G_MB_LIB.T6G(SCH_1):GND
 180    GND  VSS77 @T6G_MB_LIB.T6G(SCH_1):GND
 182    GND  VSS78 @T6G_MB_LIB.T6G(SCH_1):GND
 184    GND  VSS79 @T6G_MB_LIB.T6G(SCH_1):GND
 186    GND  VSS80 @T6G_MB_LIB.T6G(SCH_1):GND
 188    GND  VSS81 @T6G_MB_LIB.T6G(SCH_1):GND
 191    GND  VSS82 @T6G_MB_LIB.T6G(SCH_1):GND
 193    GND  VSS83 @T6G_MB_LIB.T6G(SCH_1):GND
 195    GND  VSS84 @T6G_MB_LIB.T6G(SCH_1):GND
 197    GND  VSS85 @T6G_MB_LIB.T6G(SCH_1):GND
 199    GND  VSS86 @T6G_MB_LIB.T6G(SCH_1):GND
 202    GND  VSS87 @T6G_MB_LIB.T6G(SCH_1):GND
 204    GND  VSS88 @T6G_MB_LIB.T6G(SCH_1):GND
 206    GND  VSS89 @T6G_MB_LIB.T6G(SCH_1):GND
 208    GND  VSS90 @T6G_MB_LIB.T6G(SCH_1):GND
 210    GND  VSS91 @T6G_MB_LIB.T6G(SCH_1):GND
 212    GND  VSS92 @T6G_MB_LIB.T6G(SCH_1):GND
 214    GND  VSS93 @T6G_MB_LIB.T6G(SCH_1):GND
 216    GND  VSS94 @T6G_MB_LIB.T6G(SCH_1):GND
 219    GND  VSS95 @T6G_MB_LIB.T6G(SCH_1):GND
 222    GND  VSS96 @T6G_MB_LIB.T6G(SCH_1):GND
 224    GND  VSS97 @T6G_MB_LIB.T6G(SCH_1):GND
 226    GND  VSS98 @T6G_MB_LIB.T6G(SCH_1):GND
 228    GND  VSS99 @T6G_MB_LIB.T6G(SCH_1):GND
 233    GND VSS101 @T6G_MB_LIB.T6G(SCH_1):GND
 237    GND VSS103 @T6G_MB_LIB.T6G(SCH_1):GND
 242    GND VSS105 @T6G_MB_LIB.T6G(SCH_1):GND
 244    GND VSS106 @T6G_MB_LIB.T6G(SCH_1):GND
 246    GND VSS107 @T6G_MB_LIB.T6G(SCH_1):GND
 248    GND VSS108 @T6G_MB_LIB.T6G(SCH_1):GND
 251    GND VSS109 @T6G_MB_LIB.T6G(SCH_1):GND
 253    GND VSS110 @T6G_MB_LIB.T6G(SCH_1):GND
 255    GND VSS111 @T6G_MB_LIB.T6G(SCH_1):GND
 257    GND VSS112 @T6G_MB_LIB.T6G(SCH_1):GND
 259    GND VSS113 @T6G_MB_LIB.T6G(SCH_1):GND
 262    GND VSS114 @T6G_MB_LIB.T6G(SCH_1):GND
 264    GND VSS115 @T6G_MB_LIB.T6G(SCH_1):GND
 266    GND VSS116 @T6G_MB_LIB.T6G(SCH_1):GND
 268    GND VSS117 @T6G_MB_LIB.T6G(SCH_1):GND
 270    GND VSS118 @T6G_MB_LIB.T6G(SCH_1):GND
 273    GND VSS119 @T6G_MB_LIB.T6G(SCH_1):GND
 275    GND VSS120 @T6G_MB_LIB.T6G(SCH_1):GND
 277    GND VSS121 @T6G_MB_LIB.T6G(SCH_1):GND
 279    GND VSS122 @T6G_MB_LIB.T6G(SCH_1):GND
 281    GND VSS123 @T6G_MB_LIB.T6G(SCH_1):GND
 284    GND VSS124 @T6G_MB_LIB.T6G(SCH_1):GND
 286    GND VSS125 @T6G_MB_LIB.T6G(SCH_1):GND
 288    GND VSS126 @T6G_MB_LIB.T6G(SCH_1):GND
   1 P12V_MEM_CPU1 VIN_BULK0 @T6G_MB_LIB.T6G(SCH_1):P12V_MEM_CPU1
 145 P12V_MEM_CPU1 VIN_BULK1 @T6G_MB_LIB.T6G(SCH_1):P12V_MEM_CPU1
 146 P12V_MEM_CPU1 VIN_BULK2 @T6G_MB_LIB.T6G(SCH_1):P12V_MEM_CPU1
 230    GND VSS100 @T6G_MB_LIB.T6G(SCH_1):GND
 235    GND VSS102 @T6G_MB_LIB.T6G(SCH_1):GND
 240    GND VSS104 @T6G_MB_LIB.T6G(SCH_1):GND
 132    GND  VSS58 @T6G_MB_LIB.T6G(SCH_1):GND
 136    GND  VSS60 @T6G_MB_LIB.T6G(SCH_1):GND
 139    GND  VSS61 @T6G_MB_LIB.T6G(SCH_1):GND
 141    GND  VSS62 @T6G_MB_LIB.T6G(SCH_1):GND
  G1    GND     G1 @T6G_MB_LIB.T6G(SCH_1):GND
  G2    GND     G2 @T6G_MB_LIB.T6G(SCH_1):GND
  G3    GND     G3 @T6G_MB_LIB.T6G(SCH_1):GND

Q_CAP_0402-0.1UF,25V,10%,X7R,CH4104K1B00  I185  C180
   1 P3V3_AUX      A @T6G_MB_LIB.T6G(SCH_1):P3V3_AUX
   2    GND      B @T6G_MB_LIB.T6G(SCH_1):GND

Q_RES_0402LF-1K,1%,1/16W,CHIP,CS21002FB06  I188  R314
   1 PWRGD_CHL_CPU1_DIMM      A @T6G_MB_LIB.T6G(SCH_1):PWRGD_CHL_CPU1_DIMM
   2 PWRGD_CHGL_CPU1      B @T6G_MB_LIB.T6G(SCH_1):PWRGD_CHGL_CPU1

Q_RES_0402LF-1K,1%,1/16W,EMPTY,CS21002FB06  I190  R115
   1   P3V3      A @T6G_MB_LIB.T6G(SCH_1):P3V3
   2 PWRGD_CHL_CPU1_DIMM      B @T6G_MB_LIB.T6G(SCH_1):PWRGD_CHL_CPU1_DIMM

SCONN288_DDR506112002KQ-SCONN288_DDR506112002KQ,SMA  I235  J37
  93 M_L_CPU1_SB_DQS_DP<9> DQS9_B_T||TDQS9_B_T||DBI4_B_N @T6G_MB_LIB.T6G(SCH_1):M_L_CPU1_SB_DQS_DP(9)
  94 M_L_CPU1_SB_DQS_DN<9> DQS9_B_C||TDQS9_B_C @T6G_MB_LIB.T6G(SCH_1):M_L_CPU1_SB_DQS_DN(9)
 201 M_L_CPU1_SA_DQS_DP<9> DQS9_A_T||TDQS9_A_T @T6G_MB_LIB.T6G(SCH_1):M_L_CPU1_SA_DQS_DP(9)
 200 M_L_CPU1_SA_DQS_DN<9> DQS9_A_C||TDQS9_A_C @T6G_MB_LIB.T6G(SCH_1):M_L_CPU1_SA_DQS_DN(9)
 190 M_L_CPU1_SA_DQS_DP<8> DQS8_A_T||TDQS8_A_T @T6G_MB_LIB.T6G(SCH_1):M_L_CPU1_SA_DQS_DP(8)
 189 M_L_CPU1_SA_DQS_DN<8> DQS8_A_C||TDQS8_A_C @T6G_MB_LIB.T6G(SCH_1):M_L_CPU1_SA_DQS_DN(8)
 271 M_L_CPU1_SB_DQS_DN<7> DQS7_B_C||TDQS7_B_C @T6G_MB_LIB.T6G(SCH_1):M_L_CPU1_SB_DQS_DN(7)
 179 M_L_CPU1_SA_DQS_DP<7> DQS7_A_T||TDQS7_A_T @T6G_MB_LIB.T6G(SCH_1):M_L_CPU1_SA_DQS_DP(7)
 261 M_L_CPU1_SB_DQS_DP<6> DQS6_B_T||TDQS6_B_T @T6G_MB_LIB.T6G(SCH_1):M_L_CPU1_SB_DQS_DP(6)
 260 M_L_CPU1_SB_DQS_DN<6> DQS6_B_C||TDQS6_B_C @T6G_MB_LIB.T6G(SCH_1):M_L_CPU1_SB_DQS_DN(6)
 167 M_L_CPU1_SA_DQS_DN<6> DQS6_A_C||TDQS6_A_C||DQS6_A_T||TDQS6_A_T @T6G_MB_LIB.T6G(SCH_1):M_L_CPU1_SA_DQS_DN(6)
 250 M_L_CPU1_SB_DQS_DP<5> DQS5_B_T||TDQS5_B_T @T6G_MB_LIB.T6G(SCH_1):M_L_CPU1_SB_DQS_DP(5)
 249 M_L_CPU1_SB_DQS_DN<5> DQS5_B_C||TDQS5_B_C @T6G_MB_LIB.T6G(SCH_1):M_L_CPU1_SB_DQS_DN(5)
 157 M_L_CPU1_SA_DQS_DP<5> DQS5_A_T||TDQS5_A_T @T6G_MB_LIB.T6G(SCH_1):M_L_CPU1_SA_DQS_DP(5)
 156 M_L_CPU1_SA_DQS_DN<5> DQS5_A_C||TDQS5_A_C||DQS5_A_T||TDQS5_A_T @T6G_MB_LIB.T6G(SCH_1):M_L_CPU1_SA_DQS_DN(5)
 239 M_L_CPU1_SB_DQS_DP<4> DQS4_B_T @T6G_MB_LIB.T6G(SCH_1):M_L_CPU1_SB_DQS_DP(4)
 238 M_L_CPU1_SB_DQS_DN<4> DQS4_B_C @T6G_MB_LIB.T6G(SCH_1):M_L_CPU1_SB_DQS_DN(4)
  55 M_L_CPU1_SA_DQS_DP<4> DQS4_A_T @T6G_MB_LIB.T6G(SCH_1):M_L_CPU1_SA_DQS_DP(4)
  56 M_L_CPU1_SA_DQS_DN<4> DQS4_A_C @T6G_MB_LIB.T6G(SCH_1):M_L_CPU1_SA_DQS_DN(4)
 137 M_L_CPU1_SB_DQS_DP<3> DQS3_B_T @T6G_MB_LIB.T6G(SCH_1):M_L_CPU1_SB_DQS_DP(3)
 138 M_L_CPU1_SB_DQS_DN<3> DQS3_B_C @T6G_MB_LIB.T6G(SCH_1):M_L_CPU1_SB_DQS_DN(3)
  44 M_L_CPU1_SA_DQS_DP<3> DQS3_A_T @T6G_MB_LIB.T6G(SCH_1):M_L_CPU1_SA_DQS_DP(3)
  45 M_L_CPU1_SA_DQS_DN<3> DQS3_A_C @T6G_MB_LIB.T6G(SCH_1):M_L_CPU1_SA_DQS_DN(3)
 126 M_L_CPU1_SB_DQS_DP<2> DQS2_B_T @T6G_MB_LIB.T6G(SCH_1):M_L_CPU1_SB_DQS_DP(2)
 127 M_L_CPU1_SB_DQS_DN<2> DQS2_B_C @T6G_MB_LIB.T6G(SCH_1):M_L_CPU1_SB_DQS_DN(2)
  33 M_L_CPU1_SA_DQS_DP<2> DQS2_A_T @T6G_MB_LIB.T6G(SCH_1):M_L_CPU1_SA_DQS_DP(2)
  34 M_L_CPU1_SA_DQS_DN<2> DQS2_A_C @T6G_MB_LIB.T6G(SCH_1):M_L_CPU1_SA_DQS_DN(2)
 115 M_L_CPU1_SB_DQS_DP<1> DQS1_B_T @T6G_MB_LIB.T6G(SCH_1):M_L_CPU1_SB_DQS_DP(1)
 116 M_L_CPU1_SB_DQS_DN<1> DQS1_B_C @T6G_MB_LIB.T6G(SCH_1):M_L_CPU1_SB_DQS_DN(1)
  22 M_L_CPU1_SA_DQS_DP<1> DQS1_A_T @T6G_MB_LIB.T6G(SCH_1):M_L_CPU1_SA_DQS_DP(1)
  23 M_L_CPU1_SA_DQS_DN<1> DQS1_A_C @T6G_MB_LIB.T6G(SCH_1):M_L_CPU1_SA_DQS_DN(1)
 104 M_L_CPU1_SB_DQS_DP<0> DQS0_B_T @T6G_MB_LIB.T6G(SCH_1):M_L_CPU1_SB_DQS_DP(0)
 105 M_L_CPU1_SB_DQS_DN<0> DQS0_B_C @T6G_MB_LIB.T6G(SCH_1):M_L_CPU1_SB_DQS_DN(0)
  11 M_L_CPU1_SA_DQS_DP<0> DQS0_A_T @T6G_MB_LIB.T6G(SCH_1):M_L_CPU1_SA_DQS_DP(0)
  12 M_L_CPU1_SA_DQS_DN<0> DQS0_A_C @T6G_MB_LIB.T6G(SCH_1):M_L_CPU1_SA_DQS_DN(0)
 272 M_L_CPU1_SB_DQS_DP<7> DQS7_B_T||TDQS7_B_T @T6G_MB_LIB.T6G(SCH_1):M_L_CPU1_SB_DQS_DP(7)
 282 M_L_CPU1_SB_DQS_DN<8> DQS8_B_C||TDQS8_B_C @T6G_MB_LIB.T6G(SCH_1):M_L_CPU1_SB_DQS_DN(8)
 283 M_L_CPU1_SB_DQS_DP<8> DQS8_B_T||TDQS8_B_T @T6G_MB_LIB.T6G(SCH_1):M_L_CPU1_SB_DQS_DP(8)
 168 M_L_CPU1_SA_DQS_DP<6> DQS6_A_T||TDQS6_A_T @T6G_MB_LIB.T6G(SCH_1):M_L_CPU1_SA_DQS_DP(6)
 178 M_L_CPU1_SA_DQS_DN<7> DQS7_A_C||TDQS7_A_C @T6G_MB_LIB.T6G(SCH_1):M_L_CPU1_SA_DQS_DN(7)

Q_CAP_C0805-10UF,25V,10%,X6S,CH6104KEA00  I237  C548
   1 P12V_MEM_CPU1      A @T6G_MB_LIB.T6G(SCH_1):P12V_MEM_CPU1
   2    GND      B @T6G_MB_LIB.T6G(SCH_1):GND

Q_CAP_C0805-10UF,25V,10%,X6S,CH6104KEA00  I238  C549
   1 P12V_MEM_CPU1      A @T6G_MB_LIB.T6G(SCH_1):P12V_MEM_CPU1
   2    GND      B @T6G_MB_LIB.T6G(SCH_1):GND

Q_RES_0402LF-49.9,1%,1/16W,CHIP,CS04992FB07  I241  R1591
   1 I3C_SPD_DDRGL_CPU1_SCL      A @T6G_MB_LIB.T6G(SCH_1):I3C_SPD_DDRGL_CPU1_SCL
   2 I3C_SPD_DDRL_CPU1_SCL      B @T6G_MB_LIB.T6G(SCH_1):I3C_SPD_DDRL_CPU1_SCL

Q_RES_0402LF-10,1%,1/16W,CHIP,CS01002FB07  I242  R1711
   1 I3C_SPD_DDRGL_CPU1_SDA      A @T6G_MB_LIB.T6G(SCH_1):I3C_SPD_DDRGL_CPU1_SDA
   2 I3C_SPD_DDRL_CPU1_SDA      B @T6G_MB_LIB.T6G(SCH_1):I3C_SPD_DDRL_CPU1_SDA


DRAWING: @T6G_MB_LIB.T6G(SCH_1):PAGE132 

MOSFET_DUAL_6P-2N7002KDW,SMLF,IC,BAM70020047  I12  Q4
   2 IRQ_LVC3_WAKE_N     G1 @T6G_MB_LIB.T6G(SCH_1):IRQ_LVC3_WAKE_N
   5 IRQ_LVC3_WAKE     G2 @T6G_MB_LIB.T6G(SCH_1):IRQ_LVC3_WAKE
   1    GND     S1 @T6G_MB_LIB.T6G(SCH_1):GND
   4    GND     S2 @T6G_MB_LIB.T6G(SCH_1):GND
   6 IRQ_LVC3_WAKE     D1 @T6G_MB_LIB.T6G(SCH_1):IRQ_LVC3_WAKE
   3 IRQ_WAKE_R_N     D2 @T6G_MB_LIB.T6G(SCH_1):IRQ_WAKE_R_N

Q_RES_0402LF-33,5%,1/16W,CHIP,CS03302JB10  I4  R1005
   1 M2_0_PEWAKE_R_N      A @T6G_MB_LIB.T6G(SCH_1):M2_0_PEWAKE_R_N
   2 IRQ_LVC3_WAKE_N      B @T6G_MB_LIB.T6G(SCH_1):IRQ_LVC3_WAKE_N

Q_RES_0402LF-33,5%,1/16W,CHIP,CS03302JB10  I5  R116
   1 IRQ_OCP_SFF_WAKE_BUF_N      A @T6G_MB_LIB.T6G(SCH_1):IRQ_OCP_SFF_WAKE_BUF_N
   2 IRQ_LVC3_WAKE_N      B @T6G_MB_LIB.T6G(SCH_1):IRQ_LVC3_WAKE_N

Q_RES_0402LF-33,5%,1/16W,CHIP,CS03302JB10  I6  R6063
   1 IRQ_OCP_V3_2_WAKE_BUF_N      A @T6G_MB_LIB.T6G(SCH_1):IRQ_OCP_V3_2_WAKE_BUF_N
   2 IRQ_LVC3_WAKE_N      B @T6G_MB_LIB.T6G(SCH_1):IRQ_LVC3_WAKE_N

Q_RES_0402LF-10K,1%,1/16W,CHIP,CS31002FB08  I7  R994
   1 P3V3_AUX      A @T6G_MB_LIB.T6G(SCH_1):P3V3_AUX
   2 IRQ_LVC3_WAKE_N      B @T6G_MB_LIB.T6G(SCH_1):IRQ_LVC3_WAKE_N

Q_RES_0402LF-10K,1%,1/16W,CHIP,CS31002FB08  I10  R1009
   1 P3V3_AUX      A @T6G_MB_LIB.T6G(SCH_1):P3V3_AUX
   2 IRQ_LVC3_WAKE      B @T6G_MB_LIB.T6G(SCH_1):IRQ_LVC3_WAKE

Q_RES_0402LF-33,5%,1/16W,CHIP,CS03302JB10  I16  R1311
   1 IRQ_WAKE_R_N      A @T6G_MB_LIB.T6G(SCH_1):IRQ_WAKE_R_N
   2 IRQ_WAKE_N      B @T6G_MB_LIB.T6G(SCH_1):IRQ_WAKE_N

Q_RES_0402LF-2.2K,5%,1/16W,CHIP,CS22202JB07  I18  R437
   1 PVDD18_S5_P0      A @T6G_MB_LIB.T6G(SCH_1):PVDD18_S5_P0
   2 IRQ_WAKE_N      B @T6G_MB_LIB.T6G(SCH_1):IRQ_WAKE_N


DRAWING: @T6G_MB_LIB.T6G(SCH_1):PAGE136 

Q_RES_0402LF-0,5%,1/16W,CHIP,CS00002JB13  I31  R1297
   1 I3C_SPD_DDRAF_CPU0_SCL      A @T6G_MB_LIB.T6G(SCH_1):I3C_SPD_DDRAF_CPU0_SCL
   2 I3C_SPD_DDRAF_CPU0_LVC1_SCL      B @T6G_MB_LIB.T6G(SCH_1):I3C_SPD_DDRAF_CPU0_LVC1_SCL

Q_RES_0402LF-0,5%,1/16W,CHIP,CS00002JB13  I32  R1298
   1 I3C_SPD_DDRAF_CPU0_SDA      A @T6G_MB_LIB.T6G(SCH_1):I3C_SPD_DDRAF_CPU0_SDA
   2 I3C_SPD_DDRAF_CPU0_LVC1_SDA      B @T6G_MB_LIB.T6G(SCH_1):I3C_SPD_DDRAF_CPU0_LVC1_SDA

Q_RES_0402LF-0,5%,1/16W,CHIP,CS00002JB13  I33  R1299
   1 I3C_SPD_DDRGL_CPU0_SCL      A @T6G_MB_LIB.T6G(SCH_1):I3C_SPD_DDRGL_CPU0_SCL
   2 I3C_SPD_DDRGL_CPU0_LVC1_SCL      B @T6G_MB_LIB.T6G(SCH_1):I3C_SPD_DDRGL_CPU0_LVC1_SCL

Q_RES_0402LF-0,5%,1/16W,CHIP,CS00002JB13  I34  R1300
   1 I3C_SPD_DDRGL_CPU0_SDA      A @T6G_MB_LIB.T6G(SCH_1):I3C_SPD_DDRGL_CPU0_SDA
   2 I3C_SPD_DDRGL_CPU0_LVC1_SDA      B @T6G_MB_LIB.T6G(SCH_1):I3C_SPD_DDRGL_CPU0_LVC1_SDA

Q_RES_0402LF-0,5%,1/16W,CHIP,CS00002JB13  I35  R1293
   1 I3C_SPD_DDRAF_CPU1_SCL      A @T6G_MB_LIB.T6G(SCH_1):I3C_SPD_DDRAF_CPU1_SCL
   2 I3C_SPD_DDRAF_CPU1_LVC1_SCL      B @T6G_MB_LIB.T6G(SCH_1):I3C_SPD_DDRAF_CPU1_LVC1_SCL

Q_RES_0402LF-0,5%,1/16W,CHIP,CS00002JB13  I36  R1294
   1 I3C_SPD_DDRAF_CPU1_SDA      A @T6G_MB_LIB.T6G(SCH_1):I3C_SPD_DDRAF_CPU1_SDA
   2 I3C_SPD_DDRAF_CPU1_LVC1_SDA      B @T6G_MB_LIB.T6G(SCH_1):I3C_SPD_DDRAF_CPU1_LVC1_SDA

Q_RES_0402LF-0,5%,1/16W,CHIP,CS00002JB13  I37  R1295
   1 I3C_SPD_DDRGL_CPU1_SCL      A @T6G_MB_LIB.T6G(SCH_1):I3C_SPD_DDRGL_CPU1_SCL
   2 I3C_SPD_DDRGL_CPU1_LVC1_SCL      B @T6G_MB_LIB.T6G(SCH_1):I3C_SPD_DDRGL_CPU1_LVC1_SCL

Q_RES_0402LF-0,5%,1/16W,CHIP,CS00002JB13  I38  R1296
   1 I3C_SPD_DDRGL_CPU1_SDA      A @T6G_MB_LIB.T6G(SCH_1):I3C_SPD_DDRGL_CPU1_SDA
   2 I3C_SPD_DDRGL_CPU1_LVC1_SDA      B @T6G_MB_LIB.T6G(SCH_1):I3C_SPD_DDRGL_CPU1_LVC1_SDA

PI3CSW12ZUAEX-PI3CSW12ZUAEX,SMLF,IC,AL3CSW12000  I47  U105
   1 I3C_0_SPD_DDRAF_CPU0_SCL    1D+ @T6G_MB_LIB.T6G(SCH_1):I3C_0_SPD_DDRAF_CPU0_SCL
   3 I3C_SCM_0_R_SCL    2D+ @T6G_MB_LIB.T6G(SCH_1):I3C_SCM_0_R_SCL
   4 I3C_SCM_0_R_SDA    2D- @T6G_MB_LIB.T6G(SCH_1):I3C_SCM_0_R_SDA
   7 I3C_SPD_DDRAF_CPU0_LVC1_SDA     D- @T6G_MB_LIB.T6G(SCH_1):I3C_SPD_DDRAF_CPU0_LVC1_SDA
   6 FM_I3C_CPU0_MUX0_OE_N    OE# @T6G_MB_LIB.T6G(SCH_1):FM_I3C_CPU0_MUX0_OE_N
   9 FM_I3C_CPU0_MUX0_SEL      S @T6G_MB_LIB.T6G(SCH_1):FM_I3C_CPU0_MUX0_SEL
  10 P3V3_AUX    VDD @T6G_MB_LIB.T6G(SCH_1):P3V3_AUX
   2 I3C_0_SPD_DDRAF_CPU0_SDA    1D- @T6G_MB_LIB.T6G(SCH_1):I3C_0_SPD_DDRAF_CPU0_SDA
   5    GND    GND @T6G_MB_LIB.T6G(SCH_1):GND
   8 I3C_SPD_DDRAF_CPU0_LVC1_SCL     D+ @T6G_MB_LIB.T6G(SCH_1):I3C_SPD_DDRAF_CPU0_LVC1_SCL

Q_CAP_0402-0.1UF,25V,10%,X7R,CH4104K1B00  I50  C1336
   1 P3V3_AUX      A @T6G_MB_LIB.T6G(SCH_1):P3V3_AUX
   2    GND      B @T6G_MB_LIB.T6G(SCH_1):GND

PI3CSW12ZUAEX-PI3CSW12ZUAEX,SMLF,IC,AL3CSW12000  I54  U106
   1 I3C_1_SPD_DDRGL_CPU0_SCL    1D+ @T6G_MB_LIB.T6G(SCH_1):I3C_1_SPD_DDRGL_CPU0_SCL
   3 I3C_SCM_1_R_SCL    2D+ @T6G_MB_LIB.T6G(SCH_1):I3C_SCM_1_R_SCL
   4 I3C_SCM_1_R_SDA    2D- @T6G_MB_LIB.T6G(SCH_1):I3C_SCM_1_R_SDA
   7 I3C_SPD_DDRGL_CPU0_LVC1_SDA     D- @T6G_MB_LIB.T6G(SCH_1):I3C_SPD_DDRGL_CPU0_LVC1_SDA
   6 FM_I3C_CPU0_MUX1_OE_N    OE# @T6G_MB_LIB.T6G(SCH_1):FM_I3C_CPU0_MUX1_OE_N
   9 FM_I3C_CPU0_MUX1_SEL      S @T6G_MB_LIB.T6G(SCH_1):FM_I3C_CPU0_MUX1_SEL
  10 P3V3_AUX    VDD @T6G_MB_LIB.T6G(SCH_1):P3V3_AUX
   2 I3C_1_SPD_DDRGL_CPU0_SDA    1D- @T6G_MB_LIB.T6G(SCH_1):I3C_1_SPD_DDRGL_CPU0_SDA
   5    GND    GND @T6G_MB_LIB.T6G(SCH_1):GND
   8 I3C_SPD_DDRGL_CPU0_LVC1_SCL     D+ @T6G_MB_LIB.T6G(SCH_1):I3C_SPD_DDRGL_CPU0_LVC1_SCL

Q_CAP_0402-0.1UF,25V,10%,X7R,CH4104K1B00  I56  C1337
   1 P3V3_AUX      A @T6G_MB_LIB.T6G(SCH_1):P3V3_AUX
   2    GND      B @T6G_MB_LIB.T6G(SCH_1):GND

Q_CAP_0402-0.1UF,25V,10%,X7R,CH4104K1B00  I61  C1338
   1 P3V3_AUX      A @T6G_MB_LIB.T6G(SCH_1):P3V3_AUX
   2    GND      B @T6G_MB_LIB.T6G(SCH_1):GND

PI3CSW12ZUAEX-PI3CSW12ZUAEX,SMLF,IC,AL3CSW12000  I63  U107
   1 I3C_0_SPD_DDRAF_CPU1_SCL    1D+ @T6G_MB_LIB.T6G(SCH_1):I3C_0_SPD_DDRAF_CPU1_SCL
   3 I3C_SCM_2_R_SCL    2D+ @T6G_MB_LIB.T6G(SCH_1):I3C_SCM_2_R_SCL
   4 I3C_SCM_2_R_SDA    2D- @T6G_MB_LIB.T6G(SCH_1):I3C_SCM_2_R_SDA
   7 I3C_SPD_DDRAF_CPU1_LVC1_SDA     D- @T6G_MB_LIB.T6G(SCH_1):I3C_SPD_DDRAF_CPU1_LVC1_SDA
   6 FM_I3C_CPU1_MUX0_OE_N    OE# @T6G_MB_LIB.T6G(SCH_1):FM_I3C_CPU1_MUX0_OE_N
   9 FM_I3C_CPU1_MUX0_SEL      S @T6G_MB_LIB.T6G(SCH_1):FM_I3C_CPU1_MUX0_SEL
  10 P3V3_AUX    VDD @T6G_MB_LIB.T6G(SCH_1):P3V3_AUX
   2 I3C_0_SPD_DDRAF_CPU1_SDA    1D- @T6G_MB_LIB.T6G(SCH_1):I3C_0_SPD_DDRAF_CPU1_SDA
   5    GND    GND @T6G_MB_LIB.T6G(SCH_1):GND
   8 I3C_SPD_DDRAF_CPU1_LVC1_SCL     D+ @T6G_MB_LIB.T6G(SCH_1):I3C_SPD_DDRAF_CPU1_LVC1_SCL

Q_CAP_0402-0.1UF,25V,10%,X7R,CH4104K1B00  I66  C1339
   1 P3V3_AUX      A @T6G_MB_LIB.T6G(SCH_1):P3V3_AUX
   2    GND      B @T6G_MB_LIB.T6G(SCH_1):GND

PI3CSW12ZUAEX-PI3CSW12ZUAEX,SMLF,IC,AL3CSW12000  I68  U108
   1 I3C_1_SPD_DDRGL_CPU1_SCL    1D+ @T6G_MB_LIB.T6G(SCH_1):I3C_1_SPD_DDRGL_CPU1_SCL
   3 I3C_SCM_3_R_SCL    2D+ @T6G_MB_LIB.T6G(SCH_1):I3C_SCM_3_R_SCL
   4 I3C_SCM_3_R_SDA    2D- @T6G_MB_LIB.T6G(SCH_1):I3C_SCM_3_R_SDA
   7 I3C_SPD_DDRGL_CPU1_LVC1_SDA     D- @T6G_MB_LIB.T6G(SCH_1):I3C_SPD_DDRGL_CPU1_LVC1_SDA
   6 FM_I3C_CPU1_MUX1_OE_N    OE# @T6G_MB_LIB.T6G(SCH_1):FM_I3C_CPU1_MUX1_OE_N
   9 FM_I3C_CPU1_MUX1_SEL      S @T6G_MB_LIB.T6G(SCH_1):FM_I3C_CPU1_MUX1_SEL
  10 P3V3_AUX    VDD @T6G_MB_LIB.T6G(SCH_1):P3V3_AUX
   2 I3C_1_SPD_DDRGL_CPU1_SDA    1D- @T6G_MB_LIB.T6G(SCH_1):I3C_1_SPD_DDRGL_CPU1_SDA
   5    GND    GND @T6G_MB_LIB.T6G(SCH_1):GND
   8 I3C_SPD_DDRGL_CPU1_LVC1_SCL     D+ @T6G_MB_LIB.T6G(SCH_1):I3C_SPD_DDRGL_CPU1_LVC1_SCL

Q_RES_0402LF-0,5%,1/16W,CHIP,CS00002JB13  I99  R426
   1 I3C_0_SPD_DDRAF_CPU0_SCL      A @T6G_MB_LIB.T6G(SCH_1):I3C_0_SPD_DDRAF_CPU0_SCL
   2 I3C_0_SPD_DDRAF_CPU0_R_SCL      B @T6G_MB_LIB.T6G(SCH_1):I3C_0_SPD_DDRAF_CPU0_R_SCL

Q_RES_0402LF-0,5%,1/16W,CHIP,CS00002JB13  I100  R427
   1 I3C_0_SPD_DDRAF_CPU0_SDA      A @T6G_MB_LIB.T6G(SCH_1):I3C_0_SPD_DDRAF_CPU0_SDA
   2 I3C_0_SPD_DDRAF_CPU0_R_SDA      B @T6G_MB_LIB.T6G(SCH_1):I3C_0_SPD_DDRAF_CPU0_R_SDA

Q_RES_0402LF-0,5%,1/16W,CHIP,CS00002JB13  I103  R428
   1 I3C_1_SPD_DDRGL_CPU0_SCL      A @T6G_MB_LIB.T6G(SCH_1):I3C_1_SPD_DDRGL_CPU0_SCL
   2 I3C_1_SPD_DDRGL_CPU0_R_SCL      B @T6G_MB_LIB.T6G(SCH_1):I3C_1_SPD_DDRGL_CPU0_R_SCL

Q_RES_0402LF-0,5%,1/16W,CHIP,CS00002JB13  I104  R429
   1 I3C_1_SPD_DDRGL_CPU0_SDA      A @T6G_MB_LIB.T6G(SCH_1):I3C_1_SPD_DDRGL_CPU0_SDA
   2 I3C_1_SPD_DDRGL_CPU0_R_SDA      B @T6G_MB_LIB.T6G(SCH_1):I3C_1_SPD_DDRGL_CPU0_R_SDA

Q_RES_0402LF-0,5%,1/16W,CHIP,CS00002JB13  I107  R565
   1 I3C_0_SPD_DDRAF_CPU1_SDA      A @T6G_MB_LIB.T6G(SCH_1):I3C_0_SPD_DDRAF_CPU1_SDA
   2 I3C_0_SPD_DDRAF_CPU1_R_SDA      B @T6G_MB_LIB.T6G(SCH_1):I3C_0_SPD_DDRAF_CPU1_R_SDA

Q_RES_0402LF-0,5%,1/16W,CHIP,CS00002JB13  I108  R564
   1 I3C_0_SPD_DDRAF_CPU1_SCL      A @T6G_MB_LIB.T6G(SCH_1):I3C_0_SPD_DDRAF_CPU1_SCL
   2 I3C_0_SPD_DDRAF_CPU1_R_SCL      B @T6G_MB_LIB.T6G(SCH_1):I3C_0_SPD_DDRAF_CPU1_R_SCL

Q_RES_0402LF-0,5%,1/16W,CHIP,CS00002JB13  I111  R566
   1 I3C_1_SPD_DDRGL_CPU1_SCL      A @T6G_MB_LIB.T6G(SCH_1):I3C_1_SPD_DDRGL_CPU1_SCL
   2 I3C_1_SPD_DDRGL_CPU1_R_SCL      B @T6G_MB_LIB.T6G(SCH_1):I3C_1_SPD_DDRGL_CPU1_R_SCL

Q_RES_0402LF-0,5%,1/16W,CHIP,CS00002JB13  I112  R567
   1 I3C_1_SPD_DDRGL_CPU1_SDA      A @T6G_MB_LIB.T6G(SCH_1):I3C_1_SPD_DDRGL_CPU1_SDA
   2 I3C_1_SPD_DDRGL_CPU1_R_SDA      B @T6G_MB_LIB.T6G(SCH_1):I3C_1_SPD_DDRGL_CPU1_R_SDA

Q_RES_0402LF-0,5%,1/16W,EMPTY,CS00002JB13  I123  R2310
   1 I3C_0_SPD_DDRAF_CPU0_R_SCL      A @T6G_MB_LIB.T6G(SCH_1):I3C_0_SPD_DDRAF_CPU0_R_SCL
   2 I3C_SPD_DDRAF_CPU0_BYPASS_SCL      B @T6G_MB_LIB.T6G(SCH_1):I3C_SPD_DDRAF_CPU0_BYPASS_SCL

Q_RES_0402LF-0,5%,1/16W,EMPTY,CS00002JB13  I124  R2311
   1 I3C_0_SPD_DDRAF_CPU0_R_SDA      A @T6G_MB_LIB.T6G(SCH_1):I3C_0_SPD_DDRAF_CPU0_R_SDA
   2 I3C_SPD_DDRAF_CPU0_BYPASS_SDA      B @T6G_MB_LIB.T6G(SCH_1):I3C_SPD_DDRAF_CPU0_BYPASS_SDA

Q_RES_0402LF-0,5%,1/16W,EMPTY,CS00002JB13  I131  R1330
   1 I3C_SPD_DDRAF_CPU0_BYPASS_SCL      A @T6G_MB_LIB.T6G(SCH_1):I3C_SPD_DDRAF_CPU0_BYPASS_SCL
   2 I3C_SPD_DDRAF_CPU0_SCL      B @T6G_MB_LIB.T6G(SCH_1):I3C_SPD_DDRAF_CPU0_SCL

Q_RES_0402LF-0,5%,1/16W,EMPTY,CS00002JB13  I132  R1331
   1 I3C_SPD_DDRAF_CPU0_BYPASS_SDA      A @T6G_MB_LIB.T6G(SCH_1):I3C_SPD_DDRAF_CPU0_BYPASS_SDA
   2 I3C_SPD_DDRAF_CPU0_SDA      B @T6G_MB_LIB.T6G(SCH_1):I3C_SPD_DDRAF_CPU0_SDA

Q_RES_0402LF-0,5%,1/16W,EMPTY,CS00002JB13  I133  R1333
   1 I3C_SPD_DDRGL_CPU0_BYPASS_SDA      A @T6G_MB_LIB.T6G(SCH_1):I3C_SPD_DDRGL_CPU0_BYPASS_SDA
   2 I3C_SPD_DDRGL_CPU0_SDA      B @T6G_MB_LIB.T6G(SCH_1):I3C_SPD_DDRGL_CPU0_SDA

Q_RES_0402LF-0,5%,1/16W,EMPTY,CS00002JB13  I134  R1332
   1 I3C_SPD_DDRGL_CPU0_BYPASS_SCL      A @T6G_MB_LIB.T6G(SCH_1):I3C_SPD_DDRGL_CPU0_BYPASS_SCL
   2 I3C_SPD_DDRGL_CPU0_SCL      B @T6G_MB_LIB.T6G(SCH_1):I3C_SPD_DDRGL_CPU0_SCL

Q_RES_0402LF-0,5%,1/16W,EMPTY,CS00002JB13  I135  R986
   1 I3C_1_SPD_DDRGL_CPU0_R_SCL      A @T6G_MB_LIB.T6G(SCH_1):I3C_1_SPD_DDRGL_CPU0_R_SCL
   2 I3C_SPD_DDRGL_CPU0_BYPASS_SCL      B @T6G_MB_LIB.T6G(SCH_1):I3C_SPD_DDRGL_CPU0_BYPASS_SCL

Q_RES_0402LF-0,5%,1/16W,EMPTY,CS00002JB13  I136  R987
   1 I3C_1_SPD_DDRGL_CPU0_R_SDA      A @T6G_MB_LIB.T6G(SCH_1):I3C_1_SPD_DDRGL_CPU0_R_SDA
   2 I3C_SPD_DDRGL_CPU0_BYPASS_SDA      B @T6G_MB_LIB.T6G(SCH_1):I3C_SPD_DDRGL_CPU0_BYPASS_SDA

Q_RES_0402LF-0,5%,1/16W,EMPTY,CS00002JB13  I137  R989
   1 I3C_0_SPD_DDRAF_CPU1_R_SDA      A @T6G_MB_LIB.T6G(SCH_1):I3C_0_SPD_DDRAF_CPU1_R_SDA
   2 I3C_SPD_DDRAF_CPU1_BYPASS_SDA      B @T6G_MB_LIB.T6G(SCH_1):I3C_SPD_DDRAF_CPU1_BYPASS_SDA

Q_RES_0402LF-0,5%,1/16W,EMPTY,CS00002JB13  I138  R988
   1 I3C_0_SPD_DDRAF_CPU1_R_SCL      A @T6G_MB_LIB.T6G(SCH_1):I3C_0_SPD_DDRAF_CPU1_R_SCL
   2 I3C_SPD_DDRAF_CPU1_BYPASS_SCL      B @T6G_MB_LIB.T6G(SCH_1):I3C_SPD_DDRAF_CPU1_BYPASS_SCL

Q_RES_0402LF-0,5%,1/16W,EMPTY,CS00002JB13  I139  R1334
   1 I3C_SPD_DDRAF_CPU1_BYPASS_SCL      A @T6G_MB_LIB.T6G(SCH_1):I3C_SPD_DDRAF_CPU1_BYPASS_SCL
   2 I3C_SPD_DDRAF_CPU1_SCL      B @T6G_MB_LIB.T6G(SCH_1):I3C_SPD_DDRAF_CPU1_SCL

Q_RES_0402LF-0,5%,1/16W,EMPTY,CS00002JB13  I140  R1335
   1 I3C_SPD_DDRAF_CPU1_BYPASS_SDA      A @T6G_MB_LIB.T6G(SCH_1):I3C_SPD_DDRAF_CPU1_BYPASS_SDA
   2 I3C_SPD_DDRAF_CPU1_SDA      B @T6G_MB_LIB.T6G(SCH_1):I3C_SPD_DDRAF_CPU1_SDA

Q_RES_0402LF-0,5%,1/16W,EMPTY,CS00002JB13  I141  R991
   1 I3C_1_SPD_DDRGL_CPU1_R_SDA      A @T6G_MB_LIB.T6G(SCH_1):I3C_1_SPD_DDRGL_CPU1_R_SDA
   2 I3C_SPD_DDRGL_CPU1_BYPASS_SDA      B @T6G_MB_LIB.T6G(SCH_1):I3C_SPD_DDRGL_CPU1_BYPASS_SDA

Q_RES_0402LF-0,5%,1/16W,EMPTY,CS00002JB13  I142  R990
   1 I3C_1_SPD_DDRGL_CPU1_R_SCL      A @T6G_MB_LIB.T6G(SCH_1):I3C_1_SPD_DDRGL_CPU1_R_SCL
   2 I3C_SPD_DDRGL_CPU1_BYPASS_SCL      B @T6G_MB_LIB.T6G(SCH_1):I3C_SPD_DDRGL_CPU1_BYPASS_SCL

Q_RES_0402LF-0,5%,1/16W,EMPTY,CS00002JB13  I143  R1336
   1 I3C_SPD_DDRGL_CPU1_BYPASS_SCL      A @T6G_MB_LIB.T6G(SCH_1):I3C_SPD_DDRGL_CPU1_BYPASS_SCL
   2 I3C_SPD_DDRGL_CPU1_SCL      B @T6G_MB_LIB.T6G(SCH_1):I3C_SPD_DDRGL_CPU1_SCL

Q_RES_0402LF-0,5%,1/16W,EMPTY,CS00002JB13  I144  R1337
   1 I3C_SPD_DDRGL_CPU1_BYPASS_SDA      A @T6G_MB_LIB.T6G(SCH_1):I3C_SPD_DDRGL_CPU1_BYPASS_SDA
   2 I3C_SPD_DDRGL_CPU1_SDA      B @T6G_MB_LIB.T6G(SCH_1):I3C_SPD_DDRGL_CPU1_SDA

Q_RES_0402LF-1K,1%,1/16W,EMPTY,CS21002FB06  I145  R5006
   1 PVDD11_S3_P0      A @T6G_MB_LIB.T6G(SCH_1):PVDD11_S3_P0
   2 I3C_SPD_DDRAF_CPU0_LVC1_SCL      B @T6G_MB_LIB.T6G(SCH_1):I3C_SPD_DDRAF_CPU0_LVC1_SCL

Q_RES_0402LF-1K,1%,1/16W,EMPTY,CS21002FB06  I147  R5007
   1 PVDD11_S3_P0      A @T6G_MB_LIB.T6G(SCH_1):PVDD11_S3_P0
   2 I3C_SPD_DDRAF_CPU0_LVC1_SDA      B @T6G_MB_LIB.T6G(SCH_1):I3C_SPD_DDRAF_CPU0_LVC1_SDA

Q_RES_0402LF-1K,1%,1/16W,EMPTY,CS21002FB06  I148  R5008
   1 PVDD11_S3_P0      A @T6G_MB_LIB.T6G(SCH_1):PVDD11_S3_P0
   2 I3C_SPD_DDRGL_CPU0_LVC1_SCL      B @T6G_MB_LIB.T6G(SCH_1):I3C_SPD_DDRGL_CPU0_LVC1_SCL

Q_RES_0402LF-1K,1%,1/16W,EMPTY,CS21002FB06  I150  R5009
   1 PVDD11_S3_P0      A @T6G_MB_LIB.T6G(SCH_1):PVDD11_S3_P0
   2 I3C_SPD_DDRGL_CPU0_LVC1_SDA      B @T6G_MB_LIB.T6G(SCH_1):I3C_SPD_DDRGL_CPU0_LVC1_SDA

Q_RES_0402LF-1K,1%,1/16W,EMPTY,CS21002FB06  I151  R5010
   1 PVDD11_S3_P1      A @T6G_MB_LIB.T6G(SCH_1):PVDD11_S3_P1
   2 I3C_SPD_DDRAF_CPU1_LVC1_SCL      B @T6G_MB_LIB.T6G(SCH_1):I3C_SPD_DDRAF_CPU1_LVC1_SCL

Q_RES_0402LF-1K,1%,1/16W,EMPTY,CS21002FB06  I152  R5011
   1 PVDD11_S3_P1      A @T6G_MB_LIB.T6G(SCH_1):PVDD11_S3_P1
   2 I3C_SPD_DDRAF_CPU1_LVC1_SDA      B @T6G_MB_LIB.T6G(SCH_1):I3C_SPD_DDRAF_CPU1_LVC1_SDA

Q_RES_0402LF-1K,1%,1/16W,EMPTY,CS21002FB06  I154  R5013
   1 PVDD11_S3_P1      A @T6G_MB_LIB.T6G(SCH_1):PVDD11_S3_P1
   2 I3C_SPD_DDRGL_CPU1_LVC1_SDA      B @T6G_MB_LIB.T6G(SCH_1):I3C_SPD_DDRGL_CPU1_LVC1_SDA

Q_RES_0402LF-1K,1%,1/16W,EMPTY,CS21002FB06  I156  R5012
   1 PVDD11_S3_P1      A @T6G_MB_LIB.T6G(SCH_1):PVDD11_S3_P1
   2 I3C_SPD_DDRGL_CPU1_LVC1_SCL      B @T6G_MB_LIB.T6G(SCH_1):I3C_SPD_DDRGL_CPU1_LVC1_SCL

Q_RES_0402LF-1K,1%,1/16W,EMPTY,CS21002FB06  I157  R5015
   1 PVDD11_S3_P0      A @T6G_MB_LIB.T6G(SCH_1):PVDD11_S3_P0
   2 I3C_SCM_0_R_SDA      B @T6G_MB_LIB.T6G(SCH_1):I3C_SCM_0_R_SDA

Q_RES_0402LF-1K,1%,1/16W,EMPTY,CS21002FB06  I159  R5014
   1 PVDD11_S3_P0      A @T6G_MB_LIB.T6G(SCH_1):PVDD11_S3_P0
   2 I3C_SCM_0_R_SCL      B @T6G_MB_LIB.T6G(SCH_1):I3C_SCM_0_R_SCL

Q_RES_0402LF-1K,1%,1/16W,EMPTY,CS21002FB06  I161  R5017
   1 PVDD11_S3_P0      A @T6G_MB_LIB.T6G(SCH_1):PVDD11_S3_P0
   2 I3C_SCM_1_R_SDA      B @T6G_MB_LIB.T6G(SCH_1):I3C_SCM_1_R_SDA

Q_RES_0402LF-1K,1%,1/16W,EMPTY,CS21002FB06  I162  R5016
   1 PVDD11_S3_P0      A @T6G_MB_LIB.T6G(SCH_1):PVDD11_S3_P0
   2 I3C_SCM_1_R_SCL      B @T6G_MB_LIB.T6G(SCH_1):I3C_SCM_1_R_SCL

Q_RES_0402LF-1K,1%,1/16W,EMPTY,CS21002FB06  I163  R5018
   1 PVDD11_S3_P1      A @T6G_MB_LIB.T6G(SCH_1):PVDD11_S3_P1
   2 I3C_SCM_2_R_SCL      B @T6G_MB_LIB.T6G(SCH_1):I3C_SCM_2_R_SCL

Q_RES_0402LF-1K,1%,1/16W,EMPTY,CS21002FB06  I164  R5019
   1 PVDD11_S3_P1      A @T6G_MB_LIB.T6G(SCH_1):PVDD11_S3_P1
   2 I3C_SCM_2_R_SDA      B @T6G_MB_LIB.T6G(SCH_1):I3C_SCM_2_R_SDA

Q_RES_0402LF-1K,1%,1/16W,EMPTY,CS21002FB06  I166  R5021
   1 PVDD11_S3_P1      A @T6G_MB_LIB.T6G(SCH_1):PVDD11_S3_P1
   2 I3C_SCM_3_R_SDA      B @T6G_MB_LIB.T6G(SCH_1):I3C_SCM_3_R_SDA

Q_RES_0402LF-1K,1%,1/16W,EMPTY,CS21002FB06  I167  R5020
   1 PVDD11_S3_P1      A @T6G_MB_LIB.T6G(SCH_1):PVDD11_S3_P1
   2 I3C_SCM_3_R_SCL      B @T6G_MB_LIB.T6G(SCH_1):I3C_SCM_3_R_SCL


DRAWING: @T6G_MB_LIB.T6G(SCH_1):PAGE138 

Q_RES_0402LF-0,5%,1/16W,EMPTY,CS00002JB13  I5  R358
   1 SMB_CPU0_CPU1_SEC_SCL_R2      A @T6G_MB_LIB.T6G(SCH_1):SMB_CPU0_CPU1_SEC_SCL_R2
   2 SMB_CPU1_SEC_R_SCL      B @T6G_MB_LIB.T6G(SCH_1):SMB_CPU1_SEC_R_SCL

Q_RES_0402LF-0,5%,1/16W,EMPTY,CS00002JB13  I6  R148
   1 SMB_CPU0_CPU1_SEC_SDA_R2      A @T6G_MB_LIB.T6G(SCH_1):SMB_CPU0_CPU1_SEC_SDA_R2
   2 SMB_CPU1_SEC_R_SDA      B @T6G_MB_LIB.T6G(SCH_1):SMB_CPU1_SEC_R_SDA

Q_RES_0402LF-0,5%,1/16W,EMPTY,CS00002JB13  I14  R145
   1 SMB_CPU0_CPU1_SEC_SCL_R2      A @T6G_MB_LIB.T6G(SCH_1):SMB_CPU0_CPU1_SEC_SCL_R2
   2 SMB_CPU0_SEC_R_SCL      B @T6G_MB_LIB.T6G(SCH_1):SMB_CPU0_SEC_R_SCL

Q_RES_0402LF-0,5%,1/16W,EMPTY,CS00002JB13  I15  R144
   1 SMB_CPU0_CPU1_SEC_SDA_R2      A @T6G_MB_LIB.T6G(SCH_1):SMB_CPU0_CPU1_SEC_SDA_R2
   2 SMB_CPU0_SEC_R_SDA      B @T6G_MB_LIB.T6G(SCH_1):SMB_CPU0_SEC_R_SDA

Q_RES_0402LF-0,5%,1/16W,EMPTY,CS00002JB13  I17  R146
   1 SMB_CPU0_CPU1_APML_MUX1_SCL      A @T6G_MB_LIB.T6G(SCH_1):SMB_CPU0_CPU1_APML_MUX1_SCL
   2 SMB_APML_CPU1_R_SCL      B @T6G_MB_LIB.T6G(SCH_1):SMB_APML_CPU1_R_SCL

Q_RES_0402LF-10K,1%,1/16W,CHIP,CS31002FB08  I27  R5004
   1 SMB_APML_CPU1_R_SDA      A @T6G_MB_LIB.T6G(SCH_1):SMB_APML_CPU1_R_SDA
   2    GND      B @T6G_MB_LIB.T6G(SCH_1):GND

Q_RES_0402LF-0,5%,1/16W,EMPTY,CS00002JB13  I30  R139
   1 I3C_MUX_CPU0_VIO      A @T6G_MB_LIB.T6G(SCH_1):I3C_MUX_CPU0_VIO
   2 PVDD18_S5_P0      B @T6G_MB_LIB.T6G(SCH_1):PVDD18_S5_P0

Q_RES_0402LF-0,5%,1/16W,EMPTY,CS00002JB13  I35  R142
   1 SMB_CPU0_CPU1_APML_MUX1_SCL      A @T6G_MB_LIB.T6G(SCH_1):SMB_CPU0_CPU1_APML_MUX1_SCL
   2 SMB_APML_CPU0_R_SCL      B @T6G_MB_LIB.T6G(SCH_1):SMB_APML_CPU0_R_SCL

Q_RES_0402LF-33,5%,1/16W,EMPTY,CS03302JB10  I38  R1156
   1 SMB_APML_CPU0_R_SCL      A @T6G_MB_LIB.T6G(SCH_1):SMB_APML_CPU0_R_SCL
   2 SMB_APML_CPU0_SCL      B @T6G_MB_LIB.T6G(SCH_1):SMB_APML_CPU0_SCL

Q_RES_0402LF-1K,1%,1/16W,CHIP,CS21002FB06  I52  R359
   1 PVDD11_S3_P1      A @T6G_MB_LIB.T6G(SCH_1):PVDD11_S3_P1
   2 SMB_APML_CPU1_SDA      B @T6G_MB_LIB.T6G(SCH_1):SMB_APML_CPU1_SDA

Q_RES_0402LF-1K,1%,1/16W,CHIP,CS21002FB06  I54  R366
   1 PVDD18_S5_P1      A @T6G_MB_LIB.T6G(SCH_1):PVDD18_S5_P1
   2 SMB_CPU1_SEC_SCL      B @T6G_MB_LIB.T6G(SCH_1):SMB_CPU1_SEC_SCL

Q_RES_0402LF-1K,1%,1/16W,CHIP,CS21002FB06  I56  R363
   1 PVDD11_S3_P0      A @T6G_MB_LIB.T6G(SCH_1):PVDD11_S3_P0
   2 SMB_APML_CPU0_SCL      B @T6G_MB_LIB.T6G(SCH_1):SMB_APML_CPU0_SCL

Q_RES_0402LF-1K,1%,1/16W,CHIP,CS21002FB06  I58  R369
   1 PVDD18_S5_P1      A @T6G_MB_LIB.T6G(SCH_1):PVDD18_S5_P1
   2 SMB_CPU1_SEC_SDA      B @T6G_MB_LIB.T6G(SCH_1):SMB_CPU1_SEC_SDA

Q_RES_0402LF-1K,1%,1/16W,CHIP,CS21002FB06  I60  R370
   1 PVDD18_S5_P0      A @T6G_MB_LIB.T6G(SCH_1):PVDD18_S5_P0
   2 SMB_CPU0_SEC_SDA      B @T6G_MB_LIB.T6G(SCH_1):SMB_CPU0_SEC_SDA

Q_RES_0402LF-0,5%,1/16W,EMPTY,CS00002JB13  I16  R147
   1 SMB_CPU0_CPU1_APML_MUX1_SDA      A @T6G_MB_LIB.T6G(SCH_1):SMB_CPU0_CPU1_APML_MUX1_SDA
   2 SMB_APML_CPU1_R_SDA      B @T6G_MB_LIB.T6G(SCH_1):SMB_APML_CPU1_R_SDA

Q_RES_0402LF-0,5%,1/16W,CHIP,CS00002JB13  I22  R1162
   1 SMB_CPU1_SEC_R_SDA      A @T6G_MB_LIB.T6G(SCH_1):SMB_CPU1_SEC_R_SDA
   2 SMB_CPU1_SEC_SDA      B @T6G_MB_LIB.T6G(SCH_1):SMB_CPU1_SEC_SDA

Q_RES_0402LF-0,5%,1/16W,CHIP,CS00002JB13  I23  R1161
   1 SMB_CPU1_SEC_R_SCL      A @T6G_MB_LIB.T6G(SCH_1):SMB_CPU1_SEC_R_SCL
   2 SMB_CPU1_SEC_SCL      B @T6G_MB_LIB.T6G(SCH_1):SMB_CPU1_SEC_SCL

Q_RES_0402LF-0,5%,1/16W,EMPTY,CS00002JB13  I34  R143
   1 SMB_CPU0_CPU1_APML_MUX1_SDA      A @T6G_MB_LIB.T6G(SCH_1):SMB_CPU0_CPU1_APML_MUX1_SDA
   2 SMB_APML_CPU0_R_SDA      B @T6G_MB_LIB.T6G(SCH_1):SMB_APML_CPU0_R_SDA

Q_RES_0402LF-33,5%,1/16W,EMPTY,CS03302JB10  I39  R1155
   1 SMB_APML_CPU0_R_SDA      A @T6G_MB_LIB.T6G(SCH_1):SMB_APML_CPU0_R_SDA
   2 SMB_APML_CPU0_SDA      B @T6G_MB_LIB.T6G(SCH_1):SMB_APML_CPU0_SDA

Q_RES_0402LF-1K,1%,1/16W,CHIP,CS21002FB06  I53  R362
   1 PVDD11_S3_P1      A @T6G_MB_LIB.T6G(SCH_1):PVDD11_S3_P1
   2 SMB_APML_CPU1_SCL      B @T6G_MB_LIB.T6G(SCH_1):SMB_APML_CPU1_SCL

Q_RES_0402LF-1K,1%,1/16W,CHIP,CS21002FB06  I55  R360
   1 PVDD11_S3_P0      A @T6G_MB_LIB.T6G(SCH_1):PVDD11_S3_P0
   2 SMB_APML_CPU0_SDA      B @T6G_MB_LIB.T6G(SCH_1):SMB_APML_CPU0_SDA

Q_RES_0402LF-1K,1%,1/16W,CHIP,CS21002FB06  I57  R367
   1 PVDD18_S5_P0      A @T6G_MB_LIB.T6G(SCH_1):PVDD18_S5_P0
   2 SMB_CPU0_SEC_SCL      B @T6G_MB_LIB.T6G(SCH_1):SMB_CPU0_SEC_SCL

PI3CSW12ZUAEX-PI3CSW12ZUAEX,SMLF,IC,AL3CSW12000  I67  U6
   1 SMB_CPU0_SEC_R_SCL    1D+ @T6G_MB_LIB.T6G(SCH_1):SMB_CPU0_SEC_R_SCL
   3 SMB_CPU1_SEC_R_SCL    2D+ @T6G_MB_LIB.T6G(SCH_1):SMB_CPU1_SEC_R_SCL
   4 SMB_CPU1_SEC_R_SDA    2D- @T6G_MB_LIB.T6G(SCH_1):SMB_CPU1_SEC_R_SDA
   7 SMB_CPU0_CPU1_SEC_SDA_R2     D- @T6G_MB_LIB.T6G(SCH_1):SMB_CPU0_CPU1_SEC_SDA_R2
   6 FM_SEC_MUX_OE_N    OE# @T6G_MB_LIB.T6G(SCH_1):FM_SEC_MUX_OE_N
   9 FM_SEC_MUX_SEL      S @T6G_MB_LIB.T6G(SCH_1):FM_SEC_MUX_SEL
  10 P3V3_AUX    VDD @T6G_MB_LIB.T6G(SCH_1):P3V3_AUX
   2 SMB_CPU0_SEC_R_SDA    1D- @T6G_MB_LIB.T6G(SCH_1):SMB_CPU0_SEC_R_SDA
   5    GND    GND @T6G_MB_LIB.T6G(SCH_1):GND
   8 SMB_CPU0_CPU1_SEC_SCL_R2     D+ @T6G_MB_LIB.T6G(SCH_1):SMB_CPU0_CPU1_SEC_SCL_R2

Q_CAP_0402-0.1UF,25V,10%,X7R,CH4104K1B00  I69  C25
   1 P3V3_AUX      A @T6G_MB_LIB.T6G(SCH_1):P3V3_AUX
   2    GND      B @T6G_MB_LIB.T6G(SCH_1):GND

Q_RES_0402LF-33,5%,1/16W,EMPTY,CS03302JB10  I73  R1158
   1 SMB_APML_CPU1_R_SDA      A @T6G_MB_LIB.T6G(SCH_1):SMB_APML_CPU1_R_SDA
   2 SMB_APML_CPU1_SDA      B @T6G_MB_LIB.T6G(SCH_1):SMB_APML_CPU1_SDA

Q_RES_0402LF-33,5%,1/16W,EMPTY,CS03302JB10  I74  R1157
   1 SMB_APML_CPU1_R_SCL      A @T6G_MB_LIB.T6G(SCH_1):SMB_APML_CPU1_R_SCL
   2 SMB_APML_CPU1_SCL      B @T6G_MB_LIB.T6G(SCH_1):SMB_APML_CPU1_SCL

Q_RES_0402LF-0,5%,1/16W,CHIP,CS00002JB13  I75  R1160
   1 SMB_CPU0_SEC_R_SDA      A @T6G_MB_LIB.T6G(SCH_1):SMB_CPU0_SEC_R_SDA
   2 SMB_CPU0_SEC_SDA      B @T6G_MB_LIB.T6G(SCH_1):SMB_CPU0_SEC_SDA

Q_RES_0402LF-0,5%,1/16W,CHIP,CS00002JB13  I76  R1159
   1 SMB_CPU0_SEC_R_SCL      A @T6G_MB_LIB.T6G(SCH_1):SMB_CPU0_SEC_R_SCL
   2 SMB_CPU0_SEC_SCL      B @T6G_MB_LIB.T6G(SCH_1):SMB_CPU0_SEC_SCL

Q_CAP_0402-0.1UF,25V,10%,X7R,CH4104K1B00  I89  C11
   1 P3V3_AUX      A @T6G_MB_LIB.T6G(SCH_1):P3V3_AUX
   2    GND      B @T6G_MB_LIB.T6G(SCH_1):GND

Q_RES_0402LF-0,5%,1/16W,CHIP,CS00002JB13  I91  R327
   1 SMB_APML_CPU0_MUX2_SCL      A @T6G_MB_LIB.T6G(SCH_1):SMB_APML_CPU0_MUX2_SCL
   2 SMB_APML_CPU0_SCL      B @T6G_MB_LIB.T6G(SCH_1):SMB_APML_CPU0_SCL

Q_RES_0402LF-0,5%,1/16W,CHIP,CS00002JB13  I92  R328
   1 SMB_APML_CPU0_MUX2_SDA      A @T6G_MB_LIB.T6G(SCH_1):SMB_APML_CPU0_MUX2_SDA
   2 SMB_APML_CPU0_SDA      B @T6G_MB_LIB.T6G(SCH_1):SMB_APML_CPU0_SDA

Q_RES_0402LF-0,5%,1/16W,CHIP,CS00002JB13  I93  R337
   1 SMB_APML_CPU1_MUX2_SCL      A @T6G_MB_LIB.T6G(SCH_1):SMB_APML_CPU1_MUX2_SCL
   2 SMB_APML_CPU1_SCL      B @T6G_MB_LIB.T6G(SCH_1):SMB_APML_CPU1_SCL

Q_RES_0402LF-0,5%,1/16W,CHIP,CS00002JB13  I94  R338
   1 SMB_APML_CPU1_MUX2_SDA      A @T6G_MB_LIB.T6G(SCH_1):SMB_APML_CPU1_MUX2_SDA
   2 SMB_APML_CPU1_SDA      B @T6G_MB_LIB.T6G(SCH_1):SMB_APML_CPU1_SDA

Q_RES_0402LF-0,5%,1/16W,CHIP,CS00002JB13  I99  R325
   1 SMB_CPU0_CPU1_APML_SCL_R2      A @T6G_MB_LIB.T6G(SCH_1):SMB_CPU0_CPU1_APML_SCL_R2
   2 SMB_CPU0_CPU1_APML_MUX2_SCL      B @T6G_MB_LIB.T6G(SCH_1):SMB_CPU0_CPU1_APML_MUX2_SCL

Q_RES_0402LF-0,5%,1/16W,CHIP,CS00002JB13  I100  R326
   1 SMB_CPU0_CPU1_APML_SDA_R2      A @T6G_MB_LIB.T6G(SCH_1):SMB_CPU0_CPU1_APML_SDA_R2
   2 SMB_CPU0_CPU1_APML_MUX2_SDA      B @T6G_MB_LIB.T6G(SCH_1):SMB_CPU0_CPU1_APML_MUX2_SDA

Q_RES_0402LF-0,5%,1/16W,EMPTY,CS00002JB13  I109  R323
   1 SMB_CPU0_CPU1_APML_SDA_R2      A @T6G_MB_LIB.T6G(SCH_1):SMB_CPU0_CPU1_APML_SDA_R2
   2 SMB_CPU0_CPU1_APML_MUX1_SDA      B @T6G_MB_LIB.T6G(SCH_1):SMB_CPU0_CPU1_APML_MUX1_SDA

Q_RES_0402LF-0,5%,1/16W,EMPTY,CS00002JB13  I110  R324
   1 SMB_CPU0_CPU1_APML_SCL_R2      A @T6G_MB_LIB.T6G(SCH_1):SMB_CPU0_CPU1_APML_SCL_R2
   2 SMB_CPU0_CPU1_APML_MUX1_SCL      B @T6G_MB_LIB.T6G(SCH_1):SMB_CPU0_CPU1_APML_MUX1_SCL

IML3112Y2B000NCG8-IML3112-Y2B000NCG8,SMLF,EMPTY,ALA  I111  U213
   2 SMB_CPU0_CPU1_APML_MUX1_SDA   HSDA @T6G_MB_LIB.T6G(SCH_1):SMB_CPU0_CPU1_APML_MUX1_SDA
   5 PVDD18_S5_P0    VDD @T6G_MB_LIB.T6G(SCH_1):PVDD18_S5_P0
   6 SMB_APML_CPU1_R_SCL LSCL_1 @T6G_MB_LIB.T6G(SCH_1):SMB_APML_CPU1_R_SCL
   7 I3C_MUX_CPU0_VIO    VIO @T6G_MB_LIB.T6G(SCH_1):I3C_MUX_CPU0_VIO
   1 SMB_APML_CPU0_R_SDA LSDA_0 @T6G_MB_LIB.T6G(SCH_1):SMB_APML_CPU0_R_SDA
   4 SMB_APML_CPU0_R_SCL LSCL_0 @T6G_MB_LIB.T6G(SCH_1):SMB_APML_CPU0_R_SCL
   3 SMB_CPU0_CPU1_APML_MUX1_SCL   HSCL @T6G_MB_LIB.T6G(SCH_1):SMB_CPU0_CPU1_APML_MUX1_SCL
   8 SMB_APML_CPU1_R_SDA LSDA_1||HSA @T6G_MB_LIB.T6G(SCH_1):SMB_APML_CPU1_R_SDA
   9    GND TH_GND @T6G_MB_LIB.T6G(SCH_1):GND

Q_CAP_C0402-10UF,6.3V,20%,EMPTY,CH6101MEB01  I112  C24
   1 PVDD18_S5_P0      A @T6G_MB_LIB.T6G(SCH_1):PVDD18_S5_P0
   2    GND      B @T6G_MB_LIB.T6G(SCH_1):GND

Q_CAP_C0402-1UF,25V,10%,EMPTY,CH5104KEB02  I113  C9
   1 I3C_MUX_CPU0_VIO      A @T6G_MB_LIB.T6G(SCH_1):I3C_MUX_CPU0_VIO
   2    GND      B @T6G_MB_LIB.T6G(SCH_1):GND

PI3CSW12ZUAEX-PI3CSW12ZUAEX,SMLF,IC,AL3CSW12000  I114  U4
   1 SMB_APML_CPU0_MUX2_SCL    1D+ @T6G_MB_LIB.T6G(SCH_1):SMB_APML_CPU0_MUX2_SCL
   3 SMB_APML_CPU1_MUX2_SCL    2D+ @T6G_MB_LIB.T6G(SCH_1):SMB_APML_CPU1_MUX2_SCL
   4 SMB_APML_CPU1_MUX2_SDA    2D- @T6G_MB_LIB.T6G(SCH_1):SMB_APML_CPU1_MUX2_SDA
   7 SMB_CPU0_CPU1_APML_MUX2_SDA     D- @T6G_MB_LIB.T6G(SCH_1):SMB_CPU0_CPU1_APML_MUX2_SDA
   6 FM_APML_MUX2_OE_N    OE# @T6G_MB_LIB.T6G(SCH_1):FM_APML_MUX2_OE_N
   9 FM_APML_MUX2_SEL      S @T6G_MB_LIB.T6G(SCH_1):FM_APML_MUX2_SEL
  10 P3V3_AUX    VDD @T6G_MB_LIB.T6G(SCH_1):P3V3_AUX
   2 SMB_APML_CPU0_MUX2_SDA    1D- @T6G_MB_LIB.T6G(SCH_1):SMB_APML_CPU0_MUX2_SDA
   5    GND    GND @T6G_MB_LIB.T6G(SCH_1):GND
   8 SMB_CPU0_CPU1_APML_MUX2_SCL     D+ @T6G_MB_LIB.T6G(SCH_1):SMB_CPU0_CPU1_APML_MUX2_SCL


DRAWING: @T6G_MB_LIB.T6G(SCH_1):PAGE141 

MOSFET_N_GSD-NX138BK,SMLF,IC,BAM01380023  I89  Q61
   G UART_LS_EN   GATE @T6G_MB_LIB.T6G(SCH_1):UART_LS_EN
   S    GND SOURCE @T6G_MB_LIB.T6G(SCH_1):GND
   D UART_LS_EN_R_N  DRAIN @T6G_MB_LIB.T6G(SCH_1):UART_LS_EN_R_N

Q_RES_0402LF-4.7K,5%,1/16W,CHIP,CS24702JB10  I91  R1419
   1 PVDD18_S5_P0      A @T6G_MB_LIB.T6G(SCH_1):PVDD18_S5_P0
   2 UART_LS_EN_R_N      B @T6G_MB_LIB.T6G(SCH_1):UART_LS_EN_R_N

SN74AVC4T774PWR-SN74AVC4T774PWR,SMLF,IC,AL04T774K00  I117  U116
   1 PVDD18_S5_P0   DIR1 @T6G_MB_LIB.T6G(SCH_1):PVDD18_S5_P0
   2    GND   DIR2 @T6G_MB_LIB.T6G(SCH_1):GND
   3 UART_CPU0_SCM_UART1_TX     A1 @T6G_MB_LIB.T6G(SCH_1):UART_CPU0_SCM_UART1_TX
   4 UART_CPU0_SCM_UART1_R_RX     A2 @T6G_MB_LIB.T6G(SCH_1):UART_CPU0_SCM_UART1_R_RX
   5 UART_CPU0_UART0_TX     A3 @T6G_MB_LIB.T6G(SCH_1):UART_CPU0_UART0_TX
   6 UART_CPU0_UART0_R_RX     A4 @T6G_MB_LIB.T6G(SCH_1):UART_CPU0_UART0_R_RX
   7 PVDD18_S5_P0   DIR3 @T6G_MB_LIB.T6G(SCH_1):PVDD18_S5_P0
   8    GND   DIR4 @T6G_MB_LIB.T6G(SCH_1):GND
   9 UART_LS_EN_N     OE @T6G_MB_LIB.T6G(SCH_1):UART_LS_EN_N
  10    GND    GND @T6G_MB_LIB.T6G(SCH_1):GND
  11 UART_CPU0_LVC3_UART0_R_RX     B4 @T6G_MB_LIB.T6G(SCH_1):UART_CPU0_LVC3_UART0_R_RX
  12 UART_CPU0_LVC3_UART0_R_TX     B3 @T6G_MB_LIB.T6G(SCH_1):UART_CPU0_LVC3_UART0_R_TX
  13 UART_CPU0_SCM_LVC3_UART1_R_RX     B2 @T6G_MB_LIB.T6G(SCH_1):UART_CPU0_SCM_LVC3_UART1_R_RX
  14 UART_CPU0_SCM_LVC3_UART1_R_TX     B1 @T6G_MB_LIB.T6G(SCH_1):UART_CPU0_SCM_LVC3_UART1_R_TX
  15 P3V3_AUX   VCCB @T6G_MB_LIB.T6G(SCH_1):P3V3_AUX
  16 PVDD18_S5_P0   VCCA @T6G_MB_LIB.T6G(SCH_1):PVDD18_S5_P0

Q_CAP_0402-0.1UF,25V,10%,X7R,CH4104K1B00  I133  C1354
   1 P3V3_AUX      A @T6G_MB_LIB.T6G(SCH_1):P3V3_AUX
   2    GND      B @T6G_MB_LIB.T6G(SCH_1):GND

Q_CAP_0402-0.1UF,25V,10%,X7R,CH4104K1B00  I137  C1352
   1 PVDD18_S5_P0      A @T6G_MB_LIB.T6G(SCH_1):PVDD18_S5_P0
   2    GND      B @T6G_MB_LIB.T6G(SCH_1):GND

Q_RES_0402LF-10K,5%,1/16W,CHIP,CS31002JB08  I185  R821
   1 P3V3_AUX      A @T6G_MB_LIB.T6G(SCH_1):P3V3_AUX
   2 UART_VCC_J13      B @T6G_MB_LIB.T6G(SCH_1):UART_VCC_J13

Q_RES_0402LF-10K,5%,1/16W,EMPTY,CS31002JB08  I186  R820
   1 UART_VCC_J13      A @T6G_MB_LIB.T6G(SCH_1):UART_VCC_J13
   2 P5V_AUX      B @T6G_MB_LIB.T6G(SCH_1):P5V_AUX

Q_CAP_C0402-220PF,50V,5%,C0G,CH12206JB00  I187  C364
   1 UART_CPU0_LVC3_UART0_RX      A @T6G_MB_LIB.T6G(SCH_1):UART_CPU0_LVC3_UART0_RX
   2    GND      B @T6G_MB_LIB.T6G(SCH_1):GND

Q_CAP_C0402-220PF,50V,5%,C0G,CH12206JB00  I190  C363
   1 UART_CPU0_LVC3_UART0_TX      A @T6G_MB_LIB.T6G(SCH_1):UART_CPU0_LVC3_UART0_TX
   2    GND      B @T6G_MB_LIB.T6G(SCH_1):GND

CONN4_HFK1040L0P1L7H-CONN4_HFK1040-L0P1L-7H,THLF,IA  I195  J13
   4    GND      4 @T6G_MB_LIB.T6G(SCH_1):GND
   3 UART_CPU0_LVC3_UART0_TX      3 @T6G_MB_LIB.T6G(SCH_1):UART_CPU0_LVC3_UART0_TX
   2 UART_CPU0_LVC3_UART0_RX      2 @T6G_MB_LIB.T6G(SCH_1):UART_CPU0_LVC3_UART0_RX
   1 UART_VCC_J13      1 @T6G_MB_LIB.T6G(SCH_1):UART_VCC_J13

Q_RES_0402LF-10K,5%,1/16W,CHIP,CS31002JB08  I196  R816
   1 PVDD18_S5_P0      A @T6G_MB_LIB.T6G(SCH_1):PVDD18_S5_P0
   2 UART_CPU0_SCM_UART1_RX      B @T6G_MB_LIB.T6G(SCH_1):UART_CPU0_SCM_UART1_RX

Q_RES_0402LF-10K,5%,1/16W,EMPTY,CS31002JB08  I197  R815
   1 PVDD18_S5_P0      A @T6G_MB_LIB.T6G(SCH_1):PVDD18_S5_P0
   2 UART_CPU0_SCM_UART1_TX      B @T6G_MB_LIB.T6G(SCH_1):UART_CPU0_SCM_UART1_TX

Q_RES_0402LF-10K,5%,1/16W,EMPTY,CS31002JB08  I198  R814
   1 PVDD18_S5_P0      A @T6G_MB_LIB.T6G(SCH_1):PVDD18_S5_P0
   2 UART_CPU0_UART0_TX      B @T6G_MB_LIB.T6G(SCH_1):UART_CPU0_UART0_TX

Q_RES_0402LF-10K,5%,1/16W,CHIP,CS31002JB08  I199  R813
   1 PVDD18_S5_P0      A @T6G_MB_LIB.T6G(SCH_1):PVDD18_S5_P0
   2 UART_CPU0_UART0_RX      B @T6G_MB_LIB.T6G(SCH_1):UART_CPU0_UART0_RX

Q_RES_0402LF-10K,5%,1/16W,EMPTY,CS31002JB08  I203  R825
   1 P3V3_AUX      A @T6G_MB_LIB.T6G(SCH_1):P3V3_AUX
   2 UART_CPU0_LVC3_UART0_RX      B @T6G_MB_LIB.T6G(SCH_1):UART_CPU0_LVC3_UART0_RX

Q_RES_0402LF-10K,5%,1/16W,CHIP,CS31002JB08  I204  R824
   1 P3V3_AUX      A @T6G_MB_LIB.T6G(SCH_1):P3V3_AUX
   2 UART_CPU0_LVC3_UART0_TX      B @T6G_MB_LIB.T6G(SCH_1):UART_CPU0_LVC3_UART0_TX

Q_RES_0402LF-10K,5%,1/16W,EMPTY,CS31002JB08  I205  R823
   1 P3V3_AUX      A @T6G_MB_LIB.T6G(SCH_1):P3V3_AUX
   2 UART_CPU0_SCM_LVC3_UART1_R_RX      B @T6G_MB_LIB.T6G(SCH_1):UART_CPU0_SCM_LVC3_UART1_R_RX

Q_RES_0402LF-10K,5%,1/16W,CHIP,CS31002JB08  I206  R822
   1 P3V3_AUX      A @T6G_MB_LIB.T6G(SCH_1):P3V3_AUX
   2 UART_CPU0_SCM_LVC3_UART1_TX      B @T6G_MB_LIB.T6G(SCH_1):UART_CPU0_SCM_LVC3_UART1_TX

Q_RES_0402LF-33,5%,1/16W,CHIP,CS03302JB10  I211  R1253
   1 UART_LS_EN_N      A @T6G_MB_LIB.T6G(SCH_1):UART_LS_EN_N
   2 UART_LS_EN_R_N      B @T6G_MB_LIB.T6G(SCH_1):UART_LS_EN_R_N

Q_RES_0402LF-0,5%,1/16W,CHIP,CS00002JB13  I212  R819
   1 UART_CPU0_LVC3_UART0_R_RX      A @T6G_MB_LIB.T6G(SCH_1):UART_CPU0_LVC3_UART0_R_RX
   2 UART_CPU0_LVC3_UART0_RX      B @T6G_MB_LIB.T6G(SCH_1):UART_CPU0_LVC3_UART0_RX

Q_RES_0402LF-0,5%,1/16W,CHIP,CS00002JB13  I220  R818
   1 UART_CPU0_LVC3_UART0_R_TX      A @T6G_MB_LIB.T6G(SCH_1):UART_CPU0_LVC3_UART0_R_TX
   2 UART_CPU0_LVC3_UART0_TX      B @T6G_MB_LIB.T6G(SCH_1):UART_CPU0_LVC3_UART0_TX

Q_RES_0402LF-0,5%,1/16W,CHIP,CS00002JB13  I221  R1425
   1 UART_CPU0_SCM_LVC3_UART1_R_TX      A @T6G_MB_LIB.T6G(SCH_1):UART_CPU0_SCM_LVC3_UART1_R_TX
   2 UART_CPU0_SCM_LVC3_UART1_TX      B @T6G_MB_LIB.T6G(SCH_1):UART_CPU0_SCM_LVC3_UART1_TX

Q_RES_0402LF-0,5%,1/16W,CHIP,CS00002JB13  I231  R817
   1 UART_CPU0_UART0_RX      A @T6G_MB_LIB.T6G(SCH_1):UART_CPU0_UART0_RX
   2 UART_CPU0_UART0_R_RX      B @T6G_MB_LIB.T6G(SCH_1):UART_CPU0_UART0_R_RX

Q_RES_0402LF-0,5%,1/16W,CHIP,CS00002JB13  I232  R1423
   1 UART_CPU0_SCM_UART1_RX      A @T6G_MB_LIB.T6G(SCH_1):UART_CPU0_SCM_UART1_RX
   2 UART_CPU0_SCM_UART1_R_RX      B @T6G_MB_LIB.T6G(SCH_1):UART_CPU0_SCM_UART1_R_RX


DRAWING: @T6G_MB_LIB.T6G(SCH_1):PAGE143 

Q_RES_0402LF-249,1%,1/16W,CHIP,CS12492FB02  I3  R950
   1 PU_SMERR_LED      A @T6G_MB_LIB.T6G(SCH_1):PU_SMERR_LED
   2 P3V3_AUX      B @T6G_MB_LIB.T6G(SCH_1):P3V3_AUX

Q_RES_0402LF-4.7K,5%,1/16W,CHIP,CS24702JB10  I5  R946
   1 P3V3_AUX      A @T6G_MB_LIB.T6G(SCH_1):P3V3_AUX
   2 BOOT_RDY_LED      B @T6G_MB_LIB.T6G(SCH_1):BOOT_RDY_LED

Q_RES_0402LF-130,1%,1/16W,CHIP,CS11302FB03  I7  R948
   1 PU_BOOT_RDY_LED      A @T6G_MB_LIB.T6G(SCH_1):PU_BOOT_RDY_LED
   2 P3V3_AUX      B @T6G_MB_LIB.T6G(SCH_1):P3V3_AUX

Q_LED_SMLF-LED_BLUE,LTST-C281TBKT-5A,IC,BEBL0172Z00  I8  D5
   A PU_BOOT_RDY_LED      A @T6G_MB_LIB.T6G(SCH_1):PU_BOOT_RDY_LED
   C BOOT_RDY_LED_N      C @T6G_MB_LIB.T6G(SCH_1):BOOT_RDY_LED_N

Q_LED_SMLF-LED_YELLOW,LTST-C190KSKT-P,IC,BEYL0159ZA  I9  D6
   A PU_SMERR_LED      A @T6G_MB_LIB.T6G(SCH_1):PU_SMERR_LED
   C SMERR_LED_N      C @T6G_MB_LIB.T6G(SCH_1):SMERR_LED_N

Q_RES_0402LF-4.7K,5%,1/16W,CHIP,CS24702JB10  I11  R947
   1 P3V3_AUX      A @T6G_MB_LIB.T6G(SCH_1):P3V3_AUX
   2 SMERR_LED      B @T6G_MB_LIB.T6G(SCH_1):SMERR_LED

Q_RES_0402LF-4.7K,5%,1/16W,CHIP,CS24702JB10  I15  R944
   1 P3V3_AUX      A @T6G_MB_LIB.T6G(SCH_1):P3V3_AUX
   2 BOOT_RDY_BUF_LED      B @T6G_MB_LIB.T6G(SCH_1):BOOT_RDY_BUF_LED

MOSFET_DUAL_6P-2N7002KDW,SMLF,IC,BAM70020047  I16  Q2
   2 BOOT_RDY_BUF_LED     G1 @T6G_MB_LIB.T6G(SCH_1):BOOT_RDY_BUF_LED
   5 BOOT_RDY_LED     G2 @T6G_MB_LIB.T6G(SCH_1):BOOT_RDY_LED
   1    GND     S1 @T6G_MB_LIB.T6G(SCH_1):GND
   4    GND     S2 @T6G_MB_LIB.T6G(SCH_1):GND
   6 BOOT_RDY_LED     D1 @T6G_MB_LIB.T6G(SCH_1):BOOT_RDY_LED
   3 BOOT_RDY_LED_N     D2 @T6G_MB_LIB.T6G(SCH_1):BOOT_RDY_LED_N

Q_RES_0402LF-4.7K,5%,1/16W,CHIP,CS24702JB10  I18  R945
   1 P3V3_AUX      A @T6G_MB_LIB.T6G(SCH_1):P3V3_AUX
   2 FM_SMERR_BUF_R_LED_N      B @T6G_MB_LIB.T6G(SCH_1):FM_SMERR_BUF_R_LED_N

MOSFET_DUAL_6P-2N7002KDW,SMLF,IC,BAM70020047  I19  Q11
   2 FM_SMERR_BUF_R_LED_N     G1 @T6G_MB_LIB.T6G(SCH_1):FM_SMERR_BUF_R_LED_N
   5 SMERR_LED     G2 @T6G_MB_LIB.T6G(SCH_1):SMERR_LED
   1    GND     S1 @T6G_MB_LIB.T6G(SCH_1):GND
   4    GND     S2 @T6G_MB_LIB.T6G(SCH_1):GND
   6 SMERR_LED     D1 @T6G_MB_LIB.T6G(SCH_1):SMERR_LED
   3 SMERR_LED_N     D2 @T6G_MB_LIB.T6G(SCH_1):SMERR_LED_N

Q_RES_0402LF-0,5%,1/16W,CHIP,CS00002JB13  I21  R935
   1 BOOT_RDY_BUF_R_LED      A @T6G_MB_LIB.T6G(SCH_1):BOOT_RDY_BUF_R_LED
   2 BOOT_RDY_BUF_LED      B @T6G_MB_LIB.T6G(SCH_1):BOOT_RDY_BUF_LED

Q_RES_0402LF-0,5%,1/16W,CHIP,CS00002JB13  I22  R936
   1 FM_SMERR_BUF_LED_N      A @T6G_MB_LIB.T6G(SCH_1):FM_SMERR_BUF_LED_N
   2 FM_SMERR_BUF_R_LED_N      B @T6G_MB_LIB.T6G(SCH_1):FM_SMERR_BUF_R_LED_N

Q_CAP_0402-0.1UF,25V,10%,X7R,CH4104K1B00  I24  C218
   1 P1V8_AUX      A @T6G_MB_LIB.T6G(SCH_1):P1V8_AUX
   2    GND      B @T6G_MB_LIB.T6G(SCH_1):GND

SN74LVC1G07DBVR_SMLF-SN74LVC1G07DBVR,IC,AL1G0007024  I26  U82
   2 BOOT_RDY_R1_N      A @T6G_MB_LIB.T6G(SCH_1):BOOT_RDY_R1_N
   4 BOOT_RDY_BUF_R_LED      Y @T6G_MB_LIB.T6G(SCH_1):BOOT_RDY_BUF_R_LED
   1     NC     NC     NC
   5 P1V8_AUX    VCC @T6G_MB_LIB.T6G(SCH_1):P1V8_AUX
   3    GND    GND @T6G_MB_LIB.T6G(SCH_1):GND

Q_CAP_0402-0.1UF,25V,10%,X7R,CH4104K1B00  I29  C219
   1 P1V8_AUX      A @T6G_MB_LIB.T6G(SCH_1):P1V8_AUX
   2    GND      B @T6G_MB_LIB.T6G(SCH_1):GND

SN74LVC1G07DBVR_SMLF-SN74LVC1G07DBVR,IC,AL1G0007024  I31  U86
   2 FM_SMERR_LED_N      A @T6G_MB_LIB.T6G(SCH_1):FM_SMERR_LED_N
   4 FM_SMERR_BUF_LED_N      Y @T6G_MB_LIB.T6G(SCH_1):FM_SMERR_BUF_LED_N
   1     NC     NC     NC
   5 P1V8_AUX    VCC @T6G_MB_LIB.T6G(SCH_1):P1V8_AUX
   3    GND    GND @T6G_MB_LIB.T6G(SCH_1):GND

Q_RES_0402LF-0,5%,1/16W,CHIP,CS00002JB13  I33  R934
   1 FM_BIOS_POST_CMPLT_N      A @T6G_MB_LIB.T6G(SCH_1):FM_BIOS_POST_CMPLT_N
   2 BOOT_RDY_R1_N      B @T6G_MB_LIB.T6G(SCH_1):BOOT_RDY_R1_N

Q_RES_0402LF-0,5%,1/16W,EMPTY,CS00002JB13  I34  R941
   1 BOOT_RDY_H      A @T6G_MB_LIB.T6G(SCH_1):BOOT_RDY_H
   2 BOOT_RDY_R1_N      B @T6G_MB_LIB.T6G(SCH_1):BOOT_RDY_R1_N

Q_LED_SMLF-LED_BLUE,LTST-C281TBKT-5A,IC,BEBL0172Z00  I38  D49
   A P5V_STBY_PWR_LED      A @T6G_MB_LIB.T6G(SCH_1):P5V_STBY_PWR_LED
   C    GND      C @T6G_MB_LIB.T6G(SCH_1):GND

Q_RES_0402LF-470,1%,1/16W,CHIP,CS14702FB04  I41  R1207
   1 P5V_STBY_PWR_LED      A @T6G_MB_LIB.T6G(SCH_1):P5V_STBY_PWR_LED
   2 P5V_AUX      B @T6G_MB_LIB.T6G(SCH_1):P5V_AUX

Q_RES_0402LF-470,1%,1/16W,CHIP,CS14702FB04  I42  R1208
   1 PU_P12V_ALL_PWROK_LED      A @T6G_MB_LIB.T6G(SCH_1):PU_P12V_ALL_PWROK_LED
   2 P5V_AUX      B @T6G_MB_LIB.T6G(SCH_1):P5V_AUX

Q_LED_SMLF-LED_BLUE,LTST-C281TBKT-5A,IC,BEBL0172Z00  I43  D46
   A PU_P12V_ALL_PWROK_LED      A @T6G_MB_LIB.T6G(SCH_1):PU_P12V_ALL_PWROK_LED
   C P12V_ALL_PWROK_N      C @T6G_MB_LIB.T6G(SCH_1):P12V_ALL_PWROK_N

MOSFET_N_GSD-NX138BK,SMLF,IC,BAM01380023  I44  Q12
   G P12V_ALL_PWROK   GATE @T6G_MB_LIB.T6G(SCH_1):P12V_ALL_PWROK
   S    GND SOURCE @T6G_MB_LIB.T6G(SCH_1):GND
   D P12V_ALL_PWROK_N  DRAIN @T6G_MB_LIB.T6G(SCH_1):P12V_ALL_PWROK_N


DRAWING: @T6G_MB_LIB.T6G(SCH_1):PAGE144 

SN74LVC1G07DBVR_SMLF-SN74LVC1G07DBVR,IC,AL1G0007024  I38  U124
   2 FM_JTAG_BMC_R_OE      A @T6G_MB_LIB.T6G(SCH_1):FM_JTAG_BMC_R_OE
   4 JTAG_BMC_OE      Y @T6G_MB_LIB.T6G(SCH_1):JTAG_BMC_OE
   1     NC     NC     NC
   5 U124_VCC    VCC @T6G_MB_LIB.T6G(SCH_1):U124_VCC
   3    GND    GND @T6G_MB_LIB.T6G(SCH_1):GND

Q_CAP_0402-0.1UF,25V,10%,X7R,CH4104K1B00  I39  C693
   1 U124_VCC      A @T6G_MB_LIB.T6G(SCH_1):U124_VCC
   2    GND      B @T6G_MB_LIB.T6G(SCH_1):GND

Q_RES_0402LF-100,1%,1/16W,CHIP,CS11002FB07  I6  R1508
   1    GND      A @T6G_MB_LIB.T6G(SCH_1):GND
   2 PD_BIOS_DEBUG_MODE      B @T6G_MB_LIB.T6G(SCH_1):PD_BIOS_DEBUG_MODE

Q_RES_0402LF-10K,5%,1/16W,CHIP,CS31002JB08  I15  R1261
   1 P1V8_AUX      A @T6G_MB_LIB.T6G(SCH_1):P1V8_AUX
   2 FM_SPD_CPU0_SWITCH_CTRL_N      B @T6G_MB_LIB.T6G(SCH_1):FM_SPD_CPU0_SWITCH_CTRL_N

Q_RES_0402LF-0,5%,1/16W,CHIP,CS00002JB13  I17  R744
   1 PRSNT_CPU1_N      A @T6G_MB_LIB.T6G(SCH_1):PRSNT_CPU1_N
   2 FM_PRSNT_CPU1_N      B @T6G_MB_LIB.T6G(SCH_1):FM_PRSNT_CPU1_N

Q_RES_0402LF-0,5%,1/16W,CHIP,CS00002JB13  I19  R734
   1 PRSNT_CPU0_N      A @T6G_MB_LIB.T6G(SCH_1):PRSNT_CPU0_N
   2 FM_PRSNT_CPU0_N      B @T6G_MB_LIB.T6G(SCH_1):FM_PRSNT_CPU0_N

Q_RES_0402LF-10K,5%,1/16W,CHIP,CS31002JB08  I30  R1262
   1 P1V8_AUX      A @T6G_MB_LIB.T6G(SCH_1):P1V8_AUX
   2 BMC_JTAG_SEL      B @T6G_MB_LIB.T6G(SCH_1):BMC_JTAG_SEL

Q_RES_0402LF-10K,5%,1/16W,CHIP,CS31002JB08  I33  R6044
   1 FM_FORCE_ALL_PWRON      A @T6G_MB_LIB.T6G(SCH_1):FM_FORCE_ALL_PWRON
   2    GND      B @T6G_MB_LIB.T6G(SCH_1):GND

Q_RES_0402LF-100,1%,1/16W,CHIP,CS11002FB07  I34  R5071
   1 P1V8_AUX      A @T6G_MB_LIB.T6G(SCH_1):P1V8_AUX
   2 FM_FORCE_ALL_PWRON_ON      B @T6G_MB_LIB.T6G(SCH_1):FM_FORCE_ALL_PWRON_ON

Q_RES_0402LF-1K,1%,1/16W,EMPTY,CS21002FB06  I44  R1264
   1 P1V8_AUX      A @T6G_MB_LIB.T6G(SCH_1):P1V8_AUX
   2 BIOS_DEBUG_MODE      B @T6G_MB_LIB.T6G(SCH_1):BIOS_DEBUG_MODE

Q_RES_0402LF-100K,1%,1/16W,CHIP,CS41002FB09  I47  R8
   1    GND      A @T6G_MB_LIB.T6G(SCH_1):GND
   2 JTAG_BMC_OE      B @T6G_MB_LIB.T6G(SCH_1):JTAG_BMC_OE

Q_RES_0402LF-100,1%,1/16W,EMPTY,CS11002FB07  I50  R733
   1 P1V8_AUX      A @T6G_MB_LIB.T6G(SCH_1):P1V8_AUX
   2 FM_JTAG_BMC_R_OE      B @T6G_MB_LIB.T6G(SCH_1):FM_JTAG_BMC_R_OE

Q_RES_0402LF-10K,5%,1/16W,CHIP,CS31002JB08  I52  R1265
   1 FM_BIOS_USB_RECOVERY      A @T6G_MB_LIB.T6G(SCH_1):FM_BIOS_USB_RECOVERY
   2    GND      B @T6G_MB_LIB.T6G(SCH_1):GND

Q_RES_0402LF-100,1%,1/16W,CHIP,CS11002FB07  I54  R22
   1 P1V8_AUX      A @T6G_MB_LIB.T6G(SCH_1):P1V8_AUX
   2 PU_BIOS_USB_RECOVERY      B @T6G_MB_LIB.T6G(SCH_1):PU_BIOS_USB_RECOVERY

Q_RES_0402LF-100K,1%,1/16W,CHIP,CS41002FB09  I61  R6043
   1    GND      A @T6G_MB_LIB.T6G(SCH_1):GND
   2 FPGA_DEBUG_SW_SPARE      B @T6G_MB_LIB.T6G(SCH_1):FPGA_DEBUG_SW_SPARE

Q_RES_0402LF-10K,5%,1/16W,CHIP,CS31002JB08  I62  R6042
   1 P3V3_AUX      A @T6G_MB_LIB.T6G(SCH_1):P3V3_AUX
   2 PU_FPGA_DEBUG_SW_SPARE      B @T6G_MB_LIB.T6G(SCH_1):PU_FPGA_DEBUG_SW_SPARE

Q_RES_0402LF-100K,1%,1/16W,CHIP,CS41002FB09  I69  R6041
   1    GND      A @T6G_MB_LIB.T6G(SCH_1):GND
   2 FPGA_DEBUG_LED_CTRL      B @T6G_MB_LIB.T6G(SCH_1):FPGA_DEBUG_LED_CTRL

Q_RES_0402LF-10K,5%,1/16W,CHIP,CS31002JB08  I70  R6040
   1 P1V8_AUX      A @T6G_MB_LIB.T6G(SCH_1):P1V8_AUX
   2 PU_FPGA_DEBUG_LED_CTRL      B @T6G_MB_LIB.T6G(SCH_1):PU_FPGA_DEBUG_LED_CTRL

Q_RES_0402LF-10K,5%,1/16W,EMPTY,CS31002JB08  I72  R1358
   1 P1V8_AUX      A @T6G_MB_LIB.T6G(SCH_1):P1V8_AUX
   2 FM_PASSWORD_CLEAR_N      B @T6G_MB_LIB.T6G(SCH_1):FM_PASSWORD_CLEAR_N

Q_RES_0402LF-2.2K,5%,1/16W,CHIP,CS22202JB07  I74  R1357
   1 P3V3_AUX      A @T6G_MB_LIB.T6G(SCH_1):P3V3_AUX
   2 FM_PRSNT_CPU1_N      B @T6G_MB_LIB.T6G(SCH_1):FM_PRSNT_CPU1_N

Q_RES_0402LF-4.7K,5%,1/16W,CHIP,CS24702JB10  I77  R1356
   1 P3V3_AUX      A @T6G_MB_LIB.T6G(SCH_1):P3V3_AUX
   2 FM_PRSNT_CPU0_N      B @T6G_MB_LIB.T6G(SCH_1):FM_PRSNT_CPU0_N

Q_RES_0402LF-10K,5%,1/16W,CHIP,CS31002JB08  I81  R6106
   1 PVDD18_S5_P0      A @T6G_MB_LIB.T6G(SCH_1):PVDD18_S5_P0
   2 FM_PASSWORD_CLEAR_N      B @T6G_MB_LIB.T6G(SCH_1):FM_PASSWORD_CLEAR_N

Q_RES_0402LF-10K,5%,1/16W,CHIP,CS31002JB08  I83  R6107
   1 PVDD18_S5_P0      A @T6G_MB_LIB.T6G(SCH_1):PVDD18_S5_P0
   2 BIOS_DEBUG_MODE      B @T6G_MB_LIB.T6G(SCH_1):BIOS_DEBUG_MODE

Q_RES_0402LF-0,5%,1/16W,CHIP,CS00002JB13  I84  R8018
   1 P1V8_AUX      A @T6G_MB_LIB.T6G(SCH_1):P1V8_AUX
   2 U124_VCC      B @T6G_MB_LIB.T6G(SCH_1):U124_VCC

Q_RES_0402LF-0,5%,1/16W,EMPTY,CS00002JB13  I85  R8017
   1 P3V3_AUX      A @T6G_MB_LIB.T6G(SCH_1):P3V3_AUX
   2 U124_VCC      B @T6G_MB_LIB.T6G(SCH_1):U124_VCC

Q_RES_0402LF-100,1%,1/16W,EMPTY,CS11002FB07  I89  R8019
   1 P3V3_AUX      A @T6G_MB_LIB.T6G(SCH_1):P3V3_AUX
   2 FM_JTAG_BMC_R_OE      B @T6G_MB_LIB.T6G(SCH_1):FM_JTAG_BMC_R_OE

SW20S_DHNF10FQTR-SW20S_DHNF-10F-Q-T/R,SMLF,MECH,DHA  I90  SW1
   1    GND      1 @T6G_MB_LIB.T6G(SCH_1):GND
   2 FM_FORCE_ALL_PWRON_ON      2 @T6G_MB_LIB.T6G(SCH_1):FM_FORCE_ALL_PWRON_ON
   3    GND      3 @T6G_MB_LIB.T6G(SCH_1):GND
   4 PU_BIOS_USB_RECOVERY      4 @T6G_MB_LIB.T6G(SCH_1):PU_BIOS_USB_RECOVERY
  11 FM_SPD_CPU0_SWITCH_CTRL_N     11 @T6G_MB_LIB.T6G(SCH_1):FM_SPD_CPU0_SWITCH_CTRL_N
  12 FM_FORCE_ALL_PWRON     12 @T6G_MB_LIB.T6G(SCH_1):FM_FORCE_ALL_PWRON
  13 BMC_JTAG_SEL     13 @T6G_MB_LIB.T6G(SCH_1):BMC_JTAG_SEL
  14 FM_BIOS_USB_RECOVERY     14 @T6G_MB_LIB.T6G(SCH_1):FM_BIOS_USB_RECOVERY
   5 PU_FPGA_DEBUG_SW_SPARE      5 @T6G_MB_LIB.T6G(SCH_1):PU_FPGA_DEBUG_SW_SPARE
   6 PD_BIOS_DEBUG_MODE      6 @T6G_MB_LIB.T6G(SCH_1):PD_BIOS_DEBUG_MODE
   7 PRSNT_CPU0_N      7 @T6G_MB_LIB.T6G(SCH_1):PRSNT_CPU0_N
   8 PRSNT_CPU1_N      8 @T6G_MB_LIB.T6G(SCH_1):PRSNT_CPU1_N
  15 FPGA_DEBUG_SW_SPARE     15 @T6G_MB_LIB.T6G(SCH_1):FPGA_DEBUG_SW_SPARE
  16 BIOS_DEBUG_MODE     16 @T6G_MB_LIB.T6G(SCH_1):BIOS_DEBUG_MODE
  17 FM_PRSNT_CPU0_N     17 @T6G_MB_LIB.T6G(SCH_1):FM_PRSNT_CPU0_N
  18 FM_PRSNT_CPU1_N     18 @T6G_MB_LIB.T6G(SCH_1):FM_PRSNT_CPU1_N
  19 FM_PASSWORD_CLEAR_N     19 @T6G_MB_LIB.T6G(SCH_1):FM_PASSWORD_CLEAR_N
  20 FPGA_DEBUG_LED_CTRL     20 @T6G_MB_LIB.T6G(SCH_1):FPGA_DEBUG_LED_CTRL
   9    GND      9 @T6G_MB_LIB.T6G(SCH_1):GND
  10 PU_FPGA_DEBUG_LED_CTRL     10 @T6G_MB_LIB.T6G(SCH_1):PU_FPGA_DEBUG_LED_CTRL


DRAWING: @T6G_MB_LIB.T6G(SCH_1):PAGE148 

Q_RES_0402LF-10K,1%,1/16W,CHIP,CS31002FB08  I244  R1734
   1 P3V3_AUX      A @T6G_MB_LIB.T6G(SCH_1):P3V3_AUX
   2 JTAG_SCM_TCK      B @T6G_MB_LIB.T6G(SCH_1):JTAG_SCM_TCK

Q_RES_0402LF-10K,1%,1/16W,EMPTY,CS31002FB08  I245  R1731
   1 P3V3_AUX      A @T6G_MB_LIB.T6G(SCH_1):P3V3_AUX
   2 JTAG_SCM_TMS      B @T6G_MB_LIB.T6G(SCH_1):JTAG_SCM_TMS

Q_RES_0402LF-10K,1%,1/16W,EMPTY,CS31002FB08  I246  R1735
   1 JTAG_SCM_TCK      A @T6G_MB_LIB.T6G(SCH_1):JTAG_SCM_TCK
   2    GND      B @T6G_MB_LIB.T6G(SCH_1):GND

Q_RES_0402LF-10K,1%,1/16W,EMPTY,CS31002FB08  I249  R1728
   1 P3V3_AUX      A @T6G_MB_LIB.T6G(SCH_1):P3V3_AUX
   2 JTAG_SCM_TDI      B @T6G_MB_LIB.T6G(SCH_1):JTAG_SCM_TDI

Q_RES_0402LF-10K,1%,1/16W,EMPTY,CS31002FB08  I250  R1727
   1 P3V3_AUX      A @T6G_MB_LIB.T6G(SCH_1):P3V3_AUX
   2 JTAG_SCM_TDO      B @T6G_MB_LIB.T6G(SCH_1):JTAG_SCM_TDO

Q_RES_0402LF-10K,1%,1/16W,CHIP,CS31002FB08  I255  R1747
   1 P3V3_AUX      A @T6G_MB_LIB.T6G(SCH_1):P3V3_AUX
   2 JTAG_SCM_MUX_TCK      B @T6G_MB_LIB.T6G(SCH_1):JTAG_SCM_MUX_TCK

Q_RES_0402LF-10K,1%,1/16W,CHIP,CS31002FB08  I256  R1746
   1 P3V3_AUX      A @T6G_MB_LIB.T6G(SCH_1):P3V3_AUX
   2 JTAG_SCM_MUX_TMS      B @T6G_MB_LIB.T6G(SCH_1):JTAG_SCM_MUX_TMS

Q_RES_0402LF-10K,1%,1/16W,CHIP,CS31002FB08  I257  R1745
   1 P3V3_AUX      A @T6G_MB_LIB.T6G(SCH_1):P3V3_AUX
   2 JTAG_SCM_MUX_TDO      B @T6G_MB_LIB.T6G(SCH_1):JTAG_SCM_MUX_TDO

Q_RES_0402LF-10K,1%,1/16W,EMPTY,CS31002FB08  I258  R1748
   1 JTAG_SCM_MUX_TCK      A @T6G_MB_LIB.T6G(SCH_1):JTAG_SCM_MUX_TCK
   2    GND      B @T6G_MB_LIB.T6G(SCH_1):GND

Q_RES_0402LF-10K,1%,1/16W,CHIP,CS31002FB08  I261  R1744
   1 P3V3_AUX      A @T6G_MB_LIB.T6G(SCH_1):P3V3_AUX
   2 JTAG_SCM_MUX_TDI      B @T6G_MB_LIB.T6G(SCH_1):JTAG_SCM_MUX_TDI

74LV4052PW-74LV4052PW,SMLF,IC,ALLV4052K19  I266  U160
   1 TP_JTAG_SCM_SLOT3_R_TMS    2Y0 @T6G_MB_LIB.T6G(SCH_1):TP_JTAG_SCM_SLOT3_R_TMS
   2 JTAG_SCM_PLD_R_TMS    2Y2 @T6G_MB_LIB.T6G(SCH_1):JTAG_SCM_PLD_R_TMS
   3 JTAG_SCM_TMS     2Z @T6G_MB_LIB.T6G(SCH_1):JTAG_SCM_TMS
   4 JTAG_SCM_PLD_R_TMS    2Y3 @T6G_MB_LIB.T6G(SCH_1):JTAG_SCM_PLD_R_TMS
   5 JTAG_SCM_MUX_R_TMS    2Y1 @T6G_MB_LIB.T6G(SCH_1):JTAG_SCM_MUX_R_TMS
   6 U160_EN_N    E_N @T6G_MB_LIB.T6G(SCH_1):U160_EN_N
   7    GND    VEE @T6G_MB_LIB.T6G(SCH_1):GND
   8    GND    GND @T6G_MB_LIB.T6G(SCH_1):GND
   9 SCM_JTAG_MUX_S1     S1 @T6G_MB_LIB.T6G(SCH_1):SCM_JTAG_MUX_S1
  10 SCM_JTAG_MUX_S0_R1     S0 @T6G_MB_LIB.T6G(SCH_1):SCM_JTAG_MUX_S0_R1
  11 JTAG_SCM_PLD_R_TCK    1Y3 @T6G_MB_LIB.T6G(SCH_1):JTAG_SCM_PLD_R_TCK
  12 TP_JTAG_SCM_SLOT3_R_TCK    1Y0 @T6G_MB_LIB.T6G(SCH_1):TP_JTAG_SCM_SLOT3_R_TCK
  13 JTAG_SCM_TCK     1Z @T6G_MB_LIB.T6G(SCH_1):JTAG_SCM_TCK
  14 JTAG_SCM_MUX_R_TCK    1Y1 @T6G_MB_LIB.T6G(SCH_1):JTAG_SCM_MUX_R_TCK
  15 JTAG_SCM_PLD_R_TCK    1Y2 @T6G_MB_LIB.T6G(SCH_1):JTAG_SCM_PLD_R_TCK
  16 P3V3_AUX    VCC @T6G_MB_LIB.T6G(SCH_1):P3V3_AUX

Q_CAP_C0402-0.1UF,16V,10%,X7R,CH4103K1B08  I293  C1554
   1 P3V3_AUX      A @T6G_MB_LIB.T6G(SCH_1):P3V3_AUX
   2    GND      B @T6G_MB_LIB.T6G(SCH_1):GND

Q_CAP_C0402-0.1UF,16V,10%,X7R,CH4103K1B08  I299  C194
   1 P3V3_AUX      A @T6G_MB_LIB.T6G(SCH_1):P3V3_AUX
   2    GND      B @T6G_MB_LIB.T6G(SCH_1):GND

74LV4052PW-74LV4052PW,SMLF,IC,ALLV4052K19  I302  U212
   1 TP_JTAG_SCM_SLOT3_R_TDO    2Y0 @T6G_MB_LIB.T6G(SCH_1):TP_JTAG_SCM_SLOT3_R_TDO
   2 JTAG_SCM_PLD_R_TDO    2Y2 @T6G_MB_LIB.T6G(SCH_1):JTAG_SCM_PLD_R_TDO
   3 JTAG_SCM_TDO     2Z @T6G_MB_LIB.T6G(SCH_1):JTAG_SCM_TDO
   4 JTAG_SCM_PLD_R_TDO    2Y3 @T6G_MB_LIB.T6G(SCH_1):JTAG_SCM_PLD_R_TDO
   5 JTAG_SCM_MUX_R_TDO    2Y1 @T6G_MB_LIB.T6G(SCH_1):JTAG_SCM_MUX_R_TDO
   6 U212_EN_N    E_N @T6G_MB_LIB.T6G(SCH_1):U212_EN_N
   7    GND    VEE @T6G_MB_LIB.T6G(SCH_1):GND
   8    GND    GND @T6G_MB_LIB.T6G(SCH_1):GND
   9 SCM_JTAG_MUX_S1     S1 @T6G_MB_LIB.T6G(SCH_1):SCM_JTAG_MUX_S1
  10 SCM_JTAG_MUX_S0_R2     S0 @T6G_MB_LIB.T6G(SCH_1):SCM_JTAG_MUX_S0_R2
  11 JTAG_SCM_PLD_R_TDI    1Y3 @T6G_MB_LIB.T6G(SCH_1):JTAG_SCM_PLD_R_TDI
  12 TP_JTAG_SCM_SLOT3_R_TDI    1Y0 @T6G_MB_LIB.T6G(SCH_1):TP_JTAG_SCM_SLOT3_R_TDI
  13 JTAG_SCM_TDI     1Z @T6G_MB_LIB.T6G(SCH_1):JTAG_SCM_TDI
  14 JTAG_SCM_MUX_R_TDI    1Y1 @T6G_MB_LIB.T6G(SCH_1):JTAG_SCM_MUX_R_TDI
  15 JTAG_SCM_PLD_R_TDI    1Y2 @T6G_MB_LIB.T6G(SCH_1):JTAG_SCM_PLD_R_TDI
  16 P3V3_AUX    VCC @T6G_MB_LIB.T6G(SCH_1):P3V3_AUX

Q_RES_0402LF-4.7K,5%,1/16W,EMPTY,CS24702JB10  I305  R1730
   1 P3V3_AUX      A @T6G_MB_LIB.T6G(SCH_1):P3V3_AUX
   2 SCM_JTAG_MUX_S1      B @T6G_MB_LIB.T6G(SCH_1):SCM_JTAG_MUX_S1

Q_RES_0402LF-4.7K,5%,1/16W,CHIP,CS24702JB10  I306  R1729
   1 SCM_JTAG_MUX_S1      A @T6G_MB_LIB.T6G(SCH_1):SCM_JTAG_MUX_S1
   2    GND      B @T6G_MB_LIB.T6G(SCH_1):GND

Q_RES_0402LF-4.7K,5%,1/16W,EMPTY,CS24702JB10  I309  R1659
   1 P3V3_AUX      A @T6G_MB_LIB.T6G(SCH_1):P3V3_AUX
   2 SCM_JTAG_MUX_S0      B @T6G_MB_LIB.T6G(SCH_1):SCM_JTAG_MUX_S0

Q_RES_0402LF-4.7K,5%,1/16W,CHIP,CS24702JB10  I310  R1658
   1 SCM_JTAG_MUX_S0      A @T6G_MB_LIB.T6G(SCH_1):SCM_JTAG_MUX_S0
   2    GND      B @T6G_MB_LIB.T6G(SCH_1):GND

Q_RES_0402LF-22,1%,1/16W,CHIP,CS02202FB02  I332  R1743
   1 JTAG_SCM_PLD_R_TDO      A @T6G_MB_LIB.T6G(SCH_1):JTAG_SCM_PLD_R_TDO
   2 JTAG_SCM_PLD_TDO      B @T6G_MB_LIB.T6G(SCH_1):JTAG_SCM_PLD_TDO

Q_RES_0402LF-4.7K,5%,1/16W,EMPTY,CS24702JB10  I339  R1343
   1 P3V3_AUX      A @T6G_MB_LIB.T6G(SCH_1):P3V3_AUX
   2 SCM_JTAG_MUX_S1      B @T6G_MB_LIB.T6G(SCH_1):SCM_JTAG_MUX_S1

SN74LVC1G07DBVR_SMLF-SN74LVC1G07DBVR,EMPTY,AL1G000A  I340  U99
   2 FW_RECOVERY_R      A @T6G_MB_LIB.T6G(SCH_1):FW_RECOVERY_R
   4 SCM_JTAG_MUX_S1      Y @T6G_MB_LIB.T6G(SCH_1):SCM_JTAG_MUX_S1
   1     NC     NC     NC
   5 P3V3_AUX    VCC @T6G_MB_LIB.T6G(SCH_1):P3V3_AUX
   3    GND    GND @T6G_MB_LIB.T6G(SCH_1):GND

Q_CAP_0402-0.1UF,25V,10%,X7R,CH4104K1B00  I342  C553
   1 P3V3_AUX      A @T6G_MB_LIB.T6G(SCH_1):P3V3_AUX
   2    GND      B @T6G_MB_LIB.T6G(SCH_1):GND

Q_RES_0402LF-0,5%,1/16W,CHIP,CS00002JB13  I349  R1738
   1 JTAG_SCM_MUX_R_TDI      A @T6G_MB_LIB.T6G(SCH_1):JTAG_SCM_MUX_R_TDI
   2 JTAG_SCM_MUX_TDI      B @T6G_MB_LIB.T6G(SCH_1):JTAG_SCM_MUX_TDI

Q_RES_0402LF-22,1%,1/16W,CHIP,CS02202FB02  I352  R1742
   1 JTAG_SCM_PLD_R_TDI      A @T6G_MB_LIB.T6G(SCH_1):JTAG_SCM_PLD_R_TDI
   2 JTAG_SCM_PLD_TDI      B @T6G_MB_LIB.T6G(SCH_1):JTAG_SCM_PLD_TDI

Q_RES_0402LF-0,5%,1/16W,CHIP,CS00002JB13  I357  R1737
   1 JTAG_SCM_MUX_R_TMS      A @T6G_MB_LIB.T6G(SCH_1):JTAG_SCM_MUX_R_TMS
   2 JTAG_SCM_MUX_TMS      B @T6G_MB_LIB.T6G(SCH_1):JTAG_SCM_MUX_TMS

Q_RES_0402LF-0,5%,1/16W,CHIP,CS00002JB13  I363  R1736
   1 JTAG_SCM_MUX_R_TCK      A @T6G_MB_LIB.T6G(SCH_1):JTAG_SCM_MUX_R_TCK
   2 JTAG_SCM_MUX_TCK      B @T6G_MB_LIB.T6G(SCH_1):JTAG_SCM_MUX_TCK

Q_RES_0402LF-22,1%,1/16W,CHIP,CS02202FB02  I366  R1741
   1 JTAG_SCM_PLD_R_TMS      A @T6G_MB_LIB.T6G(SCH_1):JTAG_SCM_PLD_R_TMS
   2 JTAG_SCM_PLD_TMS      B @T6G_MB_LIB.T6G(SCH_1):JTAG_SCM_PLD_TMS

Q_RES_0402LF-22,1%,1/16W,CHIP,CS02202FB02  I368  R1740
   1 JTAG_SCM_PLD_R_TCK      A @T6G_MB_LIB.T6G(SCH_1):JTAG_SCM_PLD_R_TCK
   2 JTAG_SCM_PLD_TCK      B @T6G_MB_LIB.T6G(SCH_1):JTAG_SCM_PLD_TCK

Q_RES_0402LF-10K,1%,1/16W,CHIP,CS31002FB08  I369  R1342
   1 FW_RECOVERY_R      A @T6G_MB_LIB.T6G(SCH_1):FW_RECOVERY_R
   2    GND      B @T6G_MB_LIB.T6G(SCH_1):GND

Q_RES_0402LF-0,5%,1/16W,CHIP,CS00002JB13  I375  R6101
   1 SCM_JTAG_MUX_S0      A @T6G_MB_LIB.T6G(SCH_1):SCM_JTAG_MUX_S0
   2 SCM_JTAG_MUX_S0_R1      B @T6G_MB_LIB.T6G(SCH_1):SCM_JTAG_MUX_S0_R1

Q_RES_0402LF-0,5%,1/16W,CHIP,CS00002JB13  I376  R6102
   1 SCM_JTAG_MUX_S0      A @T6G_MB_LIB.T6G(SCH_1):SCM_JTAG_MUX_S0
   2 SCM_JTAG_MUX_S0_R2      B @T6G_MB_LIB.T6G(SCH_1):SCM_JTAG_MUX_S0_R2

Q_RES_0402LF-4.7K,5%,1/16W,CHIP,CS24702JB10  I378  R1318
   1 PD_U212_EN_N      A @T6G_MB_LIB.T6G(SCH_1):PD_U212_EN_N
   2    GND      B @T6G_MB_LIB.T6G(SCH_1):GND

Q_RES_0402LF-4.7K,5%,1/16W,CHIP,CS24702JB10  I381  R6181
   1 P3V3_AUX      A @T6G_MB_LIB.T6G(SCH_1):P3V3_AUX
   2 PU_U212_EN_N      B @T6G_MB_LIB.T6G(SCH_1):PU_U212_EN_N

Q_RES_0402LF-4.7K,5%,1/16W,CHIP,CS24702JB10  I383  R1313
   1 PD_U160_EN_N      A @T6G_MB_LIB.T6G(SCH_1):PD_U160_EN_N
   2    GND      B @T6G_MB_LIB.T6G(SCH_1):GND

Q_RES_0402LF-4.7K,5%,1/16W,CHIP,CS24702JB10  I384  R6182
   1 P3V3_AUX      A @T6G_MB_LIB.T6G(SCH_1):P3V3_AUX
   2 PU_U160_EN_N      B @T6G_MB_LIB.T6G(SCH_1):PU_U160_EN_N

CONN3_210HP1030BR1-CONN3_210-HP1-030BR1,THLF,IO,DFA  I386  JP6000
   3 PD_U212_EN_N      3 @T6G_MB_LIB.T6G(SCH_1):PD_U212_EN_N
   2 U212_EN_N      2 @T6G_MB_LIB.T6G(SCH_1):U212_EN_N
   1 PU_U212_EN_N      1 @T6G_MB_LIB.T6G(SCH_1):PU_U212_EN_N

CONN3_210HP1030BR1-CONN3_210-HP1-030BR1,THLF,IO,DFA  I387  JP6001
   3 PD_U160_EN_N      3 @T6G_MB_LIB.T6G(SCH_1):PD_U160_EN_N
   2 U160_EN_N      2 @T6G_MB_LIB.T6G(SCH_1):U160_EN_N
   1 PU_U160_EN_N      1 @T6G_MB_LIB.T6G(SCH_1):PU_U160_EN_N

Q_RES_0402LF-0,5%,1/16W,CHIP,CS00002JB13  I388  R1739
   1 JTAG_SCM_MUX_R_TDO      A @T6G_MB_LIB.T6G(SCH_1):JTAG_SCM_MUX_R_TDO
   2 JTAG_SCM_MUX_TDO      B @T6G_MB_LIB.T6G(SCH_1):JTAG_SCM_MUX_TDO


DRAWING: @T6G_MB_LIB.T6G(SCH_1):PAGE149 

SN74AVC2T245RSWR-SN74AVC2T245RSWR,SMLF,IC,AL02T245A  I1  U147
   1    GND   DIR2 @T6G_MB_LIB.T6G(SCH_1):GND
   2 JTAG_BMC_OE_N   OE_# @T6G_MB_LIB.T6G(SCH_1):JTAG_BMC_OE_N
   3    GND    GND @T6G_MB_LIB.T6G(SCH_1):GND
   4 JTAG_TDO_R1     B2 @T6G_MB_LIB.T6G(SCH_1):JTAG_TDO_R1
   5 JTAG_TDI_R     B1 @T6G_MB_LIB.T6G(SCH_1):JTAG_TDI_R
   6 PVDD18_S5_P0   VCCB @T6G_MB_LIB.T6G(SCH_1):PVDD18_S5_P0
   7 P3V3_AUX   VCCA @T6G_MB_LIB.T6G(SCH_1):P3V3_AUX
   8 JTAG_SCM_MUX_TDO     A1 @T6G_MB_LIB.T6G(SCH_1):JTAG_SCM_MUX_TDO
   9 JTAG_SCM_MUX_TDI     A2 @T6G_MB_LIB.T6G(SCH_1):JTAG_SCM_MUX_TDI
  10 P3V3_AUX   DIR1 @T6G_MB_LIB.T6G(SCH_1):P3V3_AUX

Q_RES_0402LF-0,5%,1/16W,CHIP,CS00002JB13  I7  R1633
   1 JTAG_TCK_R      A @T6G_MB_LIB.T6G(SCH_1):JTAG_TCK_R
   2 JTAG_TCK      B @T6G_MB_LIB.T6G(SCH_1):JTAG_TCK

Q_RES_0402LF-22,1%,1/16W,CHIP,CS02202FB02  I8  R1635
   1 JTAG_TRST_R_N      A @T6G_MB_LIB.T6G(SCH_1):JTAG_TRST_R_N
   2 JTAG_TRST_N      B @T6G_MB_LIB.T6G(SCH_1):JTAG_TRST_N

Q_RES_0402LF-22,1%,1/16W,CHIP,CS02202FB02  I9  R1636
   1 JTAG_DBREQ_R_N      A @T6G_MB_LIB.T6G(SCH_1):JTAG_DBREQ_R_N
   2 JTAG_DBREQ_N      B @T6G_MB_LIB.T6G(SCH_1):JTAG_DBREQ_N

Q_CAP_C0402-0.1UF,16V,10%,X7R,CH4103K1B08  I10  C1509
   1 PVDD18_S5_P0      A @T6G_MB_LIB.T6G(SCH_1):PVDD18_S5_P0
   2    GND      B @T6G_MB_LIB.T6G(SCH_1):GND

Q_CAP_0402-33PF,50V,5%,NPO,TMP_QCH03306JB04  I21  C1512
   1 JTAG_DBREQ_N      A @T6G_MB_LIB.T6G(SCH_1):JTAG_DBREQ_N
   2    GND      B @T6G_MB_LIB.T6G(SCH_1):GND

Q_CAP_0402-33PF,50V,5%,NPO,TMP_QCH03306JB04  I23  C1511
   1 JTAG_TRST_N      A @T6G_MB_LIB.T6G(SCH_1):JTAG_TRST_N
   2    GND      B @T6G_MB_LIB.T6G(SCH_1):GND

Q_CAP_0402-33PF,50V,5%,NPO,TMP_QCH03306JB04  I25  C1510
   1 JTAG_TCK      A @T6G_MB_LIB.T6G(SCH_1):JTAG_TCK
   2    GND      B @T6G_MB_LIB.T6G(SCH_1):GND

Q_CAP_C0402-0.1UF,16V,10%,X7R,CH4103K1B08  I29  C1508
   1 PVDD18_S5_P0      A @T6G_MB_LIB.T6G(SCH_1):PVDD18_S5_P0
   2    GND      B @T6G_MB_LIB.T6G(SCH_1):GND

SN74AVC4T774PWR-SN74AVC4T774PWR,SMLF,IC,AL04T774K00  I31  U149
   1 PVDD18_S5_P0   DIR1 @T6G_MB_LIB.T6G(SCH_1):PVDD18_S5_P0
   2 PVDD18_S5_P0   DIR2 @T6G_MB_LIB.T6G(SCH_1):PVDD18_S5_P0
   3 HDT_HDR_TCK     A1 @T6G_MB_LIB.T6G(SCH_1):HDT_HDR_TCK
   4 HDT_HDR_TMS     A2 @T6G_MB_LIB.T6G(SCH_1):HDT_HDR_TMS
   5 HDT_HDR_TRST_N     A3 @T6G_MB_LIB.T6G(SCH_1):HDT_HDR_TRST_N
   6 HDT_HDR_DBREQ_N     A4 @T6G_MB_LIB.T6G(SCH_1):HDT_HDR_DBREQ_N
   7 PVDD18_S5_P0   DIR3 @T6G_MB_LIB.T6G(SCH_1):PVDD18_S5_P0
   8 PVDD18_S5_P0   DIR4 @T6G_MB_LIB.T6G(SCH_1):PVDD18_S5_P0
   9 JTAG_BMC_R_D_OE     OE @T6G_MB_LIB.T6G(SCH_1):JTAG_BMC_R_D_OE
  10    GND    GND @T6G_MB_LIB.T6G(SCH_1):GND
  11 JTAG_DBREQ_R_N     B4 @T6G_MB_LIB.T6G(SCH_1):JTAG_DBREQ_R_N
  12 JTAG_TRST_R_N     B3 @T6G_MB_LIB.T6G(SCH_1):JTAG_TRST_R_N
  13 JTAG_TMS_R     B2 @T6G_MB_LIB.T6G(SCH_1):JTAG_TMS_R
  14 JTAG_TCK_R     B1 @T6G_MB_LIB.T6G(SCH_1):JTAG_TCK_R
  15 PVDD18_S5_P0   VCCB @T6G_MB_LIB.T6G(SCH_1):PVDD18_S5_P0
  16 PVDD18_S5_P0   VCCA @T6G_MB_LIB.T6G(SCH_1):PVDD18_S5_P0

SN74AVC4T774PWR-SN74AVC4T774PWR,SMLF,IC,AL04T774K00  I34  U148
   1 P3V3_AUX   DIR1 @T6G_MB_LIB.T6G(SCH_1):P3V3_AUX
   2 P3V3_AUX   DIR2 @T6G_MB_LIB.T6G(SCH_1):P3V3_AUX
   3 JTAG_SCM_MUX_TCK     A1 @T6G_MB_LIB.T6G(SCH_1):JTAG_SCM_MUX_TCK
   4 JTAG_SCM_MUX_TMS     A2 @T6G_MB_LIB.T6G(SCH_1):JTAG_SCM_MUX_TMS
   5 JTAG_SCM_TRST_N     A3 @T6G_MB_LIB.T6G(SCH_1):JTAG_SCM_TRST_N
   6 JTAG_SCM_DBREQ_N     A4 @T6G_MB_LIB.T6G(SCH_1):JTAG_SCM_DBREQ_N
   7 P3V3_AUX   DIR3 @T6G_MB_LIB.T6G(SCH_1):P3V3_AUX
   8 P3V3_AUX   DIR4 @T6G_MB_LIB.T6G(SCH_1):P3V3_AUX
   9 JTAG_BMC_OE_N     OE @T6G_MB_LIB.T6G(SCH_1):JTAG_BMC_OE_N
  10    GND    GND @T6G_MB_LIB.T6G(SCH_1):GND
  11 JTAG_DBREQ_R_N     B4 @T6G_MB_LIB.T6G(SCH_1):JTAG_DBREQ_R_N
  12 JTAG_TRST_R_N     B3 @T6G_MB_LIB.T6G(SCH_1):JTAG_TRST_R_N
  13 JTAG_TMS_R     B2 @T6G_MB_LIB.T6G(SCH_1):JTAG_TMS_R
  14 JTAG_TCK_R     B1 @T6G_MB_LIB.T6G(SCH_1):JTAG_TCK_R
  15 PVDD18_S5_P0   VCCB @T6G_MB_LIB.T6G(SCH_1):PVDD18_S5_P0
  16 P3V3_AUX   VCCA @T6G_MB_LIB.T6G(SCH_1):P3V3_AUX

Q_CAP_C0402-0.1UF,16V,10%,X7R,CH4103K1B08  I41  C1507
   1 PVDD18_S5_P0      A @T6G_MB_LIB.T6G(SCH_1):PVDD18_S5_P0
   2    GND      B @T6G_MB_LIB.T6G(SCH_1):GND

Q_RES_0402LF-0,5%,1/16W,CHIP,CS00002JB13  I53  R1625
   1 JTAG_TDI_R      A @T6G_MB_LIB.T6G(SCH_1):JTAG_TDI_R
   2 JTAG_TDI      B @T6G_MB_LIB.T6G(SCH_1):JTAG_TDI

Q_CAP_C0402-0.1UF,16V,10%,X7R,CH4103K1B08  I56  C1504
   1 PVDD18_S5_P0      A @T6G_MB_LIB.T6G(SCH_1):PVDD18_S5_P0
   2    GND      B @T6G_MB_LIB.T6G(SCH_1):GND

Q_CAP_C0402-0.1UF,16V,10%,X7R,CH4103K1B08  I62  C1506
   1 P3V3_AUX      A @T6G_MB_LIB.T6G(SCH_1):P3V3_AUX
   2    GND      B @T6G_MB_LIB.T6G(SCH_1):GND

Q_CAP_C0402-0.1UF,16V,10%,X7R,CH4103K1B08  I74  C1505
   1 PVDD18_S5_P0      A @T6G_MB_LIB.T6G(SCH_1):PVDD18_S5_P0
   2    GND      B @T6G_MB_LIB.T6G(SCH_1):GND

SN74AVC2T245RSWR-SN74AVC2T245RSWR,SMLF,IC,AL02T245A  I76  U146
   1    GND   DIR2 @T6G_MB_LIB.T6G(SCH_1):GND
   2 JTAG_BMC_R_D_OE   OE_# @T6G_MB_LIB.T6G(SCH_1):JTAG_BMC_R_D_OE
   3    GND    GND @T6G_MB_LIB.T6G(SCH_1):GND
   4 JTAG_TDO_R1     B2 @T6G_MB_LIB.T6G(SCH_1):JTAG_TDO_R1
   5 JTAG_TDI_R     B1 @T6G_MB_LIB.T6G(SCH_1):JTAG_TDI_R
   6 PVDD18_S5_P0   VCCB @T6G_MB_LIB.T6G(SCH_1):PVDD18_S5_P0
   7 PVDD18_S5_P0   VCCA @T6G_MB_LIB.T6G(SCH_1):PVDD18_S5_P0
   8 HDT_HDR_TDI     A1 @T6G_MB_LIB.T6G(SCH_1):HDT_HDR_TDI
   9 HDT_HDR_TDO_R     A2 @T6G_MB_LIB.T6G(SCH_1):HDT_HDR_TDO_R
  10 PVDD18_S5_P0   DIR1 @T6G_MB_LIB.T6G(SCH_1):PVDD18_S5_P0

Q_CAP_C0402-0.1UF,16V,10%,X7R,CH4103K1B08  I80  C1503
   1 P3V3_AUX      A @T6G_MB_LIB.T6G(SCH_1):P3V3_AUX
   2    GND      B @T6G_MB_LIB.T6G(SCH_1):GND

Q_RES_0402LF-4.7K,5%,1/16W,CHIP,CS24702JB10  I83  R1622
   1 P3V3_AUX      A @T6G_MB_LIB.T6G(SCH_1):P3V3_AUX
   2 JTAG_BMC_OE_N      B @T6G_MB_LIB.T6G(SCH_1):JTAG_BMC_OE_N

Q_RES_0402LF-0,5%,1/16W,CHIP,CS00002JB13  I92  R1619
   1 JTAG_BMC_OE      A @T6G_MB_LIB.T6G(SCH_1):JTAG_BMC_OE
   2 JTAG_BMC_R_D_OE      B @T6G_MB_LIB.T6G(SCH_1):JTAG_BMC_R_D_OE

Q_RES_0402LF-0,5%,1/16W,CHIP,CS00002JB13  I96  R1634
   1 JTAG_TMS_R      A @T6G_MB_LIB.T6G(SCH_1):JTAG_TMS_R
   2 JTAG_TMS      B @T6G_MB_LIB.T6G(SCH_1):JTAG_TMS

Q_RES_0402LF-4.7K,5%,1/16W,CHIP,CS24702JB10  I101  R617
   1 PVDD18_S5_P0      A @T6G_MB_LIB.T6G(SCH_1):PVDD18_S5_P0
   2 JTAG_BMC_R_D_OE      B @T6G_MB_LIB.T6G(SCH_1):JTAG_BMC_R_D_OE

MOSFET_N_SMLF-BSS138K,BSS138K,IC,BAM138K0000  I102  Q62
   G JTAG_BMC_OE   GATE @T6G_MB_LIB.T6G(SCH_1):JTAG_BMC_OE
   D JTAG_BMC_OE_N  DRAIN @T6G_MB_LIB.T6G(SCH_1):JTAG_BMC_OE_N
   S    GND SOURCE @T6G_MB_LIB.T6G(SCH_1):GND

Q_RES_0402LF-0,5%,1/16W,CHIP,CS00002JB13  I109  R1354
   1 HDT_HDR_R_TDI      A @T6G_MB_LIB.T6G(SCH_1):HDT_HDR_R_TDI
   2 HDT_HDR_TDI      B @T6G_MB_LIB.T6G(SCH_1):HDT_HDR_TDI

Q_RES_0402LF-1K,1%,1/16W,CHIP,CS21002FB06  I111  R1624
   1 PVDD18_S5_P0      A @T6G_MB_LIB.T6G(SCH_1):PVDD18_S5_P0
   2 HDT_HDR_TCK      B @T6G_MB_LIB.T6G(SCH_1):HDT_HDR_TCK

Q_RES_0402LF-1K,1%,1/16W,CHIP,CS21002FB06  I112  R1629
   1 HDT_CPU0_HDT_CONN_TESTEN      A @T6G_MB_LIB.T6G(SCH_1):HDT_CPU0_HDT_CONN_TESTEN
   2    GND      B @T6G_MB_LIB.T6G(SCH_1):GND

Q_RES_0402LF-33,5%,1/16W,CHIP,CS03302JB10  I113  R1631
   1 HDT_HDR_DBREQ_R_N      A @T6G_MB_LIB.T6G(SCH_1):HDT_HDR_DBREQ_R_N
   2 HDT_HDR_DBREQ_N      B @T6G_MB_LIB.T6G(SCH_1):HDT_HDR_DBREQ_N

Q_RES_0402LF-33,5%,1/16W,CHIP,CS03302JB10  I114  R1632
   1 HDT_CPU0_HDT_CONN_TESTEN      A @T6G_MB_LIB.T6G(SCH_1):HDT_CPU0_HDT_CONN_TESTEN
   2 CPU0_HDT_CONN_TESTEN      B @T6G_MB_LIB.T6G(SCH_1):CPU0_HDT_CONN_TESTEN

Q_RES_0402LF-1K,1%,1/16W,CHIP,CS21002FB06  I115  R1626
   1 PVDD18_S5_P0      A @T6G_MB_LIB.T6G(SCH_1):PVDD18_S5_P0
   2 HDT_HDR_TMS      B @T6G_MB_LIB.T6G(SCH_1):HDT_HDR_TMS

Q_RES_0402LF-1K,1%,1/16W,CHIP,CS21002FB06  I116  R1627
   1 PVDD18_S5_P0      A @T6G_MB_LIB.T6G(SCH_1):PVDD18_S5_P0
   2 HDT_HDR_TDI      B @T6G_MB_LIB.T6G(SCH_1):HDT_HDR_TDI

Q_RES_0402LF-1K,1%,1/16W,CHIP,CS21002FB06  I117  R1628
   1 PVDD18_S5_P0      A @T6G_MB_LIB.T6G(SCH_1):PVDD18_S5_P0
   2 HDT_HDR_TDO      B @T6G_MB_LIB.T6G(SCH_1):HDT_HDR_TDO

Q_RES_0402LF-1K,1%,1/16W,CHIP,CS21002FB06  I118  R1630
   1 PVDD18_S5_P0      A @T6G_MB_LIB.T6G(SCH_1):PVDD18_S5_P0
   2 HDT_HDR_DBREQ_R_N      B @T6G_MB_LIB.T6G(SCH_1):HDT_HDR_DBREQ_R_N

Q_CAP_C0402-0.01UF,50V,10%,X7R,CH31006KB18  I123  C551
   1 CPU0_HDT_CONN_TESTEN      A @T6G_MB_LIB.T6G(SCH_1):CPU0_HDT_CONN_TESTEN
   2    GND      B @T6G_MB_LIB.T6G(SCH_1):GND

Q_RES_0402LF-0,5%,1/16W,CHIP,CS00002JB13  I132  R1352
   1 HDT_HDR_R_TCK      A @T6G_MB_LIB.T6G(SCH_1):HDT_HDR_R_TCK
   2 HDT_HDR_TCK      B @T6G_MB_LIB.T6G(SCH_1):HDT_HDR_TCK

Q_RES_0402LF-0,5%,1/16W,CHIP,CS00002JB13  I133  R1353
   1 HDT_HDR_R_TMS      A @T6G_MB_LIB.T6G(SCH_1):HDT_HDR_R_TMS
   2 HDT_HDR_TMS      B @T6G_MB_LIB.T6G(SCH_1):HDT_HDR_TMS

Q_CAP_C0402-0.001UF,50V,10%,X7R,CH30106KB19  I134  C87
   1 HDT_HDR_DBREQ_N      A @T6G_MB_LIB.T6G(SCH_1):HDT_HDR_DBREQ_N
   2    GND      B @T6G_MB_LIB.T6G(SCH_1):GND

Q_CAP_C0402-0.001UF,50V,10%,X7R,CH30106KB19  I137  C605
   1 HDT_HDR_TDI      A @T6G_MB_LIB.T6G(SCH_1):HDT_HDR_TDI
   2    GND      B @T6G_MB_LIB.T6G(SCH_1):GND

Q_CAP_C0402-0.001UF,50V,10%,X7R,CH30106KB19  I140  C604
   1 HDT_HDR_TCK      A @T6G_MB_LIB.T6G(SCH_1):HDT_HDR_TCK
   2    GND      B @T6G_MB_LIB.T6G(SCH_1):GND

SCONN20_HSU2101L00007H-SCONN20_HSU2101-L0000-7H,SMA  I142  J54
   1 PVDD18_S5_P0      1 @T6G_MB_LIB.T6G(SCH_1):PVDD18_S5_P0
   2 HDT_HDR_R_TCK      2 @T6G_MB_LIB.T6G(SCH_1):HDT_HDR_R_TCK
   3 PRSNT_HDT_R_N      3 @T6G_MB_LIB.T6G(SCH_1):PRSNT_HDT_R_N
   4 HDT_HDR_R_TMS      4 @T6G_MB_LIB.T6G(SCH_1):HDT_HDR_R_TMS
   5    GND      5 @T6G_MB_LIB.T6G(SCH_1):GND
   6 HDT_HDR_R_TDI      6 @T6G_MB_LIB.T6G(SCH_1):HDT_HDR_R_TDI
   7    GND      7 @T6G_MB_LIB.T6G(SCH_1):GND
   8 HDT_HDR_TDO      8 @T6G_MB_LIB.T6G(SCH_1):HDT_HDR_TDO
   9 HDT_HDR_TRST_N_R      9 @T6G_MB_LIB.T6G(SCH_1):HDT_HDR_TRST_N_R
  10 HDT_HDR_PWROK     10 @T6G_MB_LIB.T6G(SCH_1):HDT_HDR_PWROK
  11 HDT_CPU0_XTRIG_L6     11 @T6G_MB_LIB.T6G(SCH_1):HDT_CPU0_XTRIG_L6
  12 HDT_HDR_RESET_N     12 @T6G_MB_LIB.T6G(SCH_1):HDT_HDR_RESET_N
  13 HDT_CPU0_XTRIG_L7     13 @T6G_MB_LIB.T6G(SCH_1):HDT_CPU0_XTRIG_L7
  14     NC     14     NC
  15 HDT_CPU0_XTRIG_L5     15 @T6G_MB_LIB.T6G(SCH_1):HDT_CPU0_XTRIG_L5
  16 HDT_HDR_DBREQ_R_N     16 @T6G_MB_LIB.T6G(SCH_1):HDT_HDR_DBREQ_R_N
  17    GND     17 @T6G_MB_LIB.T6G(SCH_1):GND
  18 HDT_CPU0_HDT_CONN_TESTEN     18 @T6G_MB_LIB.T6G(SCH_1):HDT_CPU0_HDT_CONN_TESTEN
  19 PVDD18_S5_P0     19 @T6G_MB_LIB.T6G(SCH_1):PVDD18_S5_P0
  20     NC     20     NC

Q_RES_0402LF-1K,1%,1/16W,CHIP,CS21002FB06  I146  R1621
   1 PVDD18_S5_P0      A @T6G_MB_LIB.T6G(SCH_1):PVDD18_S5_P0
   2 HDT_HDR_TRST_N_R      B @T6G_MB_LIB.T6G(SCH_1):HDT_HDR_TRST_N_R

Q_RES_0402LF-33,5%,1/16W,CHIP,CS03302JB10  I147  R477
   1 CPU0_XTRIG_L7      A @T6G_MB_LIB.T6G(SCH_1):CPU0_XTRIG_L7
   2 HDT_CPU0_XTRIG_L7      B @T6G_MB_LIB.T6G(SCH_1):HDT_CPU0_XTRIG_L7

Q_RES_0402LF-33,5%,1/16W,CHIP,CS03302JB10  I148  R476
   1 CPU0_XTRIG_L6      A @T6G_MB_LIB.T6G(SCH_1):CPU0_XTRIG_L6
   2 HDT_CPU0_XTRIG_L6      B @T6G_MB_LIB.T6G(SCH_1):HDT_CPU0_XTRIG_L6

Q_RES_0402LF-33,5%,1/16W,CHIP,CS03302JB10  I149  R1620
   1 HDT_HDR_TRST_N      A @T6G_MB_LIB.T6G(SCH_1):HDT_HDR_TRST_N
   2 HDT_HDR_TRST_N_R      B @T6G_MB_LIB.T6G(SCH_1):HDT_HDR_TRST_N_R

Q_RES_0402LF-33,5%,1/16W,CHIP,CS03302JB10  I150  R478
   1 CPU0_XTRIG_L5      A @T6G_MB_LIB.T6G(SCH_1):CPU0_XTRIG_L5
   2 HDT_CPU0_XTRIG_L5      B @T6G_MB_LIB.T6G(SCH_1):HDT_CPU0_XTRIG_L5

Q_CAP_C0402-0.001UF,50V,10%,X7R,CH30106KB19  I152  C85
   1 HDT_HDR_TRST_N      A @T6G_MB_LIB.T6G(SCH_1):HDT_HDR_TRST_N
   2    GND      B @T6G_MB_LIB.T6G(SCH_1):GND

Q_RES_0402LF-33,5%,1/16W,CHIP,CS03302JB10  I157  R1528
   1 PRSNT_HDT_N      A @T6G_MB_LIB.T6G(SCH_1):PRSNT_HDT_N
   2 PRSNT_HDT_R_N      B @T6G_MB_LIB.T6G(SCH_1):PRSNT_HDT_R_N

Q_RES_0402LF-0,5%,1/16W,CHIP,CS00002JB13  I159  R6108
   1 HDT_HDR_TDO      A @T6G_MB_LIB.T6G(SCH_1):HDT_HDR_TDO
   2 HDT_HDR_TDO_R      B @T6G_MB_LIB.T6G(SCH_1):HDT_HDR_TDO_R

Q_RES_0402LF-0,5%,1/16W,CHIP,CS00002JB13  I160  R6111
   1 JTAG_TDO_R1      A @T6G_MB_LIB.T6G(SCH_1):JTAG_TDO_R1
   2 JTAG_TDO      B @T6G_MB_LIB.T6G(SCH_1):JTAG_TDO

Q_CAP_C0402-0.01UF,50V,10%,EMPTY,CH31006KB18  I161  C86
   1 JTAG_TDI      A @T6G_MB_LIB.T6G(SCH_1):JTAG_TDI
   2    GND      B @T6G_MB_LIB.T6G(SCH_1):GND

Q_CAP_0402-0.1UF,25V,10%,X7R,CH4104K1B00  I163  C8006
   1 JTAG_BMC_R_D_OE      A @T6G_MB_LIB.T6G(SCH_1):JTAG_BMC_R_D_OE
   2    GND      B @T6G_MB_LIB.T6G(SCH_1):GND


DRAWING: @T6G_MB_LIB.T6G(SCH_1):PAGE150 

SN74AVC4T774PWR-SN74AVC4T774PWR,SMLF,IC,AL04T774K00  I8  U150
   1 PVDD18_S5_P0   DIR1 @T6G_MB_LIB.T6G(SCH_1):PVDD18_S5_P0
   2 PVDD18_S5_P0   DIR2 @T6G_MB_LIB.T6G(SCH_1):PVDD18_S5_P0
   3 JTAG_TCK     A1 @T6G_MB_LIB.T6G(SCH_1):JTAG_TCK
   4 JTAG_TMS     A2 @T6G_MB_LIB.T6G(SCH_1):JTAG_TMS
   5 JTAG_TRST_N     A3 @T6G_MB_LIB.T6G(SCH_1):JTAG_TRST_N
   6 JTAG_DBREQ_N     A4 @T6G_MB_LIB.T6G(SCH_1):JTAG_DBREQ_N
   7 PVDD18_S5_P0   DIR3 @T6G_MB_LIB.T6G(SCH_1):PVDD18_S5_P0
   8 PVDD18_S5_P0   DIR4 @T6G_MB_LIB.T6G(SCH_1):PVDD18_S5_P0
   9 CPU0_JTAG_BUF_OE     OE @T6G_MB_LIB.T6G(SCH_1):CPU0_JTAG_BUF_OE
  10    GND    GND @T6G_MB_LIB.T6G(SCH_1):GND
  11 JTAG_P0_R_DBREQ_N     B4 @T6G_MB_LIB.T6G(SCH_1):JTAG_P0_R_DBREQ_N
  12 JTAG_P0_R_TRST_N     B3 @T6G_MB_LIB.T6G(SCH_1):JTAG_P0_R_TRST_N
  13 JTAG_P0_R_TMS     B2 @T6G_MB_LIB.T6G(SCH_1):JTAG_P0_R_TMS
  14 JTAG_P0_R_TCK     B1 @T6G_MB_LIB.T6G(SCH_1):JTAG_P0_R_TCK
  15 PVDD18_S5_P0   VCCB @T6G_MB_LIB.T6G(SCH_1):PVDD18_S5_P0
  16 PVDD18_S5_P0   VCCA @T6G_MB_LIB.T6G(SCH_1):PVDD18_S5_P0

Q_CAP_C0402-0.1UF,16V,10%,X7R,CH4103K1B08  I14  C1516
   1 PVDD18_S5_P0      A @T6G_MB_LIB.T6G(SCH_1):PVDD18_S5_P0
   2    GND      B @T6G_MB_LIB.T6G(SCH_1):GND

Q_CAP_C0402-0.1UF,16V,10%,X7R,CH4103K1B08  I19  C1514
   1 PVDD18_S5_P0      A @T6G_MB_LIB.T6G(SCH_1):PVDD18_S5_P0
   2    GND      B @T6G_MB_LIB.T6G(SCH_1):GND

Q_RES_0402LF-22,1%,1/16W,CHIP,CS02202FB02  I24  R1641
   1 JTAG_P0_R_DBREQ_N      A @T6G_MB_LIB.T6G(SCH_1):JTAG_P0_R_DBREQ_N
   2 JTAG_CPU0_DBREQ_N      B @T6G_MB_LIB.T6G(SCH_1):JTAG_CPU0_DBREQ_N

Q_RES_0402LF-22,1%,1/16W,CHIP,CS02202FB02  I25  R1639
   1 JTAG_P0_R_TMS      A @T6G_MB_LIB.T6G(SCH_1):JTAG_P0_R_TMS
   2 JTAG_CPU0_TMS      B @T6G_MB_LIB.T6G(SCH_1):JTAG_CPU0_TMS

Q_RES_0402LF-22,1%,1/16W,CHIP,CS02202FB02  I26  R1640
   1 JTAG_P0_R_TRST_N      A @T6G_MB_LIB.T6G(SCH_1):JTAG_P0_R_TRST_N
   2 JTAG_CPU0_TRST_N      B @T6G_MB_LIB.T6G(SCH_1):JTAG_CPU0_TRST_N

Q_RES_0402LF-22,1%,1/16W,CHIP,CS02202FB02  I27  R1638
   1 JTAG_P0_R_TCK      A @T6G_MB_LIB.T6G(SCH_1):JTAG_P0_R_TCK
   2 JTAG_CPU0_TCK      B @T6G_MB_LIB.T6G(SCH_1):JTAG_CPU0_TCK

SN74AVC4T774PWR-SN74AVC4T774PWR,SMLF,IC,AL04T774K00  I28  U151
   1 PVDD18_S5_P0   DIR1 @T6G_MB_LIB.T6G(SCH_1):PVDD18_S5_P0
   2 PVDD18_S5_P0   DIR2 @T6G_MB_LIB.T6G(SCH_1):PVDD18_S5_P0
   3 JTAG_TCK     A1 @T6G_MB_LIB.T6G(SCH_1):JTAG_TCK
   4 JTAG_TMS     A2 @T6G_MB_LIB.T6G(SCH_1):JTAG_TMS
   5 JTAG_TRST_N     A3 @T6G_MB_LIB.T6G(SCH_1):JTAG_TRST_N
   6 JTAG_DBREQ_N     A4 @T6G_MB_LIB.T6G(SCH_1):JTAG_DBREQ_N
   7 PVDD18_S5_P0   DIR3 @T6G_MB_LIB.T6G(SCH_1):PVDD18_S5_P0
   8 PVDD18_S5_P0   DIR4 @T6G_MB_LIB.T6G(SCH_1):PVDD18_S5_P0
   9 CPU1_JTAG_BUF_OE     OE @T6G_MB_LIB.T6G(SCH_1):CPU1_JTAG_BUF_OE
  10    GND    GND @T6G_MB_LIB.T6G(SCH_1):GND
  11 JTAG_P1_R_DBREQ_N     B4 @T6G_MB_LIB.T6G(SCH_1):JTAG_P1_R_DBREQ_N
  12 JTAG_P1_R_TRST_N     B3 @T6G_MB_LIB.T6G(SCH_1):JTAG_P1_R_TRST_N
  13 JTAG_P1_R_TMS     B2 @T6G_MB_LIB.T6G(SCH_1):JTAG_P1_R_TMS
  14 JTAG_P1_R_TCK     B1 @T6G_MB_LIB.T6G(SCH_1):JTAG_P1_R_TCK
  15 PVDD18_S5_P1   VCCB @T6G_MB_LIB.T6G(SCH_1):PVDD18_S5_P1
  16 PVDD18_S5_P0   VCCA @T6G_MB_LIB.T6G(SCH_1):PVDD18_S5_P0

Q_RES_0402LF-22,1%,1/16W,CHIP,CS02202FB02  I33  R1642
   1 JTAG_P1_R_TCK      A @T6G_MB_LIB.T6G(SCH_1):JTAG_P1_R_TCK
   2 JTAG_CPU1_TCK      B @T6G_MB_LIB.T6G(SCH_1):JTAG_CPU1_TCK

Q_RES_0402LF-22,1%,1/16W,CHIP,CS02202FB02  I34  R1643
   1 JTAG_P1_R_TMS      A @T6G_MB_LIB.T6G(SCH_1):JTAG_P1_R_TMS
   2 JTAG_CPU1_TMS      B @T6G_MB_LIB.T6G(SCH_1):JTAG_CPU1_TMS

Q_RES_0402LF-22,1%,1/16W,CHIP,CS02202FB02  I35  R1644
   1 JTAG_P1_R_TRST_N      A @T6G_MB_LIB.T6G(SCH_1):JTAG_P1_R_TRST_N
   2 JTAG_CPU1_TRST_N      B @T6G_MB_LIB.T6G(SCH_1):JTAG_CPU1_TRST_N

Q_RES_0402LF-22,1%,1/16W,CHIP,CS02202FB02  I36  R1645
   1 JTAG_P1_R_DBREQ_N      A @T6G_MB_LIB.T6G(SCH_1):JTAG_P1_R_DBREQ_N
   2 JTAG_CPU1_DBREQ_N      B @T6G_MB_LIB.T6G(SCH_1):JTAG_CPU1_DBREQ_N

Q_CAP_C0402-0.1UF,16V,10%,X7R,CH4103K1B08  I40  C1517
   1 PVDD18_S5_P1      A @T6G_MB_LIB.T6G(SCH_1):PVDD18_S5_P1
   2    GND      B @T6G_MB_LIB.T6G(SCH_1):GND

Q_CAP_C0402-0.1UF,16V,10%,X7R,CH4103K1B08  I43  C1515
   1 PVDD18_S5_P0      A @T6G_MB_LIB.T6G(SCH_1):PVDD18_S5_P0
   2    GND      B @T6G_MB_LIB.T6G(SCH_1):GND

SN74AVC2T245RSWR-SN74AVC2T245RSWR,SMLF,IC,AL02T245A  I60  U152
   1    GND   DIR2 @T6G_MB_LIB.T6G(SCH_1):GND
   2 U152_OE_N   OE_# @T6G_MB_LIB.T6G(SCH_1):U152_OE_N
   3    GND    GND @T6G_MB_LIB.T6G(SCH_1):GND
   4 JTAG_CPUX_TDO     B2 @T6G_MB_LIB.T6G(SCH_1):JTAG_CPUX_TDO
   5 JTAG_CPUX_TDI_R1     B1 @T6G_MB_LIB.T6G(SCH_1):JTAG_CPUX_TDI_R1
   6 PVDD18_S5_P0   VCCB @T6G_MB_LIB.T6G(SCH_1):PVDD18_S5_P0
   7 PVDD18_S5_P0   VCCA @T6G_MB_LIB.T6G(SCH_1):PVDD18_S5_P0
   8 JTAG_TDI     A1 @T6G_MB_LIB.T6G(SCH_1):JTAG_TDI
   9 JTAG_TDO_R     A2 @T6G_MB_LIB.T6G(SCH_1):JTAG_TDO_R
  10 PVDD18_S5_P0   DIR1 @T6G_MB_LIB.T6G(SCH_1):PVDD18_S5_P0

Q_CAP_C0402-0.1UF,16V,10%,X7R,CH4103K1B08  I66  C1518
   1 PVDD18_S5_P0      A @T6G_MB_LIB.T6G(SCH_1):PVDD18_S5_P0
   2    GND      B @T6G_MB_LIB.T6G(SCH_1):GND

Q_CAP_C0402-0.1UF,16V,10%,X7R,CH4103K1B08  I69  C1513
   1 PVDD18_S5_P0      A @T6G_MB_LIB.T6G(SCH_1):PVDD18_S5_P0
   2    GND      B @T6G_MB_LIB.T6G(SCH_1):GND

Q_RES_0402LF-4.7K,5%,1/16W,CHIP,CS24702JB10  I71  R1637
   1 U152_OE_N      A @T6G_MB_LIB.T6G(SCH_1):U152_OE_N
   2    GND      B @T6G_MB_LIB.T6G(SCH_1):GND

Q_RES_0402LF-0,5%,1/16W,CHIP,CS00002JB13  I76  R6103
   1 JTAG_CPUX_TDI_R1      A @T6G_MB_LIB.T6G(SCH_1):JTAG_CPUX_TDI_R1
   2 JTAG_CPUX_TDI      B @T6G_MB_LIB.T6G(SCH_1):JTAG_CPUX_TDI

Q_RES_0402LF-0,5%,1/16W,CHIP,CS00002JB13  I78  R6109
   1 JTAG_TDO      A @T6G_MB_LIB.T6G(SCH_1):JTAG_TDO
   2 JTAG_TDO_R      B @T6G_MB_LIB.T6G(SCH_1):JTAG_TDO_R


DRAWING: @T6G_MB_LIB.T6G(SCH_1):PAGE151 

SN74AUC2G66DCTR-SN74AUC2G66DCTR,SMLF,IC,AL2G0066C00  I1  U153
   1 JTAG_CPUX_TDI     1A @T6G_MB_LIB.T6G(SCH_1):JTAG_CPUX_TDI
   7 CPU0_HDT_BYPASS_SEL     1C @T6G_MB_LIB.T6G(SCH_1):CPU0_HDT_BYPASS_SEL
   5 JTAG_CPUX_TDI     2A @T6G_MB_LIB.T6G(SCH_1):JTAG_CPUX_TDI
   3 FM_PLD_CPU0_PRSNT_HDT_N     2C @T6G_MB_LIB.T6G(SCH_1):FM_PLD_CPU0_PRSNT_HDT_N
   8 PVDD18_S5_P0    VCC @T6G_MB_LIB.T6G(SCH_1):PVDD18_S5_P0
   4    GND    GND @T6G_MB_LIB.T6G(SCH_1):GND
   2 JTAG_CPU0_R_TDI     1B @T6G_MB_LIB.T6G(SCH_1):JTAG_CPU0_R_TDI
   6 JTAG_CPU0_BYPASS     2B @T6G_MB_LIB.T6G(SCH_1):JTAG_CPU0_BYPASS

Q_RES_0402LF-0,5%,1/16W,CHIP,CS00002JB13  I2  R1648
   1 JTAG_CPU0_R_TDI      A @T6G_MB_LIB.T6G(SCH_1):JTAG_CPU0_R_TDI
   2 JTAG_CPU0_TDI      B @T6G_MB_LIB.T6G(SCH_1):JTAG_CPU0_TDI

Q_CAP_C0402-0.01UF,50V,10%,EMPTY,CH31006KB18  I4  C1520
   1 JTAG_CPU0_TDI      A @T6G_MB_LIB.T6G(SCH_1):JTAG_CPU0_TDI
   2    GND      B @T6G_MB_LIB.T6G(SCH_1):GND

Q_RES_0402LF-1K,1%,1/16W,CHIP,CS21002FB06  I10  R1646
   1 PVDD18_S5_P0      A @T6G_MB_LIB.T6G(SCH_1):PVDD18_S5_P0
   2 CPU0_HDT_BYPASS_SEL      B @T6G_MB_LIB.T6G(SCH_1):CPU0_HDT_BYPASS_SEL

Q_RES_0402LF-1K,1%,1/16W,CHIP,CS21002FB06  I11  R1647
   1 PVDD18_S5_P0      A @T6G_MB_LIB.T6G(SCH_1):PVDD18_S5_P0
   2 FM_PLD_CPU0_PRSNT_HDT_N      B @T6G_MB_LIB.T6G(SCH_1):FM_PLD_CPU0_PRSNT_HDT_N

Q_CAP_C0402-0.1UF,16V,10%,X7R,CH4103K1B08  I15  C1519
   1 PVDD18_S5_P0      A @T6G_MB_LIB.T6G(SCH_1):PVDD18_S5_P0
   2    GND      B @T6G_MB_LIB.T6G(SCH_1):GND

SN74AUC2G66DCTR-SN74AUC2G66DCTR,SMLF,IC,AL2G0066C00  I17  U13
   1 JTAG_CPU0_TDO     1A @T6G_MB_LIB.T6G(SCH_1):JTAG_CPU0_TDO
   7 CPU0_HDT_BYPASS_SEL     1C @T6G_MB_LIB.T6G(SCH_1):CPU0_HDT_BYPASS_SEL
   5 JTAG_CPU0_BYPASS_R1     2A @T6G_MB_LIB.T6G(SCH_1):JTAG_CPU0_BYPASS_R1
   3 FM_PLD_CPU0_PRSNT_HDT_N     2C @T6G_MB_LIB.T6G(SCH_1):FM_PLD_CPU0_PRSNT_HDT_N
   8 PVDD18_S5_P0    VCC @T6G_MB_LIB.T6G(SCH_1):PVDD18_S5_P0
   4    GND    GND @T6G_MB_LIB.T6G(SCH_1):GND
   2 JTAG_CPU0_TDO_CPU1_TDI     1B @T6G_MB_LIB.T6G(SCH_1):JTAG_CPU0_TDO_CPU1_TDI
   6 JTAG_CPU0_TDO_CPU1_TDI_R1     2B @T6G_MB_LIB.T6G(SCH_1):JTAG_CPU0_TDO_CPU1_TDI_R1

Q_CAP_C0402-0.1UF,16V,10%,X7R,CH4103K1B08  I22  C1521
   1 PVDD18_S5_P0      A @T6G_MB_LIB.T6G(SCH_1):PVDD18_S5_P0
   2    GND      B @T6G_MB_LIB.T6G(SCH_1):GND

SN74AUC2G66DCTR-SN74AUC2G66DCTR,SMLF,IC,AL2G0066C00  I23  U14
   1 JTAG_CPU0_TDO_CPU1_TDI     1A @T6G_MB_LIB.T6G(SCH_1):JTAG_CPU0_TDO_CPU1_TDI
   7 CPU1_HDT_BYPASS_SEL     1C @T6G_MB_LIB.T6G(SCH_1):CPU1_HDT_BYPASS_SEL
   5 JTAG_CPU0_TDO_CPU1_TDI     2A @T6G_MB_LIB.T6G(SCH_1):JTAG_CPU0_TDO_CPU1_TDI
   3 FM_PLD_CPU1_PRSNT_HDT_N     2C @T6G_MB_LIB.T6G(SCH_1):FM_PLD_CPU1_PRSNT_HDT_N
   8 PVDD18_S5_P0    VCC @T6G_MB_LIB.T6G(SCH_1):PVDD18_S5_P0
   4    GND    GND @T6G_MB_LIB.T6G(SCH_1):GND
   2 JTAG_CPU1_R_TDI     1B @T6G_MB_LIB.T6G(SCH_1):JTAG_CPU1_R_TDI
   6 JTAG_CPU1_BYPASS     2B @T6G_MB_LIB.T6G(SCH_1):JTAG_CPU1_BYPASS

Q_RES_0402LF-1K,1%,1/16W,CHIP,CS21002FB06  I25  R1649
   1 PVDD18_S5_P0      A @T6G_MB_LIB.T6G(SCH_1):PVDD18_S5_P0
   2 CPU1_HDT_BYPASS_SEL      B @T6G_MB_LIB.T6G(SCH_1):CPU1_HDT_BYPASS_SEL

Q_RES_0402LF-1K,1%,1/16W,CHIP,CS21002FB06  I27  R1650
   1 PVDD18_S5_P0      A @T6G_MB_LIB.T6G(SCH_1):PVDD18_S5_P0
   2 FM_PLD_CPU1_PRSNT_HDT_N      B @T6G_MB_LIB.T6G(SCH_1):FM_PLD_CPU1_PRSNT_HDT_N

SN74AUC2G66DCTR-SN74AUC2G66DCTR,SMLF,IC,AL2G0066C00  I31  U154
   1 JTAG_CPU1_TDO     1A @T6G_MB_LIB.T6G(SCH_1):JTAG_CPU1_TDO
   7 CPU1_HDT_BYPASS_SEL     1C @T6G_MB_LIB.T6G(SCH_1):CPU1_HDT_BYPASS_SEL
   5 JTAG_CPU1_BYPASS     2A @T6G_MB_LIB.T6G(SCH_1):JTAG_CPU1_BYPASS
   3 FM_PLD_CPU1_PRSNT_HDT_N     2C @T6G_MB_LIB.T6G(SCH_1):FM_PLD_CPU1_PRSNT_HDT_N
   8 PVDD18_S5_P0    VCC @T6G_MB_LIB.T6G(SCH_1):PVDD18_S5_P0
   4    GND    GND @T6G_MB_LIB.T6G(SCH_1):GND
   2 JTAG_CPUX_TDO_R     1B @T6G_MB_LIB.T6G(SCH_1):JTAG_CPUX_TDO_R
   6 JTAG_CPUX_TDO_R     2B @T6G_MB_LIB.T6G(SCH_1):JTAG_CPUX_TDO_R

Q_RES_0402LF-0,5%,1/16W,CHIP,CS00002JB13  I34  R1651
   1 JTAG_CPU1_R_TDI      A @T6G_MB_LIB.T6G(SCH_1):JTAG_CPU1_R_TDI
   2 JTAG_CPU1_TDI      B @T6G_MB_LIB.T6G(SCH_1):JTAG_CPU1_TDI

Q_CAP_C0402-0.1UF,16V,10%,X7R,CH4103K1B08  I36  C1522
   1 PVDD18_S5_P0      A @T6G_MB_LIB.T6G(SCH_1):PVDD18_S5_P0
   2    GND      B @T6G_MB_LIB.T6G(SCH_1):GND

Q_CAP_C0402-0.1UF,16V,10%,X7R,CH4103K1B08  I42  C1523
   1 PVDD18_S5_P0      A @T6G_MB_LIB.T6G(SCH_1):PVDD18_S5_P0
   2    GND      B @T6G_MB_LIB.T6G(SCH_1):GND

MOSFET_N_SMLF-BSS138K,BSS138K,IC,BAM138K0000  I45  Q63
   G CPU0_HDT_BYPASS_SEL   GATE @T6G_MB_LIB.T6G(SCH_1):CPU0_HDT_BYPASS_SEL
   D FM_PLD_CPU0_PRSNT_HDT_N  DRAIN @T6G_MB_LIB.T6G(SCH_1):FM_PLD_CPU0_PRSNT_HDT_N
   S    GND SOURCE @T6G_MB_LIB.T6G(SCH_1):GND

MOSFET_N_SMLF-BSS138K,BSS138K,IC,BAM138K0000  I46  Q64
   G CPU1_HDT_BYPASS_SEL   GATE @T6G_MB_LIB.T6G(SCH_1):CPU1_HDT_BYPASS_SEL
   D FM_PLD_CPU1_PRSNT_HDT_N  DRAIN @T6G_MB_LIB.T6G(SCH_1):FM_PLD_CPU1_PRSNT_HDT_N
   S    GND SOURCE @T6G_MB_LIB.T6G(SCH_1):GND

Q_RES_0402LF-0,5%,1/16W,CHIP,CS00002JB13  I48  R6104
   1 JTAG_CPU0_BYPASS      A @T6G_MB_LIB.T6G(SCH_1):JTAG_CPU0_BYPASS
   2 JTAG_CPU0_BYPASS_R1      B @T6G_MB_LIB.T6G(SCH_1):JTAG_CPU0_BYPASS_R1

Q_RES_0402LF-0,5%,1/16W,CHIP,CS00002JB13  I49  R6105
   1 JTAG_CPU0_TDO_CPU1_TDI_R1      A @T6G_MB_LIB.T6G(SCH_1):JTAG_CPU0_TDO_CPU1_TDI_R1
   2 JTAG_CPU0_TDO_CPU1_TDI      B @T6G_MB_LIB.T6G(SCH_1):JTAG_CPU0_TDO_CPU1_TDI

Q_RES_0402LF-0,5%,1/16W,CHIP,CS00002JB13  I50  R6110
   1 JTAG_CPUX_TDO_R      A @T6G_MB_LIB.T6G(SCH_1):JTAG_CPUX_TDO_R
   2 JTAG_CPUX_TDO      B @T6G_MB_LIB.T6G(SCH_1):JTAG_CPUX_TDO


DRAWING: @T6G_MB_LIB.T6G(SCH_1):PAGE142 

Q_LED_SMLF-LED_BLUE,LTST-C281TBKT-5A,IC,BEBL0172Z00  I79  D9
   A LED_BIOS_DBG_MODE_R      A @T6G_MB_LIB.T6G(SCH_1):LED_BIOS_DBG_MODE_R
   C LED_BIOS_DBG_MODE      C @T6G_MB_LIB.T6G(SCH_1):LED_BIOS_DBG_MODE

MOSFET_N_GSD-NX138BK,SMLF,IC,BAM01380023  I80  Q29
   G LED_BIOS_DBG_MODE_N   GATE @T6G_MB_LIB.T6G(SCH_1):LED_BIOS_DBG_MODE_N
   S    GND SOURCE @T6G_MB_LIB.T6G(SCH_1):GND
   D LED_BIOS_DBG_MODE  DRAIN @T6G_MB_LIB.T6G(SCH_1):LED_BIOS_DBG_MODE

MOSFET_N_GSD-NX138BK,SMLF,IC,BAM01380023  I81  Q30
   G BIOS_DEBUG_MODE   GATE @T6G_MB_LIB.T6G(SCH_1):BIOS_DEBUG_MODE
   S    GND SOURCE @T6G_MB_LIB.T6G(SCH_1):GND
   D LED_BIOS_DBG_MODE_N  DRAIN @T6G_MB_LIB.T6G(SCH_1):LED_BIOS_DBG_MODE_N

Q_RES_0402LF-130,1%,1/16W,CHIP,CS11302FB03  I82  R1444
   1 P3V3_AUX      A @T6G_MB_LIB.T6G(SCH_1):P3V3_AUX
   2 LED_BIOS_DBG_MODE_R      B @T6G_MB_LIB.T6G(SCH_1):LED_BIOS_DBG_MODE_R

Q_RES_0402LF-1K,1%,1/16W,CHIP,CS21002FB06  I87  R1507
   1 P3V3_AUX      A @T6G_MB_LIB.T6G(SCH_1):P3V3_AUX
   2 LED_BIOS_DBG_MODE_N      B @T6G_MB_LIB.T6G(SCH_1):LED_BIOS_DBG_MODE_N


DRAWING: @T6G_MB_LIB.T6G(SCH_1):PAGE84 

Q_RES_0402LF-0,5%,1/16W,CHIP,CS00002JB13  I36  R14
   1 JTAG_PLD_TMS      A @T6G_MB_LIB.T6G(SCH_1):JTAG_PLD_TMS
   2 JTAG_SCM_PLD_TMS      B @T6G_MB_LIB.T6G(SCH_1):JTAG_SCM_PLD_TMS

Q_RES_0402LF-1K,1%,1/16W,CHIP,CS21002FB06  I5  R1303
   1 FM_SMB_RST_E1S_0_N      A @T6G_MB_LIB.T6G(SCH_1):FM_SMB_RST_E1S_0_N
   2 P3V3_AUX      B @T6G_MB_LIB.T6G(SCH_1):P3V3_AUX

Q_RES_0402LF-0,5%,1/16W,CHIP,CS00002JB13  I37  R9
   1 JTAG_PLD_TDI      A @T6G_MB_LIB.T6G(SCH_1):JTAG_PLD_TDI
   2 JTAG_SCM_PLD_TDI      B @T6G_MB_LIB.T6G(SCH_1):JTAG_SCM_PLD_TDI

Q_RES_0402LF-0,5%,1/16W,CHIP,CS00002JB13  I38  R13
   1 JTAG_PLD_TDO      A @T6G_MB_LIB.T6G(SCH_1):JTAG_PLD_TDO
   2 JTAG_SCM_PLD_TDO      B @T6G_MB_LIB.T6G(SCH_1):JTAG_SCM_PLD_TDO

CONN8_HBB1081L200D8H-CONN8_HBB1081-L200D-8H,THLF,IA  I41  J57
   1 P3V3_AUX      1 @T6G_MB_LIB.T6G(SCH_1):P3V3_AUX
   2 JTAG_PLD_TDI      2 @T6G_MB_LIB.T6G(SCH_1):JTAG_PLD_TDI
   3 JTAG_PLD_TDO      3 @T6G_MB_LIB.T6G(SCH_1):JTAG_PLD_TDO
   4     NC      4     NC
   5     NC      5     NC
   6 JTAG_PLD_TMS      6 @T6G_MB_LIB.T6G(SCH_1):JTAG_PLD_TMS
   7    GND      7 @T6G_MB_LIB.T6G(SCH_1):GND
   8 JTAG_PLD_TCK      8 @T6G_MB_LIB.T6G(SCH_1):JTAG_PLD_TCK

Q_CAP_C0402-0.1UF,16V,10%,X7R,CH4103K1B08  I42  C20
   1 P3V3_AUX      A @T6G_MB_LIB.T6G(SCH_1):P3V3_AUX
   2    GND      B @T6G_MB_LIB.T6G(SCH_1):GND

Q_RES_0402LF-0,5%,1/16W,CHIP,CS00002JB13  I6  R1036
   1 FM_SMB_RST_E1S_0_N      A @T6G_MB_LIB.T6G(SCH_1):FM_SMB_RST_E1S_0_N
   2 FM_SMB_RST_E1S_0_R_N      B @T6G_MB_LIB.T6G(SCH_1):FM_SMB_RST_E1S_0_R_N

Q_RES_0402LF-0,5%,1/16W,CHIP,CS00002JB13  I27  R530
   1 RST_CPU0_RESETL_N      A @T6G_MB_LIB.T6G(SCH_1):RST_CPU0_RESETL_N
   2 RST_CPU1_RESETL_N      B @T6G_MB_LIB.T6G(SCH_1):RST_CPU1_RESETL_N

Q_RES_0402LF-0,5%,1/16W,CHIP,CS00002JB13  I35  R15
   1 JTAG_PLD_TCK      A @T6G_MB_LIB.T6G(SCH_1):JTAG_PLD_TCK
   2 JTAG_SCM_PLD_TCK      B @T6G_MB_LIB.T6G(SCH_1):JTAG_SCM_PLD_TCK

Q_RES_0402LF-200,1%,1/16W,CHIP,CS12002FB06  I45  R1266
   1 P3V3_AUX      A @T6G_MB_LIB.T6G(SCH_1):P3V3_AUX
   2 BMC_FPGA_LED1_R_N      B @T6G_MB_LIB.T6G(SCH_1):BMC_FPGA_LED1_R_N

Q_RES_0402LF-200,1%,1/16W,CHIP,CS12002FB06  I46  R1194
   1 P3V3_AUX      A @T6G_MB_LIB.T6G(SCH_1):P3V3_AUX
   2 BMC_FPGA_LED2_R_N      B @T6G_MB_LIB.T6G(SCH_1):BMC_FPGA_LED2_R_N

MOSFET_DUAL_6P-2N7002KDW,SMLF,IC,BAM70020047  I48  Q28
   2 BMC_FPGA_LED1     G1 @T6G_MB_LIB.T6G(SCH_1):BMC_FPGA_LED1
   5 BMC_FPGA_LED2     G2 @T6G_MB_LIB.T6G(SCH_1):BMC_FPGA_LED2
   1    GND     S1 @T6G_MB_LIB.T6G(SCH_1):GND
   4    GND     S2 @T6G_MB_LIB.T6G(SCH_1):GND
   6 BMC_FPGA_LED1_N     D1 @T6G_MB_LIB.T6G(SCH_1):BMC_FPGA_LED1_N
   3 BMC_FPGA_LED2_N     D2 @T6G_MB_LIB.T6G(SCH_1):BMC_FPGA_LED2_N

Q_RES_0402LF-0,5%,1/16W,CHIP,CS00002JB13  I53  R6074
   1 FM_THERMAL_ALERT_N      A @T6G_MB_LIB.T6G(SCH_1):FM_THERMAL_ALERT_N
   2 FM_THERMAL_ALERT_R_N      B @T6G_MB_LIB.T6G(SCH_1):FM_THERMAL_ALERT_R_N

Q_RES_0402LF-0,5%,1/16W,CHIP,CS00002JB13  I57  R6075
   1 LED_HDD_ACTIVITY_B_N      A @T6G_MB_LIB.T6G(SCH_1):LED_HDD_ACTIVITY_B_N
   2 LED_HDD_ACTIVITY_B_PLD_N      B @T6G_MB_LIB.T6G(SCH_1):LED_HDD_ACTIVITY_B_PLD_N

Q_RES_0402LF-0,5%,1/16W,CHIP,CS00002JB13  I61  R6078
   1 PWRGD_P3V3_AUX      A @T6G_MB_LIB.T6G(SCH_1):PWRGD_P3V3_AUX
   2 PWRGD_P3V3_AUX_PDB      B @T6G_MB_LIB.T6G(SCH_1):PWRGD_P3V3_AUX_PDB

Q_RES_0402LF-10K,1%,1/16W,EMPTY,CS31002FB08  I63  R2343
   1 P5V_AUX_VCC      A @T6G_MB_LIB.T6G(SCH_1):P5V_AUX_VCC
   2 PWRGD_P5V_AUX      B @T6G_MB_LIB.T6G(SCH_1):PWRGD_P5V_AUX

MOSFET_NCH_DUAL-PJT138K,SMLF,IC,BAM138K0003  I65  Q50
   1    GND     S1 @T6G_MB_LIB.T6G(SCH_1):GND
   2 PWRGD_P5V_AUX     G1 @T6G_MB_LIB.T6G(SCH_1):PWRGD_P5V_AUX
   6 PWRGD_P5V_AUX_R1     D1 @T6G_MB_LIB.T6G(SCH_1):PWRGD_P5V_AUX_R1

Q_RES_0402LF-4.7K,5%,1/16W,CHIP,CS24702JB10  I67  R2344
   1 P3V3_AUX      A @T6G_MB_LIB.T6G(SCH_1):P3V3_AUX
   2 PWRGD_P5V_AUX_R1      B @T6G_MB_LIB.T6G(SCH_1):PWRGD_P5V_AUX_R1

Q_RES_0402LF-100K,1%,1/16W,CHIP,CS41002FB09  I70  R2346
   1 P3V3_AUX      A @T6G_MB_LIB.T6G(SCH_1):P3V3_AUX
   2 PWRGD_P5V_AUX_R2      B @T6G_MB_LIB.T6G(SCH_1):PWRGD_P5V_AUX_R2

MOSFET_NCH_DUAL-PJT138K,SMLF,IC,BAM138K0003  I73  Q50
   3 PWRGD_P5V_AUX_R2     D2 @T6G_MB_LIB.T6G(SCH_1):PWRGD_P5V_AUX_R2
   5 PWRGD_P5V_AUX_R1     G2 @T6G_MB_LIB.T6G(SCH_1):PWRGD_P5V_AUX_R1
   4    GND     S2 @T6G_MB_LIB.T6G(SCH_1):GND

Q_RES_0402LF-33.2,1%,1/16W,CHIP,CS03322FB03  I75  R6113
   1 RST_PERST_CPU1_SWB_N      A @T6G_MB_LIB.T6G(SCH_1):RST_PERST_CPU1_SWB_N
   2 RST_PERST_CPU1_SWB_R_N      B @T6G_MB_LIB.T6G(SCH_1):RST_PERST_CPU1_SWB_R_N

Q_RES_0402LF-4.7K,5%,1/16W,CHIP,CS24702JB10  I77  R6090
   1 JTAG_SCM_PLD_TCK      A @T6G_MB_LIB.T6G(SCH_1):JTAG_SCM_PLD_TCK
   2    GND      B @T6G_MB_LIB.T6G(SCH_1):GND

Q_RES_0402LF-0,5%,1/16W,CHIP,CS00002JB13  I82  R6092
   1 SCM_SYS_PWROK_R      A @T6G_MB_LIB.T6G(SCH_1):SCM_SYS_PWROK_R
   2 SCM_SYS_PWROK_R1      B @T6G_MB_LIB.T6G(SCH_1):SCM_SYS_PWROK_R1

Q_RES_0402LF-0,5%,1/16W,CHIP,CS00002JB13  I84  R6093
   1 SCM_SYS_PWROK_R      A @T6G_MB_LIB.T6G(SCH_1):SCM_SYS_PWROK_R
   2 SCM_SYS_PWROK_R2      B @T6G_MB_LIB.T6G(SCH_1):SCM_SYS_PWROK_R2

Q_CAP_0402-100PF,50V,5%,NPO,CH11006JB00  I88  C1209
   1 SCM_SYS_PWROK_R2      A @T6G_MB_LIB.T6G(SCH_1):SCM_SYS_PWROK_R2
   2    GND      B @T6G_MB_LIB.T6G(SCH_1):GND

Q_RES_0402LF-33.2,1%,1/16W,CHIP,CS03322FB03  I91  R6112
   1 RST_PERST_CPU0_SWB_N      A @T6G_MB_LIB.T6G(SCH_1):RST_PERST_CPU0_SWB_N
   2 RST_PERST_CPU0_SWB_R_N      B @T6G_MB_LIB.T6G(SCH_1):RST_PERST_CPU0_SWB_R_N

Q_RES_0402LF-33.2,1%,1/16W,CHIP,CS03322FB03  I94  R2
   1 RST_PERST_CPU1_SWB_1_N      A @T6G_MB_LIB.T6G(SCH_1):RST_PERST_CPU1_SWB_1_N
   2 RST_PERST_CPU1_SWB_1_R_N      B @T6G_MB_LIB.T6G(SCH_1):RST_PERST_CPU1_SWB_1_R_N

Q_LED_SMLF-LED_YELLOW,LTST-C190KSKT-P,IC,BEYL0159ZA  I96  D7
   A BMC_FPGA_LED2_R_N      A @T6G_MB_LIB.T6G(SCH_1):BMC_FPGA_LED2_R_N
   C BMC_FPGA_LED2_N      C @T6G_MB_LIB.T6G(SCH_1):BMC_FPGA_LED2_N

Q_LED_SMLF-LED_YELLOW,LTST-C190KSKT-P,IC,BEYL0159ZA  I97  D8
   A BMC_FPGA_LED1_R_N      A @T6G_MB_LIB.T6G(SCH_1):BMC_FPGA_LED1_R_N
   C BMC_FPGA_LED1_N      C @T6G_MB_LIB.T6G(SCH_1):BMC_FPGA_LED1_N

Q_CAP_0402-0.1UF,25V,10%,X7R,CH4104K1B00  I101  C8005
   1 PWRGD_P5V_AUX_R3      A @T6G_MB_LIB.T6G(SCH_1):PWRGD_P5V_AUX_R3
   2    GND      B @T6G_MB_LIB.T6G(SCH_1):GND

Q_RES_0402LF-0,5%,1/16W,CHIP,CS00002JB13  I103  R6118
   1 PWRGD_P5V_AUX_R3      A @T6G_MB_LIB.T6G(SCH_1):PWRGD_P5V_AUX_R3
   2 PWRGD_P5V_AUX_R2      B @T6G_MB_LIB.T6G(SCH_1):PWRGD_P5V_AUX_R2

Q_RES_0402LF-100,1%,1/16W,CHIP,CS11002FB07  I104  R1422
   1 PWRGD_CPU0_PWROK      A @T6G_MB_LIB.T6G(SCH_1):PWRGD_CPU0_PWROK
   2 PWRGD_CPU1_PWROK      B @T6G_MB_LIB.T6G(SCH_1):PWRGD_CPU1_PWROK

Q_RES_0402LF-100K,1%,1/16W,EMPTY,CS41002FB09  I106  R9025
   1 IRQ_HSC_FAULT_N      A @T6G_MB_LIB.T6G(SCH_1):IRQ_HSC_FAULT_N
   2    GND      B @T6G_MB_LIB.T6G(SCH_1):GND

MOSFET_NCH_DUAL-PJT138K,SMLF,IC,BAM138K0003  I111  Q9003
   1    GND     S1 @T6G_MB_LIB.T6G(SCH_1):GND
   2 IRQ_HSC_FAULT_N     G1 @T6G_MB_LIB.T6G(SCH_1):IRQ_HSC_FAULT_N
   6 IRQ_HSC_FAULT     D1 @T6G_MB_LIB.T6G(SCH_1):IRQ_HSC_FAULT

Q_RES_0402LF-4.7K,5%,1/16W,CHIP,CS24702JB10  I112  R9026
   1 P3V3_AUX      A @T6G_MB_LIB.T6G(SCH_1):P3V3_AUX
   2 IRQ_HSC_FAULT      B @T6G_MB_LIB.T6G(SCH_1):IRQ_HSC_FAULT

Q_RES_0402LF-100K,1%,1/16W,CHIP,CS41002FB09  I114  R9027
   1 P3V3_AUX      A @T6G_MB_LIB.T6G(SCH_1):P3V3_AUX
   2 IRQ_HSC_FAULT_BUF_N      B @T6G_MB_LIB.T6G(SCH_1):IRQ_HSC_FAULT_BUF_N

Q_CAP_0402-0.1UF,25V,10%,X7R,CH4104K1B00  I116  C9005
   1 IRQ_HSC_FAULT_BUF_N      A @T6G_MB_LIB.T6G(SCH_1):IRQ_HSC_FAULT_BUF_N
   2    GND      B @T6G_MB_LIB.T6G(SCH_1):GND

Q_RES_0402LF-0,5%,1/16W,EMPTY,CS00002JB13  I118  R9028
   1 IRQ_HSC_FAULT_N      A @T6G_MB_LIB.T6G(SCH_1):IRQ_HSC_FAULT_N
   2 IRQ_HSC_FAULT_BUF_N      B @T6G_MB_LIB.T6G(SCH_1):IRQ_HSC_FAULT_BUF_N

MOSFET_NCH_DUAL-PJT138K,SMLF,IC,BAM138K0003  I121  Q9003
   3 IRQ_HSC_FAULT_BUF_N     D2 @T6G_MB_LIB.T6G(SCH_1):IRQ_HSC_FAULT_BUF_N
   5 IRQ_HSC_FAULT     G2 @T6G_MB_LIB.T6G(SCH_1):IRQ_HSC_FAULT
   4    GND     S2 @T6G_MB_LIB.T6G(SCH_1):GND


DRAWING: @T6G_MB_LIB.T6G(SCH_1):PAGE201 

Q_CAP_0402-0.1UF,25V,10%,X7R,CH4104K1B00  I3  PC6002
   1 P12V_AUX      A @T6G_MB_LIB.T6G(SCH_1):P12V_AUX
   2    GND      B @T6G_MB_LIB.T6G(SCH_1):GND

Q_CAP_0402-0.1UF,25V,10%,EMPTY,CH4104K1B00  I6  C675
   1 PVDD18_S5_P1_EN      A @T6G_MB_LIB.T6G(SCH_1):PVDD18_S5_P1_EN
   2    GND      B @T6G_MB_LIB.T6G(SCH_1):GND

Q_RES_0402LF-8.66K,1%,1/16W,CHIP,CS28662FB02  I11  PR8
   1 PVDD18_S5_P1_CS      A @T6G_MB_LIB.T6G(SCH_1):PVDD18_S5_P1_CS
   2    GND      B @T6G_MB_LIB.T6G(SCH_1):GND

Q_RES_0402LF-0,5%,1/16W,CHIP,CS00002JB13  I12  PR397
   1 P3V3_AUX      A @T6G_MB_LIB.T6G(SCH_1):P3V3_AUX
   2 PVDD18_S5_P1_VCC      B @T6G_MB_LIB.T6G(SCH_1):PVDD18_S5_P1_VCC

MPQ8633BGLEC838Z-MPQ8633BGLE-C838-Z,SMLF,IC,AL0086A  I15  PU3
  10 SW_P12V_AUX_PVDD18_S5_P1_FLT   VIN1 @T6G_MB_LIB.T6G(SCH_1):SW_P12V_AUX_PVDD18_S5_P1_FLT
   9 PWRGD_PVDD18_S5_P1  PGOOD @T6G_MB_LIB.T6G(SCH_1):PWRGD_PVDD18_S5_P1
11_18    GND   PGND @T6G_MB_LIB.T6G(SCH_1):GND
   8 PVDD18_S5_P1_EN     EN @T6G_MB_LIB.T6G(SCH_1):PVDD18_S5_P1_EN
   1 SW_PVDD18_S5_P1_BST    BST @T6G_MB_LIB.T6G(SCH_1):SW_PVDD18_S5_P1_BST
   7 PVDD18_S5_P1_FB     FB @T6G_MB_LIB.T6G(SCH_1):PVDD18_S5_P1_FB
   2    GND   AGND @T6G_MB_LIB.T6G(SCH_1):GND
  19 PVDD18_S5_P1_VCC    VCC @T6G_MB_LIB.T6G(SCH_1):PVDD18_S5_P1_VCC
   6 PVDD18_SS_P1_RGND   RGND @T6G_MB_LIB.T6G(SCH_1):PVDD18_SS_P1_RGND
  20 SW_PVDD18_S5_P1_SW     SW @T6G_MB_LIB.T6G(SCH_1):SW_PVDD18_S5_P1_SW
   5 PVDD18_S5_P1_REF TRK_REF @T6G_MB_LIB.T6G(SCH_1):PVDD18_S5_P1_REF
   4 PVDD18_S5_P1_MODE   MODE @T6G_MB_LIB.T6G(SCH_1):PVDD18_S5_P1_MODE
   3 PVDD18_S5_P1_CS     CS @T6G_MB_LIB.T6G(SCH_1):PVDD18_S5_P1_CS
  21 SW_P12V_AUX_PVDD18_S5_P1_FLT   VIN2 @T6G_MB_LIB.T6G(SCH_1):SW_P12V_AUX_PVDD18_S5_P1_FLT

Q_CAP_0402-0.022UF,25V,10%,X7R,CH3224K1B01  I18  PC153
   1 PVDD18_S5_P1_REF      A @T6G_MB_LIB.T6G(SCH_1):PVDD18_S5_P1_REF
   2    GND      B @T6G_MB_LIB.T6G(SCH_1):GND

Q_CAP_0402-0.1UF,25V,10%,X7R,CH4104K1B00  I19  PC62
   1 PVDD18_S5_P1_REF      A @T6G_MB_LIB.T6G(SCH_1):PVDD18_S5_P1_REF
   2 PVDD18_SS_P1_RGND      B @T6G_MB_LIB.T6G(SCH_1):PVDD18_SS_P1_RGND

Q_CAP_C0805-22UF,16V,20%,X6S,CH6223MEA01  I21  PC61
   1 SW_P12V_AUX_PVDD18_S5_P1_FLT      A @T6G_MB_LIB.T6G(SCH_1):SW_P12V_AUX_PVDD18_S5_P1_FLT
   2    GND      B @T6G_MB_LIB.T6G(SCH_1):GND

Q_CAP_C0805-22UF,16V,20%,X6S,CH6223MEA01  I22  PC150
   1 SW_P12V_AUX_PVDD18_S5_P1_FLT      A @T6G_MB_LIB.T6G(SCH_1):SW_P12V_AUX_PVDD18_S5_P1_FLT
   2    GND      B @T6G_MB_LIB.T6G(SCH_1):GND

Q_CAP_C0805-22UF,16V,20%,X6S,CH6223MEA01  I23  PC152
   1 SW_P12V_AUX_PVDD18_S5_P1_FLT      A @T6G_MB_LIB.T6G(SCH_1):SW_P12V_AUX_PVDD18_S5_P1_FLT
   2    GND      B @T6G_MB_LIB.T6G(SCH_1):GND

Q_CAP_C0402-1UF,25V,10%,X6S,CH5104KEB02  I24  PC22
   1 SW_P12V_AUX_PVDD18_S5_P1_FLT      A @T6G_MB_LIB.T6G(SCH_1):SW_P12V_AUX_PVDD18_S5_P1_FLT
   2    GND      B @T6G_MB_LIB.T6G(SCH_1):GND

Q_RES_0402LF-10K,5%,1/16W,CHIP,CS31002JB08  I26  R8009
   1 P3V3_AUX      A @T6G_MB_LIB.T6G(SCH_1):P3V3_AUX
   2 PWRGD_PVDD18_S5_P1      B @T6G_MB_LIB.T6G(SCH_1):PWRGD_PVDD18_S5_P1

Q_CAP_C0805-22UF,4V,20%,X6S,CH622KMEA03  I37  PC65
   1 PVDD18_S5_P1      A @T6G_MB_LIB.T6G(SCH_1):PVDD18_S5_P1
   2    GND      B @T6G_MB_LIB.T6G(SCH_1):GND

Q_CAP_C0805-22UF,4V,20%,X6S,CH622KMEA03  I38  PC83
   1 PVDD18_S5_P1      A @T6G_MB_LIB.T6G(SCH_1):PVDD18_S5_P1
   2    GND      B @T6G_MB_LIB.T6G(SCH_1):GND

Q_RES_0402LF-49.9,1%,1/16W,CHIP,CS04992FB07  I39  PR402
   1 PVDD18_S5_P1      A @T6G_MB_LIB.T6G(SCH_1):PVDD18_S5_P1
   2 PVDD18_S5_P1_FB_RC      B @T6G_MB_LIB.T6G(SCH_1):PVDD18_S5_P1_FB_RC

Q_CAP_C0805-22UF,4V,20%,EMPTY,CH622KMEA03  I42  PC88
   1 PVDD18_S5_P1      A @T6G_MB_LIB.T6G(SCH_1):PVDD18_S5_P1
   2    GND      B @T6G_MB_LIB.T6G(SCH_1):GND

Q_CAPP_SMLF-390UF,2.5V,20%,ALUM,CC7390JMZ13  I43  PC89
   1 PVDD18_S5_P1      A @T6G_MB_LIB.T6G(SCH_1):PVDD18_S5_P1
   2    GND      B @T6G_MB_LIB.T6G(SCH_1):GND

Q_RES_0402LF-33,5%,1/16W,CHIP,CS03302JB10  I48  R259
   1 PWRGD_PVDD18_S5_P1      A @T6G_MB_LIB.T6G(SCH_1):PWRGD_PVDD18_S5_P1
   2 PWRGD_PVDD18_S5_R_P1      B @T6G_MB_LIB.T6G(SCH_1):PWRGD_PVDD18_S5_R_P1

Q_RES_0402LF-1K,1%,1/16W,CHIP,CS21002FB06  I50  PR403
   1 PVDD18_S5_P1      A @T6G_MB_LIB.T6G(SCH_1):PVDD18_S5_P1
   2    GND      B @T6G_MB_LIB.T6G(SCH_1):GND

Q_CAP_C0402-1UF,25V,10%,X6S,CH5104KEB02  I53  PC20
   1 PVDD18_S5_P1_VCC      A @T6G_MB_LIB.T6G(SCH_1):PVDD18_S5_P1_VCC
   2    GND      B @T6G_MB_LIB.T6G(SCH_1):GND

Q_INDUCTOR_SMLF-BLM18SN220TN1D/8000MA,IND,CX220TN1A  I4  PL26
   2 SW_P12V_AUX_PVDD18_S5_P1_FLT      2 @T6G_MB_LIB.T6G(SCH_1):SW_P12V_AUX_PVDD18_S5_P1_FLT
   1 P12V_AUX      1 @T6G_MB_LIB.T6G(SCH_1):P12V_AUX

Q_RES_0402LF-0,5%,1/16W,CHIP,CS00002JB13  I14  PR398
   1    GND      A @T6G_MB_LIB.T6G(SCH_1):GND
   2 PVDD18_S5_P1_MODE      B @T6G_MB_LIB.T6G(SCH_1):PVDD18_S5_P1_MODE

Q_CAP_0402-0.22UF,16V,10%,X7R,CH4223K1B00  I25  PC19
   1 SW_PVDD18_S5_P1_BST_R      A @T6G_MB_LIB.T6G(SCH_1):SW_PVDD18_S5_P1_BST_R
   2 SW_PVDD18_S5_P1_SW      B @T6G_MB_LIB.T6G(SCH_1):SW_PVDD18_S5_P1_SW

Q_RES_0402LF-49.9,1%,1/16W,CHIP,CS04992FB07  I29  PR399
   1    GND      A @T6G_MB_LIB.T6G(SCH_1):GND
   2 PVDD18_SS_P1_RGND      B @T6G_MB_LIB.T6G(SCH_1):PVDD18_SS_P1_RGND

Q_RES_0402LF-10K,1%,1/16W,CHIP,CS31002FB08  I30  PR147
   1 PVDD18_S5_P1_FB      A @T6G_MB_LIB.T6G(SCH_1):PVDD18_S5_P1_FB
   2 PVDD18_SS_P1_RGND      B @T6G_MB_LIB.T6G(SCH_1):PVDD18_SS_P1_RGND

Q_CAP_0402-220PF,50V,10%,X7R,TMP_QCH12206KB14  I31  PC64
   1 PVDD18_S5_P1_FB      A @T6G_MB_LIB.T6G(SCH_1):PVDD18_S5_P1_FB
   2 PVDD18_S5_P1_FB_RC      B @T6G_MB_LIB.T6G(SCH_1):PVDD18_S5_P1_FB_RC

Q_RES_0402LF-20K,1%,1/16W,CHIP,CS32002FB06  I32  PR148
   1 PVDD18_S5_P1_FB      A @T6G_MB_LIB.T6G(SCH_1):PVDD18_S5_P1_FB
   2 PVDD18_S5_P1_FB_RC      B @T6G_MB_LIB.T6G(SCH_1):PVDD18_S5_P1_FB_RC

Q_INDUCTOR_SMLF-1.0UH/18A,IND,CV-10I0MZ01  I33  PL57
   2 PVDD18_S5_P1      2 @T6G_MB_LIB.T6G(SCH_1):PVDD18_S5_P1
   1 SW_PVDD18_S5_P1_SW      1 @T6G_MB_LIB.T6G(SCH_1):SW_PVDD18_S5_P1_SW

Q_CAP_C0402-0.01UF,25V,10%,EMPTY,CH3104K1B11  I34  PC6006
   1 PVDD18_S5_P1_FB_RC      A @T6G_MB_LIB.T6G(SCH_1):PVDD18_S5_P1_FB_RC
   2 PVDD18_SS_P1_RGND      B @T6G_MB_LIB.T6G(SCH_1):PVDD18_SS_P1_RGND

Q_RES_0402LF-0,5%,1/16W,CHIP,CS00002JB13  I35  PR401
   1 PVDD18_SS_P1_RGND      A @T6G_MB_LIB.T6G(SCH_1):PVDD18_SS_P1_RGND
   2 VSENSE_PVDD18_S5_P1_DN      B @T6G_MB_LIB.T6G(SCH_1):VSENSE_PVDD18_S5_P1_DN

Q_RES_0402LF-10,1%,1/16W,CHIP,CS01002FB07  I36  PR400
   1 PVDD18_S5_P1_FB_RC      A @T6G_MB_LIB.T6G(SCH_1):PVDD18_S5_P1_FB_RC
   2 VSENSE_PVDD18_S5_P1_DP      B @T6G_MB_LIB.T6G(SCH_1):VSENSE_PVDD18_S5_P1_DP

Q_CAP_C0805-22UF,4V,20%,X6S,CH622KMEA03  I40  PC84
   1 PVDD18_S5_P1      A @T6G_MB_LIB.T6G(SCH_1):PVDD18_S5_P1
   2    GND      B @T6G_MB_LIB.T6G(SCH_1):GND

Q_CAP_C0805-22UF,4V,20%,EMPTY,CH622KMEA03  I41  PC87
   1 PVDD18_S5_P1      A @T6G_MB_LIB.T6G(SCH_1):PVDD18_S5_P1
   2    GND      B @T6G_MB_LIB.T6G(SCH_1):GND

Q_CAP_0402-0.1UF,25V,10%,X7R,CH4104K1B00  I47  PC21
   1 PVDD18_S5_P1      A @T6G_MB_LIB.T6G(SCH_1):PVDD18_S5_P1
   2    GND      B @T6G_MB_LIB.T6G(SCH_1):GND

Q_CAP_C0805-22UF,16V,20%,X6S,CH6223MEA01  I54  PC60
   1 SW_P12V_AUX_PVDD18_S5_P1_FLT      A @T6G_MB_LIB.T6G(SCH_1):SW_P12V_AUX_PVDD18_S5_P1_FLT
   2    GND      B @T6G_MB_LIB.T6G(SCH_1):GND

Q_CAP_0402-1000PF,50V,5%,X7R,TMP_QCH21006JB10  I55  C5016
   1 PWRGD_PVDD18_S5_R_P1      A @T6G_MB_LIB.T6G(SCH_1):PWRGD_PVDD18_S5_R_P1
   2    GND      B @T6G_MB_LIB.T6G(SCH_1):GND

Q_CAP_C0805-22UF,16V,20%,X6S,CH6223MEA01  I57  PC8003
   1 SW_P12V_AUX_PVDD18_S5_P1_FLT      A @T6G_MB_LIB.T6G(SCH_1):SW_P12V_AUX_PVDD18_S5_P1_FLT
   2    GND      B @T6G_MB_LIB.T6G(SCH_1):GND

Q_RES_0402LF-2.2,1%,1/16W,CHIP,CS-2202FB01  I58  PR8002
   1 SW_PVDD18_S5_P1_BST      A @T6G_MB_LIB.T6G(SCH_1):SW_PVDD18_S5_P1_BST
   2 SW_PVDD18_S5_P1_BST_R      B @T6G_MB_LIB.T6G(SCH_1):SW_PVDD18_S5_P1_BST_R


DRAWING: @T6G_MB_LIB.T6G(SCH_1):PAGE200 

Q_RES_0402LF-1.5,1%,1/8W,EMPTY,CS-1504FB00  I25  PR519
   1 SW_PVDD11_S3_P1_SW2_RC      A @T6G_MB_LIB.T6G(SCH_1):SW_PVDD11_S3_P1_SW2_RC
   2    GND      B @T6G_MB_LIB.T6G(SCH_1):GND

Q_RES_0402LF-5.6,1%,1/16W,CHIP,CS-5602FB01  I26  PR331
   1 SW_PVDD11_S3_P1_BOOT2      A @T6G_MB_LIB.T6G(SCH_1):SW_PVDD11_S3_P1_BOOT2
   2 SW_PVDD11_S3_P1_BOOT2_RC      B @T6G_MB_LIB.T6G(SCH_1):SW_PVDD11_S3_P1_BOOT2_RC

Q_CAP_0402-0.1UF,25V,10%,X7R,CH4104K1B00  I29  PC510_2
   1 SW_P12V_AUX_PVDD11_S3_P1_FLT      A @T6G_MB_LIB.T6G(SCH_1):SW_P12V_AUX_PVDD11_S3_P1_FLT
   2    GND      B @T6G_MB_LIB.T6G(SCH_1):GND

Q_CAP_0402-0.1UF,25V,10%,X7R,CH4104K1B00  I34  PC503_1
   1 PVDD11_S3_P1_VCCS      A @T6G_MB_LIB.T6G(SCH_1):PVDD11_S3_P1_VCCS
   2    GND      B @T6G_MB_LIB.T6G(SCH_1):GND

Q_RES_0402LF-4.87K,1%,1/16W,EMPTY,CS24872FB07  I37  PR328
   1    GND      A @T6G_MB_LIB.T6G(SCH_1):GND
   2 PVDD11_S3_P1_LSET1      B @T6G_MB_LIB.T6G(SCH_1):PVDD11_S3_P1_LSET1

Q_CAP_C0402-2.2UF,10V,10%,X6S,CH5222KEB01  I43  PC507_11P1_1
   1 PVDD11_S3_P1_PVCC      A @T6G_MB_LIB.T6G(SCH_1):PVDD11_S3_P1_PVCC
   2    GND      B @T6G_MB_LIB.T6G(SCH_1):GND

Q_CAP_0402-0.1UF,25V,10%,X7R,CH4104K1B00  I48  PC509_1
   1 SW_P12V_AUX_PVDD11_S3_P1_FLT      A @T6G_MB_LIB.T6G(SCH_1):SW_P12V_AUX_PVDD11_S3_P1_FLT
   2    GND      B @T6G_MB_LIB.T6G(SCH_1):GND

Q_CAP_C0805-22UF,16V,20%,X6S,CH6223MEA01  I52  PC518_2
   1 SW_P12V_AUX_PVDD11_S3_P1_FLT      A @T6G_MB_LIB.T6G(SCH_1):SW_P12V_AUX_PVDD11_S3_P1_FLT
   2    GND      B @T6G_MB_LIB.T6G(SCH_1):GND

Q_CAPP_SMLF-470UF,2.5V,20%,SPCAP,CH747LM8825  I63  PC528
   1 PVDD11_S3_P1      A @T6G_MB_LIB.T6G(SCH_1):PVDD11_S3_P1
   2    GND      B @T6G_MB_LIB.T6G(SCH_1):GND

Q_CAP_C0805-22UF,4V,20%,X6S,CH622KMEA03  I67  PC527_2
   1 PVDD11_S3_P1      A @T6G_MB_LIB.T6G(SCH_1):PVDD11_S3_P1
   2    GND      B @T6G_MB_LIB.T6G(SCH_1):GND

Q_CAPP_SMLF-390UF,2.5V,20%,ALUM,CC7390JMZ13  I69  PC530
   1 PVDD11_S3_P1      A @T6G_MB_LIB.T6G(SCH_1):PVDD11_S3_P1
   2    GND      B @T6G_MB_LIB.T6G(SCH_1):GND

Q_CAPP_THLF-270UF,16V,20%,OSCON,CC72703MD38  I81  PC522
   1 SW_P12V_AUX_PVDD11_S3_P1_FLT      A @T6G_MB_LIB.T6G(SCH_1):SW_P12V_AUX_PVDD11_S3_P1_FLT
   2    GND      B @T6G_MB_LIB.T6G(SCH_1):GND

Q_INDUCTOR_SMLF-100NH/16A,IND,CV+10G0MZ04  I84  PL56
   2 P12V_AUX      2 @T6G_MB_LIB.T6G(SCH_1):P12V_AUX
   1 SW_P12V_AUX_PVDD11_S3_P1_FLT      1 @T6G_MB_LIB.T6G(SCH_1):SW_P12V_AUX_PVDD11_S3_P1_FLT

Q_RES_0402LF-0,5%,1/16W,CHIP,CS00002JB13  I3  PR387
   1 PVDD11_S3_P1_PVCC      A @T6G_MB_LIB.T6G(SCH_1):PVDD11_S3_P1_PVCC
   2 P5V_AUX      B @T6G_MB_LIB.T6G(SCH_1):P5V_AUX

Q_CAP_0402-0.1UF,25V,10%,X7R,CH4104K1B00  I8  PC504_2
   1 PVDD11_S3_P1_VCCS      A @T6G_MB_LIB.T6G(SCH_1):PVDD11_S3_P1_VCCS
   2    GND      B @T6G_MB_LIB.T6G(SCH_1):GND

Q_CAP_C0402-2.2UF,10V,10%,X6S,CH5222KEB01  I10  PC506
   1 PVDD11_S3_P1_VCC2      A @T6G_MB_LIB.T6G(SCH_1):PVDD11_S3_P1_VCC2
   2    GND      B @T6G_MB_LIB.T6G(SCH_1):GND

Q_RES_0402LF-4.87K,1%,1/16W,EMPTY,CS24872FB07  I12  PR329
   1    GND      A @T6G_MB_LIB.T6G(SCH_1):GND
   2 PVDD11_S3_P1_LSET2      B @T6G_MB_LIB.T6G(SCH_1):PVDD11_S3_P1_LSET2

Q_RES_0402LF-2.2,1%,1/16W,CHIP,CS-2202FB01  I14  PR327
   1 PVDD11_S3_P1_PVCC      A @T6G_MB_LIB.T6G(SCH_1):PVDD11_S3_P1_PVCC
   2 PVDD11_S3_P1_VCC2      B @T6G_MB_LIB.T6G(SCH_1):PVDD11_S3_P1_VCC2

Q_CAP_C0402-2.2UF,10V,10%,X6S,CH5222KEB01  I17  PC508_11P1_2
   1 PVDD11_S3_P1_PVCC      A @T6G_MB_LIB.T6G(SCH_1):PVDD11_S3_P1_PVCC
   2    GND      B @T6G_MB_LIB.T6G(SCH_1):GND

ISL99390FRZTR5935-ISL99390FRZ-TR5935,SMLF,IC,AL099A  I22  PU44
  34 PVDD11_S3_P1_PWM1    PWM @T6G_MB_LIB.T6G(SCH_1):PVDD11_S3_P1_PWM1
  39 PVDD11_S3_P1_VCCS  REFIN @T6G_MB_LIB.T6G(SCH_1):PVDD11_S3_P1_VCCS
   3 PVDD11_S3_P1_VCC1    VCC @T6G_MB_LIB.T6G(SCH_1):PVDD11_S3_P1_VCC1
   2    GND   AGND @T6G_MB_LIB.T6G(SCH_1):GND
  33 SW_PVDD11_S3_P1_BOOT1   BOOT @T6G_MB_LIB.T6G(SCH_1):SW_PVDD11_S3_P1_BOOT1
25_29 SW_P12V_AUX_PVDD11_S3_P1_FLT   VIN1 @T6G_MB_LIB.T6G(SCH_1):SW_P12V_AUX_PVDD11_S3_P1_FLT
  32 SW_PVDD11_S3_P1_PH1  PHASE @T6G_MB_LIB.T6G(SCH_1):SW_PVDD11_S3_P1_PH1
   4 PVDD11_S3_P1_PVCC   PVCC @T6G_MB_LIB.T6G(SCH_1):PVDD11_S3_P1_PVCC
  36 PVDD11_S3_P1_TEMP0 TOUT_FLT @T6G_MB_LIB.T6G(SCH_1):PVDD11_S3_P1_TEMP0
  38 PVDD11_S3_P1_IMON1   IOUT @T6G_MB_LIB.T6G(SCH_1):PVDD11_S3_P1_IMON1
  37 PVDD11_S3_P1_LSET1   LSET @T6G_MB_LIB.T6G(SCH_1):PVDD11_S3_P1_LSET1
10_19 SW_PVDD11_S3_P1_SW1     SW @T6G_MB_LIB.T6G(SCH_1):SW_PVDD11_S3_P1_SW1
   5    GND  PGND1 @T6G_MB_LIB.T6G(SCH_1):GND
  30 SW_P12V_AUX_PVDD11_S3_P1_FLT   VIN2 @T6G_MB_LIB.T6G(SCH_1):SW_P12V_AUX_PVDD11_S3_P1_FLT
   1 PVDD11_S3_P1_VOS1    VOS @T6G_MB_LIB.T6G(SCH_1):PVDD11_S3_P1_VOS1
  40    GND  PGND3 @T6G_MB_LIB.T6G(SCH_1):GND
  35 PVDD11_S3_P1_VCC1     EN @T6G_MB_LIB.T6G(SCH_1):PVDD11_S3_P1_VCC1
  31 NC_PVDD11_S3_P1_DNC1    DNC @T6G_MB_LIB.T6G(SCH_1):NC_PVDD11_S3_P1_DNC1
   6 NC_PVDD11_S3_P1_GL1_1    GL1 @T6G_MB_LIB.T6G(SCH_1):NC_PVDD11_S3_P1_GL1_1
  41 NC_PVDD11_S3_P1_GL2_1    GL2 @T6G_MB_LIB.T6G(SCH_1):NC_PVDD11_S3_P1_GL2_1
7_9-20_24    GND  PGND2 @T6G_MB_LIB.T6G(SCH_1):GND

Q_CAP_C0402-560PF,50V,10%,EMPTY,CH1566K1B09  I27  PC255
   1 SW_PVDD11_S3_P1_SW2      A @T6G_MB_LIB.T6G(SCH_1):SW_PVDD11_S3_P1_SW2
   2 SW_PVDD11_S3_P1_SW2_RC      B @T6G_MB_LIB.T6G(SCH_1):SW_PVDD11_S3_P1_SW2_RC

Q_CAP_C0805-22UF,16V,20%,X6S,CH6223MEA01  I30  PC514_2
   1 SW_P12V_AUX_PVDD11_S3_P1_FLT      A @T6G_MB_LIB.T6G(SCH_1):SW_P12V_AUX_PVDD11_S3_P1_FLT
   2    GND      B @T6G_MB_LIB.T6G(SCH_1):GND

Q_CAP_C0805-22UF,16V,20%,X6S,CH6223MEA01  I31  PC516_2
   1 SW_P12V_AUX_PVDD11_S3_P1_FLT      A @T6G_MB_LIB.T6G(SCH_1):SW_P12V_AUX_PVDD11_S3_P1_FLT
   2    GND      B @T6G_MB_LIB.T6G(SCH_1):GND

Q_RES_0402LF-1.5,1%,1/8W,EMPTY,CS-1504FB00  I33  PR520
   1 SW_PVDD11_S3_P1_SW1_RC      A @T6G_MB_LIB.T6G(SCH_1):SW_PVDD11_S3_P1_SW1_RC
   2    GND      B @T6G_MB_LIB.T6G(SCH_1):GND

Q_CAP_C0402-2.2UF,10V,10%,X6S,CH5222KEB01  I36  PC505
   1 PVDD11_S3_P1_VCC1      A @T6G_MB_LIB.T6G(SCH_1):PVDD11_S3_P1_VCC1
   2    GND      B @T6G_MB_LIB.T6G(SCH_1):GND

Q_RES_0402LF-2.2,1%,1/16W,CHIP,CS-2202FB01  I40  PR326
   1 PVDD11_S3_P1_PVCC      A @T6G_MB_LIB.T6G(SCH_1):PVDD11_S3_P1_PVCC
   2 PVDD11_S3_P1_VCC1      B @T6G_MB_LIB.T6G(SCH_1):PVDD11_S3_P1_VCC1

Q_RES_0402LF-0,5%,1/16W,EMPTY,CS00002JB13  I41  PR394
   1 PVDD11_S3_P1_PVCC      A @T6G_MB_LIB.T6G(SCH_1):PVDD11_S3_P1_PVCC
   2 P3V3_AUX      B @T6G_MB_LIB.T6G(SCH_1):P3V3_AUX

Q_CAP_C0402-1UF,25V,10%,X6S,CH5104KEB02  I45  PC511_1
   1 SW_P12V_AUX_PVDD11_S3_P1_FLT      A @T6G_MB_LIB.T6G(SCH_1):SW_P12V_AUX_PVDD11_S3_P1_FLT
   2    GND      B @T6G_MB_LIB.T6G(SCH_1):GND

Q_CAP_C0402-560PF,50V,10%,EMPTY,CH1566K1B09  I46  PC315
   1 SW_PVDD11_S3_P1_SW1      A @T6G_MB_LIB.T6G(SCH_1):SW_PVDD11_S3_P1_SW1
   2 SW_PVDD11_S3_P1_SW1_RC      B @T6G_MB_LIB.T6G(SCH_1):SW_PVDD11_S3_P1_SW1_RC

Q_RES_0402LF-5.6,1%,1/16W,CHIP,CS-5602FB01  I47  PR330
   1 SW_PVDD11_S3_P1_BOOT1      A @T6G_MB_LIB.T6G(SCH_1):SW_PVDD11_S3_P1_BOOT1
   2 SW_PVDD11_S3_P1_BOOT1_RC      B @T6G_MB_LIB.T6G(SCH_1):SW_PVDD11_S3_P1_BOOT1_RC

Q_CAP_C0805-22UF,16V,20%,X6S,CH6223MEA01  I49  PC513_1
   1 SW_P12V_AUX_PVDD11_S3_P1_FLT      A @T6G_MB_LIB.T6G(SCH_1):SW_P12V_AUX_PVDD11_S3_P1_FLT
   2    GND      B @T6G_MB_LIB.T6G(SCH_1):GND

Q_CAP_C0805-22UF,16V,20%,X6S,CH6223MEA01  I50  PC515_1
   1 SW_P12V_AUX_PVDD11_S3_P1_FLT      A @T6G_MB_LIB.T6G(SCH_1):SW_P12V_AUX_PVDD11_S3_P1_FLT
   2    GND      B @T6G_MB_LIB.T6G(SCH_1):GND

Q_CAP_C0805-22UF,16V,20%,X6S,CH6223MEA01  I51  PC517_1
   1 SW_P12V_AUX_PVDD11_S3_P1_FLT      A @T6G_MB_LIB.T6G(SCH_1):SW_P12V_AUX_PVDD11_S3_P1_FLT
   2    GND      B @T6G_MB_LIB.T6G(SCH_1):GND

Q_RES_0402LF-0,5%,1/16W,CHIP,CS00002JB13  I53  PR333
   1 PVDD11_S3_P1_VOS2      A @T6G_MB_LIB.T6G(SCH_1):PVDD11_S3_P1_VOS2
   2 PVDD11_S3_P1      B @T6G_MB_LIB.T6G(SCH_1):PVDD11_S3_P1

Q_CAP_0402-0.22UF,16V,10%,X7R,CH4223K1B00  I54  PC520
   1 SW_PVDD11_S3_P1_BOOT2_RC      A @T6G_MB_LIB.T6G(SCH_1):SW_PVDD11_S3_P1_BOOT2_RC
   2 SW_PVDD11_S3_P1_PH2      B @T6G_MB_LIB.T6G(SCH_1):SW_PVDD11_S3_P1_PH2

Q_INDUCTOR_SMLF-90NH/155A,IND,CVA90^0KZ13  I55  PL55
   2 PVDD11_S3_P1      2 @T6G_MB_LIB.T6G(SCH_1):PVDD11_S3_P1
   1 SW_PVDD11_S3_P1_SW2      1 @T6G_MB_LIB.T6G(SCH_1):SW_PVDD11_S3_P1_SW2

Q_CAP_C0805-22UF,4V,20%,X6S,CH622KMEA03  I56  PC523_2
   1 PVDD11_S3_P1      A @T6G_MB_LIB.T6G(SCH_1):PVDD11_S3_P1
   2    GND      B @T6G_MB_LIB.T6G(SCH_1):GND

Q_CAP_C0805-22UF,16V,20%,X6S,CH6223MEA01  I58  PC27
   1 SW_P12V_AUX_PVDD11_S3_P1_FLT      A @T6G_MB_LIB.T6G(SCH_1):SW_P12V_AUX_PVDD11_S3_P1_FLT
   2    GND      B @T6G_MB_LIB.T6G(SCH_1):GND

Q_RES_0402LF-0,5%,1/16W,CHIP,CS00002JB13  I60  PR332
   1 PVDD11_S3_P1_VOS1      A @T6G_MB_LIB.T6G(SCH_1):PVDD11_S3_P1_VOS1
   2 PVDD11_S3_P1      B @T6G_MB_LIB.T6G(SCH_1):PVDD11_S3_P1

Q_CAPP_SMLF-470UF,2.5V,20%,SPCAP,CH747LM8825  I62  PC525
   1 PVDD11_S3_P1      A @T6G_MB_LIB.T6G(SCH_1):PVDD11_S3_P1
   2    GND      B @T6G_MB_LIB.T6G(SCH_1):GND

Q_CAPP_SMLF-470UF,2.5V,20%,SPCAP,CH747LM8825  I65  PC802
   1 PVDD11_S3_P1      A @T6G_MB_LIB.T6G(SCH_1):PVDD11_S3_P1
   2    GND      B @T6G_MB_LIB.T6G(SCH_1):GND

Q_CAPP_SMLF-390UF,2.5V,20%,ALUM,CC7390JMZ13  I72  PC531
   1 PVDD11_S3_P1      A @T6G_MB_LIB.T6G(SCH_1):PVDD11_S3_P1
   2    GND      B @T6G_MB_LIB.T6G(SCH_1):GND

Q_CAPP_SMLF-390UF,2.5V,20%,ALUM,CC7390JMZ13  I73  PC532
   1 PVDD11_S3_P1      A @T6G_MB_LIB.T6G(SCH_1):PVDD11_S3_P1
   2    GND      B @T6G_MB_LIB.T6G(SCH_1):GND

Q_CAPP_SMLF-390UF,2.5V,20%,ALUM,CC7390JMZ13  I75  PC803
   1 PVDD11_S3_P1      A @T6G_MB_LIB.T6G(SCH_1):PVDD11_S3_P1
   2    GND      B @T6G_MB_LIB.T6G(SCH_1):GND

Q_CAP_0402-0.22UF,16V,10%,X7R,CH4223K1B00  I76  PC519
   1 SW_PVDD11_S3_P1_BOOT1_RC      A @T6G_MB_LIB.T6G(SCH_1):SW_PVDD11_S3_P1_BOOT1_RC
   2 SW_PVDD11_S3_P1_PH1      B @T6G_MB_LIB.T6G(SCH_1):SW_PVDD11_S3_P1_PH1

Q_INDUCTOR_SMLF-90NH/155A,IND,CVA90^0KZ13  I78  PL54
   2 PVDD11_S3_P1      2 @T6G_MB_LIB.T6G(SCH_1):PVDD11_S3_P1
   1 SW_PVDD11_S3_P1_SW1      1 @T6G_MB_LIB.T6G(SCH_1):SW_PVDD11_S3_P1_SW1

Q_CAP_C0805-22UF,16V,20%,X6S,CH6223MEA01  I80  PC521_1
   1 SW_P12V_AUX_PVDD11_S3_P1_FLT      A @T6G_MB_LIB.T6G(SCH_1):SW_P12V_AUX_PVDD11_S3_P1_FLT
   2    GND      B @T6G_MB_LIB.T6G(SCH_1):GND

Q_CAP_C0402-100NF,50V,10%,X7R,CH4106K1B01  I82  PC524
   1 PVDD11_S3_P1      A @T6G_MB_LIB.T6G(SCH_1):PVDD11_S3_P1
   2    GND      B @T6G_MB_LIB.T6G(SCH_1):GND

Q_CAP_0402-0.1UF,25V,10%,X7R,CH4104K1B00  I85  PC511
   1 P12V_AUX      A @T6G_MB_LIB.T6G(SCH_1):P12V_AUX
   2    GND      B @T6G_MB_LIB.T6G(SCH_1):GND

Q_CAP_C0805-22UF,4V,20%,X6S,CH622KMEA03  I87  PC526_1
   1 PVDD11_S3_P1      A @T6G_MB_LIB.T6G(SCH_1):PVDD11_S3_P1
   2    GND      B @T6G_MB_LIB.T6G(SCH_1):GND

Q_CAP_C0805-22UF,4V,20%,X6S,CH622KMEA03  I88  PC529_1
   1 PVDD11_S3_P1      A @T6G_MB_LIB.T6G(SCH_1):PVDD11_S3_P1
   2    GND      B @T6G_MB_LIB.T6G(SCH_1):GND

Q_RES_0402LF-1K,1%,1/16W,CHIP,CS21002FB06  I89  PR395
   1 PVDD11_S3_P1      A @T6G_MB_LIB.T6G(SCH_1):PVDD11_S3_P1
   2    GND      B @T6G_MB_LIB.T6G(SCH_1):GND

Q_CAP_C0402-1UF,25V,10%,X6S,CH5104KEB02  I91  PC512_2
   1 SW_P12V_AUX_PVDD11_S3_P1_FLT      A @T6G_MB_LIB.T6G(SCH_1):SW_P12V_AUX_PVDD11_S3_P1_FLT
   2    GND      B @T6G_MB_LIB.T6G(SCH_1):GND

ISL99390FRZTR5935-ISL99390FRZ-TR5935,SMLF,IC,AL099A  I92  PU45
  34 PVDD11_S3_P1_PWM2    PWM @T6G_MB_LIB.T6G(SCH_1):PVDD11_S3_P1_PWM2
  39 PVDD11_S3_P1_VCCS  REFIN @T6G_MB_LIB.T6G(SCH_1):PVDD11_S3_P1_VCCS
   3 PVDD11_S3_P1_VCC2    VCC @T6G_MB_LIB.T6G(SCH_1):PVDD11_S3_P1_VCC2
   2    GND   AGND @T6G_MB_LIB.T6G(SCH_1):GND
  33 SW_PVDD11_S3_P1_BOOT2   BOOT @T6G_MB_LIB.T6G(SCH_1):SW_PVDD11_S3_P1_BOOT2
25_29 SW_P12V_AUX_PVDD11_S3_P1_FLT   VIN1 @T6G_MB_LIB.T6G(SCH_1):SW_P12V_AUX_PVDD11_S3_P1_FLT
  32 SW_PVDD11_S3_P1_PH2  PHASE @T6G_MB_LIB.T6G(SCH_1):SW_PVDD11_S3_P1_PH2
   4 PVDD11_S3_P1_PVCC   PVCC @T6G_MB_LIB.T6G(SCH_1):PVDD11_S3_P1_PVCC
  36 PVDD11_S3_P1_TEMP0 TOUT_FLT @T6G_MB_LIB.T6G(SCH_1):PVDD11_S3_P1_TEMP0
  38 PVDD11_S3_P1_IMON2   IOUT @T6G_MB_LIB.T6G(SCH_1):PVDD11_S3_P1_IMON2
  37 PVDD11_S3_P1_LSET2   LSET @T6G_MB_LIB.T6G(SCH_1):PVDD11_S3_P1_LSET2
10_19 SW_PVDD11_S3_P1_SW2     SW @T6G_MB_LIB.T6G(SCH_1):SW_PVDD11_S3_P1_SW2
   5    GND  PGND1 @T6G_MB_LIB.T6G(SCH_1):GND
  30 SW_P12V_AUX_PVDD11_S3_P1_FLT   VIN2 @T6G_MB_LIB.T6G(SCH_1):SW_P12V_AUX_PVDD11_S3_P1_FLT
   1 PVDD11_S3_P1_VOS2    VOS @T6G_MB_LIB.T6G(SCH_1):PVDD11_S3_P1_VOS2
  40    GND  PGND3 @T6G_MB_LIB.T6G(SCH_1):GND
  35 PVDD11_S3_P1_VCC2     EN @T6G_MB_LIB.T6G(SCH_1):PVDD11_S3_P1_VCC2
  31 NC_PVDD11_S3_P1_DNC2    DNC @T6G_MB_LIB.T6G(SCH_1):NC_PVDD11_S3_P1_DNC2
   6 NC_PVDD11_S3_P1_GL1_2    GL1 @T6G_MB_LIB.T6G(SCH_1):NC_PVDD11_S3_P1_GL1_2
  41 NC_PVDD11_S3_P1_GL2_2    GL2 @T6G_MB_LIB.T6G(SCH_1):NC_PVDD11_S3_P1_GL2_2
7_9-20_24    GND  PGND2 @T6G_MB_LIB.T6G(SCH_1):GND

Q_CAP_C0805-22UF,16V,20%,X6S,CH6223MEA01  I93  PC8006
   1 SW_P12V_AUX_PVDD11_S3_P1_FLT      A @T6G_MB_LIB.T6G(SCH_1):SW_P12V_AUX_PVDD11_S3_P1_FLT
   2    GND      B @T6G_MB_LIB.T6G(SCH_1):GND

Q_CAP_C0805-22UF,16V,20%,X6S,CH6223MEA01  I94  PC8007
   1 SW_P12V_AUX_PVDD11_S3_P1_FLT      A @T6G_MB_LIB.T6G(SCH_1):SW_P12V_AUX_PVDD11_S3_P1_FLT
   2    GND      B @T6G_MB_LIB.T6G(SCH_1):GND

Q_CAP_C0805-22UF,16V,20%,X6S,CH6223MEA01  I95  PC7003
   1 SW_P12V_AUX_PVDD11_S3_P1_FLT      A @T6G_MB_LIB.T6G(SCH_1):SW_P12V_AUX_PVDD11_S3_P1_FLT
   2    GND      B @T6G_MB_LIB.T6G(SCH_1):GND


DRAWING: @T6G_MB_LIB.T6G(SCH_1):PAGE168 

Q_RES_0402LF-0,5%,1/16W,CHIP,CS00002JB13  I4  PR283
   1 SVID_PVDDCR_CPU0_P0_SVTI      A @T6G_MB_LIB.T6G(SCH_1):SVID_PVDDCR_CPU0_P0_SVTI
   2    GND      B @T6G_MB_LIB.T6G(SCH_1):GND

Q_CAP_0402-1000PF,50V,5%,X7R,TMP_QCH21006JB10  I13  C461
   1 PVDDCR_SOC_P0_EN_RC      A @T6G_MB_LIB.T6G(SCH_1):PVDDCR_SOC_P0_EN_RC
   2    GND      B @T6G_MB_LIB.T6G(SCH_1):GND

Q_RES_0402LF-49.9,1%,1/16W,CHIP,CS04992FB07  I36  PR297
   1 VSENSE_VSS_SENSE_A_P0      A @T6G_MB_LIB.T6G(SCH_1):VSENSE_VSS_SENSE_A_P0
   2    GND      B @T6G_MB_LIB.T6G(SCH_1):GND

Q_RES_0402LF-1K,1%,1/16W,CHIP,CS21002FB06  I42  R8317
   1 PVDD18_S5_P0      A @T6G_MB_LIB.T6G(SCH_1):PVDD18_S5_P0
   2 PVDDCR_CPU0_P0_RESET_N_R      B @T6G_MB_LIB.T6G(SCH_1):PVDDCR_CPU0_P0_RESET_N_R

Q_RES_0402LF-4.99K,1%,1/16W,EMPTY,CS24992FB07  I47  PR599
   1 PVDDCR_CPU0_P0_VINSEN      A @T6G_MB_LIB.T6G(SCH_1):PVDDCR_CPU0_P0_VINSEN
   2    GND      B @T6G_MB_LIB.T6G(SCH_1):GND

Q_RES_0402LF-49.9,1%,1/16W,CHIP,CS04992FB07  I57  R315
   1 PVDDCR_CPU0_P0_RESET_N      A @T6G_MB_LIB.T6G(SCH_1):PVDDCR_CPU0_P0_RESET_N
   2 PVDDCR_CPU0_P0_RESET_N_R      B @T6G_MB_LIB.T6G(SCH_1):PVDDCR_CPU0_P0_RESET_N_R

Q_RES_0402LF-0,5%,1/16W,CHIP,CS00002JB13  I58  R8301
   1 PVDDCR_CPU0_P0_OCP_N      A @T6G_MB_LIB.T6G(SCH_1):PVDDCR_CPU0_P0_OCP_N
   2 PVDDCR_CPU0_P0_OCP_N_R      B @T6G_MB_LIB.T6G(SCH_1):PVDDCR_CPU0_P0_OCP_N_R

Q_CAP_0402-3300PF,50V,10%,X7R,TMP_QCH2336K1B12  I62  PC463
   1 VSENSE_PVDDCR_CPU0_P0_VSEN0      A @T6G_MB_LIB.T6G(SCH_1):VSENSE_PVDDCR_CPU0_P0_VSEN0
   2 VSENSE_VSS_SENSE_A_P0      B @T6G_MB_LIB.T6G(SCH_1):VSENSE_VSS_SENSE_A_P0

Q_CAP_0402-10PF,50V,5%,EMPTY,CH01006JB08  I66  C299
   1 SVID_PVDDCR_CPU0_P0_SVD_R      A @T6G_MB_LIB.T6G(SCH_1):SVID_PVDDCR_CPU0_P0_SVD_R
   2    GND      B @T6G_MB_LIB.T6G(SCH_1):GND

Q_CAP_0402-10PF,50V,5%,EMPTY,CH01006JB08  I68  C302
   1 SVID_PVDDCR_CPU0_P0_SVC_R      A @T6G_MB_LIB.T6G(SCH_1):SVID_PVDDCR_CPU0_P0_SVC_R
   2    GND      B @T6G_MB_LIB.T6G(SCH_1):GND

Q_RES_0402LF-1K,1%,1/16W,CHIP,CS21002FB06  I82  R8300
   1 P3V3_AUX      A @T6G_MB_LIB.T6G(SCH_1):P3V3_AUX
   2 PWRGD_PVDDCR_CPU0_P0_R      B @T6G_MB_LIB.T6G(SCH_1):PWRGD_PVDDCR_CPU0_P0_R

Q_RES_0402LF-0,5%,1/16W,CHIP,CS00002JB13  I86  PR305
   1 SVID_PVDDCR_CPU0_P0_SVTI      A @T6G_MB_LIB.T6G(SCH_1):SVID_PVDDCR_CPU0_P0_SVTI
   2 SVID_PVDDCR_CPU0_P0_SVTI_R      B @T6G_MB_LIB.T6G(SCH_1):SVID_PVDDCR_CPU0_P0_SVTI_R

Q_RES_0402LF-49.9,1%,1/16W,CHIP,CS04992FB07  I87  R8304
   1 SVID_PVDDCR_CPU0_P0_SVTO      A @T6G_MB_LIB.T6G(SCH_1):SVID_PVDDCR_CPU0_P0_SVTO
   2 SVID_PVDDCR_CPU0_P0_SVTO_R      B @T6G_MB_LIB.T6G(SCH_1):SVID_PVDDCR_CPU0_P0_SVTO_R

Q_RES_0402LF-0,5%,1/16W,CHIP,CS00002JB13  I88  R8312
   1 PVDDCR_CPU0_P0_EN      A @T6G_MB_LIB.T6G(SCH_1):PVDDCR_CPU0_P0_EN
   2 PVDDCR_CPU0_P0_EN_R      B @T6G_MB_LIB.T6G(SCH_1):PVDDCR_CPU0_P0_EN_R

Q_CAP_0402-1000PF,50V,5%,X7R,TMP_QCH21006JB10  I90  C468
   1 PVDDCR_CPU0_P0_EN_R      A @T6G_MB_LIB.T6G(SCH_1):PVDDCR_CPU0_P0_EN_R
   2    GND      B @T6G_MB_LIB.T6G(SCH_1):GND

Q_CAP_0402-0.1UF,25V,10%,X7R,CH4104K1B00  I118  PC13
   1 PVDDCR_CPU0_P0_VCCS      A @T6G_MB_LIB.T6G(SCH_1):PVDDCR_CPU0_P0_VCCS
   2    GND      B @T6G_MB_LIB.T6G(SCH_1):GND

Q_RES_0402LF-0,5%,1/16W,CHIP,CS00002JB13  I2  R8282
   1 PVDDCR_SOC_P0_EN      A @T6G_MB_LIB.T6G(SCH_1):PVDDCR_SOC_P0_EN
   2 PVDDCR_SOC_P0_EN_RC      B @T6G_MB_LIB.T6G(SCH_1):PVDDCR_SOC_P0_EN_RC

Q_RES_0402LF-1K,1%,1/16W,EMPTY,CS21002FB06  I6  R8286
   1 SVID_PVDDCR_CPU0_P0_SVTO      A @T6G_MB_LIB.T6G(SCH_1):SVID_PVDDCR_CPU0_P0_SVTO
   2    GND      B @T6G_MB_LIB.T6G(SCH_1):GND

Q_RES_0402LF-1K,1%,1/16W,EMPTY,CS21002FB06  I10  PR284
   1 PVDD18_S5_P0      A @T6G_MB_LIB.T6G(SCH_1):PVDD18_S5_P0
   2 SVID_PVDDCR_CPU0_P0_SVTI      B @T6G_MB_LIB.T6G(SCH_1):SVID_PVDDCR_CPU0_P0_SVTI

Q_RES_0402LF-40.2K,1%,1/16W,CHIP,CS34022FB04  I15  PR290
   1 P5V_AUX      A @T6G_MB_LIB.T6G(SCH_1):P5V_AUX
   2 PVDDCR_CPU0_P0_VMON      B @T6G_MB_LIB.T6G(SCH_1):PVDDCR_CPU0_P0_VMON

MOSFET_N_SMLF-BSS138K,BSS138K,IC,BAM138K0000  I17  PQ17
   G PVDDCR_SOC_P0_EN_RC   GATE @T6G_MB_LIB.T6G(SCH_1):PVDDCR_SOC_P0_EN_RC
   D PVDDCR_SOC_P0_EN_GD  DRAIN @T6G_MB_LIB.T6G(SCH_1):PVDDCR_SOC_P0_EN_GD
   S    GND SOURCE @T6G_MB_LIB.T6G(SCH_1):GND

Q_RES_0402LF-1K,1%,1/16W,CHIP,CS21002FB06  I18  PR285
   1 P3V3_AUX      A @T6G_MB_LIB.T6G(SCH_1):P3V3_AUX
   2 PVDDCR_SOC_P0_EN_GD      B @T6G_MB_LIB.T6G(SCH_1):PVDDCR_SOC_P0_EN_GD

MOSFET_PCH_GDS_ESD_PROTECTED-PJA3415AE,SMLF,IC,BAMA  I19  PQ13
   D PVDDCR_SOC_P0_EN//ADDR_CFG      D @T6G_MB_LIB.T6G(SCH_1):PVDDCR_SOC_P0_EN//ADDR_CFG
   G PVDDCR_SOC_P0_EN_GD      G @T6G_MB_LIB.T6G(SCH_1):PVDDCR_SOC_P0_EN_GD
   S P3V3_AUX      S @T6G_MB_LIB.T6G(SCH_1):P3V3_AUX

Q_RES_0402LF-10K,1%,1/16W,CHIP,CS31002FB08  I21  PR5
   1 PVDDCR_CPU0_P0_VMON      A @T6G_MB_LIB.T6G(SCH_1):PVDDCR_CPU0_P0_VMON
   2    GND      B @T6G_MB_LIB.T6G(SCH_1):GND

Q_CAP_0402-0.1UF,25V,10%,X7R,CH4104K1B00  I23  PC462
   1 PVDDCR_CPU0_P0_VMON      A @T6G_MB_LIB.T6G(SCH_1):PVDDCR_CPU0_P0_VMON
   2    GND      B @T6G_MB_LIB.T6G(SCH_1):GND

Q_RES_0402LF-33,5%,1/16W,CHIP,CS03302JB10  I24  R8299
   1 PWRGD_PVDDCR_SOC_P0      A @T6G_MB_LIB.T6G(SCH_1):PWRGD_PVDDCR_SOC_P0
   2 PWRGD_PVDDCR_SOC_P0_R      B @T6G_MB_LIB.T6G(SCH_1):PWRGD_PVDDCR_SOC_P0_R

Q_RES_0402LF-681,1%,1/16W,CHIP,CS16812FB02  I27  PR292
   1 PVDDCR_SOC_P0_EN//ADDR_CFG      A @T6G_MB_LIB.T6G(SCH_1):PVDDCR_SOC_P0_EN//ADDR_CFG
   2    GND      B @T6G_MB_LIB.T6G(SCH_1):GND

Q_RES_0402LF-1K,1%,1/16W,CHIP,CS21002FB06  I28  R8298
   1 P3V3_AUX      A @T6G_MB_LIB.T6G(SCH_1):P3V3_AUX
   2 PWRGD_PVDDCR_SOC_P0_R      B @T6G_MB_LIB.T6G(SCH_1):PWRGD_PVDDCR_SOC_P0_R

Q_RES_0402LF-49.9,1%,1/16W,CHIP,CS04992FB07  I40  PR296
   1 PVDDCR_SOC_P0      A @T6G_MB_LIB.T6G(SCH_1):PVDDCR_SOC_P0
   2 VSENSE_PVDDCR_SOC_P0_DP      B @T6G_MB_LIB.T6G(SCH_1):VSENSE_PVDDCR_SOC_P0_DP

Q_RES_0402LF-49.9,1%,1/16W,CHIP,CS04992FB07  I44  PR295
   1 VSENSE_VSS_SENSE_A_P0      A @T6G_MB_LIB.T6G(SCH_1):VSENSE_VSS_SENSE_A_P0
   2    GND      B @T6G_MB_LIB.T6G(SCH_1):GND

Q_RES_0402LF-0,5%,1/16W,CHIP,CS00002JB13  I48  PR314
   1 P12V_AUX      A @T6G_MB_LIB.T6G(SCH_1):P12V_AUX
   2 PVDDCR_CPU0_P0_VINSEN      B @T6G_MB_LIB.T6G(SCH_1):PVDDCR_CPU0_P0_VINSEN

Q_CAP_0402-0.1UF,25V,10%,X7R,CH4104K1B00  I50  PC7
   1 PVDDCR_CPU0_P0_VINSEN      A @T6G_MB_LIB.T6G(SCH_1):PVDDCR_CPU0_P0_VINSEN
   2    GND      B @T6G_MB_LIB.T6G(SCH_1):GND

Q_CAP_0402-1000PF,50V,5%,EMPTY,TMP_QCH21006JB10  I51  C465
   1 PWRGD_PVDDCR_SOC_P0_R      A @T6G_MB_LIB.T6G(SCH_1):PWRGD_PVDDCR_SOC_P0_R
   2    GND      B @T6G_MB_LIB.T6G(SCH_1):GND

Q_CAP_0402-1UF,6.3V,10%,X7R,CH5101K1B01  I52  PC466
   1 PVDD18_S5_P0      A @T6G_MB_LIB.T6G(SCH_1):PVDD18_S5_P0
   2    GND      B @T6G_MB_LIB.T6G(SCH_1):GND

Q_RES_0402LF-1K,1%,1/16W,CHIP,CS21002FB06  I54  R8313
   1 PVDD18_S5_P0      A @T6G_MB_LIB.T6G(SCH_1):PVDD18_S5_P0
   2 PVDDCR_CPU0_P0_OCP_N_R      B @T6G_MB_LIB.T6G(SCH_1):PVDDCR_CPU0_P0_OCP_N_R

Q_RES_0402LF-0,5%,1/16W,CHIP,CS00002JB13  I59  PR307
   1 VSENSE_PVDDCR_SOC_P0_DP      A @T6G_MB_LIB.T6G(SCH_1):VSENSE_PVDDCR_SOC_P0_DP
   2 VSENSE_PVDDCR_SOC_P0_VSEN1      B @T6G_MB_LIB.T6G(SCH_1):VSENSE_PVDDCR_SOC_P0_VSEN1

Q_CAP_0402-3300PF,50V,10%,X7R,TMP_QCH2336K1B12  I60  PC464
   1 VSENSE_PVDDCR_SOC_P0_VSEN1      A @T6G_MB_LIB.T6G(SCH_1):VSENSE_PVDDCR_SOC_P0_VSEN1
   2 VSENSE_VSS_SENSE_A_P0      B @T6G_MB_LIB.T6G(SCH_1):VSENSE_VSS_SENSE_A_P0

Q_RES_0402LF-0,5%,1/16W,CHIP,CS00002JB13  I61  PR306
   1 VSENSE_PVDDCR_CPU0_P0_DP      A @T6G_MB_LIB.T6G(SCH_1):VSENSE_PVDDCR_CPU0_P0_DP
   2 VSENSE_PVDDCR_CPU0_P0_VSEN0      B @T6G_MB_LIB.T6G(SCH_1):VSENSE_PVDDCR_CPU0_P0_VSEN0

Q_CAP_0402-10PF,50V,5%,EMPTY,CH01006JB08  I64  C298
   1 SVID_PVDDCR_CPU0_P0_SVTO      A @T6G_MB_LIB.T6G(SCH_1):SVID_PVDDCR_CPU0_P0_SVTO
   2    GND      B @T6G_MB_LIB.T6G(SCH_1):GND

Q_RES_0402LF-1K,1%,1/16W,EMPTY,CS21002FB06  I69  R8287
   1 PVDD18_S5_P0      A @T6G_MB_LIB.T6G(SCH_1):PVDD18_S5_P0
   2 SVID_PVDDCR_CPU0_P0_SVTO      B @T6G_MB_LIB.T6G(SCH_1):SVID_PVDDCR_CPU0_P0_SVTO

Q_RES_0402LF-1K,1%,1/16W,EMPTY,CS21002FB06  I70  R8289
   1 PVDD18_S5_P0      A @T6G_MB_LIB.T6G(SCH_1):PVDD18_S5_P0
   2 SVID_PVDDCR_CPU0_P0_SVD_R      B @T6G_MB_LIB.T6G(SCH_1):SVID_PVDDCR_CPU0_P0_SVD_R

Q_RES_0402LF-1K,1%,1/16W,EMPTY,CS21002FB06  I71  R8293
   1 PVDD18_S5_P0      A @T6G_MB_LIB.T6G(SCH_1):PVDD18_S5_P0
   2 SVID_PVDDCR_CPU0_P0_SVC_R      B @T6G_MB_LIB.T6G(SCH_1):SVID_PVDDCR_CPU0_P0_SVC_R

Q_RES_0402LF-49.9,1%,1/16W,CHIP,CS04992FB07  I72  PR294
   1 PVDDCR_CPU0_P0      A @T6G_MB_LIB.T6G(SCH_1):PVDDCR_CPU0_P0
   2 VSENSE_PVDDCR_CPU0_P0_DP      B @T6G_MB_LIB.T6G(SCH_1):VSENSE_PVDDCR_CPU0_P0_DP

Q_RES_0402LF-33,5%,1/16W,CHIP,CS03302JB10  I83  R8310
   1 PVDDCR_CPU0_P0_PMALERT      A @T6G_MB_LIB.T6G(SCH_1):PVDDCR_CPU0_P0_PMALERT
   2 PVDDCR_CPU0_P0_PMALERT_R      B @T6G_MB_LIB.T6G(SCH_1):PVDDCR_CPU0_P0_PMALERT_R

Q_RES_0402LF-0,5%,1/16W,CHIP,CS00002JB13  I84  R8309
   1 SMB_SCM_2_R3_SDA      A @T6G_MB_LIB.T6G(SCH_1):SMB_SCM_2_R3_SDA
   2 PVDDCR_CPU0_P0_PMSDA_R      B @T6G_MB_LIB.T6G(SCH_1):PVDDCR_CPU0_P0_PMSDA_R

Q_RES_0402LF-0,5%,1/16W,CHIP,CS00002JB13  I85  R8308
   1 SMB_SCM_2_R3_SCL      A @T6G_MB_LIB.T6G(SCH_1):SMB_SCM_2_R3_SCL
   2 PVDDCR_CPU0_P0_PMSCL_R      B @T6G_MB_LIB.T6G(SCH_1):PVDDCR_CPU0_P0_PMSCL_R

Q_RES_0402LF-33,5%,1/16W,CHIP,CS03302JB10  I89  R8311
   1 PWRGD_PVDDCR_CPU0_P0      A @T6G_MB_LIB.T6G(SCH_1):PWRGD_PVDDCR_CPU0_P0
   2 PWRGD_PVDDCR_CPU0_P0_R      B @T6G_MB_LIB.T6G(SCH_1):PWRGD_PVDDCR_CPU0_P0_R

Q_CAP_0402-1000PF,50V,5%,EMPTY,TMP_QCH21006JB10  I92  C467
   1 PWRGD_PVDDCR_CPU0_P0_R      A @T6G_MB_LIB.T6G(SCH_1):PWRGD_PVDDCR_CPU0_P0_R
   2    GND      B @T6G_MB_LIB.T6G(SCH_1):GND

Q_CAP_0402-470PF,50V,10%,X7R,TMP_QCH14706KB18  I95  PC469
   1 PVDDCR_CPU0_P0_TEMP0      A @T6G_MB_LIB.T6G(SCH_1):PVDDCR_CPU0_P0_TEMP0
   2    GND      B @T6G_MB_LIB.T6G(SCH_1):GND

Q_CAP_0402-470PF,50V,10%,X7R,TMP_QCH14706KB18  I98  PC472
   1 PVDDCR_SOC_P0_TEMP1      A @T6G_MB_LIB.T6G(SCH_1):PVDDCR_SOC_P0_TEMP1
   2    GND      B @T6G_MB_LIB.T6G(SCH_1):GND

Q_RES_0402LF-0,5%,1/16W,CHIP,CS00002JB13  I107  PR441
   1 NC_PVDDCR_CPU0_P0_IMON9      A @T6G_MB_LIB.T6G(SCH_1):NC_PVDDCR_CPU0_P0_IMON9
   2    GND      B @T6G_MB_LIB.T6G(SCH_1):GND

Q_RES_0402LF-0,5%,1/16W,CHIP,CS00002JB13  I108  PR440
   1 NC_PVDDCR_CPU0_P0_IMON8      A @T6G_MB_LIB.T6G(SCH_1):NC_PVDDCR_CPU0_P0_IMON8
   2    GND      B @T6G_MB_LIB.T6G(SCH_1):GND

Q_RES_0402LF-0,5%,1/16W,CHIP,CS00002JB13  I111  PR531
   1 NC_PVDDCR_CPU0_P0_IMON7      A @T6G_MB_LIB.T6G(SCH_1):NC_PVDDCR_CPU0_P0_IMON7
   2    GND      B @T6G_MB_LIB.T6G(SCH_1):GND

Q_CAP_0402-0.1UF,25V,10%,X7R,CH4104K1B00  I120  PC12
   1 PVDDCR_CPU0_P0_VCC      A @T6G_MB_LIB.T6G(SCH_1):PVDDCR_CPU0_P0_VCC
   2    GND      B @T6G_MB_LIB.T6G(SCH_1):GND

Q_CAP_C0402-10UF,6.3V,20%,X6S,CH6101MEB03  I129  PC470
   1 PVDDCR_CPU0_P0_VCCS      A @T6G_MB_LIB.T6G(SCH_1):PVDDCR_CPU0_P0_VCCS
   2    GND      B @T6G_MB_LIB.T6G(SCH_1):GND

Q_CAP_C0402-1UF,16V,10%,X6S,CH5103KEB01  I131  PC471
   1 PVDDCR_CPU0_P0_VCC      A @T6G_MB_LIB.T6G(SCH_1):PVDDCR_CPU0_P0_VCC
   2    GND      B @T6G_MB_LIB.T6G(SCH_1):GND

Q_RES_0402LF-1,1%,1/16W,CHIP,CS-1002FB04  I133  PR316
   1 PVDDCR_CPU0_P0_VCC      A @T6G_MB_LIB.T6G(SCH_1):PVDDCR_CPU0_P0_VCC
   2 P3V3_AUX      B @T6G_MB_LIB.T6G(SCH_1):P3V3_AUX

RAA229620GNPHA0-RAA229620GNP#HA0,SMLF,IC,ARF0TGP40A  I135  PU42
  27 PVDDCR_CPU0_P0_IMON1   CS11 @T6G_MB_LIB.T6G(SCH_1):PVDDCR_CPU0_P0_IMON1
  47 PVDDCR_CPU0_P0_VCC    VCC @T6G_MB_LIB.T6G(SCH_1):PVDDCR_CPU0_P0_VCC
  24 SVID_PVDDCR_CPU0_P0_SVTI_R   SVTI @T6G_MB_LIB.T6G(SCH_1):SVID_PVDDCR_CPU0_P0_SVTI_R
  14 PVDDCR_CPU0_P0_PMSCL_R  PMSCL @T6G_MB_LIB.T6G(SCH_1):PVDDCR_CPU0_P0_PMSCL_R
  22 SVID_PVDDCR_CPU0_P0_SVC_R1    SVC @T6G_MB_LIB.T6G(SCH_1):SVID_PVDDCR_CPU0_P0_SVC_R1
  32 PVDDCR_CPU0_P0_IMON6    CS6 @T6G_MB_LIB.T6G(SCH_1):PVDDCR_CPU0_P0_IMON6
  23 SVID_PVDDCR_CPU0_P0_SVTO_R   SVTO @T6G_MB_LIB.T6G(SCH_1):SVID_PVDDCR_CPU0_P0_SVTO_R
  18 PVDDCR_CPU0_P0_RESET_N_R RESET_L @T6G_MB_LIB.T6G(SCH_1):PVDDCR_CPU0_P0_RESET_N_R
  33 NC_PVDDCR_CPU0_P0_IMON7    CS5 @T6G_MB_LIB.T6G(SCH_1):NC_PVDDCR_CPU0_P0_IMON7
  34 NC_PVDDCR_CPU0_P0_IMON8    CS4 @T6G_MB_LIB.T6G(SCH_1):NC_PVDDCR_CPU0_P0_IMON8
  20 PWRGD_PVDDCR_SOC_P0_R    PG1 @T6G_MB_LIB.T6G(SCH_1):PWRGD_PVDDCR_SOC_P0_R
  21 SVID_PVDDCR_CPU0_P0_SVD_R1    SVD @T6G_MB_LIB.T6G(SCH_1):SVID_PVDDCR_CPU0_P0_SVD_R1
  15 PVDDCR_CPU0_P0_PMALERT_R NPMALERT @T6G_MB_LIB.T6G(SCH_1):PVDDCR_CPU0_P0_PMALERT_R
  17 PVDDCR_CPU0_P0_EN_R    EN0 @T6G_MB_LIB.T6G(SCH_1):PVDDCR_CPU0_P0_EN_R
  26 VSENSE_VSS_SENSE_A_P0  RGND0 @T6G_MB_LIB.T6G(SCH_1):VSENSE_VSS_SENSE_A_P0
  13 PVDDCR_CPU0_P0_PMSDA_R  PMSDA @T6G_MB_LIB.T6G(SCH_1):PVDDCR_CPU0_P0_PMSDA_R
   5 NC_PVDDCR_CPU0_P0_PWM8   PWM4 @T6G_MB_LIB.T6G(SCH_1):NC_PVDDCR_CPU0_P0_PWM8
   6 NC_PVDDCR_CPU0_P0_PWM7   PWM5 @T6G_MB_LIB.T6G(SCH_1):NC_PVDDCR_CPU0_P0_PWM7
  25 VSENSE_PVDDCR_CPU0_P0_VSEN0  VSEN0 @T6G_MB_LIB.T6G(SCH_1):VSENSE_PVDDCR_CPU0_P0_VSEN0
   2 PVDDCR_SOC_P0_PWM2   PWM1 @T6G_MB_LIB.T6G(SCH_1):PVDDCR_SOC_P0_PWM2
  16 PWRGD_PVDDCR_CPU0_P0_R    PG0 @T6G_MB_LIB.T6G(SCH_1):PWRGD_PVDDCR_CPU0_P0_R
   7 PVDDCR_CPU0_P0_PWM6   PWM6 @T6G_MB_LIB.T6G(SCH_1):PVDDCR_CPU0_P0_PWM6
  48 PVDDCR_CPU0_P0_VCCS   VCCS @T6G_MB_LIB.T6G(SCH_1):PVDDCR_CPU0_P0_VCCS
  45 PVDDCR_CPU0_P0_VMON VMON||IINSEN @T6G_MB_LIB.T6G(SCH_1):PVDDCR_CPU0_P0_VMON
  46 PVDDCR_CPU0_P0_VINSEN VINSEN @T6G_MB_LIB.T6G(SCH_1):PVDDCR_CPU0_P0_VINSEN
  44 PVDDCR_CPU0_P0_TEMP0  TEMP0 @T6G_MB_LIB.T6G(SCH_1):PVDDCR_CPU0_P0_TEMP0
  19 PVDD18_S5_P0  VDDIO @T6G_MB_LIB.T6G(SCH_1):PVDD18_S5_P0
  40 VSENSE_PVDDCR_SOC_P0_VSEN1  VSEN1 @T6G_MB_LIB.T6G(SCH_1):VSENSE_PVDDCR_SOC_P0_VSEN1
  39 VSENSE_VSS_SENSE_A_P0  RGND1 @T6G_MB_LIB.T6G(SCH_1):VSENSE_VSS_SENSE_A_P0
  37 PVDDCR_SOC_P0_IMON2    CS1 @T6G_MB_LIB.T6G(SCH_1):PVDDCR_SOC_P0_IMON2
  12 PVDDCR_CPU0_P0_PWM1  PWM11 @T6G_MB_LIB.T6G(SCH_1):PVDDCR_CPU0_P0_PWM1
   4 NC_PVDDCR_CPU0_P0_PWM9   PWM3 @T6G_MB_LIB.T6G(SCH_1):NC_PVDDCR_CPU0_P0_PWM9
  35 NC_PVDDCR_CPU0_P0_IMON9    CS3 @T6G_MB_LIB.T6G(SCH_1):NC_PVDDCR_CPU0_P0_IMON9
   3 PVDDCR_SOC_P0_PWM3   PWM2 @T6G_MB_LIB.T6G(SCH_1):PVDDCR_SOC_P0_PWM3
  36 PVDDCR_SOC_P0_IMON3    CS2 @T6G_MB_LIB.T6G(SCH_1):PVDDCR_SOC_P0_IMON3
  41 PVDDCR_CPU0_P0_OCP_N_R  OCP_L @T6G_MB_LIB.T6G(SCH_1):PVDDCR_CPU0_P0_OCP_N_R
  TH    GND TH_GND @T6G_MB_LIB.T6G(SCH_1):GND
  42 PVDDCR_SOC_P0_EN//ADDR_CFG EN1||ADDR_CFG @T6G_MB_LIB.T6G(SCH_1):PVDDCR_SOC_P0_EN//ADDR_CFG
  43 PVDDCR_SOC_P0_TEMP1  TEMP1 @T6G_MB_LIB.T6G(SCH_1):PVDDCR_SOC_P0_TEMP1
   1 PVDDCR_SOC_P0_PWM1   PWM0 @T6G_MB_LIB.T6G(SCH_1):PVDDCR_SOC_P0_PWM1
  38 PVDDCR_SOC_P0_IMON1    CS0 @T6G_MB_LIB.T6G(SCH_1):PVDDCR_SOC_P0_IMON1
   8 PVDDCR_CPU0_P0_PWM5   PWM7 @T6G_MB_LIB.T6G(SCH_1):PVDDCR_CPU0_P0_PWM5
  31 PVDDCR_CPU0_P0_IMON5    CS7 @T6G_MB_LIB.T6G(SCH_1):PVDDCR_CPU0_P0_IMON5
   9 PVDDCR_CPU0_P0_PWM4   PWM8 @T6G_MB_LIB.T6G(SCH_1):PVDDCR_CPU0_P0_PWM4
  30 PVDDCR_CPU0_P0_IMON4    CS8 @T6G_MB_LIB.T6G(SCH_1):PVDDCR_CPU0_P0_IMON4
  10 PVDDCR_CPU0_P0_PWM3   PWM9 @T6G_MB_LIB.T6G(SCH_1):PVDDCR_CPU0_P0_PWM3
  29 PVDDCR_CPU0_P0_IMON3    CS9 @T6G_MB_LIB.T6G(SCH_1):PVDDCR_CPU0_P0_IMON3
  11 PVDDCR_CPU0_P0_PWM2  PWM10 @T6G_MB_LIB.T6G(SCH_1):PVDDCR_CPU0_P0_PWM2
  28 PVDDCR_CPU0_P0_IMON2   CS10 @T6G_MB_LIB.T6G(SCH_1):PVDDCR_CPU0_P0_IMON2

Q_RES_0402LF-10K,1%,1/16W,EMPTY,CS31002FB08  I136  R6089
   1 PVDDCR_SOC_P0_EN_RC      A @T6G_MB_LIB.T6G(SCH_1):PVDDCR_SOC_P0_EN_RC
   2    GND      B @T6G_MB_LIB.T6G(SCH_1):GND

Q_CAP_0402-1000PF,50V,5%,X7R,TMP_QCH21006JB10  I138  C5018
   1    GND      A @T6G_MB_LIB.T6G(SCH_1):GND
   2 PWRGD_PVDDCR_SOC_P0      B @T6G_MB_LIB.T6G(SCH_1):PWRGD_PVDDCR_SOC_P0

Q_CAP_0402-1000PF,50V,5%,X7R,TMP_QCH21006JB10  I139  C5017
   1    GND      A @T6G_MB_LIB.T6G(SCH_1):GND
   2 PWRGD_PVDDCR_CPU0_P0      B @T6G_MB_LIB.T6G(SCH_1):PWRGD_PVDDCR_CPU0_P0

Q_CAP_0402-1000PF,50V,5%,X7R,TMP_QCH21006JB10  I142  C5011
   1 PVDDCR_CPU0_P0_PMALERT      A @T6G_MB_LIB.T6G(SCH_1):PVDDCR_CPU0_P0_PMALERT
   2    GND      B @T6G_MB_LIB.T6G(SCH_1):GND

CONN3_210HP1030BR1-CONN3_210-HP1-030BR1,THLF,IO,DFA  I143  PJ1
   3 SMB_SCM_2_R3_SCL      3 @T6G_MB_LIB.T6G(SCH_1):SMB_SCM_2_R3_SCL
   2 SMB_SCM_2_R3_SDA      2 @T6G_MB_LIB.T6G(SCH_1):SMB_SCM_2_R3_SDA
   1    GND      1 @T6G_MB_LIB.T6G(SCH_1):GND

Q_RES_0402LF-0,5%,1/16W,CHIP,CS00002JB13  I147  PR8005
   1 SVID_PVDDCR_CPU0_P0_SVC_R      A @T6G_MB_LIB.T6G(SCH_1):SVID_PVDDCR_CPU0_P0_SVC_R
   2 SVID_PVDDCR_CPU0_P0_SVC_R1      B @T6G_MB_LIB.T6G(SCH_1):SVID_PVDDCR_CPU0_P0_SVC_R1

Q_RES_0402LF-0,5%,1/16W,CHIP,CS00002JB13  I148  PR8006
   1 SVID_PVDDCR_CPU0_P0_SVD_R      A @T6G_MB_LIB.T6G(SCH_1):SVID_PVDDCR_CPU0_P0_SVD_R
   2 SVID_PVDDCR_CPU0_P0_SVD_R1      B @T6G_MB_LIB.T6G(SCH_1):SVID_PVDDCR_CPU0_P0_SVD_R1


DRAWING: @T6G_MB_LIB.T6G(SCH_1):PAGE169 

Q_RES_0402LF-0,5%,1/16W,CHIP,CS00002JB13  I3  PR445
   1 PVDDCR_CPU0_P0_PVCC      A @T6G_MB_LIB.T6G(SCH_1):PVDDCR_CPU0_P0_PVCC
   2 P5V_AUX      B @T6G_MB_LIB.T6G(SCH_1):P5V_AUX

Q_RES_0402LF-0,5%,1/16W,EMPTY,CS00002JB13  I4  PR446
   1 PVDDCR_CPU0_P0_PVCC      A @T6G_MB_LIB.T6G(SCH_1):PVDDCR_CPU0_P0_PVCC
   2 P3V3_AUX      B @T6G_MB_LIB.T6G(SCH_1):P3V3_AUX

ISL99390FRZTR5935-ISL99390FRZ-TR5935,SMLF,IC,AL099A  I16  PU43
  34 PVDDCR_CPU0_P0_PWM2    PWM @T6G_MB_LIB.T6G(SCH_1):PVDDCR_CPU0_P0_PWM2
  39 PVDDCR_CPU0_P0_VCCS  REFIN @T6G_MB_LIB.T6G(SCH_1):PVDDCR_CPU0_P0_VCCS
   3 PVDDCR_CPU0_P0_VCC2    VCC @T6G_MB_LIB.T6G(SCH_1):PVDDCR_CPU0_P0_VCC2
   2    GND   AGND @T6G_MB_LIB.T6G(SCH_1):GND
  33 SW_PVDDCR_CPU0_P0_BOOT2   BOOT @T6G_MB_LIB.T6G(SCH_1):SW_PVDDCR_CPU0_P0_BOOT2
25_29 SW_P12V_AUX_PVDDCR_CPU0_P0_FLT   VIN1 @T6G_MB_LIB.T6G(SCH_1):SW_P12V_AUX_PVDDCR_CPU0_P0_FLT
  32 SW_PVDDCR_CPU0_P0_PH2  PHASE @T6G_MB_LIB.T6G(SCH_1):SW_PVDDCR_CPU0_P0_PH2
   4 PVDDCR_CPU0_P0_PVCC   PVCC @T6G_MB_LIB.T6G(SCH_1):PVDDCR_CPU0_P0_PVCC
  36 PVDDCR_CPU0_P0_TEMP0 TOUT_FLT @T6G_MB_LIB.T6G(SCH_1):PVDDCR_CPU0_P0_TEMP0
  38 PVDDCR_CPU0_P0_IMON2   IOUT @T6G_MB_LIB.T6G(SCH_1):PVDDCR_CPU0_P0_IMON2
  37 PVDDCR_CPU0_P0_LSET2   LSET @T6G_MB_LIB.T6G(SCH_1):PVDDCR_CPU0_P0_LSET2
10_19 SW_PVDDCR_CPU0_P0_SW2     SW @T6G_MB_LIB.T6G(SCH_1):SW_PVDDCR_CPU0_P0_SW2
   5    GND  PGND1 @T6G_MB_LIB.T6G(SCH_1):GND
  30 SW_P12V_AUX_PVDDCR_CPU0_P0_FLT   VIN2 @T6G_MB_LIB.T6G(SCH_1):SW_P12V_AUX_PVDDCR_CPU0_P0_FLT
   1 PVDDCR_CPU0_P0_VOS2    VOS @T6G_MB_LIB.T6G(SCH_1):PVDDCR_CPU0_P0_VOS2
  40    GND  PGND3 @T6G_MB_LIB.T6G(SCH_1):GND
  35 PVDDCR_CPU0_P0_VCC2     EN @T6G_MB_LIB.T6G(SCH_1):PVDDCR_CPU0_P0_VCC2
  31 NC_PVDDCR_CPU0_P0_DNC2    DNC @T6G_MB_LIB.T6G(SCH_1):NC_PVDDCR_CPU0_P0_DNC2
   6 NC_PVDDCR_CPU0_P0_GL1_2    GL1 @T6G_MB_LIB.T6G(SCH_1):NC_PVDDCR_CPU0_P0_GL1_2
  41 NC_PVDDCR_CPU0_P0_GL2_2    GL2 @T6G_MB_LIB.T6G(SCH_1):NC_PVDDCR_CPU0_P0_GL2_2
7_9-20_24    GND  PGND2 @T6G_MB_LIB.T6G(SCH_1):GND

Q_RES_0402LF-2.2,1%,1/16W,CHIP,CS-2202FB01  I17  PR319
   1 PVDDCR_CPU0_P0_PVCC      A @T6G_MB_LIB.T6G(SCH_1):PVDDCR_CPU0_P0_PVCC
   2 PVDDCR_CPU0_P0_VCC2      B @T6G_MB_LIB.T6G(SCH_1):PVDDCR_CPU0_P0_VCC2

Q_CAP_C0402-2.2UF,10V,10%,X6S,CH5222KEB01  I19  PC478_C0P0_2
   1 PVDDCR_CPU0_P0_PVCC      A @T6G_MB_LIB.T6G(SCH_1):PVDDCR_CPU0_P0_PVCC
   2    GND      B @T6G_MB_LIB.T6G(SCH_1):GND

ISL99390FRZTR5935-ISL99390FRZ-TR5935,SMLF,IC,AL099A  I26  PU6
  34 PVDDCR_CPU0_P0_PWM1    PWM @T6G_MB_LIB.T6G(SCH_1):PVDDCR_CPU0_P0_PWM1
  39 PVDDCR_CPU0_P0_VCCS  REFIN @T6G_MB_LIB.T6G(SCH_1):PVDDCR_CPU0_P0_VCCS
   3 PVDDCR_CPU0_P0_VCC1    VCC @T6G_MB_LIB.T6G(SCH_1):PVDDCR_CPU0_P0_VCC1
   2    GND   AGND @T6G_MB_LIB.T6G(SCH_1):GND
  33 SW_PVDDCR_CPU0_P0_BOOT1   BOOT @T6G_MB_LIB.T6G(SCH_1):SW_PVDDCR_CPU0_P0_BOOT1
25_29 SW_P12V_AUX_PVDDCR_CPU0_P0_FLT   VIN1 @T6G_MB_LIB.T6G(SCH_1):SW_P12V_AUX_PVDDCR_CPU0_P0_FLT
  32 SW_PVDDCR_CPU0_P0_PH1  PHASE @T6G_MB_LIB.T6G(SCH_1):SW_PVDDCR_CPU0_P0_PH1
   4 PVDDCR_CPU0_P0_PVCC   PVCC @T6G_MB_LIB.T6G(SCH_1):PVDDCR_CPU0_P0_PVCC
  36 PVDDCR_CPU0_P0_TEMP0 TOUT_FLT @T6G_MB_LIB.T6G(SCH_1):PVDDCR_CPU0_P0_TEMP0
  38 PVDDCR_CPU0_P0_IMON1   IOUT @T6G_MB_LIB.T6G(SCH_1):PVDDCR_CPU0_P0_IMON1
  37 PVDDCR_CPU0_P0_LSET1   LSET @T6G_MB_LIB.T6G(SCH_1):PVDDCR_CPU0_P0_LSET1
10_19 SW_PVDDCR_CPU0_P0_SW1     SW @T6G_MB_LIB.T6G(SCH_1):SW_PVDDCR_CPU0_P0_SW1
   5    GND  PGND1 @T6G_MB_LIB.T6G(SCH_1):GND
  30 SW_P12V_AUX_PVDDCR_CPU0_P0_FLT   VIN2 @T6G_MB_LIB.T6G(SCH_1):SW_P12V_AUX_PVDDCR_CPU0_P0_FLT
   1 PVDDCR_CPU0_P0_VOS1    VOS @T6G_MB_LIB.T6G(SCH_1):PVDDCR_CPU0_P0_VOS1
  40    GND  PGND3 @T6G_MB_LIB.T6G(SCH_1):GND
  35 PVDDCR_CPU0_P0_VCC1     EN @T6G_MB_LIB.T6G(SCH_1):PVDDCR_CPU0_P0_VCC1
  31 NC_PVDDCR_CPU0_P0_DNC1    DNC @T6G_MB_LIB.T6G(SCH_1):NC_PVDDCR_CPU0_P0_DNC1
   6 NC_PVDDCR_CPU0_P0_GL1_1    GL1 @T6G_MB_LIB.T6G(SCH_1):NC_PVDDCR_CPU0_P0_GL1_1
  41 NC_PVDDCR_CPU0_P0_GL2_1    GL2 @T6G_MB_LIB.T6G(SCH_1):NC_PVDDCR_CPU0_P0_GL2_1
7_9-20_24    GND  PGND2 @T6G_MB_LIB.T6G(SCH_1):GND

Q_CAP_C0402-560PF,50V,10%,EMPTY,CH1566K1B09  I31  PC179
   1 SW_PVDDCR_CPU0_P0_SW2      A @T6G_MB_LIB.T6G(SCH_1):SW_PVDDCR_CPU0_P0_SW2
   2 SW_PVDDCR_CPU0_P0_SW2_RC      B @T6G_MB_LIB.T6G(SCH_1):SW_PVDDCR_CPU0_P0_SW2_RC

Q_RES_0402LF-5.6,1%,1/16W,CHIP,CS-5602FB01  I32  PR323
   1 SW_PVDDCR_CPU0_P0_BOOT2      A @T6G_MB_LIB.T6G(SCH_1):SW_PVDDCR_CPU0_P0_BOOT2
   2 SW_PVDDCR_CPU0_P0_BOOT2_RC      B @T6G_MB_LIB.T6G(SCH_1):SW_PVDDCR_CPU0_P0_BOOT2_RC

Q_CAP_0402-0.1UF,25V,10%,X7R,CH4104K1B00  I33  PC482_2
   1 SW_P12V_AUX_PVDDCR_CPU0_P0_FLT      A @T6G_MB_LIB.T6G(SCH_1):SW_P12V_AUX_PVDDCR_CPU0_P0_FLT
   2    GND      B @T6G_MB_LIB.T6G(SCH_1):GND

Q_INDUCTOR4P_14-150NH,SMLF,IND,CV+15^0TZ04  I62  PL52
   2 IND_CPU0_P0_CPL1      2 @T6G_MB_LIB.T6G(SCH_1):IND_CPU0_P0_CPL1
   3 IND_CPU0_P0_CPL2      3 @T6G_MB_LIB.T6G(SCH_1):IND_CPU0_P0_CPL2
   4 PVDDCR_CPU0_P0      4 @T6G_MB_LIB.T6G(SCH_1):PVDDCR_CPU0_P0
   1 SW_PVDDCR_CPU0_P0_SW2      1 @T6G_MB_LIB.T6G(SCH_1):SW_PVDDCR_CPU0_P0_SW2

Q_CAPP_SMLF-220UF,4V,20%,SPCAP,CH122KM8801  I64  PC108
   1 PVDDCR_CPU0_P0      A @T6G_MB_LIB.T6G(SCH_1):PVDDCR_CPU0_P0
   2    GND      B @T6G_MB_LIB.T6G(SCH_1):GND

Q_CAPP_SMLF-220UF,4V,20%,SPCAP,CH122KM8801  I65  PC494
   1 PVDDCR_CPU0_P0      A @T6G_MB_LIB.T6G(SCH_1):PVDDCR_CPU0_P0
   2    GND      B @T6G_MB_LIB.T6G(SCH_1):GND

Q_CAPP_SMLF-220UF,4V,20%,SPCAP,CH122KM8801  I66  PC495
   1 PVDDCR_CPU0_P0      A @T6G_MB_LIB.T6G(SCH_1):PVDDCR_CPU0_P0
   2    GND      B @T6G_MB_LIB.T6G(SCH_1):GND

Q_CAPP_SMLF-220UF,4V,20%,SPCAP,CH122KM8801  I67  PC496
   1 PVDDCR_CPU0_P0      A @T6G_MB_LIB.T6G(SCH_1):PVDDCR_CPU0_P0
   2    GND      B @T6G_MB_LIB.T6G(SCH_1):GND

Q_CAP_C0805-22UF,4V,20%,X6S,CH622KMEA03  I68  PC499_2
   1 PVDDCR_CPU0_P0      A @T6G_MB_LIB.T6G(SCH_1):PVDDCR_CPU0_P0
   2    GND      B @T6G_MB_LIB.T6G(SCH_1):GND

Q_CAP_0402-0.1UF,25V,10%,X7R,CH4104K1B00  I8  PC474_2
   1 PVDDCR_CPU0_P0_VCCS      A @T6G_MB_LIB.T6G(SCH_1):PVDDCR_CPU0_P0_VCCS
   2    GND      B @T6G_MB_LIB.T6G(SCH_1):GND

Q_RES_0402LF-8.87K,1%,1/16W,EMPTY,CS28872FB01  I10  PR321
   1    GND      A @T6G_MB_LIB.T6G(SCH_1):GND
   2 PVDDCR_CPU0_P0_LSET2      B @T6G_MB_LIB.T6G(SCH_1):PVDDCR_CPU0_P0_LSET2

Q_CAP_C0402-2.2UF,10V,10%,X6S,CH5222KEB01  I14  PC476
   1 PVDDCR_CPU0_P0_VCC2      A @T6G_MB_LIB.T6G(SCH_1):PVDDCR_CPU0_P0_VCC2
   2    GND      B @T6G_MB_LIB.T6G(SCH_1):GND

Q_CAP_0402-0.1UF,25V,10%,X7R,CH4104K1B00  I22  PC473_1
   1 PVDDCR_CPU0_P0_VCCS      A @T6G_MB_LIB.T6G(SCH_1):PVDDCR_CPU0_P0_VCCS
   2    GND      B @T6G_MB_LIB.T6G(SCH_1):GND

Q_RES_0402LF-1.5,1%,1/8W,EMPTY,CS-1504FB00  I28  PR496
   1 SW_PVDDCR_CPU0_P0_SW2_RC      A @T6G_MB_LIB.T6G(SCH_1):SW_PVDDCR_CPU0_P0_SW2_RC
   2    GND      B @T6G_MB_LIB.T6G(SCH_1):GND

Q_RES_0402LF-0,5%,1/16W,CHIP,CS00002JB13  I30  PR325
   1 PVDDCR_CPU0_P0_VOS2      A @T6G_MB_LIB.T6G(SCH_1):PVDDCR_CPU0_P0_VOS2
   2 PVDDCR_CPU0_P0      B @T6G_MB_LIB.T6G(SCH_1):PVDDCR_CPU0_P0

Q_CAP_C0402-1UF,25V,10%,X6S,CH5104KEB02  I34  PC480_2
   1 SW_P12V_AUX_PVDDCR_CPU0_P0_FLT      A @T6G_MB_LIB.T6G(SCH_1):SW_P12V_AUX_PVDDCR_CPU0_P0_FLT
   2    GND      B @T6G_MB_LIB.T6G(SCH_1):GND

Q_CAP_C0805-22UF,16V,20%,X6S,CH6223MEA01  I36  PC484_2
   1 SW_P12V_AUX_PVDDCR_CPU0_P0_FLT      A @T6G_MB_LIB.T6G(SCH_1):SW_P12V_AUX_PVDDCR_CPU0_P0_FLT
   2    GND      B @T6G_MB_LIB.T6G(SCH_1):GND

Q_CAP_C0805-22UF,16V,20%,X6S,CH6223MEA01  I37  PC486_2
   1 SW_P12V_AUX_PVDDCR_CPU0_P0_FLT      A @T6G_MB_LIB.T6G(SCH_1):SW_P12V_AUX_PVDDCR_CPU0_P0_FLT
   2    GND      B @T6G_MB_LIB.T6G(SCH_1):GND

Q_CAP_C0805-22UF,16V,20%,X6S,CH6223MEA01  I39  PC488_2
   1 SW_P12V_AUX_PVDDCR_CPU0_P0_FLT      A @T6G_MB_LIB.T6G(SCH_1):SW_P12V_AUX_PVDDCR_CPU0_P0_FLT
   2    GND      B @T6G_MB_LIB.T6G(SCH_1):GND

Q_RES_0402LF-1.5,1%,1/8W,EMPTY,CS-1504FB00  I42  PR495
   1 SW_PVDDCR_CPU0_P0_SW1_RC      A @T6G_MB_LIB.T6G(SCH_1):SW_PVDDCR_CPU0_P0_SW1_RC
   2    GND      B @T6G_MB_LIB.T6G(SCH_1):GND

Q_RES_0402LF-0,5%,1/16W,CHIP,CS00002JB13  I43  PR324
   1 PVDDCR_CPU0_P0_VOS1      A @T6G_MB_LIB.T6G(SCH_1):PVDDCR_CPU0_P0_VOS1
   2 PVDDCR_CPU0_P0      B @T6G_MB_LIB.T6G(SCH_1):PVDDCR_CPU0_P0

Q_CAP_C0402-2.2UF,10V,10%,X6S,CH5222KEB01  I45  PC475
   1 PVDDCR_CPU0_P0_VCC1      A @T6G_MB_LIB.T6G(SCH_1):PVDDCR_CPU0_P0_VCC1
   2    GND      B @T6G_MB_LIB.T6G(SCH_1):GND

Q_RES_0402LF-8.87K,1%,1/16W,EMPTY,CS28872FB01  I46  PR320
   1    GND      A @T6G_MB_LIB.T6G(SCH_1):GND
   2 PVDDCR_CPU0_P0_LSET1      B @T6G_MB_LIB.T6G(SCH_1):PVDDCR_CPU0_P0_LSET1

Q_RES_0402LF-2.2,1%,1/16W,CHIP,CS-2202FB01  I49  PR318
   1 PVDDCR_CPU0_P0_PVCC      A @T6G_MB_LIB.T6G(SCH_1):PVDDCR_CPU0_P0_PVCC
   2 PVDDCR_CPU0_P0_VCC1      B @T6G_MB_LIB.T6G(SCH_1):PVDDCR_CPU0_P0_VCC1

Q_CAP_C0402-2.2UF,10V,10%,X6S,CH5222KEB01  I51  PC477_C0P0_1
   1 PVDDCR_CPU0_P0_PVCC      A @T6G_MB_LIB.T6G(SCH_1):PVDDCR_CPU0_P0_PVCC
   2    GND      B @T6G_MB_LIB.T6G(SCH_1):GND

Q_CAP_0402-0.1UF,25V,10%,X7R,CH4104K1B00  I52  PC479_1
   1 SW_P12V_AUX_PVDDCR_CPU0_P0_FLT      A @T6G_MB_LIB.T6G(SCH_1):SW_P12V_AUX_PVDDCR_CPU0_P0_FLT
   2    GND      B @T6G_MB_LIB.T6G(SCH_1):GND

Q_CAP_C0402-1UF,25V,10%,X6S,CH5104KEB02  I53  PC481_1
   1 SW_P12V_AUX_PVDDCR_CPU0_P0_FLT      A @T6G_MB_LIB.T6G(SCH_1):SW_P12V_AUX_PVDDCR_CPU0_P0_FLT
   2    GND      B @T6G_MB_LIB.T6G(SCH_1):GND

Q_CAP_C0402-560PF,50V,10%,EMPTY,CH1566K1B09  I54  PC178
   1 SW_PVDDCR_CPU0_P0_SW1      A @T6G_MB_LIB.T6G(SCH_1):SW_PVDDCR_CPU0_P0_SW1
   2 SW_PVDDCR_CPU0_P0_SW1_RC      B @T6G_MB_LIB.T6G(SCH_1):SW_PVDDCR_CPU0_P0_SW1_RC

Q_RES_0402LF-5.6,1%,1/16W,CHIP,CS-5602FB01  I55  PR322
   1 SW_PVDDCR_CPU0_P0_BOOT1      A @T6G_MB_LIB.T6G(SCH_1):SW_PVDDCR_CPU0_P0_BOOT1
   2 SW_PVDDCR_CPU0_P0_BOOT1_RC      B @T6G_MB_LIB.T6G(SCH_1):SW_PVDDCR_CPU0_P0_BOOT1_RC

Q_CAP_C0805-22UF,16V,20%,X6S,CH6223MEA01  I57  PC483_1
   1 SW_P12V_AUX_PVDDCR_CPU0_P0_FLT      A @T6G_MB_LIB.T6G(SCH_1):SW_P12V_AUX_PVDDCR_CPU0_P0_FLT
   2    GND      B @T6G_MB_LIB.T6G(SCH_1):GND

Q_CAP_C0805-22UF,16V,20%,X6S,CH6223MEA01  I58  PC485_1
   1 SW_P12V_AUX_PVDDCR_CPU0_P0_FLT      A @T6G_MB_LIB.T6G(SCH_1):SW_P12V_AUX_PVDDCR_CPU0_P0_FLT
   2    GND      B @T6G_MB_LIB.T6G(SCH_1):GND

Q_CAP_C0805-22UF,16V,20%,X6S,CH6223MEA01  I59  PC487_1
   1 SW_P12V_AUX_PVDDCR_CPU0_P0_FLT      A @T6G_MB_LIB.T6G(SCH_1):SW_P12V_AUX_PVDDCR_CPU0_P0_FLT
   2    GND      B @T6G_MB_LIB.T6G(SCH_1):GND

Q_CAP_0402-0.22UF,16V,10%,X7R,CH4223K1B00  I61  PC490
   1 SW_PVDDCR_CPU0_P0_BOOT2_RC      A @T6G_MB_LIB.T6G(SCH_1):SW_PVDDCR_CPU0_P0_BOOT2_RC
   2 SW_PVDDCR_CPU0_P0_PH2      B @T6G_MB_LIB.T6G(SCH_1):SW_PVDDCR_CPU0_P0_PH2

Q_CAP_C0805-22UF,4V,20%,X6S,CH622KMEA03  I70  PC501_2
   1 PVDDCR_CPU0_P0      A @T6G_MB_LIB.T6G(SCH_1):PVDDCR_CPU0_P0
   2    GND      B @T6G_MB_LIB.T6G(SCH_1):GND

Q_CAPP_SMLF-220UF,4V,20%,SPCAP,CH122KM8801  I73  PC498
   1 PVDDCR_CPU0_P0      A @T6G_MB_LIB.T6G(SCH_1):PVDDCR_CPU0_P0
   2    GND      B @T6G_MB_LIB.T6G(SCH_1):GND

Q_CAP_0402-0.22UF,16V,10%,X7R,CH4223K1B00  I76  PC489
   1 SW_PVDDCR_CPU0_P0_BOOT1_RC      A @T6G_MB_LIB.T6G(SCH_1):SW_PVDDCR_CPU0_P0_BOOT1_RC
   2 SW_PVDDCR_CPU0_P0_PH1      B @T6G_MB_LIB.T6G(SCH_1):SW_PVDDCR_CPU0_P0_PH1

Q_INDUCTOR4P_14-150NH,SMLF,IND,CV+15^0TZ04  I77  PL51
   2 IND_CPU0_P0_CPL5      2 @T6G_MB_LIB.T6G(SCH_1):IND_CPU0_P0_CPL5
   3 IND_CPU0_P0_CPL1      3 @T6G_MB_LIB.T6G(SCH_1):IND_CPU0_P0_CPL1
   4 PVDDCR_CPU0_P0      4 @T6G_MB_LIB.T6G(SCH_1):PVDDCR_CPU0_P0
   1 SW_PVDDCR_CPU0_P0_SW1      1 @T6G_MB_LIB.T6G(SCH_1):SW_PVDDCR_CPU0_P0_SW1

Q_CAPP_THLF-270UF,16V,20%,OSCON,CC72703MD38  I79  PC491
   1 SW_P12V_AUX_PVDDCR_CPU0_P0_FLT      A @T6G_MB_LIB.T6G(SCH_1):SW_P12V_AUX_PVDDCR_CPU0_P0_FLT
   2    GND      B @T6G_MB_LIB.T6G(SCH_1):GND

Q_CAPP_THLF-270UF,16V,20%,OSCON,CC72703MD38  I81  PC492
   1 SW_P12V_AUX_PVDDCR_CPU0_P0_FLT      A @T6G_MB_LIB.T6G(SCH_1):SW_P12V_AUX_PVDDCR_CPU0_P0_FLT
   2    GND      B @T6G_MB_LIB.T6G(SCH_1):GND

Q_INDUCTOR_SMLF-50NH/86A,IND,CVA50^0MZ09  I82  PL53
   2 P12V_AUX      2 @T6G_MB_LIB.T6G(SCH_1):P12V_AUX
   1 SW_P12V_AUX_PVDDCR_CPU0_P0_FLT      1 @T6G_MB_LIB.T6G(SCH_1):SW_P12V_AUX_PVDDCR_CPU0_P0_FLT

Q_CAP_0402-0.1UF,25V,10%,X7R,CH4104K1B00  I85  PC479
   1 P12V_AUX      A @T6G_MB_LIB.T6G(SCH_1):P12V_AUX
   2    GND      B @T6G_MB_LIB.T6G(SCH_1):GND

Q_CAP_0402-0.1UF,25V,10%,X7R,CH4104K1B00  I87  PC497
   1 PVDDCR_CPU0_P0      A @T6G_MB_LIB.T6G(SCH_1):PVDDCR_CPU0_P0
   2    GND      B @T6G_MB_LIB.T6G(SCH_1):GND

Q_CAP_C0805-22UF,4V,20%,X6S,CH622KMEA03  I88  PC500_1
   1 PVDDCR_CPU0_P0      A @T6G_MB_LIB.T6G(SCH_1):PVDDCR_CPU0_P0
   2    GND      B @T6G_MB_LIB.T6G(SCH_1):GND

Q_CAP_C0805-22UF,4V,20%,X6S,CH622KMEA03  I89  PC502_1
   1 PVDDCR_CPU0_P0      A @T6G_MB_LIB.T6G(SCH_1):PVDDCR_CPU0_P0
   2    GND      B @T6G_MB_LIB.T6G(SCH_1):GND

Q_RES_0402LF-1K,1%,1/16W,CHIP,CS21002FB06  I90  PR447
   1 PVDDCR_CPU0_P0      A @T6G_MB_LIB.T6G(SCH_1):PVDDCR_CPU0_P0
   2    GND      B @T6G_MB_LIB.T6G(SCH_1):GND


DRAWING: @T6G_MB_LIB.T6G(SCH_1):PAGE170 

Q_RES_0402LF-1.5,1%,1/8W,EMPTY,CS-1504FB00  I18  PR499
   1 SW_PVDDCR_CPU0_P0_SW4_RC      A @T6G_MB_LIB.T6G(SCH_1):SW_PVDDCR_CPU0_P0_SW4_RC
   2    GND      B @T6G_MB_LIB.T6G(SCH_1):GND

Q_CAP_C0402-560PF,50V,10%,EMPTY,CH1566K1B09  I19  PC181
   1 SW_PVDDCR_CPU0_P0_SW4      A @T6G_MB_LIB.T6G(SCH_1):SW_PVDDCR_CPU0_P0_SW4
   2 SW_PVDDCR_CPU0_P0_SW4_RC      B @T6G_MB_LIB.T6G(SCH_1):SW_PVDDCR_CPU0_P0_SW4_RC

Q_RES_0402LF-5.6,1%,1/16W,CHIP,CS-5602FB01  I20  PR349
   1 SW_PVDDCR_CPU0_P0_BOOT4      A @T6G_MB_LIB.T6G(SCH_1):SW_PVDDCR_CPU0_P0_BOOT4
   2 SW_PVDDCR_CPU0_P0_BOOT4_RC      B @T6G_MB_LIB.T6G(SCH_1):SW_PVDDCR_CPU0_P0_BOOT4_RC

Q_CAP_0402-0.1UF,25V,10%,X7R,CH4104K1B00  I21  PC551_4
   1 SW_P12V_AUX_PVDDCR_CPU0_P0_FLT      A @T6G_MB_LIB.T6G(SCH_1):SW_P12V_AUX_PVDDCR_CPU0_P0_FLT
   2    GND      B @T6G_MB_LIB.T6G(SCH_1):GND

Q_CAP_C0805-22UF,16V,20%,X6S,CH6223MEA01  I23  PC555_4
   1 SW_P12V_AUX_PVDDCR_CPU0_P0_FLT      A @T6G_MB_LIB.T6G(SCH_1):SW_P12V_AUX_PVDDCR_CPU0_P0_FLT
   2    GND      B @T6G_MB_LIB.T6G(SCH_1):GND

Q_RES_0402LF-0,5%,1/16W,CHIP,CS00002JB13  I26  PR350
   1 PVDDCR_CPU0_P0_VOS3      A @T6G_MB_LIB.T6G(SCH_1):PVDDCR_CPU0_P0_VOS3
   2 PVDDCR_CPU0_P0      B @T6G_MB_LIB.T6G(SCH_1):PVDDCR_CPU0_P0

Q_RES_0402LF-8.87K,1%,1/16W,EMPTY,CS28872FB01  I33  PR346
   1    GND      A @T6G_MB_LIB.T6G(SCH_1):GND
   2 PVDDCR_CPU0_P0_LSET3      B @T6G_MB_LIB.T6G(SCH_1):PVDDCR_CPU0_P0_LSET3

Q_CAP_0402-0.1UF,25V,10%,X7R,CH4104K1B00  I2  PC545_4
   1 PVDDCR_CPU0_P0_VCCS      A @T6G_MB_LIB.T6G(SCH_1):PVDDCR_CPU0_P0_VCCS
   2    GND      B @T6G_MB_LIB.T6G(SCH_1):GND

Q_CAP_C0402-2.2UF,10V,10%,X6S,CH5222KEB01  I6  PC547
   1 PVDDCR_CPU0_P0_VCC4      A @T6G_MB_LIB.T6G(SCH_1):PVDDCR_CPU0_P0_VCC4
   2    GND      B @T6G_MB_LIB.T6G(SCH_1):GND

ISL99390FRZTR5935-ISL99390FRZ-TR5935,SMLF,IC,AL099A  I9  PU47
  34 PVDDCR_CPU0_P0_PWM4    PWM @T6G_MB_LIB.T6G(SCH_1):PVDDCR_CPU0_P0_PWM4
  39 PVDDCR_CPU0_P0_VCCS  REFIN @T6G_MB_LIB.T6G(SCH_1):PVDDCR_CPU0_P0_VCCS
   3 PVDDCR_CPU0_P0_VCC4    VCC @T6G_MB_LIB.T6G(SCH_1):PVDDCR_CPU0_P0_VCC4
   2    GND   AGND @T6G_MB_LIB.T6G(SCH_1):GND
  33 SW_PVDDCR_CPU0_P0_BOOT4   BOOT @T6G_MB_LIB.T6G(SCH_1):SW_PVDDCR_CPU0_P0_BOOT4
25_29 SW_P12V_AUX_PVDDCR_CPU0_P0_FLT   VIN1 @T6G_MB_LIB.T6G(SCH_1):SW_P12V_AUX_PVDDCR_CPU0_P0_FLT
  32 SW_PVDDCR_CPU0_P0_PH4  PHASE @T6G_MB_LIB.T6G(SCH_1):SW_PVDDCR_CPU0_P0_PH4
   4 PVDDCR_CPU0_P0_PVCC   PVCC @T6G_MB_LIB.T6G(SCH_1):PVDDCR_CPU0_P0_PVCC
  36 PVDDCR_CPU0_P0_TEMP0 TOUT_FLT @T6G_MB_LIB.T6G(SCH_1):PVDDCR_CPU0_P0_TEMP0
  38 PVDDCR_CPU0_P0_IMON4   IOUT @T6G_MB_LIB.T6G(SCH_1):PVDDCR_CPU0_P0_IMON4
  37 PVDDCR_CPU0_P0_LSET4   LSET @T6G_MB_LIB.T6G(SCH_1):PVDDCR_CPU0_P0_LSET4
10_19 SW_PVDDCR_CPU0_P0_SW4     SW @T6G_MB_LIB.T6G(SCH_1):SW_PVDDCR_CPU0_P0_SW4
   5    GND  PGND1 @T6G_MB_LIB.T6G(SCH_1):GND
  30 SW_P12V_AUX_PVDDCR_CPU0_P0_FLT   VIN2 @T6G_MB_LIB.T6G(SCH_1):SW_P12V_AUX_PVDDCR_CPU0_P0_FLT
   1 PVDDCR_CPU0_P0_VOS4    VOS @T6G_MB_LIB.T6G(SCH_1):PVDDCR_CPU0_P0_VOS4
  40    GND  PGND3 @T6G_MB_LIB.T6G(SCH_1):GND
  35 PVDDCR_CPU0_P0_VCC4     EN @T6G_MB_LIB.T6G(SCH_1):PVDDCR_CPU0_P0_VCC4
  31 NC_PVDDCR_CPU0_P0_DNC4    DNC @T6G_MB_LIB.T6G(SCH_1):NC_PVDDCR_CPU0_P0_DNC4
   6 NC_PVDDCR_CPU0_P0_GL1_4    GL1 @T6G_MB_LIB.T6G(SCH_1):NC_PVDDCR_CPU0_P0_GL1_4
  41 NC_PVDDCR_CPU0_P0_GL2_4    GL2 @T6G_MB_LIB.T6G(SCH_1):NC_PVDDCR_CPU0_P0_GL2_4
7_9-20_24    GND  PGND2 @T6G_MB_LIB.T6G(SCH_1):GND

Q_RES_0402LF-8.87K,1%,1/16W,EMPTY,CS28872FB01  I11  PR347
   1    GND      A @T6G_MB_LIB.T6G(SCH_1):GND
   2 PVDDCR_CPU0_P0_LSET4      B @T6G_MB_LIB.T6G(SCH_1):PVDDCR_CPU0_P0_LSET4

Q_RES_0402LF-2.2,1%,1/16W,CHIP,CS-2202FB01  I12  PR345
   1 PVDDCR_CPU0_P0_PVCC      A @T6G_MB_LIB.T6G(SCH_1):PVDDCR_CPU0_P0_PVCC
   2 PVDDCR_CPU0_P0_VCC4      B @T6G_MB_LIB.T6G(SCH_1):PVDDCR_CPU0_P0_VCC4

Q_CAP_C0402-2.2UF,10V,10%,X6S,CH5222KEB01  I15  PC549_C0P0_4
   1 PVDDCR_CPU0_P0_PVCC      A @T6G_MB_LIB.T6G(SCH_1):PVDDCR_CPU0_P0_PVCC
   2    GND      B @T6G_MB_LIB.T6G(SCH_1):GND

Q_CAP_C0402-1UF,25V,10%,X6S,CH5104KEB02  I22  PC553_4
   1 SW_P12V_AUX_PVDDCR_CPU0_P0_FLT      A @T6G_MB_LIB.T6G(SCH_1):SW_P12V_AUX_PVDDCR_CPU0_P0_FLT
   2    GND      B @T6G_MB_LIB.T6G(SCH_1):GND

Q_CAP_C0805-22UF,16V,20%,X6S,CH6223MEA01  I24  PC557_4
   1 SW_P12V_AUX_PVDDCR_CPU0_P0_FLT      A @T6G_MB_LIB.T6G(SCH_1):SW_P12V_AUX_PVDDCR_CPU0_P0_FLT
   2    GND      B @T6G_MB_LIB.T6G(SCH_1):GND

Q_CAP_0402-0.1UF,25V,10%,X7R,CH4104K1B00  I27  PC544_3
   1 PVDDCR_CPU0_P0_VCCS      A @T6G_MB_LIB.T6G(SCH_1):PVDDCR_CPU0_P0_VCCS
   2    GND      B @T6G_MB_LIB.T6G(SCH_1):GND

Q_CAP_C0402-2.2UF,10V,10%,X6S,CH5222KEB01  I36  PC546
   1 PVDDCR_CPU0_P0_VCC3      A @T6G_MB_LIB.T6G(SCH_1):PVDDCR_CPU0_P0_VCC3
   2    GND      B @T6G_MB_LIB.T6G(SCH_1):GND

Q_RES_0402LF-2.2,1%,1/16W,CHIP,CS-2202FB01  I37  PR344
   1 PVDDCR_CPU0_P0_PVCC      A @T6G_MB_LIB.T6G(SCH_1):PVDDCR_CPU0_P0_PVCC
   2 PVDDCR_CPU0_P0_VCC3      B @T6G_MB_LIB.T6G(SCH_1):PVDDCR_CPU0_P0_VCC3

ISL99390FRZTR5935-ISL99390FRZ-TR5935,SMLF,IC,AL099A  I38  PU46
  34 PVDDCR_CPU0_P0_PWM3    PWM @T6G_MB_LIB.T6G(SCH_1):PVDDCR_CPU0_P0_PWM3
  39 PVDDCR_CPU0_P0_VCCS  REFIN @T6G_MB_LIB.T6G(SCH_1):PVDDCR_CPU0_P0_VCCS
   3 PVDDCR_CPU0_P0_VCC3    VCC @T6G_MB_LIB.T6G(SCH_1):PVDDCR_CPU0_P0_VCC3
   2    GND   AGND @T6G_MB_LIB.T6G(SCH_1):GND
  33 SW_PVDDCR_CPU0_P0_BOOT3   BOOT @T6G_MB_LIB.T6G(SCH_1):SW_PVDDCR_CPU0_P0_BOOT3
25_29 SW_P12V_AUX_PVDDCR_CPU0_P0_FLT   VIN1 @T6G_MB_LIB.T6G(SCH_1):SW_P12V_AUX_PVDDCR_CPU0_P0_FLT
  32 SW_PVDDCR_CPU0_P0_PH3  PHASE @T6G_MB_LIB.T6G(SCH_1):SW_PVDDCR_CPU0_P0_PH3
   4 PVDDCR_CPU0_P0_PVCC   PVCC @T6G_MB_LIB.T6G(SCH_1):PVDDCR_CPU0_P0_PVCC
  36 PVDDCR_CPU0_P0_TEMP0 TOUT_FLT @T6G_MB_LIB.T6G(SCH_1):PVDDCR_CPU0_P0_TEMP0
  38 PVDDCR_CPU0_P0_IMON3   IOUT @T6G_MB_LIB.T6G(SCH_1):PVDDCR_CPU0_P0_IMON3
  37 PVDDCR_CPU0_P0_LSET3   LSET @T6G_MB_LIB.T6G(SCH_1):PVDDCR_CPU0_P0_LSET3
10_19 SW_PVDDCR_CPU0_P0_SW3     SW @T6G_MB_LIB.T6G(SCH_1):SW_PVDDCR_CPU0_P0_SW3
   5    GND  PGND1 @T6G_MB_LIB.T6G(SCH_1):GND
  30 SW_P12V_AUX_PVDDCR_CPU0_P0_FLT   VIN2 @T6G_MB_LIB.T6G(SCH_1):SW_P12V_AUX_PVDDCR_CPU0_P0_FLT
   1 PVDDCR_CPU0_P0_VOS3    VOS @T6G_MB_LIB.T6G(SCH_1):PVDDCR_CPU0_P0_VOS3
  40    GND  PGND3 @T6G_MB_LIB.T6G(SCH_1):GND
  35 PVDDCR_CPU0_P0_VCC3     EN @T6G_MB_LIB.T6G(SCH_1):PVDDCR_CPU0_P0_VCC3
  31 NC_PVDDCR_CPU0_P0_DNC3    DNC @T6G_MB_LIB.T6G(SCH_1):NC_PVDDCR_CPU0_P0_DNC3
   6 NC_PVDDCR_CPU0_P0_GL1_3    GL1 @T6G_MB_LIB.T6G(SCH_1):NC_PVDDCR_CPU0_P0_GL1_3
  41 NC_PVDDCR_CPU0_P0_GL2_3    GL2 @T6G_MB_LIB.T6G(SCH_1):NC_PVDDCR_CPU0_P0_GL2_3
7_9-20_24    GND  PGND2 @T6G_MB_LIB.T6G(SCH_1):GND

Q_CAP_C0402-2.2UF,10V,10%,X6S,CH5222KEB01  I40  PC548_C0P0_3
   1 PVDDCR_CPU0_P0_PVCC      A @T6G_MB_LIB.T6G(SCH_1):PVDDCR_CPU0_P0_PVCC
   2    GND      B @T6G_MB_LIB.T6G(SCH_1):GND

Q_CAP_0402-0.1UF,25V,10%,X7R,CH4104K1B00  I43  PC552_3
   1 SW_P12V_AUX_PVDDCR_CPU0_P0_FLT      A @T6G_MB_LIB.T6G(SCH_1):SW_P12V_AUX_PVDDCR_CPU0_P0_FLT
   2    GND      B @T6G_MB_LIB.T6G(SCH_1):GND

Q_RES_0402LF-1.5,1%,1/8W,EMPTY,CS-1504FB00  I44  PR498
   1 SW_PVDDCR_CPU0_P0_SW3_RC      A @T6G_MB_LIB.T6G(SCH_1):SW_PVDDCR_CPU0_P0_SW3_RC
   2    GND      B @T6G_MB_LIB.T6G(SCH_1):GND

Q_CAP_C0402-560PF,50V,10%,EMPTY,CH1566K1B09  I45  PC180
   1 SW_PVDDCR_CPU0_P0_SW3      A @T6G_MB_LIB.T6G(SCH_1):SW_PVDDCR_CPU0_P0_SW3
   2 SW_PVDDCR_CPU0_P0_SW3_RC      B @T6G_MB_LIB.T6G(SCH_1):SW_PVDDCR_CPU0_P0_SW3_RC

Q_RES_0402LF-5.6,1%,1/16W,CHIP,CS-5602FB01  I46  PR348
   1 SW_PVDDCR_CPU0_P0_BOOT3      A @T6G_MB_LIB.T6G(SCH_1):SW_PVDDCR_CPU0_P0_BOOT3
   2 SW_PVDDCR_CPU0_P0_BOOT3_RC      B @T6G_MB_LIB.T6G(SCH_1):SW_PVDDCR_CPU0_P0_BOOT3_RC

Q_CAP_C0402-1UF,25V,10%,X6S,CH5104KEB02  I47  PC550_3
   1 SW_P12V_AUX_PVDDCR_CPU0_P0_FLT      A @T6G_MB_LIB.T6G(SCH_1):SW_P12V_AUX_PVDDCR_CPU0_P0_FLT
   2    GND      B @T6G_MB_LIB.T6G(SCH_1):GND

Q_CAP_C0805-22UF,16V,20%,X6S,CH6223MEA01  I48  PC554_3
   1 SW_P12V_AUX_PVDDCR_CPU0_P0_FLT      A @T6G_MB_LIB.T6G(SCH_1):SW_P12V_AUX_PVDDCR_CPU0_P0_FLT
   2    GND      B @T6G_MB_LIB.T6G(SCH_1):GND

Q_CAP_C0805-22UF,16V,20%,X6S,CH6223MEA01  I49  PC556_3
   1 SW_P12V_AUX_PVDDCR_CPU0_P0_FLT      A @T6G_MB_LIB.T6G(SCH_1):SW_P12V_AUX_PVDDCR_CPU0_P0_FLT
   2    GND      B @T6G_MB_LIB.T6G(SCH_1):GND

Q_RES_0402LF-0,5%,1/16W,CHIP,CS00002JB13  I50  PR351
   1 PVDDCR_CPU0_P0_VOS4      A @T6G_MB_LIB.T6G(SCH_1):PVDDCR_CPU0_P0_VOS4
   2 PVDDCR_CPU0_P0      B @T6G_MB_LIB.T6G(SCH_1):PVDDCR_CPU0_P0

Q_INDUCTOR4P_14-150NH,SMLF,IND,CV+15^0TZ04  I52  PL60
   2 IND_CPU0_P0_CPL3      2 @T6G_MB_LIB.T6G(SCH_1):IND_CPU0_P0_CPL3
   3    GND      3 @T6G_MB_LIB.T6G(SCH_1):GND
   4 PVDDCR_CPU0_P0      4 @T6G_MB_LIB.T6G(SCH_1):PVDDCR_CPU0_P0
   1 SW_PVDDCR_CPU0_P0_SW4      1 @T6G_MB_LIB.T6G(SCH_1):SW_PVDDCR_CPU0_P0_SW4

Q_CAP_0402-0.22UF,16V,10%,X7R,CH4223K1B00  I53  PC561
   1 SW_PVDDCR_CPU0_P0_BOOT4_RC      A @T6G_MB_LIB.T6G(SCH_1):SW_PVDDCR_CPU0_P0_BOOT4_RC
   2 SW_PVDDCR_CPU0_P0_PH4      B @T6G_MB_LIB.T6G(SCH_1):SW_PVDDCR_CPU0_P0_PH4

Q_CAP_C0805-22UF,16V,20%,X6S,CH6223MEA01  I55  PC559_4
   1 SW_P12V_AUX_PVDDCR_CPU0_P0_FLT      A @T6G_MB_LIB.T6G(SCH_1):SW_P12V_AUX_PVDDCR_CPU0_P0_FLT
   2    GND      B @T6G_MB_LIB.T6G(SCH_1):GND

Q_CAP_C0805-22UF,4V,20%,X6S,CH622KMEA03  I58  PC563_4
   1 PVDDCR_CPU0_P0      A @T6G_MB_LIB.T6G(SCH_1):PVDDCR_CPU0_P0
   2    GND      B @T6G_MB_LIB.T6G(SCH_1):GND

Q_CAP_C0805-22UF,4V,20%,X6S,CH622KMEA03  I60  PC565_4
   1 PVDDCR_CPU0_P0      A @T6G_MB_LIB.T6G(SCH_1):PVDDCR_CPU0_P0
   2    GND      B @T6G_MB_LIB.T6G(SCH_1):GND

Q_CAP_0402-0.22UF,16V,10%,X7R,CH4223K1B00  I63  PC560
   1 SW_PVDDCR_CPU0_P0_BOOT3_RC      A @T6G_MB_LIB.T6G(SCH_1):SW_PVDDCR_CPU0_P0_BOOT3_RC
   2 SW_PVDDCR_CPU0_P0_PH3      B @T6G_MB_LIB.T6G(SCH_1):SW_PVDDCR_CPU0_P0_PH3

Q_INDUCTOR4P_14-150NH,SMLF,IND,CV+15^0TZ04  I64  PL59
   2 IND_CPU0_P0_CPL2      2 @T6G_MB_LIB.T6G(SCH_1):IND_CPU0_P0_CPL2
   3 IND_CPU0_P0_CPL3      3 @T6G_MB_LIB.T6G(SCH_1):IND_CPU0_P0_CPL3
   4 PVDDCR_CPU0_P0      4 @T6G_MB_LIB.T6G(SCH_1):PVDDCR_CPU0_P0
   1 SW_PVDDCR_CPU0_P0_SW3      1 @T6G_MB_LIB.T6G(SCH_1):SW_PVDDCR_CPU0_P0_SW3

Q_CAP_C0805-22UF,16V,20%,X6S,CH6223MEA01  I66  PC558_3
   1 SW_P12V_AUX_PVDDCR_CPU0_P0_FLT      A @T6G_MB_LIB.T6G(SCH_1):SW_P12V_AUX_PVDDCR_CPU0_P0_FLT
   2    GND      B @T6G_MB_LIB.T6G(SCH_1):GND

Q_CAP_C0805-22UF,4V,20%,X6S,CH622KMEA03  I70  PC562_3
   1 PVDDCR_CPU0_P0      A @T6G_MB_LIB.T6G(SCH_1):PVDDCR_CPU0_P0
   2    GND      B @T6G_MB_LIB.T6G(SCH_1):GND

Q_CAP_C0805-22UF,4V,20%,X6S,CH622KMEA03  I71  PC564_3
   1 PVDDCR_CPU0_P0      A @T6G_MB_LIB.T6G(SCH_1):PVDDCR_CPU0_P0
   2    GND      B @T6G_MB_LIB.T6G(SCH_1):GND


DRAWING: @T6G_MB_LIB.T6G(SCH_1):PAGE173 

Q_CAP_0402-0.1UF,25V,10%,X7R,CH4104K1B00  I4  PC578_8
   1 PVDDCR_CPU0_P0_VCCS      A @T6G_MB_LIB.T6G(SCH_1):PVDDCR_CPU0_P0_VCCS
   2    GND      B @T6G_MB_LIB.T6G(SCH_1):GND

Q_RES_0402LF-1.5,1%,1/8W,EMPTY,CS-1504FB00  I19  PR503
   1 SW_PVDDCR_SOC_P0_SW2_RC      A @T6G_MB_LIB.T6G(SCH_1):SW_PVDDCR_SOC_P0_SW2_RC
   2    GND      B @T6G_MB_LIB.T6G(SCH_1):GND

Q_RES_0402LF-5.6,1%,1/16W,CHIP,CS-5602FB01  I22  PR361
   1 SW_PVDDCR_SOC_P0_BOOT2      A @T6G_MB_LIB.T6G(SCH_1):SW_PVDDCR_SOC_P0_BOOT2
   2 SW_PVDDCR_SOC_P0_BOOT2_RC      B @T6G_MB_LIB.T6G(SCH_1):SW_PVDDCR_SOC_P0_BOOT2_RC

Q_CAP_C0402-1UF,25V,10%,X6S,CH5104KEB02  I23  PC584_2
   1 SW_P12V_AUX_PVDDCR_SOC_P0_FLT      A @T6G_MB_LIB.T6G(SCH_1):SW_P12V_AUX_PVDDCR_SOC_P0_FLT
   2    GND      B @T6G_MB_LIB.T6G(SCH_1):GND

Q_CAP_C0805-22UF,16V,20%,X6S,CH6223MEA01  I24  PC588_2
   1 SW_P12V_AUX_PVDDCR_SOC_P0_FLT      A @T6G_MB_LIB.T6G(SCH_1):SW_P12V_AUX_PVDDCR_SOC_P0_FLT
   2    GND      B @T6G_MB_LIB.T6G(SCH_1):GND

Q_CAP_C0805-22UF,16V,20%,X6S,CH6223MEA01  I25  PC590_2
   1 SW_P12V_AUX_PVDDCR_SOC_P0_FLT      A @T6G_MB_LIB.T6G(SCH_1):SW_P12V_AUX_PVDDCR_SOC_P0_FLT
   2    GND      B @T6G_MB_LIB.T6G(SCH_1):GND

Q_CAP_0402-0.1UF,25V,10%,X7R,CH4104K1B00  I29  PC577_7
   1 PVDDCR_CPU0_P0_VCCS      A @T6G_MB_LIB.T6G(SCH_1):PVDDCR_CPU0_P0_VCCS
   2    GND      B @T6G_MB_LIB.T6G(SCH_1):GND

Q_CAP_0402-0.1UF,25V,10%,X7R,CH4104K1B00  I43  PC583_1
   1 SW_P12V_AUX_PVDDCR_SOC_P0_FLT      A @T6G_MB_LIB.T6G(SCH_1):SW_P12V_AUX_PVDDCR_SOC_P0_FLT
   2    GND      B @T6G_MB_LIB.T6G(SCH_1):GND

Q_RES_0402LF-5.6,1%,1/16W,CHIP,CS-5602FB01  I48  PR360
   1 SW_PVDDCR_SOC_P0_BOOT1      A @T6G_MB_LIB.T6G(SCH_1):SW_PVDDCR_SOC_P0_BOOT1
   2 SW_PVDDCR_SOC_P0_BOOT1_RC      B @T6G_MB_LIB.T6G(SCH_1):SW_PVDDCR_SOC_P0_BOOT1_RC

Q_CAP_0402-0.22UF,16V,10%,X7R,CH4223K1B00  I52  PC594
   1 SW_PVDDCR_SOC_P0_BOOT2_RC      A @T6G_MB_LIB.T6G(SCH_1):SW_PVDDCR_SOC_P0_BOOT2_RC
   2 SW_PVDDCR_SOC_P0_PH2      B @T6G_MB_LIB.T6G(SCH_1):SW_PVDDCR_SOC_P0_PH2

Q_CAPP_SMLF-470UF,2.5V,20%,EMPTY,CH747LM8825  I63  PC597
   1 PVDDCR_SOC_P0      A @T6G_MB_LIB.T6G(SCH_1):PVDDCR_SOC_P0
   2    GND      B @T6G_MB_LIB.T6G(SCH_1):GND

Q_CAPP_SMLF-470UF,2.5V,20%,SPCAP,CH747LM8825  I66  PC601
   1 PVDDCR_SOC_P0      A @T6G_MB_LIB.T6G(SCH_1):PVDDCR_SOC_P0
   2    GND      B @T6G_MB_LIB.T6G(SCH_1):GND

Q_CAP_0402-0.22UF,16V,10%,X7R,CH4223K1B00  I68  PC593
   1 SW_PVDDCR_SOC_P0_BOOT1_RC      A @T6G_MB_LIB.T6G(SCH_1):SW_PVDDCR_SOC_P0_BOOT1_RC
   2 SW_PVDDCR_SOC_P0_PH1      B @T6G_MB_LIB.T6G(SCH_1):SW_PVDDCR_SOC_P0_PH1

Q_INDUCTOR4P_14-150NH,SMLF,IND,CV+15^0TZ04  I69  PL63
   2 IND_SOC_P0_CPL2      2 @T6G_MB_LIB.T6G(SCH_1):IND_SOC_P0_CPL2
   3    GND      3 @T6G_MB_LIB.T6G(SCH_1):GND
   4 PVDDCR_SOC_P0      4 @T6G_MB_LIB.T6G(SCH_1):PVDDCR_SOC_P0
   1 SW_PVDDCR_SOC_P0_SW1      1 @T6G_MB_LIB.T6G(SCH_1):SW_PVDDCR_SOC_P0_SW1

Q_CAP_0402-0.1UF,25V,10%,X7R,CH4104K1B00  I79  PC599
   1 PVDDCR_SOC_P0      A @T6G_MB_LIB.T6G(SCH_1):PVDDCR_SOC_P0
   2    GND      B @T6G_MB_LIB.T6G(SCH_1):GND

Q_CAP_C0805-22UF,4V,20%,X6S,CH622KMEA03  I83  PC604_1
   1 PVDDCR_SOC_P0      A @T6G_MB_LIB.T6G(SCH_1):PVDDCR_SOC_P0
   2    GND      B @T6G_MB_LIB.T6G(SCH_1):GND

Q_RES_0402LF-8.87K,1%,1/16W,EMPTY,CS28872FB01  I8  PR359
   1    GND      A @T6G_MB_LIB.T6G(SCH_1):GND
   2 PVDDCR_SOC_P0_LSET2      B @T6G_MB_LIB.T6G(SCH_1):PVDDCR_SOC_P0_LSET2

Q_CAP_C0402-2.2UF,10V,10%,X6S,CH5222KEB01  I11  PC580
   1 PVDDCR_SOC_P0_VCC2      A @T6G_MB_LIB.T6G(SCH_1):PVDDCR_SOC_P0_VCC2
   2    GND      B @T6G_MB_LIB.T6G(SCH_1):GND

Q_RES_0402LF-2.2,1%,1/16W,CHIP,CS-2202FB01  I12  PR357
   1 PVDDCR_CPU0_P0_PVCC      A @T6G_MB_LIB.T6G(SCH_1):PVDDCR_CPU0_P0_PVCC
   2 PVDDCR_SOC_P0_VCC2      B @T6G_MB_LIB.T6G(SCH_1):PVDDCR_SOC_P0_VCC2

Q_CAP_C0402-2.2UF,10V,10%,X6S,CH5222KEB01  I14  PC582_SOP0_2
   1 PVDDCR_CPU0_P0_PVCC      A @T6G_MB_LIB.T6G(SCH_1):PVDDCR_CPU0_P0_PVCC
   2    GND      B @T6G_MB_LIB.T6G(SCH_1):GND

Q_RES_0402LF-0,5%,1/16W,CHIP,CS00002JB13  I18  PR363
   1 PVDDCR_SOC_P0_VOS2      A @T6G_MB_LIB.T6G(SCH_1):PVDDCR_SOC_P0_VOS2
   2 PVDDCR_SOC_P0      B @T6G_MB_LIB.T6G(SCH_1):PVDDCR_SOC_P0

Q_CAP_0402-0.1UF,25V,10%,X7R,CH4104K1B00  I21  PC586_2
   1 SW_P12V_AUX_PVDDCR_SOC_P0_FLT      A @T6G_MB_LIB.T6G(SCH_1):SW_P12V_AUX_PVDDCR_SOC_P0_FLT
   2    GND      B @T6G_MB_LIB.T6G(SCH_1):GND

Q_RES_0402LF-0,5%,1/16W,CHIP,CS00002JB13  I27  PR362
   1 PVDDCR_SOC_P0_VOS1      A @T6G_MB_LIB.T6G(SCH_1):PVDDCR_SOC_P0_VOS1
   2 PVDDCR_SOC_P0      B @T6G_MB_LIB.T6G(SCH_1):PVDDCR_SOC_P0

Q_RES_0402LF-8.87K,1%,1/16W,EMPTY,CS28872FB01  I32  PR358
   1    GND      A @T6G_MB_LIB.T6G(SCH_1):GND
   2 PVDDCR_SOC_P0_LSET1      B @T6G_MB_LIB.T6G(SCH_1):PVDDCR_SOC_P0_LSET1

Q_CAP_C0402-2.2UF,10V,10%,X6S,CH5222KEB01  I36  PC579
   1 PVDDCR_SOC_P0_VCC1      A @T6G_MB_LIB.T6G(SCH_1):PVDDCR_SOC_P0_VCC1
   2    GND      B @T6G_MB_LIB.T6G(SCH_1):GND

Q_RES_0402LF-2.2,1%,1/16W,CHIP,CS-2202FB01  I38  PR356
   1 PVDDCR_CPU0_P0_PVCC      A @T6G_MB_LIB.T6G(SCH_1):PVDDCR_CPU0_P0_PVCC
   2 PVDDCR_SOC_P0_VCC1      B @T6G_MB_LIB.T6G(SCH_1):PVDDCR_SOC_P0_VCC1

Q_CAP_C0402-2.2UF,10V,10%,X6S,CH5222KEB01  I40  PC581_SOP0_1
   1 PVDDCR_CPU0_P0_PVCC      A @T6G_MB_LIB.T6G(SCH_1):PVDDCR_CPU0_P0_PVCC
   2    GND      B @T6G_MB_LIB.T6G(SCH_1):GND

ISL99390FRZTR5935-ISL99390FRZ-TR5935,SMLF,IC,AL099A  I41  PU49
  34 PVDDCR_SOC_P0_PWM1    PWM @T6G_MB_LIB.T6G(SCH_1):PVDDCR_SOC_P0_PWM1
  39 PVDDCR_CPU0_P0_VCCS  REFIN @T6G_MB_LIB.T6G(SCH_1):PVDDCR_CPU0_P0_VCCS
   3 PVDDCR_SOC_P0_VCC1    VCC @T6G_MB_LIB.T6G(SCH_1):PVDDCR_SOC_P0_VCC1
   2    GND   AGND @T6G_MB_LIB.T6G(SCH_1):GND
  33 SW_PVDDCR_SOC_P0_BOOT1   BOOT @T6G_MB_LIB.T6G(SCH_1):SW_PVDDCR_SOC_P0_BOOT1
25_29 SW_P12V_AUX_PVDDCR_SOC_P0_FLT   VIN1 @T6G_MB_LIB.T6G(SCH_1):SW_P12V_AUX_PVDDCR_SOC_P0_FLT
  32 SW_PVDDCR_SOC_P0_PH1  PHASE @T6G_MB_LIB.T6G(SCH_1):SW_PVDDCR_SOC_P0_PH1
   4 PVDDCR_CPU0_P0_PVCC   PVCC @T6G_MB_LIB.T6G(SCH_1):PVDDCR_CPU0_P0_PVCC
  36 PVDDCR_SOC_P0_TEMP1 TOUT_FLT @T6G_MB_LIB.T6G(SCH_1):PVDDCR_SOC_P0_TEMP1
  38 PVDDCR_SOC_P0_IMON1   IOUT @T6G_MB_LIB.T6G(SCH_1):PVDDCR_SOC_P0_IMON1
  37 PVDDCR_SOC_P0_LSET1   LSET @T6G_MB_LIB.T6G(SCH_1):PVDDCR_SOC_P0_LSET1
10_19 SW_PVDDCR_SOC_P0_SW1     SW @T6G_MB_LIB.T6G(SCH_1):SW_PVDDCR_SOC_P0_SW1
   5    GND  PGND1 @T6G_MB_LIB.T6G(SCH_1):GND
  30 SW_P12V_AUX_PVDDCR_SOC_P0_FLT   VIN2 @T6G_MB_LIB.T6G(SCH_1):SW_P12V_AUX_PVDDCR_SOC_P0_FLT
   1 PVDDCR_SOC_P0_VOS1    VOS @T6G_MB_LIB.T6G(SCH_1):PVDDCR_SOC_P0_VOS1
  40    GND  PGND3 @T6G_MB_LIB.T6G(SCH_1):GND
  35 PVDDCR_SOC_P0_VCC1     EN @T6G_MB_LIB.T6G(SCH_1):PVDDCR_SOC_P0_VCC1
  31 NC_PVDDCR_SOC_P0_DNC1    DNC @T6G_MB_LIB.T6G(SCH_1):NC_PVDDCR_SOC_P0_DNC1
   6 NC_PVDDCR_SOC_P0_GL1_1    GL1 @T6G_MB_LIB.T6G(SCH_1):NC_PVDDCR_SOC_P0_GL1_1
  41 NC_PVDDCR_SOC_P0_GL2_1    GL2 @T6G_MB_LIB.T6G(SCH_1):NC_PVDDCR_SOC_P0_GL2_1
7_9-20_24    GND  PGND2 @T6G_MB_LIB.T6G(SCH_1):GND

Q_CAP_C0402-1UF,25V,10%,X6S,CH5104KEB02  I44  PC585_1
   1 SW_P12V_AUX_PVDDCR_SOC_P0_FLT      A @T6G_MB_LIB.T6G(SCH_1):SW_P12V_AUX_PVDDCR_SOC_P0_FLT
   2    GND      B @T6G_MB_LIB.T6G(SCH_1):GND

Q_RES_0402LF-1.5,1%,1/8W,EMPTY,CS-1504FB00  I45  PR502
   1 SW_PVDDCR_SOC_P0_SW1_RC      A @T6G_MB_LIB.T6G(SCH_1):SW_PVDDCR_SOC_P0_SW1_RC
   2    GND      B @T6G_MB_LIB.T6G(SCH_1):GND

Q_CAP_C0402-560PF,50V,10%,EMPTY,CH1566K1B09  I46  PC185
   1 SW_PVDDCR_SOC_P0_SW1      A @T6G_MB_LIB.T6G(SCH_1):SW_PVDDCR_SOC_P0_SW1
   2 SW_PVDDCR_SOC_P0_SW1_RC      B @T6G_MB_LIB.T6G(SCH_1):SW_PVDDCR_SOC_P0_SW1_RC

Q_CAP_C0805-22UF,16V,20%,X6S,CH6223MEA01  I49  PC587_1
   1 SW_P12V_AUX_PVDDCR_SOC_P0_FLT      A @T6G_MB_LIB.T6G(SCH_1):SW_P12V_AUX_PVDDCR_SOC_P0_FLT
   2    GND      B @T6G_MB_LIB.T6G(SCH_1):GND

Q_CAP_C0805-22UF,16V,20%,X6S,CH6223MEA01  I50  PC589_1
   1 SW_P12V_AUX_PVDDCR_SOC_P0_FLT      A @T6G_MB_LIB.T6G(SCH_1):SW_P12V_AUX_PVDDCR_SOC_P0_FLT
   2    GND      B @T6G_MB_LIB.T6G(SCH_1):GND

Q_CAP_C0805-22UF,16V,20%,X6S,CH6223MEA01  I51  PC591_1
   1 SW_P12V_AUX_PVDDCR_SOC_P0_FLT      A @T6G_MB_LIB.T6G(SCH_1):SW_P12V_AUX_PVDDCR_SOC_P0_FLT
   2    GND      B @T6G_MB_LIB.T6G(SCH_1):GND

Q_INDUCTOR4P_14-150NH,SMLF,IND,CV+15^0TZ04  I53  PL64
   2 IND_SOC_P0_CPL3      2 @T6G_MB_LIB.T6G(SCH_1):IND_SOC_P0_CPL3
   3 IND_SOC_P0_CPL2      3 @T6G_MB_LIB.T6G(SCH_1):IND_SOC_P0_CPL2
   4 PVDDCR_SOC_P0      4 @T6G_MB_LIB.T6G(SCH_1):PVDDCR_SOC_P0
   1 SW_PVDDCR_SOC_P0_SW2      1 @T6G_MB_LIB.T6G(SCH_1):SW_PVDDCR_SOC_P0_SW2

Q_CAP_C0805-22UF,16V,20%,X6S,CH6223MEA01  I56  PC592_2
   1 SW_P12V_AUX_PVDDCR_SOC_P0_FLT      A @T6G_MB_LIB.T6G(SCH_1):SW_P12V_AUX_PVDDCR_SOC_P0_FLT
   2    GND      B @T6G_MB_LIB.T6G(SCH_1):GND

Q_CAP_C0805-22UF,16V,20%,X6S,CH6223MEA01  I57  PC595_2
   1 SW_P12V_AUX_PVDDCR_SOC_P0_FLT      A @T6G_MB_LIB.T6G(SCH_1):SW_P12V_AUX_PVDDCR_SOC_P0_FLT
   2    GND      B @T6G_MB_LIB.T6G(SCH_1):GND

Q_CAP_C0805-22UF,4V,20%,X6S,CH622KMEA03  I59  PC600_2
   1 PVDDCR_SOC_P0      A @T6G_MB_LIB.T6G(SCH_1):PVDDCR_SOC_P0
   2    GND      B @T6G_MB_LIB.T6G(SCH_1):GND

Q_CAP_C0805-22UF,4V,20%,X6S,CH622KMEA03  I61  PC603_2
   1 PVDDCR_SOC_P0      A @T6G_MB_LIB.T6G(SCH_1):PVDDCR_SOC_P0
   2    GND      B @T6G_MB_LIB.T6G(SCH_1):GND

Q_CAPP_SMLF-470UF,2.5V,20%,SPCAP,CH747LM8825  I64  PC598
   1 PVDDCR_SOC_P0      A @T6G_MB_LIB.T6G(SCH_1):PVDDCR_SOC_P0
   2    GND      B @T6G_MB_LIB.T6G(SCH_1):GND

Q_CAP_C0805-22UF,16V,20%,X6S,CH6223MEA01  I72  PC593_1
   1 SW_P12V_AUX_PVDDCR_SOC_P0_FLT      A @T6G_MB_LIB.T6G(SCH_1):SW_P12V_AUX_PVDDCR_SOC_P0_FLT
   2    GND      B @T6G_MB_LIB.T6G(SCH_1):GND

Q_CAPP_THLF-270UF,16V,20%,OSCON,CC72703MD38  I73  PC596
   1 SW_P12V_AUX_PVDDCR_SOC_P0_FLT      A @T6G_MB_LIB.T6G(SCH_1):SW_P12V_AUX_PVDDCR_SOC_P0_FLT
   2    GND      B @T6G_MB_LIB.T6G(SCH_1):GND

Q_INDUCTOR_SMLF-50NH/86A,IND,CVA50^0MZ09  I74  PL65
   2 P12V_AUX      2 @T6G_MB_LIB.T6G(SCH_1):P12V_AUX
   1 SW_P12V_AUX_PVDDCR_SOC_P0_FLT      1 @T6G_MB_LIB.T6G(SCH_1):SW_P12V_AUX_PVDDCR_SOC_P0_FLT

Q_CAP_0402-0.1UF,25V,10%,X7R,CH4104K1B00  I77  PC583
   1 P12V_AUX      A @T6G_MB_LIB.T6G(SCH_1):P12V_AUX
   2    GND      B @T6G_MB_LIB.T6G(SCH_1):GND

Q_CAP_C0805-22UF,4V,20%,X6S,CH622KMEA03  I80  PC602_1
   1 PVDDCR_SOC_P0      A @T6G_MB_LIB.T6G(SCH_1):PVDDCR_SOC_P0
   2    GND      B @T6G_MB_LIB.T6G(SCH_1):GND

Q_RES_0402LF-1K,1%,1/16W,CHIP,CS21002FB06  I82  PR334
   1 PVDDCR_SOC_P0      A @T6G_MB_LIB.T6G(SCH_1):PVDDCR_SOC_P0
   2    GND      B @T6G_MB_LIB.T6G(SCH_1):GND

Q_CAP_C0402-560PF,50V,10%,EMPTY,CH1566K1B09  I85  PC187
   1 SW_PVDDCR_SOC_P0_SW2      A @T6G_MB_LIB.T6G(SCH_1):SW_PVDDCR_SOC_P0_SW2
   2 SW_PVDDCR_SOC_P0_SW2_RC      B @T6G_MB_LIB.T6G(SCH_1):SW_PVDDCR_SOC_P0_SW2_RC

ISL99390FRZTR5935-ISL99390FRZ-TR5935,SMLF,IC,AL099A  I86  PU50
  34 PVDDCR_SOC_P0_PWM2    PWM @T6G_MB_LIB.T6G(SCH_1):PVDDCR_SOC_P0_PWM2
  39 PVDDCR_CPU0_P0_VCCS  REFIN @T6G_MB_LIB.T6G(SCH_1):PVDDCR_CPU0_P0_VCCS
   3 PVDDCR_SOC_P0_VCC2    VCC @T6G_MB_LIB.T6G(SCH_1):PVDDCR_SOC_P0_VCC2
   2    GND   AGND @T6G_MB_LIB.T6G(SCH_1):GND
  33 SW_PVDDCR_SOC_P0_BOOT2   BOOT @T6G_MB_LIB.T6G(SCH_1):SW_PVDDCR_SOC_P0_BOOT2
25_29 SW_P12V_AUX_PVDDCR_SOC_P0_FLT   VIN1 @T6G_MB_LIB.T6G(SCH_1):SW_P12V_AUX_PVDDCR_SOC_P0_FLT
  32 SW_PVDDCR_SOC_P0_PH2  PHASE @T6G_MB_LIB.T6G(SCH_1):SW_PVDDCR_SOC_P0_PH2
   4 PVDDCR_CPU0_P0_PVCC   PVCC @T6G_MB_LIB.T6G(SCH_1):PVDDCR_CPU0_P0_PVCC
  36 PVDDCR_SOC_P0_TEMP1 TOUT_FLT @T6G_MB_LIB.T6G(SCH_1):PVDDCR_SOC_P0_TEMP1
  38 PVDDCR_SOC_P0_IMON2   IOUT @T6G_MB_LIB.T6G(SCH_1):PVDDCR_SOC_P0_IMON2
  37 PVDDCR_SOC_P0_LSET2   LSET @T6G_MB_LIB.T6G(SCH_1):PVDDCR_SOC_P0_LSET2
10_19 SW_PVDDCR_SOC_P0_SW2     SW @T6G_MB_LIB.T6G(SCH_1):SW_PVDDCR_SOC_P0_SW2
   5    GND  PGND1 @T6G_MB_LIB.T6G(SCH_1):GND
  30 SW_P12V_AUX_PVDDCR_SOC_P0_FLT   VIN2 @T6G_MB_LIB.T6G(SCH_1):SW_P12V_AUX_PVDDCR_SOC_P0_FLT
   1 PVDDCR_SOC_P0_VOS2    VOS @T6G_MB_LIB.T6G(SCH_1):PVDDCR_SOC_P0_VOS2
  40    GND  PGND3 @T6G_MB_LIB.T6G(SCH_1):GND
  35 PVDDCR_SOC_P0_VCC2     EN @T6G_MB_LIB.T6G(SCH_1):PVDDCR_SOC_P0_VCC2
  31 NC_PVDDCR_SOC_P0_DNC2    DNC @T6G_MB_LIB.T6G(SCH_1):NC_PVDDCR_SOC_P0_DNC2
   6 NC_PVDDCR_SOC_P0_GL1_2    GL1 @T6G_MB_LIB.T6G(SCH_1):NC_PVDDCR_SOC_P0_GL1_2
  41 NC_PVDDCR_SOC_P0_GL2_2    GL2 @T6G_MB_LIB.T6G(SCH_1):NC_PVDDCR_SOC_P0_GL2_2
7_9-20_24    GND  PGND2 @T6G_MB_LIB.T6G(SCH_1):GND

Q_CAP_C0805-22UF,16V,20%,X6S,CH6223MEA01  I87  PC8009
   1 SW_P12V_AUX_PVDDCR_SOC_P0_FLT      A @T6G_MB_LIB.T6G(SCH_1):SW_P12V_AUX_PVDDCR_SOC_P0_FLT
   2    GND      B @T6G_MB_LIB.T6G(SCH_1):GND

Q_CAP_C0805-22UF,16V,20%,X6S,CH6223MEA01  I88  PC8010
   1 SW_P12V_AUX_PVDDCR_SOC_P0_FLT      A @T6G_MB_LIB.T6G(SCH_1):SW_P12V_AUX_PVDDCR_SOC_P0_FLT
   2    GND      B @T6G_MB_LIB.T6G(SCH_1):GND


DRAWING: @T6G_MB_LIB.T6G(SCH_1):PAGE174 

Q_RES_0402LF-8.87K,1%,1/16W,EMPTY,CS28872FB01  I7  PR365
   1    GND      A @T6G_MB_LIB.T6G(SCH_1):GND
   2 PVDDCR_SOC_P0_LSET3      B @T6G_MB_LIB.T6G(SCH_1):PVDDCR_SOC_P0_LSET3

Q_RES_0402LF-5.6,1%,1/16W,CHIP,CS-5602FB01  I20  PR366
   1 SW_PVDDCR_SOC_P0_BOOT3      A @T6G_MB_LIB.T6G(SCH_1):SW_PVDDCR_SOC_P0_BOOT3
   2 SW_PVDDCR_SOC_P0_BOOT3_RC      B @T6G_MB_LIB.T6G(SCH_1):SW_PVDDCR_SOC_P0_BOOT3_RC

Q_CAP_C0402-1UF,25V,10%,X6S,CH5104KEB02  I21  PC608_3
   1 SW_P12V_AUX_PVDDCR_SOC_P0_FLT      A @T6G_MB_LIB.T6G(SCH_1):SW_P12V_AUX_PVDDCR_SOC_P0_FLT
   2    GND      B @T6G_MB_LIB.T6G(SCH_1):GND

Q_CAP_C0805-22UF,16V,20%,X6S,CH6223MEA01  I22  PC610_3
   1 SW_P12V_AUX_PVDDCR_SOC_P0_FLT      A @T6G_MB_LIB.T6G(SCH_1):SW_P12V_AUX_PVDDCR_SOC_P0_FLT
   2    GND      B @T6G_MB_LIB.T6G(SCH_1):GND

Q_INDUCTOR4P_14-150NH,SMLF,IND,CV+15^0TZ04  I25  PL66
   2 IND_SOC_P0_CPL0      2 @T6G_MB_LIB.T6G(SCH_1):IND_SOC_P0_CPL0
   3 IND_SOC_P0_CPL3      3 @T6G_MB_LIB.T6G(SCH_1):IND_SOC_P0_CPL3
   4 PVDDCR_SOC_P0      4 @T6G_MB_LIB.T6G(SCH_1):PVDDCR_SOC_P0
   1 SW_PVDDCR_SOC_P0_SW3      1 @T6G_MB_LIB.T6G(SCH_1):SW_PVDDCR_SOC_P0_SW3

Q_CAP_C0805-22UF,4V,20%,X6S,CH622KMEA03  I29  PC615_3
   1 PVDDCR_SOC_P0      A @T6G_MB_LIB.T6G(SCH_1):PVDDCR_SOC_P0
   2    GND      B @T6G_MB_LIB.T6G(SCH_1):GND

Q_CAP_C0805-22UF,16V,20%,X6S,CH6223MEA01  I31  PC611_3
   1 SW_P12V_AUX_PVDDCR_SOC_P0_FLT      A @T6G_MB_LIB.T6G(SCH_1):SW_P12V_AUX_PVDDCR_SOC_P0_FLT
   2    GND      B @T6G_MB_LIB.T6G(SCH_1):GND

Q_CAP_C0805-22UF,16V,20%,X6S,CH6223MEA01  I32  PC613_3
   1 SW_P12V_AUX_PVDDCR_SOC_P0_FLT      A @T6G_MB_LIB.T6G(SCH_1):SW_P12V_AUX_PVDDCR_SOC_P0_FLT
   2    GND      B @T6G_MB_LIB.T6G(SCH_1):GND

Q_CAP_0402-0.1UF,25V,10%,X7R,CH4104K1B00  I37  PC609_3
   1 SW_P12V_AUX_PVDDCR_SOC_P0_FLT      A @T6G_MB_LIB.T6G(SCH_1):SW_P12V_AUX_PVDDCR_SOC_P0_FLT
   2    GND      B @T6G_MB_LIB.T6G(SCH_1):GND

ISL99390FRZTR5935-ISL99390FRZ-TR5935,SMLF,IC,AL099A  I38  PU51
  34 PVDDCR_SOC_P0_PWM3    PWM @T6G_MB_LIB.T6G(SCH_1):PVDDCR_SOC_P0_PWM3
  39 PVDDCR_CPU0_P0_VCCS  REFIN @T6G_MB_LIB.T6G(SCH_1):PVDDCR_CPU0_P0_VCCS
   3 PVDDCR_SOC_P0_VCC3    VCC @T6G_MB_LIB.T6G(SCH_1):PVDDCR_SOC_P0_VCC3
   2    GND   AGND @T6G_MB_LIB.T6G(SCH_1):GND
  33 SW_PVDDCR_SOC_P0_BOOT3   BOOT @T6G_MB_LIB.T6G(SCH_1):SW_PVDDCR_SOC_P0_BOOT3
25_29 SW_P12V_AUX_PVDDCR_SOC_P0_FLT   VIN1 @T6G_MB_LIB.T6G(SCH_1):SW_P12V_AUX_PVDDCR_SOC_P0_FLT
  32 SW_PVDDCR_SOC_P0_PH3  PHASE @T6G_MB_LIB.T6G(SCH_1):SW_PVDDCR_SOC_P0_PH3
   4 PVDDCR_CPU0_P0_PVCC   PVCC @T6G_MB_LIB.T6G(SCH_1):PVDDCR_CPU0_P0_PVCC
  36 PVDDCR_SOC_P0_TEMP1 TOUT_FLT @T6G_MB_LIB.T6G(SCH_1):PVDDCR_SOC_P0_TEMP1
  38 PVDDCR_SOC_P0_IMON3   IOUT @T6G_MB_LIB.T6G(SCH_1):PVDDCR_SOC_P0_IMON3
  37 PVDDCR_SOC_P0_LSET3   LSET @T6G_MB_LIB.T6G(SCH_1):PVDDCR_SOC_P0_LSET3
10_19 SW_PVDDCR_SOC_P0_SW3     SW @T6G_MB_LIB.T6G(SCH_1):SW_PVDDCR_SOC_P0_SW3
   5    GND  PGND1 @T6G_MB_LIB.T6G(SCH_1):GND
  30 SW_P12V_AUX_PVDDCR_SOC_P0_FLT   VIN2 @T6G_MB_LIB.T6G(SCH_1):SW_P12V_AUX_PVDDCR_SOC_P0_FLT
   1 PVDDCR_SOC_P0_VOS3    VOS @T6G_MB_LIB.T6G(SCH_1):PVDDCR_SOC_P0_VOS3
  40    GND  PGND3 @T6G_MB_LIB.T6G(SCH_1):GND
  35 PVDDCR_SOC_P0_VCC3     EN @T6G_MB_LIB.T6G(SCH_1):PVDDCR_SOC_P0_VCC3
  31 NC_PVDDCR_SOC_P0_DNC3    DNC @T6G_MB_LIB.T6G(SCH_1):NC_PVDDCR_SOC_P0_DNC3
   6 NC_PVDDCR_SOC_P0_GL1_3    GL1 @T6G_MB_LIB.T6G(SCH_1):NC_PVDDCR_SOC_P0_GL1_3
  41 NC_PVDDCR_SOC_P0_GL2_3    GL2 @T6G_MB_LIB.T6G(SCH_1):NC_PVDDCR_SOC_P0_GL2_3
7_9-20_24    GND  PGND2 @T6G_MB_LIB.T6G(SCH_1):GND

Q_CAP_0402-0.1UF,25V,10%,X7R,CH4104K1B00  I2  PC605_9
   1 PVDDCR_CPU0_P0_VCCS      A @T6G_MB_LIB.T6G(SCH_1):PVDDCR_CPU0_P0_VCCS
   2    GND      B @T6G_MB_LIB.T6G(SCH_1):GND

Q_RES_0402LF-1.5,1%,1/8W,EMPTY,CS-1504FB00  I10  PR505
   1 SW_PVDDCR_SOC_P0_SW3_RC      A @T6G_MB_LIB.T6G(SCH_1):SW_PVDDCR_SOC_P0_SW3_RC
   2    GND      B @T6G_MB_LIB.T6G(SCH_1):GND

Q_RES_0402LF-0,5%,1/16W,CHIP,CS00002JB13  I11  PR367
   1 PVDDCR_SOC_P0_VOS3      A @T6G_MB_LIB.T6G(SCH_1):PVDDCR_SOC_P0_VOS3
   2 PVDDCR_SOC_P0      B @T6G_MB_LIB.T6G(SCH_1):PVDDCR_SOC_P0

Q_CAP_C0402-560PF,50V,10%,EMPTY,CH1566K1B09  I12  PC188
   1 SW_PVDDCR_SOC_P0_SW3      A @T6G_MB_LIB.T6G(SCH_1):SW_PVDDCR_SOC_P0_SW3
   2 SW_PVDDCR_SOC_P0_SW3_RC      B @T6G_MB_LIB.T6G(SCH_1):SW_PVDDCR_SOC_P0_SW3_RC

Q_CAP_C0402-2.2UF,10V,10%,X6S,CH5222KEB01  I14  PC606
   1 PVDDCR_SOC_P0_VCC3      A @T6G_MB_LIB.T6G(SCH_1):PVDDCR_SOC_P0_VCC3
   2    GND      B @T6G_MB_LIB.T6G(SCH_1):GND

Q_RES_0402LF-2.2,1%,1/16W,CHIP,CS-2202FB01  I15  PR364
   1 PVDDCR_CPU0_P0_PVCC      A @T6G_MB_LIB.T6G(SCH_1):PVDDCR_CPU0_P0_PVCC
   2 PVDDCR_SOC_P0_VCC3      B @T6G_MB_LIB.T6G(SCH_1):PVDDCR_SOC_P0_VCC3

Q_CAP_C0402-2.2UF,10V,10%,X6S,CH5222KEB01  I19  PC607_SOP0_3
   1 PVDDCR_CPU0_P0_PVCC      A @T6G_MB_LIB.T6G(SCH_1):PVDDCR_CPU0_P0_PVCC
   2    GND      B @T6G_MB_LIB.T6G(SCH_1):GND

Q_INDUCTOR_SMLF-0.22UH/33A,IND,CV+22Y0EZ00  I24  PL62
   2 IND_SOC_P0_CPL0      2 @T6G_MB_LIB.T6G(SCH_1):IND_SOC_P0_CPL0
   1    GND      1 @T6G_MB_LIB.T6G(SCH_1):GND

Q_CAP_C0805-22UF,4V,20%,X6S,CH622KMEA03  I27  PC614_3
   1 PVDDCR_SOC_P0      A @T6G_MB_LIB.T6G(SCH_1):PVDDCR_SOC_P0
   2    GND      B @T6G_MB_LIB.T6G(SCH_1):GND

Q_CAP_0402-0.22UF,16V,10%,X7R,CH4223K1B00  I30  PC612
   1 SW_PVDDCR_SOC_P0_BOOT3_RC      A @T6G_MB_LIB.T6G(SCH_1):SW_PVDDCR_SOC_P0_BOOT3_RC
   2 SW_PVDDCR_SOC_P0_PH3      B @T6G_MB_LIB.T6G(SCH_1):SW_PVDDCR_SOC_P0_PH3

Q_CAP_C0805-22UF,16V,20%,X6S,CH6223MEA01  I34  PC612_3
   1 SW_P12V_AUX_PVDDCR_SOC_P0_FLT      A @T6G_MB_LIB.T6G(SCH_1):SW_P12V_AUX_PVDDCR_SOC_P0_FLT
   2    GND      B @T6G_MB_LIB.T6G(SCH_1):GND


DRAWING: @T6G_MB_LIB.T6G(SCH_1):PAGE176 

Q_CAP_0402-0.1UF,25V,10%,X7R,CH4104K1B00  I2  PC83_2
   1 PVDDCR_CPU1_P0_VCCS      A @T6G_MB_LIB.T6G(SCH_1):PVDDCR_CPU1_P0_VCCS
   2    GND      B @T6G_MB_LIB.T6G(SCH_1):GND

Q_RES_0402LF-0,5%,1/16W,CHIP,CS00002JB13  I21  PR442
   1 PVDDCR_CPU1_P0_PVCC      A @T6G_MB_LIB.T6G(SCH_1):PVDDCR_CPU1_P0_PVCC
   2 P5V_AUX      B @T6G_MB_LIB.T6G(SCH_1):P5V_AUX

Q_CAP_C0402-2.2UF,10V,10%,X6S,CH5222KEB01  I24  PC79
   1 PVDDCR_CPU1_P0_VCC1      A @T6G_MB_LIB.T6G(SCH_1):PVDDCR_CPU1_P0_VCC1
   2    GND      B @T6G_MB_LIB.T6G(SCH_1):GND

Q_CAP_C0402-560PF,50V,10%,EMPTY,CH1566K1B09  I41  PC190
   1 SW_PVDDCR_CPU1_P0_SW2      A @T6G_MB_LIB.T6G(SCH_1):SW_PVDDCR_CPU1_P0_SW2
   2 SW_PVDDCR_CPU1_P0_SW2_RC      B @T6G_MB_LIB.T6G(SCH_1):SW_PVDDCR_CPU1_P0_SW2_RC

Q_INDUCTOR4P_14-150NH,SMLF,IND,CV+15^0TZ04  I46  PL11
   2 IND_CPU1_P0_CPL1      2 @T6G_MB_LIB.T6G(SCH_1):IND_CPU1_P0_CPL1
   3 IND_CPU1_P0_CPL2      3 @T6G_MB_LIB.T6G(SCH_1):IND_CPU1_P0_CPL2
   4 PVDDCR_CPU1_P0      4 @T6G_MB_LIB.T6G(SCH_1):PVDDCR_CPU1_P0
   1 SW_PVDDCR_CPU1_P0_SW2      1 @T6G_MB_LIB.T6G(SCH_1):SW_PVDDCR_CPU1_P0_SW2

Q_CAP_C0402-1UF,25V,10%,X6S,CH5104KEB02  I47  PC88_2
   1 SW_P12V_AUX_PVDDCR_CPU1_P0_FLT      A @T6G_MB_LIB.T6G(SCH_1):SW_P12V_AUX_PVDDCR_CPU1_P0_FLT
   2    GND      B @T6G_MB_LIB.T6G(SCH_1):GND

Q_CAP_C0805-22UF,16V,20%,X6S,CH6223MEA01  I65  PC95_1
   1 SW_P12V_AUX_PVDDCR_CPU1_P0_FLT      A @T6G_MB_LIB.T6G(SCH_1):SW_P12V_AUX_PVDDCR_CPU1_P0_FLT
   2    GND      B @T6G_MB_LIB.T6G(SCH_1):GND

Q_CAPP_THLF-270UF,16V,20%,OSCON,CC72703MD38  I66  PC101
   1 SW_P12V_AUX_PVDDCR_CPU1_P0_FLT      A @T6G_MB_LIB.T6G(SCH_1):SW_P12V_AUX_PVDDCR_CPU1_P0_FLT
   2    GND      B @T6G_MB_LIB.T6G(SCH_1):GND

Q_CAPP_SMLF-220UF,4V,20%,SPCAP,CH122KM8801  I75  PC103
   1 PVDDCR_CPU1_P0      A @T6G_MB_LIB.T6G(SCH_1):PVDDCR_CPU1_P0
   2    GND      B @T6G_MB_LIB.T6G(SCH_1):GND

Q_CAP_0402-0.1UF,25V,10%,X7R,CH4104K1B00  I87  PC85
   1 P12V_AUX      A @T6G_MB_LIB.T6G(SCH_1):P12V_AUX
   2    GND      B @T6G_MB_LIB.T6G(SCH_1):GND

Q_RES_0402LF-8.87K,1%,1/16W,EMPTY,CS28872FB01  I4  PR77
   1 PVDDCR_CPU1_P0_LSET2      A @T6G_MB_LIB.T6G(SCH_1):PVDDCR_CPU1_P0_LSET2
   2    GND      B @T6G_MB_LIB.T6G(SCH_1):GND

Q_CAP_C0402-2.2UF,10V,10%,X6S,CH5222KEB01  I10  PC80
   1 PVDDCR_CPU1_P0_VCC2      A @T6G_MB_LIB.T6G(SCH_1):PVDDCR_CPU1_P0_VCC2
   2    GND      B @T6G_MB_LIB.T6G(SCH_1):GND

Q_CAP_0402-0.1UF,25V,10%,X7R,CH4104K1B00  I12  PC84_1
   1 PVDDCR_CPU1_P0_VCCS      A @T6G_MB_LIB.T6G(SCH_1):PVDDCR_CPU1_P0_VCCS
   2    GND      B @T6G_MB_LIB.T6G(SCH_1):GND

Q_RES_0402LF-2.2,1%,1/16W,CHIP,CS-2202FB01  I13  PR80
   1 PVDDCR_CPU1_P0_PVCC      A @T6G_MB_LIB.T6G(SCH_1):PVDDCR_CPU1_P0_PVCC
   2 PVDDCR_CPU1_P0_VCC2      B @T6G_MB_LIB.T6G(SCH_1):PVDDCR_CPU1_P0_VCC2

Q_CAP_C0402-2.2UF,10V,10%,X6S,CH5222KEB01  I15  PC82_C1P0_2
   1 PVDDCR_CPU1_P0_PVCC      A @T6G_MB_LIB.T6G(SCH_1):PVDDCR_CPU1_P0_PVCC
   2    GND      B @T6G_MB_LIB.T6G(SCH_1):GND

Q_RES_0402LF-8.87K,1%,1/16W,EMPTY,CS28872FB01  I18  PR78
   1 PVDDCR_CPU1_P0_LSET1      A @T6G_MB_LIB.T6G(SCH_1):PVDDCR_CPU1_P0_LSET1
   2    GND      B @T6G_MB_LIB.T6G(SCH_1):GND

Q_RES_0402LF-0,5%,1/16W,EMPTY,CS00002JB13  I27  PR443
   1 PVDDCR_CPU1_P0_PVCC      A @T6G_MB_LIB.T6G(SCH_1):PVDDCR_CPU1_P0_PVCC
   2 P3V3_AUX      B @T6G_MB_LIB.T6G(SCH_1):P3V3_AUX

Q_RES_0402LF-2.2,1%,1/16W,CHIP,CS-2202FB01  I29  PR79
   1 PVDDCR_CPU1_P0_PVCC      A @T6G_MB_LIB.T6G(SCH_1):PVDDCR_CPU1_P0_PVCC
   2 PVDDCR_CPU1_P0_VCC1      B @T6G_MB_LIB.T6G(SCH_1):PVDDCR_CPU1_P0_VCC1

Q_CAP_C0402-2.2UF,10V,10%,X6S,CH5222KEB01  I30  PC81_C1P0_1
   1 PVDDCR_CPU1_P0_PVCC      A @T6G_MB_LIB.T6G(SCH_1):PVDDCR_CPU1_P0_PVCC
   2    GND      B @T6G_MB_LIB.T6G(SCH_1):GND

ISL99390FRZTR5935-ISL99390FRZ-TR5935,SMLF,IC,AL099A  I33  PU2
  34 PVDDCR_CPU1_P0_PWM2    PWM @T6G_MB_LIB.T6G(SCH_1):PVDDCR_CPU1_P0_PWM2
  39 PVDDCR_CPU1_P0_VCCS  REFIN @T6G_MB_LIB.T6G(SCH_1):PVDDCR_CPU1_P0_VCCS
   3 PVDDCR_CPU1_P0_VCC2    VCC @T6G_MB_LIB.T6G(SCH_1):PVDDCR_CPU1_P0_VCC2
   2    GND   AGND @T6G_MB_LIB.T6G(SCH_1):GND
  33 SW_PVDDCR_CPU1_P0_BOOT2   BOOT @T6G_MB_LIB.T6G(SCH_1):SW_PVDDCR_CPU1_P0_BOOT2
25_29 SW_P12V_AUX_PVDDCR_CPU1_P0_FLT   VIN1 @T6G_MB_LIB.T6G(SCH_1):SW_P12V_AUX_PVDDCR_CPU1_P0_FLT
  32 SW_PVDDCR_CPU1_P0_BOOTR2  PHASE @T6G_MB_LIB.T6G(SCH_1):SW_PVDDCR_CPU1_P0_BOOTR2
   4 PVDDCR_CPU1_P0_PVCC   PVCC @T6G_MB_LIB.T6G(SCH_1):PVDDCR_CPU1_P0_PVCC
  36 PVDDCR_CPU1_P0_TEMP0 TOUT_FLT @T6G_MB_LIB.T6G(SCH_1):PVDDCR_CPU1_P0_TEMP0
  38 PVDDCR_CPU1_P0_IMON2   IOUT @T6G_MB_LIB.T6G(SCH_1):PVDDCR_CPU1_P0_IMON2
  37 PVDDCR_CPU1_P0_LSET2   LSET @T6G_MB_LIB.T6G(SCH_1):PVDDCR_CPU1_P0_LSET2
10_19 SW_PVDDCR_CPU1_P0_SW2     SW @T6G_MB_LIB.T6G(SCH_1):SW_PVDDCR_CPU1_P0_SW2
   5    GND  PGND1 @T6G_MB_LIB.T6G(SCH_1):GND
  30 SW_P12V_AUX_PVDDCR_CPU1_P0_FLT   VIN2 @T6G_MB_LIB.T6G(SCH_1):SW_P12V_AUX_PVDDCR_CPU1_P0_FLT
   1 PVDDCR_CPU1_P0_VOS2    VOS @T6G_MB_LIB.T6G(SCH_1):PVDDCR_CPU1_P0_VOS2
  40    GND  PGND3 @T6G_MB_LIB.T6G(SCH_1):GND
  35 PVDDCR_CPU1_P0_VCC2     EN @T6G_MB_LIB.T6G(SCH_1):PVDDCR_CPU1_P0_VCC2
  31 NC_PVDDCR_CPU1_P0_DNC2    DNC @T6G_MB_LIB.T6G(SCH_1):NC_PVDDCR_CPU1_P0_DNC2
   6 NC_PVDDCR_CPU1_P0_GL1_2    GL1 @T6G_MB_LIB.T6G(SCH_1):NC_PVDDCR_CPU1_P0_GL1_2
  41 NC_PVDDCR_CPU1_P0_GL2_2    GL2 @T6G_MB_LIB.T6G(SCH_1):NC_PVDDCR_CPU1_P0_GL2_2
7_9-20_24    GND  PGND2 @T6G_MB_LIB.T6G(SCH_1):GND

ISL99390FRZTR5935-ISL99390FRZ-TR5935,SMLF,IC,AL099A  I35  PU13
  34 PVDDCR_CPU1_P0_PWM1    PWM @T6G_MB_LIB.T6G(SCH_1):PVDDCR_CPU1_P0_PWM1
  39 PVDDCR_CPU1_P0_VCCS  REFIN @T6G_MB_LIB.T6G(SCH_1):PVDDCR_CPU1_P0_VCCS
   3 PVDDCR_CPU1_P0_VCC1    VCC @T6G_MB_LIB.T6G(SCH_1):PVDDCR_CPU1_P0_VCC1
   2    GND   AGND @T6G_MB_LIB.T6G(SCH_1):GND
  33 SW_PVDDCR_CPU1_P0_BOOT1   BOOT @T6G_MB_LIB.T6G(SCH_1):SW_PVDDCR_CPU1_P0_BOOT1
25_29 SW_P12V_AUX_PVDDCR_CPU1_P0_FLT   VIN1 @T6G_MB_LIB.T6G(SCH_1):SW_P12V_AUX_PVDDCR_CPU1_P0_FLT
  32 SW_PVDDCR_CPU1_P0_BOOTR1  PHASE @T6G_MB_LIB.T6G(SCH_1):SW_PVDDCR_CPU1_P0_BOOTR1
   4 PVDDCR_CPU1_P0_PVCC   PVCC @T6G_MB_LIB.T6G(SCH_1):PVDDCR_CPU1_P0_PVCC
  36 PVDDCR_CPU1_P0_TEMP0 TOUT_FLT @T6G_MB_LIB.T6G(SCH_1):PVDDCR_CPU1_P0_TEMP0
  38 PVDDCR_CPU1_P0_IMON1   IOUT @T6G_MB_LIB.T6G(SCH_1):PVDDCR_CPU1_P0_IMON1
  37 PVDDCR_CPU1_P0_LSET1   LSET @T6G_MB_LIB.T6G(SCH_1):PVDDCR_CPU1_P0_LSET1
10_19 SW_PVDDCR_CPU1_P0_SW1     SW @T6G_MB_LIB.T6G(SCH_1):SW_PVDDCR_CPU1_P0_SW1
   5    GND  PGND1 @T6G_MB_LIB.T6G(SCH_1):GND
  30 SW_P12V_AUX_PVDDCR_CPU1_P0_FLT   VIN2 @T6G_MB_LIB.T6G(SCH_1):SW_P12V_AUX_PVDDCR_CPU1_P0_FLT
   1 PVDDCR_CPU1_P0_VOS1    VOS @T6G_MB_LIB.T6G(SCH_1):PVDDCR_CPU1_P0_VOS1
  40    GND  PGND3 @T6G_MB_LIB.T6G(SCH_1):GND
  35 PVDDCR_CPU1_P0_VCC1     EN @T6G_MB_LIB.T6G(SCH_1):PVDDCR_CPU1_P0_VCC1
  31 NC_PVDDCR_CPU1_P0_DNC1    DNC @T6G_MB_LIB.T6G(SCH_1):NC_PVDDCR_CPU1_P0_DNC1
   6 NC_PVDDCR_CPU1_P0_GL1_1    GL1 @T6G_MB_LIB.T6G(SCH_1):NC_PVDDCR_CPU1_P0_GL1_1
  41 NC_PVDDCR_CPU1_P0_GL2_1    GL2 @T6G_MB_LIB.T6G(SCH_1):NC_PVDDCR_CPU1_P0_GL2_1
7_9-20_24    GND  PGND2 @T6G_MB_LIB.T6G(SCH_1):GND

Q_CAP_0402-0.1UF,25V,10%,X7R,CH4104K1B00  I37  PC86_2
   1 SW_P12V_AUX_PVDDCR_CPU1_P0_FLT      A @T6G_MB_LIB.T6G(SCH_1):SW_P12V_AUX_PVDDCR_CPU1_P0_FLT
   2    GND      B @T6G_MB_LIB.T6G(SCH_1):GND

Q_RES_0402LF-1.5,1%,1/8W,EMPTY,CS-1504FB00  I39  PR507
   1 SW_PVDDCR_CPU1_P0_SW2_RC      A @T6G_MB_LIB.T6G(SCH_1):SW_PVDDCR_CPU1_P0_SW2_RC
   2    GND      B @T6G_MB_LIB.T6G(SCH_1):GND

Q_RES_0402LF-5.6,1%,1/16W,CHIP,CS-5602FB01  I40  PR81
   1 SW_PVDDCR_CPU1_P0_BOOT2      A @T6G_MB_LIB.T6G(SCH_1):SW_PVDDCR_CPU1_P0_BOOT2
   2 SW_PVDDCR_CPU1_P0_BOOT2_R      B @T6G_MB_LIB.T6G(SCH_1):SW_PVDDCR_CPU1_P0_BOOT2_R

Q_RES_0402LF-0,5%,1/16W,CHIP,CS00002JB13  I42  PR83
   1 PVDDCR_CPU1_P0_VOS2      A @T6G_MB_LIB.T6G(SCH_1):PVDDCR_CPU1_P0_VOS2
   2 PVDDCR_CPU1_P0      B @T6G_MB_LIB.T6G(SCH_1):PVDDCR_CPU1_P0

Q_CAP_0402-0.22UF,16V,10%,X7R,CH4223K1B00  I44  PC94
   1 SW_PVDDCR_CPU1_P0_BOOT2_R      A @T6G_MB_LIB.T6G(SCH_1):SW_PVDDCR_CPU1_P0_BOOT2_R
   2 SW_PVDDCR_CPU1_P0_BOOTR2      B @T6G_MB_LIB.T6G(SCH_1):SW_PVDDCR_CPU1_P0_BOOTR2

Q_CAP_C0805-22UF,16V,20%,X6S,CH6223MEA01  I48  PC90_2
   1 SW_P12V_AUX_PVDDCR_CPU1_P0_FLT      A @T6G_MB_LIB.T6G(SCH_1):SW_P12V_AUX_PVDDCR_CPU1_P0_FLT
   2    GND      B @T6G_MB_LIB.T6G(SCH_1):GND

Q_RES_0402LF-1.5,1%,1/8W,EMPTY,CS-1504FB00  I50  PR506
   1 SW_PVDDCR_CPU1_P0_SW1_RC      A @T6G_MB_LIB.T6G(SCH_1):SW_PVDDCR_CPU1_P0_SW1_RC
   2    GND      B @T6G_MB_LIB.T6G(SCH_1):GND

Q_CAP_C0805-22UF,16V,20%,X6S,CH6223MEA01  I51  PC93_2
   1 SW_P12V_AUX_PVDDCR_CPU1_P0_FLT      A @T6G_MB_LIB.T6G(SCH_1):SW_P12V_AUX_PVDDCR_CPU1_P0_FLT
   2    GND      B @T6G_MB_LIB.T6G(SCH_1):GND

Q_CAP_C0805-22UF,16V,20%,X6S,CH6223MEA01  I52  PC96_2
   1 SW_P12V_AUX_PVDDCR_CPU1_P0_FLT      A @T6G_MB_LIB.T6G(SCH_1):SW_P12V_AUX_PVDDCR_CPU1_P0_FLT
   2    GND      B @T6G_MB_LIB.T6G(SCH_1):GND

Q_RES_0402LF-0,5%,1/16W,CHIP,CS00002JB13  I54  PR84
   1 PVDDCR_CPU1_P0_VOS1      A @T6G_MB_LIB.T6G(SCH_1):PVDDCR_CPU1_P0_VOS1
   2 PVDDCR_CPU1_P0      B @T6G_MB_LIB.T6G(SCH_1):PVDDCR_CPU1_P0

Q_CAP_0402-0.1UF,25V,10%,X7R,CH4104K1B00  I55  PC85_1
   1 SW_P12V_AUX_PVDDCR_CPU1_P0_FLT      A @T6G_MB_LIB.T6G(SCH_1):SW_P12V_AUX_PVDDCR_CPU1_P0_FLT
   2    GND      B @T6G_MB_LIB.T6G(SCH_1):GND

Q_RES_0402LF-5.6,1%,1/16W,CHIP,CS-5602FB01  I56  PR82
   1 SW_PVDDCR_CPU1_P0_BOOT1      A @T6G_MB_LIB.T6G(SCH_1):SW_PVDDCR_CPU1_P0_BOOT1
   2 SW_PVDDCR_CPU1_P0_BOOT1_R      B @T6G_MB_LIB.T6G(SCH_1):SW_PVDDCR_CPU1_P0_BOOT1_R

Q_CAP_C0402-560PF,50V,10%,EMPTY,CH1566K1B09  I57  PC189
   1 SW_PVDDCR_CPU1_P0_SW1      A @T6G_MB_LIB.T6G(SCH_1):SW_PVDDCR_CPU1_P0_SW1
   2 SW_PVDDCR_CPU1_P0_SW1_RC      B @T6G_MB_LIB.T6G(SCH_1):SW_PVDDCR_CPU1_P0_SW1_RC

Q_CAP_C0402-1UF,25V,10%,X6S,CH5104KEB02  I59  PC87_1
   1 SW_P12V_AUX_PVDDCR_CPU1_P0_FLT      A @T6G_MB_LIB.T6G(SCH_1):SW_P12V_AUX_PVDDCR_CPU1_P0_FLT
   2    GND      B @T6G_MB_LIB.T6G(SCH_1):GND

Q_CAP_C0805-22UF,16V,20%,X6S,CH6223MEA01  I60  PC89_1
   1 SW_P12V_AUX_PVDDCR_CPU1_P0_FLT      A @T6G_MB_LIB.T6G(SCH_1):SW_P12V_AUX_PVDDCR_CPU1_P0_FLT
   2    GND      B @T6G_MB_LIB.T6G(SCH_1):GND

Q_CAP_0402-0.22UF,16V,10%,X7R,CH4223K1B00  I61  PC92
   1 SW_PVDDCR_CPU1_P0_BOOT1_R      A @T6G_MB_LIB.T6G(SCH_1):SW_PVDDCR_CPU1_P0_BOOT1_R
   2 SW_PVDDCR_CPU1_P0_BOOTR1      B @T6G_MB_LIB.T6G(SCH_1):SW_PVDDCR_CPU1_P0_BOOTR1

Q_INDUCTOR4P_14-150NH,SMLF,IND,CV+15^0TZ04  I62  PL10
   2 IND_CPU1_P0_CPL5      2 @T6G_MB_LIB.T6G(SCH_1):IND_CPU1_P0_CPL5
   3 IND_CPU1_P0_CPL1      3 @T6G_MB_LIB.T6G(SCH_1):IND_CPU1_P0_CPL1
   4 PVDDCR_CPU1_P0      4 @T6G_MB_LIB.T6G(SCH_1):PVDDCR_CPU1_P0
   1 SW_PVDDCR_CPU1_P0_SW1      1 @T6G_MB_LIB.T6G(SCH_1):SW_PVDDCR_CPU1_P0_SW1

Q_CAP_C0805-22UF,16V,20%,X6S,CH6223MEA01  I64  PC91_1
   1 SW_P12V_AUX_PVDDCR_CPU1_P0_FLT      A @T6G_MB_LIB.T6G(SCH_1):SW_P12V_AUX_PVDDCR_CPU1_P0_FLT
   2    GND      B @T6G_MB_LIB.T6G(SCH_1):GND

Q_CAP_C0805-22UF,4V,20%,X6S,CH622KMEA03  I69  PC106_2
   1 PVDDCR_CPU1_P0      A @T6G_MB_LIB.T6G(SCH_1):PVDDCR_CPU1_P0
   2    GND      B @T6G_MB_LIB.T6G(SCH_1):GND

Q_CAPP_SMLF-220UF,4V,20%,SPCAP,CH122KM8801  I70  PC102
   1 PVDDCR_CPU1_P0      A @T6G_MB_LIB.T6G(SCH_1):PVDDCR_CPU1_P0
   2    GND      B @T6G_MB_LIB.T6G(SCH_1):GND

Q_CAPP_SMLF-220UF,4V,20%,SPCAP,CH122KM8801  I71  PC97
   1 PVDDCR_CPU1_P0      A @T6G_MB_LIB.T6G(SCH_1):PVDDCR_CPU1_P0
   2    GND      B @T6G_MB_LIB.T6G(SCH_1):GND

Q_CAPP_SMLF-220UF,4V,20%,SPCAP,CH122KM8801  I72  PC98
   1 PVDDCR_CPU1_P0      A @T6G_MB_LIB.T6G(SCH_1):PVDDCR_CPU1_P0
   2    GND      B @T6G_MB_LIB.T6G(SCH_1):GND

Q_CAPP_SMLF-220UF,4V,20%,SPCAP,CH122KM8801  I73  PC100
   1 PVDDCR_CPU1_P0      A @T6G_MB_LIB.T6G(SCH_1):PVDDCR_CPU1_P0
   2    GND      B @T6G_MB_LIB.T6G(SCH_1):GND

Q_CAP_C0805-22UF,4V,20%,X6S,CH622KMEA03  I77  PC108_2
   1 PVDDCR_CPU1_P0      A @T6G_MB_LIB.T6G(SCH_1):PVDDCR_CPU1_P0
   2    GND      B @T6G_MB_LIB.T6G(SCH_1):GND

Q_CAPP_THLF-270UF,16V,20%,OSCON,CC72703MD38  I82  PC104
   1 SW_P12V_AUX_PVDDCR_CPU1_P0_FLT      A @T6G_MB_LIB.T6G(SCH_1):SW_P12V_AUX_PVDDCR_CPU1_P0_FLT
   2    GND      B @T6G_MB_LIB.T6G(SCH_1):GND

Q_INDUCTOR_SMLF-50NH/86A,IND,CVA50^0MZ09  I83  PL12
   2 P12V_AUX      2 @T6G_MB_LIB.T6G(SCH_1):P12V_AUX
   1 SW_P12V_AUX_PVDDCR_CPU1_P0_FLT      1 @T6G_MB_LIB.T6G(SCH_1):SW_P12V_AUX_PVDDCR_CPU1_P0_FLT

Q_CAP_0402-0.1UF,25V,10%,X7R,CH4104K1B00  I84  PC99
   1 PVDDCR_CPU1_P0      A @T6G_MB_LIB.T6G(SCH_1):PVDDCR_CPU1_P0
   2    GND      B @T6G_MB_LIB.T6G(SCH_1):GND

Q_CAP_C0805-22UF,4V,20%,X6S,CH622KMEA03  I86  PC102_1
   1 PVDDCR_CPU1_P0      A @T6G_MB_LIB.T6G(SCH_1):PVDDCR_CPU1_P0
   2    GND      B @T6G_MB_LIB.T6G(SCH_1):GND

Q_CAP_C0805-22UF,4V,20%,X6S,CH622KMEA03  I89  PC105_1
   1 PVDDCR_CPU1_P0      A @T6G_MB_LIB.T6G(SCH_1):PVDDCR_CPU1_P0
   2    GND      B @T6G_MB_LIB.T6G(SCH_1):GND

Q_RES_0402LF-1K,1%,1/16W,CHIP,CS21002FB06  I90  PR444
   1 PVDDCR_CPU1_P0      A @T6G_MB_LIB.T6G(SCH_1):PVDDCR_CPU1_P0
   2    GND      B @T6G_MB_LIB.T6G(SCH_1):GND


DRAWING: @T6G_MB_LIB.T6G(SCH_1):PAGE177 

Q_CAP_0402-0.1UF,25V,10%,X7R,CH4104K1B00  I2  PC113_4
   1 PVDDCR_CPU1_P0_VCCS      A @T6G_MB_LIB.T6G(SCH_1):PVDDCR_CPU1_P0_VCCS
   2    GND      B @T6G_MB_LIB.T6G(SCH_1):GND

Q_RES_0402LF-2.2,1%,1/16W,CHIP,CS-2202FB01  I30  PR88
   1 PVDDCR_CPU1_P0_PVCC      A @T6G_MB_LIB.T6G(SCH_1):PVDDCR_CPU1_P0_PVCC
   2 PVDDCR_CPU1_P0_VCC3      B @T6G_MB_LIB.T6G(SCH_1):PVDDCR_CPU1_P0_VCC3

Q_RES_0402LF-5.6,1%,1/16W,CHIP,CS-5602FB01  I37  PR89
   1 SW_PVDDCR_CPU1_P0_BOOT4      A @T6G_MB_LIB.T6G(SCH_1):SW_PVDDCR_CPU1_P0_BOOT4
   2 SW_PVDDCR_CPU1_P0_BOOT4_R      B @T6G_MB_LIB.T6G(SCH_1):SW_PVDDCR_CPU1_P0_BOOT4_R

Q_CAP_C0402-560PF,50V,10%,EMPTY,CH1566K1B09  I38  PC191
   1 SW_PVDDCR_CPU1_P0_SW4      A @T6G_MB_LIB.T6G(SCH_1):SW_PVDDCR_CPU1_P0_SW4
   2 SW_PVDDCR_CPU1_P0_SW4_RC      B @T6G_MB_LIB.T6G(SCH_1):SW_PVDDCR_CPU1_P0_SW4_RC

Q_RES_0402LF-0,5%,1/16W,CHIP,CS00002JB13  I40  PR91
   1 PVDDCR_CPU1_P0_VOS4      A @T6G_MB_LIB.T6G(SCH_1):PVDDCR_CPU1_P0_VOS4
   2 PVDDCR_CPU1_P0      B @T6G_MB_LIB.T6G(SCH_1):PVDDCR_CPU1_P0

Q_INDUCTOR4P_14-150NH,SMLF,IND,CV+15^0TZ04  I42  PL13
   2 IND_CPU1_P0_CPL3      2 @T6G_MB_LIB.T6G(SCH_1):IND_CPU1_P0_CPL3
   3    GND      3 @T6G_MB_LIB.T6G(SCH_1):GND
   4 PVDDCR_CPU1_P0      4 @T6G_MB_LIB.T6G(SCH_1):PVDDCR_CPU1_P0
   1 SW_PVDDCR_CPU1_P0_SW4      1 @T6G_MB_LIB.T6G(SCH_1):SW_PVDDCR_CPU1_P0_SW4

Q_RES_0402LF-0,5%,1/16W,CHIP,CS00002JB13  I51  PR92
   1 PVDDCR_CPU1_P0_VOS3      A @T6G_MB_LIB.T6G(SCH_1):PVDDCR_CPU1_P0_VOS3
   2 PVDDCR_CPU1_P0      B @T6G_MB_LIB.T6G(SCH_1):PVDDCR_CPU1_P0

Q_CAP_C0805-22UF,4V,20%,X6S,CH622KMEA03  I55  PC128_4
   1 PVDDCR_CPU1_P0      A @T6G_MB_LIB.T6G(SCH_1):PVDDCR_CPU1_P0
   2    GND      B @T6G_MB_LIB.T6G(SCH_1):GND

Q_RES_0402LF-8.87K,1%,1/16W,EMPTY,CS28872FB01  I4  PR85
   1 PVDDCR_CPU1_P0_LSET4      A @T6G_MB_LIB.T6G(SCH_1):PVDDCR_CPU1_P0_LSET4
   2    GND      B @T6G_MB_LIB.T6G(SCH_1):GND

Q_CAP_C0402-2.2UF,10V,10%,X6S,CH5222KEB01  I7  PC109
   1 PVDDCR_CPU1_P0_VCC4      A @T6G_MB_LIB.T6G(SCH_1):PVDDCR_CPU1_P0_VCC4
   2    GND      B @T6G_MB_LIB.T6G(SCH_1):GND

Q_CAP_0402-0.1UF,25V,10%,X7R,CH4104K1B00  I12  PC114_3
   1 PVDDCR_CPU1_P0_VCCS      A @T6G_MB_LIB.T6G(SCH_1):PVDDCR_CPU1_P0_VCCS
   2    GND      B @T6G_MB_LIB.T6G(SCH_1):GND

Q_RES_0402LF-2.2,1%,1/16W,CHIP,CS-2202FB01  I13  PR87
   1 PVDDCR_CPU1_P0_PVCC      A @T6G_MB_LIB.T6G(SCH_1):PVDDCR_CPU1_P0_PVCC
   2 PVDDCR_CPU1_P0_VCC4      B @T6G_MB_LIB.T6G(SCH_1):PVDDCR_CPU1_P0_VCC4

Q_CAP_C0402-2.2UF,10V,10%,X6S,CH5222KEB01  I16  PC111_C1P0_4
   1 PVDDCR_CPU1_P0_PVCC      A @T6G_MB_LIB.T6G(SCH_1):PVDDCR_CPU1_P0_PVCC
   2    GND      B @T6G_MB_LIB.T6G(SCH_1):GND

Q_RES_0402LF-8.87K,1%,1/16W,EMPTY,CS28872FB01  I18  PR86
   1 PVDDCR_CPU1_P0_LSET3      A @T6G_MB_LIB.T6G(SCH_1):PVDDCR_CPU1_P0_LSET3
   2    GND      B @T6G_MB_LIB.T6G(SCH_1):GND

ISL99390FRZTR5935-ISL99390FRZ-TR5935,SMLF,IC,AL099A  I21  PU14
  34 PVDDCR_CPU1_P0_PWM4    PWM @T6G_MB_LIB.T6G(SCH_1):PVDDCR_CPU1_P0_PWM4
  39 PVDDCR_CPU1_P0_VCCS  REFIN @T6G_MB_LIB.T6G(SCH_1):PVDDCR_CPU1_P0_VCCS
   3 PVDDCR_CPU1_P0_VCC4    VCC @T6G_MB_LIB.T6G(SCH_1):PVDDCR_CPU1_P0_VCC4
   2    GND   AGND @T6G_MB_LIB.T6G(SCH_1):GND
  33 SW_PVDDCR_CPU1_P0_BOOT4   BOOT @T6G_MB_LIB.T6G(SCH_1):SW_PVDDCR_CPU1_P0_BOOT4
25_29 SW_P12V_AUX_PVDDCR_CPU1_P0_FLT   VIN1 @T6G_MB_LIB.T6G(SCH_1):SW_P12V_AUX_PVDDCR_CPU1_P0_FLT
  32 SW_PVDDCR_CPU1_P0_BOOTR4  PHASE @T6G_MB_LIB.T6G(SCH_1):SW_PVDDCR_CPU1_P0_BOOTR4
   4 PVDDCR_CPU1_P0_PVCC   PVCC @T6G_MB_LIB.T6G(SCH_1):PVDDCR_CPU1_P0_PVCC
  36 PVDDCR_CPU1_P0_TEMP0 TOUT_FLT @T6G_MB_LIB.T6G(SCH_1):PVDDCR_CPU1_P0_TEMP0
  38 PVDDCR_CPU1_P0_IMON4   IOUT @T6G_MB_LIB.T6G(SCH_1):PVDDCR_CPU1_P0_IMON4
  37 PVDDCR_CPU1_P0_LSET4   LSET @T6G_MB_LIB.T6G(SCH_1):PVDDCR_CPU1_P0_LSET4
10_19 SW_PVDDCR_CPU1_P0_SW4     SW @T6G_MB_LIB.T6G(SCH_1):SW_PVDDCR_CPU1_P0_SW4
   5    GND  PGND1 @T6G_MB_LIB.T6G(SCH_1):GND
  30 SW_P12V_AUX_PVDDCR_CPU1_P0_FLT   VIN2 @T6G_MB_LIB.T6G(SCH_1):SW_P12V_AUX_PVDDCR_CPU1_P0_FLT
   1 PVDDCR_CPU1_P0_VOS4    VOS @T6G_MB_LIB.T6G(SCH_1):PVDDCR_CPU1_P0_VOS4
  40    GND  PGND3 @T6G_MB_LIB.T6G(SCH_1):GND
  35 PVDDCR_CPU1_P0_VCC4     EN @T6G_MB_LIB.T6G(SCH_1):PVDDCR_CPU1_P0_VCC4
  31 NC_PVDDCR_CPU1_P0_DNC4    DNC @T6G_MB_LIB.T6G(SCH_1):NC_PVDDCR_CPU1_P0_DNC4
   6 NC_PVDDCR_CPU1_P0_GL1_4    GL1 @T6G_MB_LIB.T6G(SCH_1):NC_PVDDCR_CPU1_P0_GL1_4
  41 NC_PVDDCR_CPU1_P0_GL2_4    GL2 @T6G_MB_LIB.T6G(SCH_1):NC_PVDDCR_CPU1_P0_GL2_4
7_9-20_24    GND  PGND2 @T6G_MB_LIB.T6G(SCH_1):GND

ISL99390FRZTR5935-ISL99390FRZ-TR5935,SMLF,IC,AL099A  I23  PU15
  34 PVDDCR_CPU1_P0_PWM3    PWM @T6G_MB_LIB.T6G(SCH_1):PVDDCR_CPU1_P0_PWM3
  39 PVDDCR_CPU1_P0_VCCS  REFIN @T6G_MB_LIB.T6G(SCH_1):PVDDCR_CPU1_P0_VCCS
   3 PVDDCR_CPU1_P0_VCC3    VCC @T6G_MB_LIB.T6G(SCH_1):PVDDCR_CPU1_P0_VCC3
   2    GND   AGND @T6G_MB_LIB.T6G(SCH_1):GND
  33 SW_PVDDCR_CPU1_P0_BOOT3   BOOT @T6G_MB_LIB.T6G(SCH_1):SW_PVDDCR_CPU1_P0_BOOT3
25_29 SW_P12V_AUX_PVDDCR_CPU1_P0_FLT   VIN1 @T6G_MB_LIB.T6G(SCH_1):SW_P12V_AUX_PVDDCR_CPU1_P0_FLT
  32 SW_PVDDCR_CPU1_P0_BOOTR3  PHASE @T6G_MB_LIB.T6G(SCH_1):SW_PVDDCR_CPU1_P0_BOOTR3
   4 PVDDCR_CPU1_P0_PVCC   PVCC @T6G_MB_LIB.T6G(SCH_1):PVDDCR_CPU1_P0_PVCC
  36 PVDDCR_CPU1_P0_TEMP0 TOUT_FLT @T6G_MB_LIB.T6G(SCH_1):PVDDCR_CPU1_P0_TEMP0
  38 PVDDCR_CPU1_P0_IMON3   IOUT @T6G_MB_LIB.T6G(SCH_1):PVDDCR_CPU1_P0_IMON3
  37 PVDDCR_CPU1_P0_LSET3   LSET @T6G_MB_LIB.T6G(SCH_1):PVDDCR_CPU1_P0_LSET3
10_19 SW_PVDDCR_CPU1_P0_SW3     SW @T6G_MB_LIB.T6G(SCH_1):SW_PVDDCR_CPU1_P0_SW3
   5    GND  PGND1 @T6G_MB_LIB.T6G(SCH_1):GND
  30 SW_P12V_AUX_PVDDCR_CPU1_P0_FLT   VIN2 @T6G_MB_LIB.T6G(SCH_1):SW_P12V_AUX_PVDDCR_CPU1_P0_FLT
   1 PVDDCR_CPU1_P0_VOS3    VOS @T6G_MB_LIB.T6G(SCH_1):PVDDCR_CPU1_P0_VOS3
  40    GND  PGND3 @T6G_MB_LIB.T6G(SCH_1):GND
  35 PVDDCR_CPU1_P0_VCC3     EN @T6G_MB_LIB.T6G(SCH_1):PVDDCR_CPU1_P0_VCC3
  31 NC_PVDDCR_CPU1_P0_DNC3    DNC @T6G_MB_LIB.T6G(SCH_1):NC_PVDDCR_CPU1_P0_DNC3
   6 NC_PVDDCR_CPU1_P0_GL1_3    GL1 @T6G_MB_LIB.T6G(SCH_1):NC_PVDDCR_CPU1_P0_GL1_3
  41 NC_PVDDCR_CPU1_P0_GL2_3    GL2 @T6G_MB_LIB.T6G(SCH_1):NC_PVDDCR_CPU1_P0_GL2_3
7_9-20_24    GND  PGND2 @T6G_MB_LIB.T6G(SCH_1):GND

Q_CAP_0402-0.1UF,25V,10%,X7R,CH4104K1B00  I24  PC115_4
   1 SW_P12V_AUX_PVDDCR_CPU1_P0_FLT      A @T6G_MB_LIB.T6G(SCH_1):SW_P12V_AUX_PVDDCR_CPU1_P0_FLT
   2    GND      B @T6G_MB_LIB.T6G(SCH_1):GND

Q_CAP_C0402-2.2UF,10V,10%,X6S,CH5222KEB01  I28  PC110
   1 PVDDCR_CPU1_P0_VCC3      A @T6G_MB_LIB.T6G(SCH_1):PVDDCR_CPU1_P0_VCC3
   2    GND      B @T6G_MB_LIB.T6G(SCH_1):GND

Q_CAP_C0402-2.2UF,10V,10%,X6S,CH5222KEB01  I32  PC112_C1P0_3
   1 PVDDCR_CPU1_P0_PVCC      A @T6G_MB_LIB.T6G(SCH_1):PVDDCR_CPU1_P0_PVCC
   2    GND      B @T6G_MB_LIB.T6G(SCH_1):GND

Q_CAP_0402-0.1UF,25V,10%,X7R,CH4104K1B00  I34  PC116_3
   1 SW_P12V_AUX_PVDDCR_CPU1_P0_FLT      A @T6G_MB_LIB.T6G(SCH_1):SW_P12V_AUX_PVDDCR_CPU1_P0_FLT
   2    GND      B @T6G_MB_LIB.T6G(SCH_1):GND

Q_RES_0402LF-1.5,1%,1/8W,EMPTY,CS-1504FB00  I36  PR509
   1 SW_PVDDCR_CPU1_P0_SW4_RC      A @T6G_MB_LIB.T6G(SCH_1):SW_PVDDCR_CPU1_P0_SW4_RC
   2    GND      B @T6G_MB_LIB.T6G(SCH_1):GND

Q_CAP_0402-0.22UF,16V,10%,X7R,CH4223K1B00  I41  PC121
   1 SW_PVDDCR_CPU1_P0_BOOT4_R      A @T6G_MB_LIB.T6G(SCH_1):SW_PVDDCR_CPU1_P0_BOOT4_R
   2 SW_PVDDCR_CPU1_P0_BOOTR4      B @T6G_MB_LIB.T6G(SCH_1):SW_PVDDCR_CPU1_P0_BOOTR4

Q_CAP_C0402-1UF,25V,10%,X6S,CH5104KEB02  I43  PC117_4
   1 SW_P12V_AUX_PVDDCR_CPU1_P0_FLT      A @T6G_MB_LIB.T6G(SCH_1):SW_P12V_AUX_PVDDCR_CPU1_P0_FLT
   2    GND      B @T6G_MB_LIB.T6G(SCH_1):GND

Q_CAP_C0805-22UF,16V,20%,X6S,CH6223MEA01  I44  PC119_4
   1 SW_P12V_AUX_PVDDCR_CPU1_P0_FLT      A @T6G_MB_LIB.T6G(SCH_1):SW_P12V_AUX_PVDDCR_CPU1_P0_FLT
   2    GND      B @T6G_MB_LIB.T6G(SCH_1):GND

Q_RES_0402LF-1.5,1%,1/8W,EMPTY,CS-1504FB00  I46  PR510
   1 SW_PVDDCR_CPU1_P0_SW3_RC      A @T6G_MB_LIB.T6G(SCH_1):SW_PVDDCR_CPU1_P0_SW3_RC
   2    GND      B @T6G_MB_LIB.T6G(SCH_1):GND

Q_CAP_C0805-22UF,16V,20%,X6S,CH6223MEA01  I47  PC123_4
   1 SW_P12V_AUX_PVDDCR_CPU1_P0_FLT      A @T6G_MB_LIB.T6G(SCH_1):SW_P12V_AUX_PVDDCR_CPU1_P0_FLT
   2    GND      B @T6G_MB_LIB.T6G(SCH_1):GND

Q_CAP_C0805-22UF,16V,20%,X6S,CH6223MEA01  I49  PC125_4
   1 SW_P12V_AUX_PVDDCR_CPU1_P0_FLT      A @T6G_MB_LIB.T6G(SCH_1):SW_P12V_AUX_PVDDCR_CPU1_P0_FLT
   2    GND      B @T6G_MB_LIB.T6G(SCH_1):GND

Q_CAP_C0805-22UF,4V,20%,X6S,CH622KMEA03  I54  PC127_4
   1 PVDDCR_CPU1_P0      A @T6G_MB_LIB.T6G(SCH_1):PVDDCR_CPU1_P0
   2    GND      B @T6G_MB_LIB.T6G(SCH_1):GND

Q_RES_0402LF-5.6,1%,1/16W,CHIP,CS-5602FB01  I57  PR90
   1 SW_PVDDCR_CPU1_P0_BOOT3      A @T6G_MB_LIB.T6G(SCH_1):SW_PVDDCR_CPU1_P0_BOOT3
   2 SW_PVDDCR_CPU1_P0_BOOT3_R      B @T6G_MB_LIB.T6G(SCH_1):SW_PVDDCR_CPU1_P0_BOOT3_R

Q_CAP_C0402-560PF,50V,10%,EMPTY,CH1566K1B09  I58  PC192
   1 SW_PVDDCR_CPU1_P0_SW3      A @T6G_MB_LIB.T6G(SCH_1):SW_PVDDCR_CPU1_P0_SW3
   2 SW_PVDDCR_CPU1_P0_SW3_RC      B @T6G_MB_LIB.T6G(SCH_1):SW_PVDDCR_CPU1_P0_SW3_RC

Q_CAP_C0402-1UF,25V,10%,X6S,CH5104KEB02  I60  PC118_3
   1 SW_P12V_AUX_PVDDCR_CPU1_P0_FLT      A @T6G_MB_LIB.T6G(SCH_1):SW_P12V_AUX_PVDDCR_CPU1_P0_FLT
   2    GND      B @T6G_MB_LIB.T6G(SCH_1):GND

Q_CAP_C0805-22UF,16V,20%,X6S,CH6223MEA01  I61  PC120_3
   1 SW_P12V_AUX_PVDDCR_CPU1_P0_FLT      A @T6G_MB_LIB.T6G(SCH_1):SW_P12V_AUX_PVDDCR_CPU1_P0_FLT
   2    GND      B @T6G_MB_LIB.T6G(SCH_1):GND

Q_CAP_0402-0.22UF,16V,10%,X7R,CH4223K1B00  I62  PC122
   1 SW_PVDDCR_CPU1_P0_BOOT3_R      A @T6G_MB_LIB.T6G(SCH_1):SW_PVDDCR_CPU1_P0_BOOT3_R
   2 SW_PVDDCR_CPU1_P0_BOOTR3      B @T6G_MB_LIB.T6G(SCH_1):SW_PVDDCR_CPU1_P0_BOOTR3

Q_INDUCTOR4P_14-150NH,SMLF,IND,CV+15^0TZ04  I64  PL14
   2 IND_CPU1_P0_CPL2      2 @T6G_MB_LIB.T6G(SCH_1):IND_CPU1_P0_CPL2
   3 IND_CPU1_P0_CPL3      3 @T6G_MB_LIB.T6G(SCH_1):IND_CPU1_P0_CPL3
   4 PVDDCR_CPU1_P0      4 @T6G_MB_LIB.T6G(SCH_1):PVDDCR_CPU1_P0
   1 SW_PVDDCR_CPU1_P0_SW3      1 @T6G_MB_LIB.T6G(SCH_1):SW_PVDDCR_CPU1_P0_SW3

Q_CAP_C0805-22UF,16V,20%,X6S,CH6223MEA01  I65  PC124_3
   1 SW_P12V_AUX_PVDDCR_CPU1_P0_FLT      A @T6G_MB_LIB.T6G(SCH_1):SW_P12V_AUX_PVDDCR_CPU1_P0_FLT
   2    GND      B @T6G_MB_LIB.T6G(SCH_1):GND

Q_CAP_C0805-22UF,16V,20%,X6S,CH6223MEA01  I66  PC126_3
   1 SW_P12V_AUX_PVDDCR_CPU1_P0_FLT      A @T6G_MB_LIB.T6G(SCH_1):SW_P12V_AUX_PVDDCR_CPU1_P0_FLT
   2    GND      B @T6G_MB_LIB.T6G(SCH_1):GND

Q_CAP_C0805-22UF,4V,20%,X6S,CH622KMEA03  I69  PC129_3
   1 PVDDCR_CPU1_P0      A @T6G_MB_LIB.T6G(SCH_1):PVDDCR_CPU1_P0
   2    GND      B @T6G_MB_LIB.T6G(SCH_1):GND

Q_CAP_C0805-22UF,4V,20%,X6S,CH622KMEA03  I71  PC130_3
   1 PVDDCR_CPU1_P0      A @T6G_MB_LIB.T6G(SCH_1):PVDDCR_CPU1_P0
   2    GND      B @T6G_MB_LIB.T6G(SCH_1):GND


DRAWING: @T6G_MB_LIB.T6G(SCH_1):PAGE178 

Q_CAP_C0402-2.2UF,10V,10%,X6S,CH5222KEB01  I31  PC133_C1P0_5
   1 PVDDCR_CPU1_P0_PVCC      A @T6G_MB_LIB.T6G(SCH_1):PVDDCR_CPU1_P0_PVCC
   2    GND      B @T6G_MB_LIB.T6G(SCH_1):GND

Q_RES_0402LF-5.6,1%,1/16W,CHIP,CS-5602FB01  I39  PR420
   1 SW_PVDDCR_CPU1_P0_BOOT6      A @T6G_MB_LIB.T6G(SCH_1):SW_PVDDCR_CPU1_P0_BOOT6
   2 SW_PVDDCR_CPU1_P0_BOOT6_R      B @T6G_MB_LIB.T6G(SCH_1):SW_PVDDCR_CPU1_P0_BOOT6_R

Q_CAP_0402-0.1UF,25V,10%,X7R,CH4104K1B00  I40  PC114_6
   1 SW_P12V_AUX_PVDDCR_CPU1_P0_FLT      A @T6G_MB_LIB.T6G(SCH_1):SW_P12V_AUX_PVDDCR_CPU1_P0_FLT
   2    GND      B @T6G_MB_LIB.T6G(SCH_1):GND

Q_CAP_C0402-1UF,25V,10%,X6S,CH5104KEB02  I59  PC135_5
   1 SW_P12V_AUX_PVDDCR_CPU1_P0_FLT      A @T6G_MB_LIB.T6G(SCH_1):SW_P12V_AUX_PVDDCR_CPU1_P0_FLT
   2    GND      B @T6G_MB_LIB.T6G(SCH_1):GND

Q_CAP_C0805-22UF,16V,20%,X6S,CH6223MEA01  I60  PC136_5
   1 SW_P12V_AUX_PVDDCR_CPU1_P0_FLT      A @T6G_MB_LIB.T6G(SCH_1):SW_P12V_AUX_PVDDCR_CPU1_P0_FLT
   2    GND      B @T6G_MB_LIB.T6G(SCH_1):GND

Q_CAP_0402-0.1UF,25V,10%,X7R,CH4104K1B00  I2  PC111_6
   1 PVDDCR_CPU1_P0_VCCS      A @T6G_MB_LIB.T6G(SCH_1):PVDDCR_CPU1_P0_VCCS
   2    GND      B @T6G_MB_LIB.T6G(SCH_1):GND

Q_RES_0402LF-8.87K,1%,1/16W,EMPTY,CS28872FB01  I4  PR7
   1 PVDDCR_CPU1_P0_LSET6      A @T6G_MB_LIB.T6G(SCH_1):PVDDCR_CPU1_P0_LSET6
   2    GND      B @T6G_MB_LIB.T6G(SCH_1):GND

Q_CAP_0402-0.1UF,25V,10%,X7R,CH4104K1B00  I10  PC132_5
   1 PVDDCR_CPU1_P0_VCCS      A @T6G_MB_LIB.T6G(SCH_1):PVDDCR_CPU1_P0_VCCS
   2    GND      B @T6G_MB_LIB.T6G(SCH_1):GND

Q_CAP_C0402-2.2UF,10V,10%,X6S,CH5222KEB01  I11  PC112
   1 PVDDCR_CPU1_P0_VCC6      A @T6G_MB_LIB.T6G(SCH_1):PVDDCR_CPU1_P0_VCC6
   2    GND      B @T6G_MB_LIB.T6G(SCH_1):GND

Q_RES_0402LF-2.2,1%,1/16W,CHIP,CS-2202FB01  I13  PR416
   1 PVDDCR_CPU1_P0_PVCC      A @T6G_MB_LIB.T6G(SCH_1):PVDDCR_CPU1_P0_PVCC
   2 PVDDCR_CPU1_P0_VCC6      B @T6G_MB_LIB.T6G(SCH_1):PVDDCR_CPU1_P0_VCC6

Q_RES_0402LF-8.87K,1%,1/16W,EMPTY,CS28872FB01  I15  PR93
   1 PVDDCR_CPU1_P0_LSET5      A @T6G_MB_LIB.T6G(SCH_1):PVDDCR_CPU1_P0_LSET5
   2    GND      B @T6G_MB_LIB.T6G(SCH_1):GND

Q_CAP_C0402-2.2UF,10V,10%,X6S,CH5222KEB01  I20  PC113_C1P0_6
   1 PVDDCR_CPU1_P0_PVCC      A @T6G_MB_LIB.T6G(SCH_1):PVDDCR_CPU1_P0_PVCC
   2    GND      B @T6G_MB_LIB.T6G(SCH_1):GND

ISL99390FRZTR5935-ISL99390FRZ-TR5935,SMLF,IC,AL099A  I22  PU16
  34 PVDDCR_CPU1_P0_PWM5    PWM @T6G_MB_LIB.T6G(SCH_1):PVDDCR_CPU1_P0_PWM5
  39 PVDDCR_CPU1_P0_VCCS  REFIN @T6G_MB_LIB.T6G(SCH_1):PVDDCR_CPU1_P0_VCCS
   3 PVDDCR_CPU1_P0_VCC5    VCC @T6G_MB_LIB.T6G(SCH_1):PVDDCR_CPU1_P0_VCC5
   2    GND   AGND @T6G_MB_LIB.T6G(SCH_1):GND
  33 SW_PVDDCR_CPU1_P0_BOOT5   BOOT @T6G_MB_LIB.T6G(SCH_1):SW_PVDDCR_CPU1_P0_BOOT5
25_29 SW_P12V_AUX_PVDDCR_CPU1_P0_FLT   VIN1 @T6G_MB_LIB.T6G(SCH_1):SW_P12V_AUX_PVDDCR_CPU1_P0_FLT
  32 SW_PVDDCR_CPU1_P0_BOOTR5  PHASE @T6G_MB_LIB.T6G(SCH_1):SW_PVDDCR_CPU1_P0_BOOTR5
   4 PVDDCR_CPU1_P0_PVCC   PVCC @T6G_MB_LIB.T6G(SCH_1):PVDDCR_CPU1_P0_PVCC
  36 PVDDCR_CPU1_P0_TEMP0 TOUT_FLT @T6G_MB_LIB.T6G(SCH_1):PVDDCR_CPU1_P0_TEMP0
  38 PVDDCR_CPU1_P0_IMON5   IOUT @T6G_MB_LIB.T6G(SCH_1):PVDDCR_CPU1_P0_IMON5
  37 PVDDCR_CPU1_P0_LSET5   LSET @T6G_MB_LIB.T6G(SCH_1):PVDDCR_CPU1_P0_LSET5
10_19 SW_PVDDCR_CPU1_P0_SW5     SW @T6G_MB_LIB.T6G(SCH_1):SW_PVDDCR_CPU1_P0_SW5
   5    GND  PGND1 @T6G_MB_LIB.T6G(SCH_1):GND
  30 SW_P12V_AUX_PVDDCR_CPU1_P0_FLT   VIN2 @T6G_MB_LIB.T6G(SCH_1):SW_P12V_AUX_PVDDCR_CPU1_P0_FLT
   1 PVDDCR_CPU1_P0_VOS5    VOS @T6G_MB_LIB.T6G(SCH_1):PVDDCR_CPU1_P0_VOS5
  40    GND  PGND3 @T6G_MB_LIB.T6G(SCH_1):GND
  35 PVDDCR_CPU1_P0_VCC5     EN @T6G_MB_LIB.T6G(SCH_1):PVDDCR_CPU1_P0_VCC5
  31 NC_PVDDCR_CPU1_P0_DNC5    DNC @T6G_MB_LIB.T6G(SCH_1):NC_PVDDCR_CPU1_P0_DNC5
   6 NC_PVDDCR_CPU1_P0_GL1_5    GL1 @T6G_MB_LIB.T6G(SCH_1):NC_PVDDCR_CPU1_P0_GL1_5
  41 NC_PVDDCR_CPU1_P0_GL2_5    GL2 @T6G_MB_LIB.T6G(SCH_1):NC_PVDDCR_CPU1_P0_GL2_5
7_9-20_24    GND  PGND2 @T6G_MB_LIB.T6G(SCH_1):GND

Q_CAP_C0402-2.2UF,10V,10%,X6S,CH5222KEB01  I27  PC131
   1 PVDDCR_CPU1_P0_VCC5      A @T6G_MB_LIB.T6G(SCH_1):PVDDCR_CPU1_P0_VCC5
   2    GND      B @T6G_MB_LIB.T6G(SCH_1):GND

Q_RES_0402LF-2.2,1%,1/16W,CHIP,CS-2202FB01  I28  PR94
   1 PVDDCR_CPU1_P0_PVCC      A @T6G_MB_LIB.T6G(SCH_1):PVDDCR_CPU1_P0_PVCC
   2 PVDDCR_CPU1_P0_VCC5      B @T6G_MB_LIB.T6G(SCH_1):PVDDCR_CPU1_P0_VCC5

Q_RES_0402LF-1.5,1%,1/8W,EMPTY,CS-1504FB00  I33  PR155
   1 SW_PVDDCR_CPU1_P0_SW6_RC      A @T6G_MB_LIB.T6G(SCH_1):SW_PVDDCR_CPU1_P0_SW6_RC
   2    GND      B @T6G_MB_LIB.T6G(SCH_1):GND

Q_RES_0402LF-0,5%,1/16W,CHIP,CS00002JB13  I35  PR421
   1 PVDDCR_CPU1_P0_VOS6      A @T6G_MB_LIB.T6G(SCH_1):PVDDCR_CPU1_P0_VOS6
   2 PVDDCR_CPU1_P0      B @T6G_MB_LIB.T6G(SCH_1):PVDDCR_CPU1_P0

Q_INDUCTOR_SMLF-120NH/69A,IND,CV+12^0EZ03  I36  PL9
   2    GND      2 @T6G_MB_LIB.T6G(SCH_1):GND
   1 IND_CPU1_P0_CPL0      1 @T6G_MB_LIB.T6G(SCH_1):IND_CPU1_P0_CPL0

Q_CAP_0402-0.22UF,16V,10%,X7R,CH4223K1B00  I37  PC117
   1 SW_PVDDCR_CPU1_P0_BOOT6_R      A @T6G_MB_LIB.T6G(SCH_1):SW_PVDDCR_CPU1_P0_BOOT6_R
   2 SW_PVDDCR_CPU1_P0_BOOTR6      B @T6G_MB_LIB.T6G(SCH_1):SW_PVDDCR_CPU1_P0_BOOTR6

Q_INDUCTOR4P_14-150NH,SMLF,IND,CV+15^0TZ04  I38  PL7
   2 IND_CPU1_P0_CPL0      2 @T6G_MB_LIB.T6G(SCH_1):IND_CPU1_P0_CPL0
   3 IND_CPU1_P0_CPL6      3 @T6G_MB_LIB.T6G(SCH_1):IND_CPU1_P0_CPL6
   4 PVDDCR_CPU1_P0      4 @T6G_MB_LIB.T6G(SCH_1):PVDDCR_CPU1_P0
   1 SW_PVDDCR_CPU1_P0_SW6      1 @T6G_MB_LIB.T6G(SCH_1):SW_PVDDCR_CPU1_P0_SW6

Q_CAP_C0402-1UF,25V,10%,X6S,CH5104KEB02  I41  PC115_6
   1 SW_P12V_AUX_PVDDCR_CPU1_P0_FLT      A @T6G_MB_LIB.T6G(SCH_1):SW_P12V_AUX_PVDDCR_CPU1_P0_FLT
   2    GND      B @T6G_MB_LIB.T6G(SCH_1):GND

Q_CAP_C0805-22UF,16V,20%,X6S,CH6223MEA01  I42  PC116_6
   1 SW_P12V_AUX_PVDDCR_CPU1_P0_FLT      A @T6G_MB_LIB.T6G(SCH_1):SW_P12V_AUX_PVDDCR_CPU1_P0_FLT
   2    GND      B @T6G_MB_LIB.T6G(SCH_1):GND

Q_RES_0402LF-1.5,1%,1/8W,EMPTY,CS-1504FB00  I44  PR158
   1 SW_PVDDCR_CPU1_P0_SW5_RC      A @T6G_MB_LIB.T6G(SCH_1):SW_PVDDCR_CPU1_P0_SW5_RC
   2    GND      B @T6G_MB_LIB.T6G(SCH_1):GND

Q_CAP_C0805-22UF,16V,20%,X6S,CH6223MEA01  I45  PC118_6
   1 SW_P12V_AUX_PVDDCR_CPU1_P0_FLT      A @T6G_MB_LIB.T6G(SCH_1):SW_P12V_AUX_PVDDCR_CPU1_P0_FLT
   2    GND      B @T6G_MB_LIB.T6G(SCH_1):GND

Q_CAP_C0805-22UF,16V,20%,X6S,CH6223MEA01  I47  PC119_6
   1 SW_P12V_AUX_PVDDCR_CPU1_P0_FLT      A @T6G_MB_LIB.T6G(SCH_1):SW_P12V_AUX_PVDDCR_CPU1_P0_FLT
   2    GND      B @T6G_MB_LIB.T6G(SCH_1):GND

Q_RES_0402LF-0,5%,1/16W,CHIP,CS00002JB13  I49  PR96
   1 PVDDCR_CPU1_P0_VOS5      A @T6G_MB_LIB.T6G(SCH_1):PVDDCR_CPU1_P0_VOS5
   2 PVDDCR_CPU1_P0      B @T6G_MB_LIB.T6G(SCH_1):PVDDCR_CPU1_P0

Q_CAP_C0805-22UF,4V,20%,X6S,CH622KMEA03  I51  PC120_6
   1 PVDDCR_CPU1_P0      A @T6G_MB_LIB.T6G(SCH_1):PVDDCR_CPU1_P0
   2    GND      B @T6G_MB_LIB.T6G(SCH_1):GND

Q_CAP_C0805-22UF,4V,20%,X6S,CH622KMEA03  I53  PC123_6
   1 PVDDCR_CPU1_P0      A @T6G_MB_LIB.T6G(SCH_1):PVDDCR_CPU1_P0
   2    GND      B @T6G_MB_LIB.T6G(SCH_1):GND

Q_RES_0402LF-5.6,1%,1/16W,CHIP,CS-5602FB01  I56  PR95
   1 SW_PVDDCR_CPU1_P0_BOOT5      A @T6G_MB_LIB.T6G(SCH_1):SW_PVDDCR_CPU1_P0_BOOT5
   2 SW_PVDDCR_CPU1_P0_BOOT5_R      B @T6G_MB_LIB.T6G(SCH_1):SW_PVDDCR_CPU1_P0_BOOT5_R

Q_CAP_C0402-560PF,50V,10%,EMPTY,CH1566K1B09  I57  PC157
   1 SW_PVDDCR_CPU1_P0_SW5      A @T6G_MB_LIB.T6G(SCH_1):SW_PVDDCR_CPU1_P0_SW5
   2 SW_PVDDCR_CPU1_P0_SW5_RC      B @T6G_MB_LIB.T6G(SCH_1):SW_PVDDCR_CPU1_P0_SW5_RC

Q_CAP_0402-0.1UF,25V,10%,X7R,CH4104K1B00  I58  PC134_5
   1 SW_P12V_AUX_PVDDCR_CPU1_P0_FLT      A @T6G_MB_LIB.T6G(SCH_1):SW_P12V_AUX_PVDDCR_CPU1_P0_FLT
   2    GND      B @T6G_MB_LIB.T6G(SCH_1):GND

Q_CAP_0402-0.22UF,16V,10%,X7R,CH4223K1B00  I62  PC137
   1 SW_PVDDCR_CPU1_P0_BOOT5_R      A @T6G_MB_LIB.T6G(SCH_1):SW_PVDDCR_CPU1_P0_BOOT5_R
   2 SW_PVDDCR_CPU1_P0_BOOTR5      B @T6G_MB_LIB.T6G(SCH_1):SW_PVDDCR_CPU1_P0_BOOTR5

Q_INDUCTOR4P_14-150NH,SMLF,IND,CV+15^0TZ04  I63  PL15
   2 IND_CPU1_P0_CPL6      2 @T6G_MB_LIB.T6G(SCH_1):IND_CPU1_P0_CPL6
   3 IND_CPU1_P0_CPL5      3 @T6G_MB_LIB.T6G(SCH_1):IND_CPU1_P0_CPL5
   4 PVDDCR_CPU1_P0      4 @T6G_MB_LIB.T6G(SCH_1):PVDDCR_CPU1_P0
   1 SW_PVDDCR_CPU1_P0_SW5      1 @T6G_MB_LIB.T6G(SCH_1):SW_PVDDCR_CPU1_P0_SW5

Q_CAP_C0805-22UF,16V,20%,X6S,CH6223MEA01  I65  PC138_5
   1 SW_P12V_AUX_PVDDCR_CPU1_P0_FLT      A @T6G_MB_LIB.T6G(SCH_1):SW_P12V_AUX_PVDDCR_CPU1_P0_FLT
   2    GND      B @T6G_MB_LIB.T6G(SCH_1):GND

Q_CAP_C0805-22UF,16V,20%,X6S,CH6223MEA01  I66  PC139_5
   1 SW_P12V_AUX_PVDDCR_CPU1_P0_FLT      A @T6G_MB_LIB.T6G(SCH_1):SW_P12V_AUX_PVDDCR_CPU1_P0_FLT
   2    GND      B @T6G_MB_LIB.T6G(SCH_1):GND

Q_CAP_C0805-22UF,4V,20%,X6S,CH622KMEA03  I69  PC140_5
   1 PVDDCR_CPU1_P0      A @T6G_MB_LIB.T6G(SCH_1):PVDDCR_CPU1_P0
   2    GND      B @T6G_MB_LIB.T6G(SCH_1):GND

Q_CAP_C0805-22UF,4V,20%,X6S,CH622KMEA03  I70  PC141_5
   1 PVDDCR_CPU1_P0      A @T6G_MB_LIB.T6G(SCH_1):PVDDCR_CPU1_P0
   2    GND      B @T6G_MB_LIB.T6G(SCH_1):GND

Q_CAP_C0402-560PF,50V,10%,EMPTY,CH1566K1B09  I72  PC154
   1 SW_PVDDCR_CPU1_P0_SW6      A @T6G_MB_LIB.T6G(SCH_1):SW_PVDDCR_CPU1_P0_SW6
   2 SW_PVDDCR_CPU1_P0_SW6_RC      B @T6G_MB_LIB.T6G(SCH_1):SW_PVDDCR_CPU1_P0_SW6_RC

ISL99390FRZTR5935-ISL99390FRZ-TR5935,SMLF,IC,AL099A  I73  PU11
  34 PVDDCR_CPU1_P0_PWM6    PWM @T6G_MB_LIB.T6G(SCH_1):PVDDCR_CPU1_P0_PWM6
  39 PVDDCR_CPU1_P0_VCCS  REFIN @T6G_MB_LIB.T6G(SCH_1):PVDDCR_CPU1_P0_VCCS
   3 PVDDCR_CPU1_P0_VCC6    VCC @T6G_MB_LIB.T6G(SCH_1):PVDDCR_CPU1_P0_VCC6
   2    GND   AGND @T6G_MB_LIB.T6G(SCH_1):GND
  33 SW_PVDDCR_CPU1_P0_BOOT6   BOOT @T6G_MB_LIB.T6G(SCH_1):SW_PVDDCR_CPU1_P0_BOOT6
25_29 SW_P12V_AUX_PVDDCR_CPU1_P0_FLT   VIN1 @T6G_MB_LIB.T6G(SCH_1):SW_P12V_AUX_PVDDCR_CPU1_P0_FLT
  32 SW_PVDDCR_CPU1_P0_BOOTR6  PHASE @T6G_MB_LIB.T6G(SCH_1):SW_PVDDCR_CPU1_P0_BOOTR6
   4 PVDDCR_CPU1_P0_PVCC   PVCC @T6G_MB_LIB.T6G(SCH_1):PVDDCR_CPU1_P0_PVCC
  36 PVDDCR_CPU1_P0_TEMP0 TOUT_FLT @T6G_MB_LIB.T6G(SCH_1):PVDDCR_CPU1_P0_TEMP0
  38 PVDDCR_CPU1_P0_IMON6   IOUT @T6G_MB_LIB.T6G(SCH_1):PVDDCR_CPU1_P0_IMON6
  37 PVDDCR_CPU1_P0_LSET6   LSET @T6G_MB_LIB.T6G(SCH_1):PVDDCR_CPU1_P0_LSET6
10_19 SW_PVDDCR_CPU1_P0_SW6     SW @T6G_MB_LIB.T6G(SCH_1):SW_PVDDCR_CPU1_P0_SW6
   5    GND  PGND1 @T6G_MB_LIB.T6G(SCH_1):GND
  30 SW_P12V_AUX_PVDDCR_CPU1_P0_FLT   VIN2 @T6G_MB_LIB.T6G(SCH_1):SW_P12V_AUX_PVDDCR_CPU1_P0_FLT
   1 PVDDCR_CPU1_P0_VOS6    VOS @T6G_MB_LIB.T6G(SCH_1):PVDDCR_CPU1_P0_VOS6
  40    GND  PGND3 @T6G_MB_LIB.T6G(SCH_1):GND
  35 PVDDCR_CPU1_P0_VCC6     EN @T6G_MB_LIB.T6G(SCH_1):PVDDCR_CPU1_P0_VCC6
  31 NC_PVDDCR_CPU1_P0_DNC6    DNC @T6G_MB_LIB.T6G(SCH_1):NC_PVDDCR_CPU1_P0_DNC6
   6 NC_PVDDCR_CPU1_P0_GL1_6    GL1 @T6G_MB_LIB.T6G(SCH_1):NC_PVDDCR_CPU1_P0_GL1_6
  41 NC_PVDDCR_CPU1_P0_GL2_6    GL2 @T6G_MB_LIB.T6G(SCH_1):NC_PVDDCR_CPU1_P0_GL2_6
7_9-20_24    GND  PGND2 @T6G_MB_LIB.T6G(SCH_1):GND


DRAWING: @T6G_MB_LIB.T6G(SCH_1):PAGE181 

Q_RES_0402LF-2.2,1%,1/16W,CHIP,CS-2202FB01  I28  PR108
   1 PVDDCR_CPU1_P0_PVCC      A @T6G_MB_LIB.T6G(SCH_1):PVDDCR_CPU1_P0_PVCC
   2 PVDDIO_P0_VCC3      B @T6G_MB_LIB.T6G(SCH_1):PVDDIO_P0_VCC3

Q_CAP_0402-0.22UF,16V,10%,X7R,CH4223K1B00  I44  PC183
   1 SW_PVDDIO_P0_BOOT4_R      A @T6G_MB_LIB.T6G(SCH_1):SW_PVDDIO_P0_BOOT4_R
   2 SW_PVDDIO_P0_BOOTR4      B @T6G_MB_LIB.T6G(SCH_1):SW_PVDDIO_P0_BOOTR4

Q_CAP_C0805-22UF,16V,20%,X6S,CH6223MEA01  I46  PC182_4
   1 SW_P12V_AUX_PVDDIO_P0_FLT      A @T6G_MB_LIB.T6G(SCH_1):SW_P12V_AUX_PVDDIO_P0_FLT
   2    GND      B @T6G_MB_LIB.T6G(SCH_1):GND

Q_RES_0402LF-1.5,1%,1/8W,EMPTY,CS-1504FB00  I55  PR379
   1 SW_PVDDIO_P0_SW3_RC      A @T6G_MB_LIB.T6G(SCH_1):SW_PVDDIO_P0_SW3_RC
   2    GND      B @T6G_MB_LIB.T6G(SCH_1):GND

Q_CAP_0402-0.22UF,16V,10%,X7R,CH4223K1B00  I59  PC186
   1 SW_PVDDIO_P0_BOOT3_R      A @T6G_MB_LIB.T6G(SCH_1):SW_PVDDIO_P0_BOOT3_R
   2 SW_PVDDIO_P0_BOOTR3      B @T6G_MB_LIB.T6G(SCH_1):SW_PVDDIO_P0_BOOTR3

Q_CAP_C0805-22UF,4V,20%,X6S,CH622KMEA03  I68  PC191_4
   1 PVDDIO_P0      A @T6G_MB_LIB.T6G(SCH_1):PVDDIO_P0
   2    GND      B @T6G_MB_LIB.T6G(SCH_1):GND

Q_CAP_C0805-22UF,4V,20%,X6S,CH622KMEA03  I71  PC192_3
   1 PVDDIO_P0      A @T6G_MB_LIB.T6G(SCH_1):PVDDIO_P0
   2    GND      B @T6G_MB_LIB.T6G(SCH_1):GND

Q_CAP_0402-0.1UF,25V,10%,X7R,CH4104K1B00  I1  PC176_10
   1 PVDDCR_CPU1_P0_VCCS      A @T6G_MB_LIB.T6G(SCH_1):PVDDCR_CPU1_P0_VCCS
   2    GND      B @T6G_MB_LIB.T6G(SCH_1):GND

Q_RES_0402LF-8.87K,1%,1/16W,EMPTY,CS28872FB01  I4  PR105
   1 PVDDIO_P0_LSET4      A @T6G_MB_LIB.T6G(SCH_1):PVDDIO_P0_LSET4
   2    GND      B @T6G_MB_LIB.T6G(SCH_1):GND

Q_CAP_C0402-2.2UF,10V,10%,X6S,CH5222KEB01  I10  PC171
   1 PVDDIO_P0_VCC4      A @T6G_MB_LIB.T6G(SCH_1):PVDDIO_P0_VCC4
   2    GND      B @T6G_MB_LIB.T6G(SCH_1):GND

Q_RES_0402LF-2.2,1%,1/16W,CHIP,CS-2202FB01  I12  PR107
   1 PVDDCR_CPU1_P0_PVCC      A @T6G_MB_LIB.T6G(SCH_1):PVDDCR_CPU1_P0_PVCC
   2 PVDDIO_P0_VCC4      B @T6G_MB_LIB.T6G(SCH_1):PVDDIO_P0_VCC4

Q_CAP_C0402-2.2UF,10V,10%,X6S,CH5222KEB01  I13  PC173_IOP0_4
   1 PVDDCR_CPU1_P0_PVCC      A @T6G_MB_LIB.T6G(SCH_1):PVDDCR_CPU1_P0_PVCC
   2    GND      B @T6G_MB_LIB.T6G(SCH_1):GND

Q_RES_0402LF-5.6,1%,1/16W,CHIP,CS-5602FB01  I16  PR109
   1 SW_PVDDIO_P0_BOOT4      A @T6G_MB_LIB.T6G(SCH_1):SW_PVDDIO_P0_BOOT4
   2 SW_PVDDIO_P0_BOOT4_R      B @T6G_MB_LIB.T6G(SCH_1):SW_PVDDIO_P0_BOOT4_R

Q_CAP_0402-0.1UF,25V,10%,X7R,CH4104K1B00  I17  PC178_4
   1 SW_P12V_AUX_PVDDIO_P0_FLT      A @T6G_MB_LIB.T6G(SCH_1):SW_P12V_AUX_PVDDIO_P0_FLT
   2    GND      B @T6G_MB_LIB.T6G(SCH_1):GND

Q_CAP_0402-0.1UF,25V,10%,X7R,CH4104K1B00  I19  PC175_9
   1 PVDDCR_CPU1_P0_VCCS      A @T6G_MB_LIB.T6G(SCH_1):PVDDCR_CPU1_P0_VCCS
   2    GND      B @T6G_MB_LIB.T6G(SCH_1):GND

Q_RES_0402LF-8.87K,1%,1/16W,EMPTY,CS28872FB01  I21  PR106
   1 PVDDIO_P0_LSET3      A @T6G_MB_LIB.T6G(SCH_1):PVDDIO_P0_LSET3
   2    GND      B @T6G_MB_LIB.T6G(SCH_1):GND

Q_CAP_C0402-2.2UF,10V,10%,X6S,CH5222KEB01  I27  PC172
   1 PVDDIO_P0_VCC3      A @T6G_MB_LIB.T6G(SCH_1):PVDDIO_P0_VCC3
   2    GND      B @T6G_MB_LIB.T6G(SCH_1):GND

Q_CAP_C0402-2.2UF,10V,10%,X6S,CH5222KEB01  I30  PC174_IOP0_3
   1 PVDDCR_CPU1_P0_PVCC      A @T6G_MB_LIB.T6G(SCH_1):PVDDCR_CPU1_P0_PVCC
   2    GND      B @T6G_MB_LIB.T6G(SCH_1):GND

ISL99390FRZTR5935-ISL99390FRZ-TR5935,SMLF,IC,AL099A  I32  PU19
  34 PVDDIO_P0_PWM3    PWM @T6G_MB_LIB.T6G(SCH_1):PVDDIO_P0_PWM3
  39 PVDDCR_CPU1_P0_VCCS  REFIN @T6G_MB_LIB.T6G(SCH_1):PVDDCR_CPU1_P0_VCCS
   3 PVDDIO_P0_VCC3    VCC @T6G_MB_LIB.T6G(SCH_1):PVDDIO_P0_VCC3
   2    GND   AGND @T6G_MB_LIB.T6G(SCH_1):GND
  33 SW_PVDDIO_P0_BOOT3   BOOT @T6G_MB_LIB.T6G(SCH_1):SW_PVDDIO_P0_BOOT3
25_29 SW_P12V_AUX_PVDDIO_P0_FLT   VIN1 @T6G_MB_LIB.T6G(SCH_1):SW_P12V_AUX_PVDDIO_P0_FLT
  32 SW_PVDDIO_P0_BOOTR3  PHASE @T6G_MB_LIB.T6G(SCH_1):SW_PVDDIO_P0_BOOTR3
   4 PVDDCR_CPU1_P0_PVCC   PVCC @T6G_MB_LIB.T6G(SCH_1):PVDDCR_CPU1_P0_PVCC
  36 PVDDIO_P0_TEMP1 TOUT_FLT @T6G_MB_LIB.T6G(SCH_1):PVDDIO_P0_TEMP1
  38 PVDDIO_P0_IMON3   IOUT @T6G_MB_LIB.T6G(SCH_1):PVDDIO_P0_IMON3
  37 PVDDIO_P0_LSET3   LSET @T6G_MB_LIB.T6G(SCH_1):PVDDIO_P0_LSET3
10_19 SW_PVDDIO_P0_SW3     SW @T6G_MB_LIB.T6G(SCH_1):SW_PVDDIO_P0_SW3
   5    GND  PGND1 @T6G_MB_LIB.T6G(SCH_1):GND
  30 SW_P12V_AUX_PVDDIO_P0_FLT   VIN2 @T6G_MB_LIB.T6G(SCH_1):SW_P12V_AUX_PVDDIO_P0_FLT
   1 PVDDIO_P0_VOS3    VOS @T6G_MB_LIB.T6G(SCH_1):PVDDIO_P0_VOS3
  40    GND  PGND3 @T6G_MB_LIB.T6G(SCH_1):GND
  35 PVDDIO_P0_VCC3     EN @T6G_MB_LIB.T6G(SCH_1):PVDDIO_P0_VCC3
  31 NC_PVDDIO_P0_DNC3    DNC @T6G_MB_LIB.T6G(SCH_1):NC_PVDDIO_P0_DNC3
   6 NC_PVDDIO_P0_GL1_3    GL1 @T6G_MB_LIB.T6G(SCH_1):NC_PVDDIO_P0_GL1_3
  41 NC_PVDDIO_P0_GL2_3    GL2 @T6G_MB_LIB.T6G(SCH_1):NC_PVDDIO_P0_GL2_3
7_9-20_24    GND  PGND2 @T6G_MB_LIB.T6G(SCH_1):GND

Q_RES_0402LF-5.6,1%,1/16W,CHIP,CS-5602FB01  I34  PR110
   1 SW_PVDDIO_P0_BOOT3      A @T6G_MB_LIB.T6G(SCH_1):SW_PVDDIO_P0_BOOT3
   2 SW_PVDDIO_P0_BOOT3_R      B @T6G_MB_LIB.T6G(SCH_1):SW_PVDDIO_P0_BOOT3_R

Q_CAP_0402-0.1UF,25V,10%,X7R,CH4104K1B00  I35  PC177_3
   1 SW_P12V_AUX_PVDDIO_P0_FLT      A @T6G_MB_LIB.T6G(SCH_1):SW_P12V_AUX_PVDDIO_P0_FLT
   2    GND      B @T6G_MB_LIB.T6G(SCH_1):GND

Q_CAP_C0402-1UF,25V,10%,X6S,CH5104KEB02  I36  PC179_3
   1 SW_P12V_AUX_PVDDIO_P0_FLT      A @T6G_MB_LIB.T6G(SCH_1):SW_P12V_AUX_PVDDIO_P0_FLT
   2    GND      B @T6G_MB_LIB.T6G(SCH_1):GND

Q_RES_0402LF-1.5,1%,1/8W,EMPTY,CS-1504FB00  I38  PR291
   1 SW_PVDDIO_P0_SW4_RC      A @T6G_MB_LIB.T6G(SCH_1):SW_PVDDIO_P0_SW4_RC
   2    GND      B @T6G_MB_LIB.T6G(SCH_1):GND

Q_CAP_C0402-560PF,50V,10%,EMPTY,CH1566K1B09  I39  PC163
   1 SW_PVDDIO_P0_SW4      A @T6G_MB_LIB.T6G(SCH_1):SW_PVDDIO_P0_SW4
   2 SW_PVDDIO_P0_SW4_RC      B @T6G_MB_LIB.T6G(SCH_1):SW_PVDDIO_P0_SW4_RC

Q_RES_0402LF-0,5%,1/16W,CHIP,CS00002JB13  I41  PR112
   1 PVDDIO_P0_VOS4      A @T6G_MB_LIB.T6G(SCH_1):PVDDIO_P0_VOS4
   2 PVDDIO_P0      B @T6G_MB_LIB.T6G(SCH_1):PVDDIO_P0

Q_INDUCTOR4P_14-150NH,SMLF,IND,CV+15^0TZ04  I42  PL20
   2 IND_PVDDIO_P0_CPL0      2 @T6G_MB_LIB.T6G(SCH_1):IND_PVDDIO_P0_CPL0
   3 IND_PVDDIO_P0_CPL4      3 @T6G_MB_LIB.T6G(SCH_1):IND_PVDDIO_P0_CPL4
   4 PVDDIO_P0      4 @T6G_MB_LIB.T6G(SCH_1):PVDDIO_P0
   1 SW_PVDDIO_P0_SW4      1 @T6G_MB_LIB.T6G(SCH_1):SW_PVDDIO_P0_SW4

Q_INDUCTOR_SMLF-0.22UH/33A,IND,CV+22Y0EZ00  I43  PL16
   2    GND      2 @T6G_MB_LIB.T6G(SCH_1):GND
   1 IND_PVDDIO_P0_CPL0      1 @T6G_MB_LIB.T6G(SCH_1):IND_PVDDIO_P0_CPL0

Q_CAP_C0402-1UF,25V,10%,X6S,CH5104KEB02  I45  PC180_4
   1 SW_P12V_AUX_PVDDIO_P0_FLT      A @T6G_MB_LIB.T6G(SCH_1):SW_P12V_AUX_PVDDIO_P0_FLT
   2    GND      B @T6G_MB_LIB.T6G(SCH_1):GND

Q_CAP_C0805-22UF,16V,20%,X6S,CH6223MEA01  I47  PC185_4
   1 SW_P12V_AUX_PVDDIO_P0_FLT      A @T6G_MB_LIB.T6G(SCH_1):SW_P12V_AUX_PVDDIO_P0_FLT
   2    GND      B @T6G_MB_LIB.T6G(SCH_1):GND

Q_CAP_C0805-22UF,16V,20%,X6S,CH6223MEA01  I49  PC188_4
   1 SW_P12V_AUX_PVDDIO_P0_FLT      A @T6G_MB_LIB.T6G(SCH_1):SW_P12V_AUX_PVDDIO_P0_FLT
   2    GND      B @T6G_MB_LIB.T6G(SCH_1):GND

Q_RES_0402LF-0,5%,1/16W,CHIP,CS00002JB13  I50  PR111
   1 PVDDIO_P0_VOS3      A @T6G_MB_LIB.T6G(SCH_1):PVDDIO_P0_VOS3
   2 PVDDIO_P0      B @T6G_MB_LIB.T6G(SCH_1):PVDDIO_P0

Q_CAP_C0805-22UF,4V,20%,X6S,CH622KMEA03  I53  PC189_4
   1 PVDDIO_P0      A @T6G_MB_LIB.T6G(SCH_1):PVDDIO_P0
   2    GND      B @T6G_MB_LIB.T6G(SCH_1):GND

Q_CAP_C0402-560PF,50V,10%,EMPTY,CH1566K1B09  I56  PC166
   1 SW_PVDDIO_P0_SW3      A @T6G_MB_LIB.T6G(SCH_1):SW_PVDDIO_P0_SW3
   2 SW_PVDDIO_P0_SW3_RC      B @T6G_MB_LIB.T6G(SCH_1):SW_PVDDIO_P0_SW3_RC

Q_CAP_C0805-22UF,16V,20%,X6S,CH6223MEA01  I58  PC181_3
   1 SW_P12V_AUX_PVDDIO_P0_FLT      A @T6G_MB_LIB.T6G(SCH_1):SW_P12V_AUX_PVDDIO_P0_FLT
   2    GND      B @T6G_MB_LIB.T6G(SCH_1):GND

Q_CAP_C0805-22UF,16V,20%,X6S,CH6223MEA01  I60  PC184_3
   1 SW_P12V_AUX_PVDDIO_P0_FLT      A @T6G_MB_LIB.T6G(SCH_1):SW_P12V_AUX_PVDDIO_P0_FLT
   2    GND      B @T6G_MB_LIB.T6G(SCH_1):GND

Q_INDUCTOR4P_14-150NH,SMLF,IND,CV+15^0TZ04  I61  PL21
   2 IND_PVDDIO_P0_CPL4      2 @T6G_MB_LIB.T6G(SCH_1):IND_PVDDIO_P0_CPL4
   3 IND_PVDDIO_P0_CPL3      3 @T6G_MB_LIB.T6G(SCH_1):IND_PVDDIO_P0_CPL3
   4 PVDDIO_P0      4 @T6G_MB_LIB.T6G(SCH_1):PVDDIO_P0
   1 SW_PVDDIO_P0_SW3      1 @T6G_MB_LIB.T6G(SCH_1):SW_PVDDIO_P0_SW3

Q_CAP_C0805-22UF,16V,20%,X6S,CH6223MEA01  I63  PC187_3
   1 SW_P12V_AUX_PVDDIO_P0_FLT      A @T6G_MB_LIB.T6G(SCH_1):SW_P12V_AUX_PVDDIO_P0_FLT
   2    GND      B @T6G_MB_LIB.T6G(SCH_1):GND

Q_CAP_C0805-22UF,4V,20%,X6S,CH622KMEA03  I66  PC190_3
   1 PVDDIO_P0      A @T6G_MB_LIB.T6G(SCH_1):PVDDIO_P0
   2    GND      B @T6G_MB_LIB.T6G(SCH_1):GND

ISL99390FRZTR5935-ISL99390FRZ-TR5935,SMLF,IC,AL099A  I73  PU20
  34 PVDDIO_P0_PWM4    PWM @T6G_MB_LIB.T6G(SCH_1):PVDDIO_P0_PWM4
  39 PVDDCR_CPU1_P0_VCCS  REFIN @T6G_MB_LIB.T6G(SCH_1):PVDDCR_CPU1_P0_VCCS
   3 PVDDIO_P0_VCC4    VCC @T6G_MB_LIB.T6G(SCH_1):PVDDIO_P0_VCC4
   2    GND   AGND @T6G_MB_LIB.T6G(SCH_1):GND
  33 SW_PVDDIO_P0_BOOT4   BOOT @T6G_MB_LIB.T6G(SCH_1):SW_PVDDIO_P0_BOOT4
25_29 SW_P12V_AUX_PVDDIO_P0_FLT   VIN1 @T6G_MB_LIB.T6G(SCH_1):SW_P12V_AUX_PVDDIO_P0_FLT
  32 SW_PVDDIO_P0_BOOTR4  PHASE @T6G_MB_LIB.T6G(SCH_1):SW_PVDDIO_P0_BOOTR4
   4 PVDDCR_CPU1_P0_PVCC   PVCC @T6G_MB_LIB.T6G(SCH_1):PVDDCR_CPU1_P0_PVCC
  36 PVDDIO_P0_TEMP1 TOUT_FLT @T6G_MB_LIB.T6G(SCH_1):PVDDIO_P0_TEMP1
  38 PVDDIO_P0_IMON4   IOUT @T6G_MB_LIB.T6G(SCH_1):PVDDIO_P0_IMON4
  37 PVDDIO_P0_LSET4   LSET @T6G_MB_LIB.T6G(SCH_1):PVDDIO_P0_LSET4
10_19 SW_PVDDIO_P0_SW4     SW @T6G_MB_LIB.T6G(SCH_1):SW_PVDDIO_P0_SW4
   5    GND  PGND1 @T6G_MB_LIB.T6G(SCH_1):GND
  30 SW_P12V_AUX_PVDDIO_P0_FLT   VIN2 @T6G_MB_LIB.T6G(SCH_1):SW_P12V_AUX_PVDDIO_P0_FLT
   1 PVDDIO_P0_VOS4    VOS @T6G_MB_LIB.T6G(SCH_1):PVDDIO_P0_VOS4
  40    GND  PGND3 @T6G_MB_LIB.T6G(SCH_1):GND
  35 PVDDIO_P0_VCC4     EN @T6G_MB_LIB.T6G(SCH_1):PVDDIO_P0_VCC4
  31 NC_PVDDIO_P0_DNC4    DNC @T6G_MB_LIB.T6G(SCH_1):NC_PVDDIO_P0_DNC4
   6 NC_PVDDIO_P0_GL1_4    GL1 @T6G_MB_LIB.T6G(SCH_1):NC_PVDDIO_P0_GL1_4
  41 NC_PVDDIO_P0_GL2_4    GL2 @T6G_MB_LIB.T6G(SCH_1):NC_PVDDIO_P0_GL2_4
7_9-20_24    GND  PGND2 @T6G_MB_LIB.T6G(SCH_1):GND


DRAWING: @T6G_MB_LIB.T6G(SCH_1):PAGE182 

Q_RES_0402LF-0,5%,1/16W,EMPTY,CS00002JB13  I13  R8116
   1 PVDD11_S3_P0_OCP_N      A @T6G_MB_LIB.T6G(SCH_1):PVDD11_S3_P0_OCP_N
   2 PVDD11_S3_P0_OCP_N_R      B @T6G_MB_LIB.T6G(SCH_1):PVDD11_S3_P0_OCP_N_R

Q_CAP_0402-1000PF,50V,5%,EMPTY,TMP_QCH21006JB10  I47  C196
   1 PWRGD_PVDD11_S3_P0_R      A @T6G_MB_LIB.T6G(SCH_1):PWRGD_PVDD11_S3_P0_R
   2    GND      B @T6G_MB_LIB.T6G(SCH_1):GND

Q_RES_0402LF-0,5%,1/16W,EMPTY,CS00002JB13  I67  PR129
   1 PVDD11_S3_P0_RESET_N_R      A @T6G_MB_LIB.T6G(SCH_1):PVDD11_S3_P0_RESET_N_R
   2 PVDD11_S3_P0_RESET_N      B @T6G_MB_LIB.T6G(SCH_1):PVDD11_S3_P0_RESET_N

Q_RES_0402LF-1K,1%,1/16W,EMPTY,CS21002FB06  I68  PR128
   1 PVDD11_S3_P0_RESET_N_R      A @T6G_MB_LIB.T6G(SCH_1):PVDD11_S3_P0_RESET_N_R
   2 PVDD18_S5_P0      B @T6G_MB_LIB.T6G(SCH_1):PVDD18_S5_P0

Q_CAP_0402-0.1UF,25V,10%,X7R,CH4104K1B00  I77  PC9
   1 PVDD11_S3_P0_VCCS      A @T6G_MB_LIB.T6G(SCH_1):PVDD11_S3_P0_VCCS
   2    GND      B @T6G_MB_LIB.T6G(SCH_1):GND

Q_CAP_C0402-1UF,16V,10%,X6S,CH5103KEB01  I82  PC200
   1 PVDD11_S3_P0_VCC      A @T6G_MB_LIB.T6G(SCH_1):PVDD11_S3_P0_VCC
   2    GND      B @T6G_MB_LIB.T6G(SCH_1):GND

Q_RES_0402LF-40.2K,1%,1/16W,CHIP,CS34022FB04  I2  PR113
   1 P5V_AUX      A @T6G_MB_LIB.T6G(SCH_1):P5V_AUX
   2 PVDD11_S3_P0_VMON      B @T6G_MB_LIB.T6G(SCH_1):PVDD11_S3_P0_VMON

Q_CAP_0402-0.1UF,25V,10%,X7R,CH4104K1B00  I4  PC193
   1 PVDD11_S3_P0_VMON      A @T6G_MB_LIB.T6G(SCH_1):PVDD11_S3_P0_VMON
   2    GND      B @T6G_MB_LIB.T6G(SCH_1):GND

Q_RES_0402LF-10K,1%,1/16W,CHIP,CS31002FB08  I6  PR3
   1 PVDD11_S3_P0_VMON      A @T6G_MB_LIB.T6G(SCH_1):PVDD11_S3_P0_VMON
   2    GND      B @T6G_MB_LIB.T6G(SCH_1):GND

Q_RES_0402LF-0,5%,1/16W,EMPTY,CS00002JB13  I9  R8458
   1 P3V3_AUX      A @T6G_MB_LIB.T6G(SCH_1):P3V3_AUX
   2 PVDD11_S3_P0_VDDIO      B @T6G_MB_LIB.T6G(SCH_1):PVDD11_S3_P0_VDDIO

Q_RES_0402LF-49.9,1%,1/16W,CHIP,CS04992FB07  I15  PR115
   1 VSENSE_VSS_SENSE_C_P0      A @T6G_MB_LIB.T6G(SCH_1):VSENSE_VSS_SENSE_C_P0
   2    GND      B @T6G_MB_LIB.T6G(SCH_1):GND

Q_RES_0402LF-0,5%,1/16W,CHIP,CS00002JB13  I16  PR125
   1 P12V_AUX      A @T6G_MB_LIB.T6G(SCH_1):P12V_AUX
   2 PVDD11_S3_P0_VINSEN      B @T6G_MB_LIB.T6G(SCH_1):PVDD11_S3_P0_VINSEN

Q_RES_0402LF-4.99K,1%,1/16W,EMPTY,CS24992FB07  I18  PR601
   1 PVDD11_S3_P0_VINSEN      A @T6G_MB_LIB.T6G(SCH_1):PVDD11_S3_P0_VINSEN
   2    GND      B @T6G_MB_LIB.T6G(SCH_1):GND

Q_CAP_0402-0.1UF,25V,10%,X7R,CH4104K1B00  I20  PC5
   1 PVDD11_S3_P0_VINSEN      A @T6G_MB_LIB.T6G(SCH_1):PVDD11_S3_P0_VINSEN
   2    GND      B @T6G_MB_LIB.T6G(SCH_1):GND

Q_RES_0402LF-3.09K,1%,1/16W,CHIP,CS23092FB04  I22  PR126
   1 PVDD11_S3_P0_ADDR_CFG      A @T6G_MB_LIB.T6G(SCH_1):PVDD11_S3_P0_ADDR_CFG
   2    GND      B @T6G_MB_LIB.T6G(SCH_1):GND

RAA229621GNPHA0-RAA229621GNP#HA0,SMLF,IC,ARF0TGP40A  I24  PU21
  23 PVDD11_S3_P0_IMON1    CS7 @T6G_MB_LIB.T6G(SCH_1):PVDD11_S3_P0_IMON1
  39 PVDD11_S3_P0_VCC    VCC @T6G_MB_LIB.T6G(SCH_1):PVDD11_S3_P0_VCC
  20    GND   SVTI @T6G_MB_LIB.T6G(SCH_1):GND
  10 PVDD11_S3_P0_PMSCL_R  PMSCL @T6G_MB_LIB.T6G(SCH_1):PVDD11_S3_P0_PMSCL_R
  18    GND    SVC @T6G_MB_LIB.T6G(SCH_1):GND
  24 PVDD11_S3_P0_IMON2    CS6 @T6G_MB_LIB.T6G(SCH_1):PVDD11_S3_P0_IMON2
  19 NC_PVDD11_S3_P0_SVTO   SVTO @T6G_MB_LIB.T6G(SCH_1):NC_PVDD11_S3_P0_SVTO
  14 PVDD11_S3_P0_RESET_N_R RESET_L @T6G_MB_LIB.T6G(SCH_1):PVDD11_S3_P0_RESET_N_R
  25 NC_PVDD11_S3_P0_IMON3    CS5 @T6G_MB_LIB.T6G(SCH_1):NC_PVDD11_S3_P0_IMON3
  26 NC_PVDD11_S3_P0_IMON4    CS4 @T6G_MB_LIB.T6G(SCH_1):NC_PVDD11_S3_P0_IMON4
  16 NC_PVDD11_S3_P0_PG1    PG1 @T6G_MB_LIB.T6G(SCH_1):NC_PVDD11_S3_P0_PG1
  17    GND    SVD @T6G_MB_LIB.T6G(SCH_1):GND
  11 PVDD11_S3_P0_PMALERT_R NPMALERT @T6G_MB_LIB.T6G(SCH_1):PVDD11_S3_P0_PMALERT_R
  13 PVDD11_S3_P0_EN_R    EN0 @T6G_MB_LIB.T6G(SCH_1):PVDD11_S3_P0_EN_R
  22 VSENSE_VSS_SENSE_C_P0  RGND0 @T6G_MB_LIB.T6G(SCH_1):VSENSE_VSS_SENSE_C_P0
   9 PVDD11_S3_P0_PMSDA_R  PMSDA @T6G_MB_LIB.T6G(SCH_1):PVDD11_S3_P0_PMSDA_R
   5 NC_PVDD11_S3_P0_PWM4   PWM4 @T6G_MB_LIB.T6G(SCH_1):NC_PVDD11_S3_P0_PWM4
   6 NC_PVDD11_S3_P0_PWM3   PWM5 @T6G_MB_LIB.T6G(SCH_1):NC_PVDD11_S3_P0_PWM3
  21 VSENSE_PVDD11_S3_P0_R  VSEN0 @T6G_MB_LIB.T6G(SCH_1):VSENSE_PVDD11_S3_P0_R
   2 NC_PVDD11_S3_P0_PWM7   PWM1 @T6G_MB_LIB.T6G(SCH_1):NC_PVDD11_S3_P0_PWM7
  12 PWRGD_PVDD11_S3_P0_R    PG0 @T6G_MB_LIB.T6G(SCH_1):PWRGD_PVDD11_S3_P0_R
   7 PVDD11_S3_P0_PWM2   PWM6 @T6G_MB_LIB.T6G(SCH_1):PVDD11_S3_P0_PWM2
  40 PVDD11_S3_P0_VCCS   VCCS @T6G_MB_LIB.T6G(SCH_1):PVDD11_S3_P0_VCCS
  37 PVDD11_S3_P0_VMON VMON||IINSEN @T6G_MB_LIB.T6G(SCH_1):PVDD11_S3_P0_VMON
  38 PVDD11_S3_P0_VINSEN VINSEN @T6G_MB_LIB.T6G(SCH_1):PVDD11_S3_P0_VINSEN
  36 PVDD11_S3_P0_TEMP0  TEMP0 @T6G_MB_LIB.T6G(SCH_1):PVDD11_S3_P0_TEMP0
  15 PVDD11_S3_P0_VDDIO  VDDIO @T6G_MB_LIB.T6G(SCH_1):PVDD11_S3_P0_VDDIO
  32    GND  VSEN1 @T6G_MB_LIB.T6G(SCH_1):GND
  31    GND  RGND1 @T6G_MB_LIB.T6G(SCH_1):GND
  29 NC_PVDD11_S3_P0_IMON7    CS1 @T6G_MB_LIB.T6G(SCH_1):NC_PVDD11_S3_P0_IMON7
   8 PVDD11_S3_P0_PWM1   PWM7 @T6G_MB_LIB.T6G(SCH_1):PVDD11_S3_P0_PWM1
   4 NC_PVDD11_S3_P0_PWM5   PWM3 @T6G_MB_LIB.T6G(SCH_1):NC_PVDD11_S3_P0_PWM5
  27 NC_PVDD11_S3_P0_IMON5    CS3 @T6G_MB_LIB.T6G(SCH_1):NC_PVDD11_S3_P0_IMON5
   3 NC_PVDD11_S3_P0_PWM6   PWM2 @T6G_MB_LIB.T6G(SCH_1):NC_PVDD11_S3_P0_PWM6
  28 NC_PVDD11_S3_P0_IMON6    CS2 @T6G_MB_LIB.T6G(SCH_1):NC_PVDD11_S3_P0_IMON6
  33 PVDD11_S3_P0_OCP_N_R  OCP_L @T6G_MB_LIB.T6G(SCH_1):PVDD11_S3_P0_OCP_N_R
  TH    GND TH_GND @T6G_MB_LIB.T6G(SCH_1):GND
  34 PVDD11_S3_P0_ADDR_CFG EN1||ADDR_CFG @T6G_MB_LIB.T6G(SCH_1):PVDD11_S3_P0_ADDR_CFG
  35 PVDD11_S3_P0_TEMP1  TEMP1 @T6G_MB_LIB.T6G(SCH_1):PVDD11_S3_P0_TEMP1
   1 NC_PVDD11_S3_P0_PWM8   PWM0 @T6G_MB_LIB.T6G(SCH_1):NC_PVDD11_S3_P0_PWM8
  30 NC_PVDD11_S3_P0_IMON8    CS0 @T6G_MB_LIB.T6G(SCH_1):NC_PVDD11_S3_P0_IMON8

Q_RES_0402LF-1K,1%,1/16W,EMPTY,CS21002FB06  I25  R124
   1 PVDD18_S5_P0      A @T6G_MB_LIB.T6G(SCH_1):PVDD18_S5_P0
   2 PVDD11_S3_P0_OCP_N_R      B @T6G_MB_LIB.T6G(SCH_1):PVDD11_S3_P0_OCP_N_R

Q_RES_0402LF-0,5%,1/16W,CHIP,CS00002JB13  I28  PR121
   1 VSENSE_PVDD11_S3_P0_DP      A @T6G_MB_LIB.T6G(SCH_1):VSENSE_PVDD11_S3_P0_DP
   2 VSENSE_PVDD11_S3_P0_R      B @T6G_MB_LIB.T6G(SCH_1):VSENSE_PVDD11_S3_P0_R

Q_CAP_0402-3300PF,50V,10%,X7R,TMP_QCH2336K1B12  I29  PC194
   1 VSENSE_PVDD11_S3_P0_R      A @T6G_MB_LIB.T6G(SCH_1):VSENSE_PVDD11_S3_P0_R
   2 VSENSE_VSS_SENSE_C_P0      B @T6G_MB_LIB.T6G(SCH_1):VSENSE_VSS_SENSE_C_P0

Q_RES_0402LF-49.9,1%,1/16W,CHIP,CS04992FB07  I30  PR114
   1 PVDD11_S3_P0      A @T6G_MB_LIB.T6G(SCH_1):PVDD11_S3_P0
   2 VSENSE_PVDD11_S3_P0_DP      B @T6G_MB_LIB.T6G(SCH_1):VSENSE_PVDD11_S3_P0_DP

Q_RES_0402LF-1K,1%,1/16W,CHIP,CS21002FB06  I38  R117
   1 P3V3_AUX      A @T6G_MB_LIB.T6G(SCH_1):P3V3_AUX
   2 PWRGD_PVDD11_S3_P0_R      B @T6G_MB_LIB.T6G(SCH_1):PWRGD_PVDD11_S3_P0_R

Q_RES_0402LF-33,5%,1/16W,CHIP,CS03302JB10  I39  R120
   1 PVDD11_S3_P0_PMALERT      A @T6G_MB_LIB.T6G(SCH_1):PVDD11_S3_P0_PMALERT
   2 PVDD11_S3_P0_PMALERT_R      B @T6G_MB_LIB.T6G(SCH_1):PVDD11_S3_P0_PMALERT_R

Q_RES_0402LF-0,5%,1/16W,CHIP,CS00002JB13  I40  R119
   1 SMB_SCM_2_R6_SDA      A @T6G_MB_LIB.T6G(SCH_1):SMB_SCM_2_R6_SDA
   2 PVDD11_S3_P0_PMSDA_R      B @T6G_MB_LIB.T6G(SCH_1):PVDD11_S3_P0_PMSDA_R

Q_RES_0402LF-0,5%,1/16W,CHIP,CS00002JB13  I41  R118
   1 SMB_SCM_2_R6_SCL      A @T6G_MB_LIB.T6G(SCH_1):SMB_SCM_2_R6_SCL
   2 PVDD11_S3_P0_PMSCL_R      B @T6G_MB_LIB.T6G(SCH_1):PVDD11_S3_P0_PMSCL_R

Q_RES_0402LF-0,5%,1/16W,CHIP,CS00002JB13  I43  R123
   1 PVDD11_S3_P0_EN      A @T6G_MB_LIB.T6G(SCH_1):PVDD11_S3_P0_EN
   2 PVDD11_S3_P0_EN_R      B @T6G_MB_LIB.T6G(SCH_1):PVDD11_S3_P0_EN_R

Q_RES_0402LF-0,5%,1/16W,CHIP,CS00002JB13  I44  R122
   1 PWRGD_PVDD11_S3_P0      A @T6G_MB_LIB.T6G(SCH_1):PWRGD_PVDD11_S3_P0
   2 PWRGD_PVDD11_S3_P0_R      B @T6G_MB_LIB.T6G(SCH_1):PWRGD_PVDD11_S3_P0_R

Q_CAP_0402-1000PF,50V,5%,X7R,TMP_QCH21006JB10  I45  C197
   1 PVDD11_S3_P0_EN_R      A @T6G_MB_LIB.T6G(SCH_1):PVDD11_S3_P0_EN_R
   2    GND      B @T6G_MB_LIB.T6G(SCH_1):GND

Q_CAP_0402-470PF,50V,10%,X7R,TMP_QCH14706KB18  I50  PC198
   1 PVDD11_S3_P0_TEMP0      A @T6G_MB_LIB.T6G(SCH_1):PVDD11_S3_P0_TEMP0
   2    GND      B @T6G_MB_LIB.T6G(SCH_1):GND

Q_RES_0402LF-0,5%,1/16W,CHIP,CS00002JB13  I52  PR412
   1 PVDD11_S3_P0_TEMP1      A @T6G_MB_LIB.T6G(SCH_1):PVDD11_S3_P0_TEMP1
   2    GND      B @T6G_MB_LIB.T6G(SCH_1):GND

Q_RES_0402LF-0,5%,1/16W,CHIP,CS00002JB13  I53  PR36
   1 NC_PVDD11_S3_P0_IMON8      A @T6G_MB_LIB.T6G(SCH_1):NC_PVDD11_S3_P0_IMON8
   2    GND      B @T6G_MB_LIB.T6G(SCH_1):GND

Q_RES_0402LF-0,5%,1/16W,EMPTY,CS00002JB13  I57  PR127
   1 PVDD11_S3_P0_RESET_N_R      A @T6G_MB_LIB.T6G(SCH_1):PVDD11_S3_P0_RESET_N_R
   2    GND      B @T6G_MB_LIB.T6G(SCH_1):GND

Q_RES_0402LF-0,5%,1/16W,CHIP,CS00002JB13  I58  PR419
   1 NC_PVDD11_S3_P0_IMON7      A @T6G_MB_LIB.T6G(SCH_1):NC_PVDD11_S3_P0_IMON7
   2    GND      B @T6G_MB_LIB.T6G(SCH_1):GND

Q_RES_0402LF-0,5%,1/16W,CHIP,CS00002JB13  I59  PR35
   1 NC_PVDD11_S3_P0_IMON6      A @T6G_MB_LIB.T6G(SCH_1):NC_PVDD11_S3_P0_IMON6
   2    GND      B @T6G_MB_LIB.T6G(SCH_1):GND

Q_RES_0402LF-0,5%,1/16W,CHIP,CS00002JB13  I60  PR34
   1 NC_PVDD11_S3_P0_IMON5      A @T6G_MB_LIB.T6G(SCH_1):NC_PVDD11_S3_P0_IMON5
   2    GND      B @T6G_MB_LIB.T6G(SCH_1):GND

Q_RES_0402LF-0,5%,1/16W,CHIP,CS00002JB13  I61  PR33
   1 NC_PVDD11_S3_P0_IMON4      A @T6G_MB_LIB.T6G(SCH_1):NC_PVDD11_S3_P0_IMON4
   2    GND      B @T6G_MB_LIB.T6G(SCH_1):GND

Q_RES_0402LF-0,5%,1/16W,CHIP,CS00002JB13  I71  PR37
   1 NC_PVDD11_S3_P0_IMON3      A @T6G_MB_LIB.T6G(SCH_1):NC_PVDD11_S3_P0_IMON3
   2    GND      B @T6G_MB_LIB.T6G(SCH_1):GND

Q_CAP_0402-0.1UF,25V,10%,X7R,CH4104K1B00  I79  PC4
   1 PVDD11_S3_P0_VCC      A @T6G_MB_LIB.T6G(SCH_1):PVDD11_S3_P0_VCC
   2    GND      B @T6G_MB_LIB.T6G(SCH_1):GND

Q_CAP_C0402-10UF,6.3V,20%,X6S,CH6101MEB03  I80  PC199
   1 PVDD11_S3_P0_VCCS      A @T6G_MB_LIB.T6G(SCH_1):PVDD11_S3_P0_VCCS
   2    GND      B @T6G_MB_LIB.T6G(SCH_1):GND

Q_RES_0402LF-1,1%,1/16W,CHIP,CS-1002FB04  I85  PR130
   1 PVDD11_S3_P0_VCC      A @T6G_MB_LIB.T6G(SCH_1):PVDD11_S3_P0_VCC
   2 P3V3_AUX      B @T6G_MB_LIB.T6G(SCH_1):P3V3_AUX

Q_CAP_0402-1000PF,50V,5%,X7R,TMP_QCH21006JB10  I88  C5009
   1 PVDD11_S3_P0_PMALERT      A @T6G_MB_LIB.T6G(SCH_1):PVDD11_S3_P0_PMALERT
   2    GND      B @T6G_MB_LIB.T6G(SCH_1):GND


DRAWING: @T6G_MB_LIB.T6G(SCH_1):PAGE183 

Q_RES_0402LF-1.5,1%,1/8W,EMPTY,CS-1504FB00  I24  PR389
   1 SW_PVDD11_S3_P0_SW2_RC      A @T6G_MB_LIB.T6G(SCH_1):SW_PVDD11_S3_P0_SW2_RC
   2    GND      B @T6G_MB_LIB.T6G(SCH_1):GND

Q_RES_0402LF-5.6,1%,1/16W,CHIP,CS-5602FB01  I25  PR136
   1 SW_PVDD11_S3_P0_BOOT2      A @T6G_MB_LIB.T6G(SCH_1):SW_PVDD11_S3_P0_BOOT2
   2 SW_PVDD11_S3_P0_BOOT2_RC      B @T6G_MB_LIB.T6G(SCH_1):SW_PVDD11_S3_P0_BOOT2_RC

Q_CAP_C0402-560PF,50V,10%,EMPTY,CH1566K1B09  I26  PC168
   1 SW_PVDD11_S3_P0_SW2      A @T6G_MB_LIB.T6G(SCH_1):SW_PVDD11_S3_P0_SW2
   2 SW_PVDD11_S3_P0_SW2_RC      B @T6G_MB_LIB.T6G(SCH_1):SW_PVDD11_S3_P0_SW2_RC

Q_CAP_C0402-1UF,25V,10%,X6S,CH5104KEB02  I27  PC210_2
   1 SW_P12V_AUX_PVDD11_S3_P0_FLT      A @T6G_MB_LIB.T6G(SCH_1):SW_P12V_AUX_PVDD11_S3_P0_FLT
   2    GND      B @T6G_MB_LIB.T6G(SCH_1):GND

Q_CAP_0402-0.1UF,25V,10%,X7R,CH4104K1B00  I29  PC208_2
   1 SW_P12V_AUX_PVDD11_S3_P0_FLT      A @T6G_MB_LIB.T6G(SCH_1):SW_P12V_AUX_PVDD11_S3_P0_FLT
   2    GND      B @T6G_MB_LIB.T6G(SCH_1):GND

Q_CAP_0402-0.1UF,25V,10%,X7R,CH4104K1B00  I34  PC201_1
   1 PVDD11_S3_P0_VCCS      A @T6G_MB_LIB.T6G(SCH_1):PVDD11_S3_P0_VCCS
   2    GND      B @T6G_MB_LIB.T6G(SCH_1):GND

Q_RES_0402LF-4.87K,1%,1/16W,EMPTY,CS24872FB01  I37  PR133
   1    GND      A @T6G_MB_LIB.T6G(SCH_1):GND
   2 PVDD11_S3_P0_LSET1      B @T6G_MB_LIB.T6G(SCH_1):PVDD11_S3_P0_LSET1

Q_CAP_C0402-1UF,25V,10%,X6S,CH5104KEB02  I44  PC209_1
   1 SW_P12V_AUX_PVDD11_S3_P0_FLT      A @T6G_MB_LIB.T6G(SCH_1):SW_P12V_AUX_PVDD11_S3_P0_FLT
   2    GND      B @T6G_MB_LIB.T6G(SCH_1):GND

Q_CAP_C0805-22UF,16V,20%,X6S,CH6223MEA01  I48  PC211_1
   1 SW_P12V_AUX_PVDD11_S3_P0_FLT      A @T6G_MB_LIB.T6G(SCH_1):SW_P12V_AUX_PVDD11_S3_P0_FLT
   2    GND      B @T6G_MB_LIB.T6G(SCH_1):GND

Q_INDUCTOR_SMLF-90NH/155A,IND,CVA90^0KZ13  I52  PL22
   2 PVDD11_S3_P0      2 @T6G_MB_LIB.T6G(SCH_1):PVDD11_S3_P0
   1 SW_PVDD11_S3_P0_SW2      1 @T6G_MB_LIB.T6G(SCH_1):SW_PVDD11_S3_P0_SW2

Q_CAPP_SMLF-390UF,2.5V,20%,ALUM,CC7390JMZ13  I66  PC229
   1 PVDD11_S3_P0      A @T6G_MB_LIB.T6G(SCH_1):PVDD11_S3_P0
   2    GND      B @T6G_MB_LIB.T6G(SCH_1):GND

Q_CAPP_SMLF-390UF,2.5V,20%,ALUM,CC7390JMZ13  I67  PC230
   1 PVDD11_S3_P0      A @T6G_MB_LIB.T6G(SCH_1):PVDD11_S3_P0
   2    GND      B @T6G_MB_LIB.T6G(SCH_1):GND

Q_CAPP_SMLF-390UF,2.5V,20%,ALUM,CC7390JMZ13  I70  PC801
   1 PVDD11_S3_P0      A @T6G_MB_LIB.T6G(SCH_1):PVDD11_S3_P0
   2    GND      B @T6G_MB_LIB.T6G(SCH_1):GND

Q_CAP_0402-0.1UF,25V,10%,X7R,CH4104K1B00  I79  PC6003
   1 P12V_AUX      A @T6G_MB_LIB.T6G(SCH_1):P12V_AUX
   2    GND      B @T6G_MB_LIB.T6G(SCH_1):GND

Q_CAP_C0805-22UF,4V,20%,X6S,CH622KMEA03  I81  PC224_1
   1 PVDD11_S3_P0      A @T6G_MB_LIB.T6G(SCH_1):PVDD11_S3_P0
   2    GND      B @T6G_MB_LIB.T6G(SCH_1):GND

Q_CAP_0402-0.1UF,25V,10%,X7R,CH4104K1B00  I7  PC202_2
   1 PVDD11_S3_P0_VCCS      A @T6G_MB_LIB.T6G(SCH_1):PVDD11_S3_P0_VCCS
   2    GND      B @T6G_MB_LIB.T6G(SCH_1):GND

Q_CAP_C0402-2.2UF,10V,10%,X6S,CH5222KEB01  I9  PC204
   1 PVDD11_S3_P0_VCC2      A @T6G_MB_LIB.T6G(SCH_1):PVDD11_S3_P0_VCC2
   2    GND      B @T6G_MB_LIB.T6G(SCH_1):GND

Q_RES_0402LF-4.87K,1%,1/16W,EMPTY,CS24872FB01  I11  PR134
   1    GND      A @T6G_MB_LIB.T6G(SCH_1):GND
   2 PVDD11_S3_P0_LSET2      B @T6G_MB_LIB.T6G(SCH_1):PVDD11_S3_P0_LSET2

ISL99390FRZTR5935-ISL99390FRZ-TR5935,SMLF,IC,AL099A  I13  PU23
  34 PVDD11_S3_P0_PWM2    PWM @T6G_MB_LIB.T6G(SCH_1):PVDD11_S3_P0_PWM2
  39 PVDD11_S3_P0_VCCS  REFIN @T6G_MB_LIB.T6G(SCH_1):PVDD11_S3_P0_VCCS
   3 PVDD11_S3_P0_VCC2    VCC @T6G_MB_LIB.T6G(SCH_1):PVDD11_S3_P0_VCC2
   2    GND   AGND @T6G_MB_LIB.T6G(SCH_1):GND
  33 SW_PVDD11_S3_P0_BOOT2   BOOT @T6G_MB_LIB.T6G(SCH_1):SW_PVDD11_S3_P0_BOOT2
25_29 SW_P12V_AUX_PVDD11_S3_P0_FLT   VIN1 @T6G_MB_LIB.T6G(SCH_1):SW_P12V_AUX_PVDD11_S3_P0_FLT
  32 SW_PVDD11_S3_P0_PH2  PHASE @T6G_MB_LIB.T6G(SCH_1):SW_PVDD11_S3_P0_PH2
   4 PVDD11_S3_P0_PVCC   PVCC @T6G_MB_LIB.T6G(SCH_1):PVDD11_S3_P0_PVCC
  36 PVDD11_S3_P0_TEMP0 TOUT_FLT @T6G_MB_LIB.T6G(SCH_1):PVDD11_S3_P0_TEMP0
  38 PVDD11_S3_P0_IMON2   IOUT @T6G_MB_LIB.T6G(SCH_1):PVDD11_S3_P0_IMON2
  37 PVDD11_S3_P0_LSET2   LSET @T6G_MB_LIB.T6G(SCH_1):PVDD11_S3_P0_LSET2
10_19 SW_PVDD11_S3_P0_SW2     SW @T6G_MB_LIB.T6G(SCH_1):SW_PVDD11_S3_P0_SW2
   5    GND  PGND1 @T6G_MB_LIB.T6G(SCH_1):GND
  30 SW_P12V_AUX_PVDD11_S3_P0_FLT   VIN2 @T6G_MB_LIB.T6G(SCH_1):SW_P12V_AUX_PVDD11_S3_P0_FLT
   1 PVDD11_S3_P0_VOS2    VOS @T6G_MB_LIB.T6G(SCH_1):PVDD11_S3_P0_VOS2
  40    GND  PGND3 @T6G_MB_LIB.T6G(SCH_1):GND
  35 PVDD11_S3_P0_VCC2     EN @T6G_MB_LIB.T6G(SCH_1):PVDD11_S3_P0_VCC2
  31 NC_PVDD11_S3_P0_DNC2    DNC @T6G_MB_LIB.T6G(SCH_1):NC_PVDD11_S3_P0_DNC2
   6 NC_PVDD11_S3_P0_GL1_2    GL1 @T6G_MB_LIB.T6G(SCH_1):NC_PVDD11_S3_P0_GL1_2
  41 NC_PVDD11_S3_P0_GL2_2    GL2 @T6G_MB_LIB.T6G(SCH_1):NC_PVDD11_S3_P0_GL2_2
7_9-20_24    GND  PGND2 @T6G_MB_LIB.T6G(SCH_1):GND

Q_RES_0402LF-2.2,1%,1/16W,CHIP,CS-2202FB01  I14  PR132
   1 PVDD11_S3_P0_PVCC      A @T6G_MB_LIB.T6G(SCH_1):PVDD11_S3_P0_PVCC
   2 PVDD11_S3_P0_VCC2      B @T6G_MB_LIB.T6G(SCH_1):PVDD11_S3_P0_VCC2

Q_CAP_C0402-2.2UF,10V,10%,X6S,CH5222KEB01  I17  PC206_11P0_2
   1 PVDD11_S3_P0_PVCC      A @T6G_MB_LIB.T6G(SCH_1):PVDD11_S3_P0_PVCC
   2    GND      B @T6G_MB_LIB.T6G(SCH_1):GND

Q_CAP_C0805-22UF,16V,20%,X6S,CH6223MEA01  I30  PC212_2
   1 SW_P12V_AUX_PVDD11_S3_P0_FLT      A @T6G_MB_LIB.T6G(SCH_1):SW_P12V_AUX_PVDD11_S3_P0_FLT
   2    GND      B @T6G_MB_LIB.T6G(SCH_1):GND

Q_CAP_C0805-22UF,16V,20%,X6S,CH6223MEA01  I31  PC214_2
   1 SW_P12V_AUX_PVDD11_S3_P0_FLT      A @T6G_MB_LIB.T6G(SCH_1):SW_P12V_AUX_PVDD11_S3_P0_FLT
   2    GND      B @T6G_MB_LIB.T6G(SCH_1):GND

Q_RES_0402LF-1.5,1%,1/8W,EMPTY,CS-1504FB00  I33  PR482
   1 SW_PVDD11_S3_P0_SW1_RC      A @T6G_MB_LIB.T6G(SCH_1):SW_PVDD11_S3_P0_SW1_RC
   2    GND      B @T6G_MB_LIB.T6G(SCH_1):GND

Q_CAP_C0402-2.2UF,10V,10%,X6S,CH5222KEB01  I36  PC203
   1 PVDD11_S3_P0_VCC1      A @T6G_MB_LIB.T6G(SCH_1):PVDD11_S3_P0_VCC1
   2    GND      B @T6G_MB_LIB.T6G(SCH_1):GND

Q_RES_0402LF-2.2,1%,1/16W,CHIP,CS-2202FB01  I40  PR131
   1 PVDD11_S3_P0_PVCC      A @T6G_MB_LIB.T6G(SCH_1):PVDD11_S3_P0_PVCC
   2 PVDD11_S3_P0_VCC1      B @T6G_MB_LIB.T6G(SCH_1):PVDD11_S3_P0_VCC1

Q_CAP_C0402-2.2UF,10V,10%,X6S,CH5222KEB01  I42  PC205_11P0_1
   1 PVDD11_S3_P0_PVCC      A @T6G_MB_LIB.T6G(SCH_1):PVDD11_S3_P0_PVCC
   2    GND      B @T6G_MB_LIB.T6G(SCH_1):GND

Q_CAP_C0402-560PF,50V,10%,EMPTY,CH1566K1B09  I45  PC169
   1 SW_PVDD11_S3_P0_SW1      A @T6G_MB_LIB.T6G(SCH_1):SW_PVDD11_S3_P0_SW1
   2 SW_PVDD11_S3_P0_SW1_RC      B @T6G_MB_LIB.T6G(SCH_1):SW_PVDD11_S3_P0_SW1_RC

Q_RES_0402LF-5.6,1%,1/16W,CHIP,CS-5602FB01  I46  PR135
   1 SW_PVDD11_S3_P0_BOOT1      A @T6G_MB_LIB.T6G(SCH_1):SW_PVDD11_S3_P0_BOOT1
   2 SW_PVDD11_S3_P0_BOOT1_RC      B @T6G_MB_LIB.T6G(SCH_1):SW_PVDD11_S3_P0_BOOT1_RC

Q_CAP_0402-0.1UF,25V,10%,X7R,CH4104K1B00  I47  PC207_1
   1 SW_P12V_AUX_PVDD11_S3_P0_FLT      A @T6G_MB_LIB.T6G(SCH_1):SW_P12V_AUX_PVDD11_S3_P0_FLT
   2    GND      B @T6G_MB_LIB.T6G(SCH_1):GND

Q_CAP_C0805-22UF,16V,20%,X6S,CH6223MEA01  I49  PC213_1
   1 SW_P12V_AUX_PVDD11_S3_P0_FLT      A @T6G_MB_LIB.T6G(SCH_1):SW_P12V_AUX_PVDD11_S3_P0_FLT
   2    GND      B @T6G_MB_LIB.T6G(SCH_1):GND

Q_CAP_C0805-22UF,16V,20%,X6S,CH6223MEA01  I50  PC216_2
   1 SW_P12V_AUX_PVDD11_S3_P0_FLT      A @T6G_MB_LIB.T6G(SCH_1):SW_P12V_AUX_PVDD11_S3_P0_FLT
   2    GND      B @T6G_MB_LIB.T6G(SCH_1):GND

Q_CAP_0402-0.22UF,16V,10%,X7R,CH4223K1B00  I51  PC218
   1 SW_PVDD11_S3_P0_BOOT2_RC      A @T6G_MB_LIB.T6G(SCH_1):SW_PVDD11_S3_P0_BOOT2_RC
   2 SW_PVDD11_S3_P0_PH2      B @T6G_MB_LIB.T6G(SCH_1):SW_PVDD11_S3_P0_PH2

Q_CAP_C0805-22UF,16V,20%,X6S,CH6223MEA01  I54  PC218_2
   1 SW_P12V_AUX_PVDD11_S3_P0_FLT      A @T6G_MB_LIB.T6G(SCH_1):SW_P12V_AUX_PVDD11_S3_P0_FLT
   2    GND      B @T6G_MB_LIB.T6G(SCH_1):GND

Q_RES_0402LF-0,5%,1/16W,CHIP,CS00002JB13  I56  PR137
   1 PVDD11_S3_P0_VOS1      A @T6G_MB_LIB.T6G(SCH_1):PVDD11_S3_P0_VOS1
   2 PVDD11_S3_P0      B @T6G_MB_LIB.T6G(SCH_1):PVDD11_S3_P0

Q_CAPP_SMLF-470UF,2.5V,20%,SPCAP,CH747LM8825  I58  PC223
   1 PVDD11_S3_P0      A @T6G_MB_LIB.T6G(SCH_1):PVDD11_S3_P0
   2    GND      B @T6G_MB_LIB.T6G(SCH_1):GND

Q_CAPP_SMLF-470UF,2.5V,20%,SPCAP,CH747LM8825  I59  PC226
   1 PVDD11_S3_P0      A @T6G_MB_LIB.T6G(SCH_1):PVDD11_S3_P0
   2    GND      B @T6G_MB_LIB.T6G(SCH_1):GND

Q_CAP_C0805-22UF,4V,20%,X6S,CH622KMEA03  I62  PC225_2
   1 PVDD11_S3_P0      A @T6G_MB_LIB.T6G(SCH_1):PVDD11_S3_P0
   2    GND      B @T6G_MB_LIB.T6G(SCH_1):GND

Q_CAPP_SMLF-390UF,2.5V,20%,ALUM,CC7390JMZ13  I65  PC228
   1 PVDD11_S3_P0      A @T6G_MB_LIB.T6G(SCH_1):PVDD11_S3_P0
   2    GND      B @T6G_MB_LIB.T6G(SCH_1):GND

Q_CAP_0402-0.22UF,16V,10%,X7R,CH4223K1B00  I71  PC217
   1 SW_PVDD11_S3_P0_BOOT1_RC      A @T6G_MB_LIB.T6G(SCH_1):SW_PVDD11_S3_P0_BOOT1_RC
   2 SW_PVDD11_S3_P0_PH1      B @T6G_MB_LIB.T6G(SCH_1):SW_PVDD11_S3_P0_PH1

Q_INDUCTOR_SMLF-90NH/155A,IND,CVA90^0KZ13  I73  PL23
   2 PVDD11_S3_P0      2 @T6G_MB_LIB.T6G(SCH_1):PVDD11_S3_P0
   1 SW_PVDD11_S3_P0_SW1      1 @T6G_MB_LIB.T6G(SCH_1):SW_PVDD11_S3_P0_SW1

Q_CAPP_THLF-270UF,16V,20%,OSCON,CC72703MD38  I75  PC220
   1 SW_P12V_AUX_PVDD11_S3_P0_FLT      A @T6G_MB_LIB.T6G(SCH_1):SW_P12V_AUX_PVDD11_S3_P0_FLT
   2    GND      B @T6G_MB_LIB.T6G(SCH_1):GND

Q_CAP_0402-0.1UF,25V,10%,X7R,CH4104K1B00  I76  PC222
   1 PVDD11_S3_P0      A @T6G_MB_LIB.T6G(SCH_1):PVDD11_S3_P0
   2    GND      B @T6G_MB_LIB.T6G(SCH_1):GND

Q_INDUCTOR_SMLF-100NH/16A,IND,CV+10G0MZ04  I78  PL24
   2 P12V_AUX      2 @T6G_MB_LIB.T6G(SCH_1):P12V_AUX
   1 SW_P12V_AUX_PVDD11_S3_P0_FLT      1 @T6G_MB_LIB.T6G(SCH_1):SW_P12V_AUX_PVDD11_S3_P0_FLT

Q_CAP_C0805-22UF,4V,20%,X6S,CH622KMEA03  I82  PC227_1
   1 PVDD11_S3_P0      A @T6G_MB_LIB.T6G(SCH_1):PVDD11_S3_P0
   2    GND      B @T6G_MB_LIB.T6G(SCH_1):GND

Q_RES_0402LF-1K,1%,1/16W,CHIP,CS21002FB06  I83  PR414
   1 PVDD11_S3_P0      A @T6G_MB_LIB.T6G(SCH_1):PVDD11_S3_P0
   2    GND      B @T6G_MB_LIB.T6G(SCH_1):GND

Q_RES_0402LF-0,5%,1/16W,CHIP,CS00002JB13  I85  PR411
   1 PVDD11_S3_P0_PVCC      A @T6G_MB_LIB.T6G(SCH_1):PVDD11_S3_P0_PVCC
   2 P5V_AUX      B @T6G_MB_LIB.T6G(SCH_1):P5V_AUX

Q_RES_0402LF-0,5%,1/16W,EMPTY,CS00002JB13  I86  PR413
   1 PVDD11_S3_P0_PVCC      A @T6G_MB_LIB.T6G(SCH_1):PVDD11_S3_P0_PVCC
   2 P3V3_AUX      B @T6G_MB_LIB.T6G(SCH_1):P3V3_AUX

Q_CAP_C0805-22UF,16V,20%,X6S,CH6223MEA01  I87  PC215_1
   1 SW_P12V_AUX_PVDD11_S3_P0_FLT      A @T6G_MB_LIB.T6G(SCH_1):SW_P12V_AUX_PVDD11_S3_P0_FLT
   2    GND      B @T6G_MB_LIB.T6G(SCH_1):GND

Q_CAP_C0805-22UF,16V,20%,X6S,CH6223MEA01  I88  PC219_1
   1 SW_P12V_AUX_PVDD11_S3_P0_FLT      A @T6G_MB_LIB.T6G(SCH_1):SW_P12V_AUX_PVDD11_S3_P0_FLT
   2    GND      B @T6G_MB_LIB.T6G(SCH_1):GND

Q_CAPP_SMLF-470UF,2.5V,20%,SPCAP,CH747LM8825  I89  PC800
   1 PVDD11_S3_P0      A @T6G_MB_LIB.T6G(SCH_1):PVDD11_S3_P0
   2    GND      B @T6G_MB_LIB.T6G(SCH_1):GND

Q_CAP_C0805-22UF,4V,20%,X6S,CH622KMEA03  I90  PC221_2
   1 PVDD11_S3_P0      A @T6G_MB_LIB.T6G(SCH_1):PVDD11_S3_P0
   2    GND      B @T6G_MB_LIB.T6G(SCH_1):GND

Q_RES_0402LF-0,5%,1/16W,CHIP,CS00002JB13  I91  PR138
   1 PVDD11_S3_P0_VOS2      A @T6G_MB_LIB.T6G(SCH_1):PVDD11_S3_P0_VOS2
   2 PVDD11_S3_P0      B @T6G_MB_LIB.T6G(SCH_1):PVDD11_S3_P0

ISL99390FRZTR5935-ISL99390FRZ-TR5935,SMLF,IC,AL099A  I92  PU22
  34 PVDD11_S3_P0_PWM1    PWM @T6G_MB_LIB.T6G(SCH_1):PVDD11_S3_P0_PWM1
  39 PVDD11_S3_P0_VCCS  REFIN @T6G_MB_LIB.T6G(SCH_1):PVDD11_S3_P0_VCCS
   3 PVDD11_S3_P0_VCC1    VCC @T6G_MB_LIB.T6G(SCH_1):PVDD11_S3_P0_VCC1
   2    GND   AGND @T6G_MB_LIB.T6G(SCH_1):GND
  33 SW_PVDD11_S3_P0_BOOT1   BOOT @T6G_MB_LIB.T6G(SCH_1):SW_PVDD11_S3_P0_BOOT1
25_29 SW_P12V_AUX_PVDD11_S3_P0_FLT   VIN1 @T6G_MB_LIB.T6G(SCH_1):SW_P12V_AUX_PVDD11_S3_P0_FLT
  32 SW_PVDD11_S3_P0_PH1  PHASE @T6G_MB_LIB.T6G(SCH_1):SW_PVDD11_S3_P0_PH1
   4 PVDD11_S3_P0_PVCC   PVCC @T6G_MB_LIB.T6G(SCH_1):PVDD11_S3_P0_PVCC
  36 PVDD11_S3_P0_TEMP0 TOUT_FLT @T6G_MB_LIB.T6G(SCH_1):PVDD11_S3_P0_TEMP0
  38 PVDD11_S3_P0_IMON1   IOUT @T6G_MB_LIB.T6G(SCH_1):PVDD11_S3_P0_IMON1
  37 PVDD11_S3_P0_LSET1   LSET @T6G_MB_LIB.T6G(SCH_1):PVDD11_S3_P0_LSET1
10_19 SW_PVDD11_S3_P0_SW1     SW @T6G_MB_LIB.T6G(SCH_1):SW_PVDD11_S3_P0_SW1
   5    GND  PGND1 @T6G_MB_LIB.T6G(SCH_1):GND
  30 SW_P12V_AUX_PVDD11_S3_P0_FLT   VIN2 @T6G_MB_LIB.T6G(SCH_1):SW_P12V_AUX_PVDD11_S3_P0_FLT
   1 PVDD11_S3_P0_VOS1    VOS @T6G_MB_LIB.T6G(SCH_1):PVDD11_S3_P0_VOS1
  40    GND  PGND3 @T6G_MB_LIB.T6G(SCH_1):GND
  35 PVDD11_S3_P0_VCC1     EN @T6G_MB_LIB.T6G(SCH_1):PVDD11_S3_P0_VCC1
  31 NC_PVDD11_S3_P0_DNC1    DNC @T6G_MB_LIB.T6G(SCH_1):NC_PVDD11_S3_P0_DNC1
   6 NC_PVDD11_S3_P0_GL1_1    GL1 @T6G_MB_LIB.T6G(SCH_1):NC_PVDD11_S3_P0_GL1_1
  41 NC_PVDD11_S3_P0_GL2_1    GL2 @T6G_MB_LIB.T6G(SCH_1):NC_PVDD11_S3_P0_GL2_1
7_9-20_24    GND  PGND2 @T6G_MB_LIB.T6G(SCH_1):GND

Q_CAP_C0805-22UF,16V,20%,X6S,CH6223MEA01  I93  PC8004
   1 SW_P12V_AUX_PVDD11_S3_P0_FLT      A @T6G_MB_LIB.T6G(SCH_1):SW_P12V_AUX_PVDD11_S3_P0_FLT
   2    GND      B @T6G_MB_LIB.T6G(SCH_1):GND

Q_CAP_C0805-22UF,16V,20%,X6S,CH6223MEA01  I94  PC8005
   1 SW_P12V_AUX_PVDD11_S3_P0_FLT      A @T6G_MB_LIB.T6G(SCH_1):SW_P12V_AUX_PVDD11_S3_P0_FLT
   2    GND      B @T6G_MB_LIB.T6G(SCH_1):GND

Q_CAP_C0805-22UF,16V,20%,X6S,CH6223MEA01  I95  PC7002
   1 SW_P12V_AUX_PVDD11_S3_P0_FLT      A @T6G_MB_LIB.T6G(SCH_1):SW_P12V_AUX_PVDD11_S3_P0_FLT
   2    GND      B @T6G_MB_LIB.T6G(SCH_1):GND


DRAWING: @T6G_MB_LIB.T6G(SCH_1):PAGE185 

Q_RES_0402LF-0,5%,1/16W,CHIP,CS00002JB13  I4  PR150
   1 SVID_PVDDCR_CPU0_P1_SVTI      A @T6G_MB_LIB.T6G(SCH_1):SVID_PVDDCR_CPU0_P1_SVTI
   2    GND      B @T6G_MB_LIB.T6G(SCH_1):GND

Q_CAP_0402-1000PF,50V,5%,X7R,TMP_QCH21006JB10  I13  C242
   1 PVDDCR_SOC_P1_EN_RC      A @T6G_MB_LIB.T6G(SCH_1):PVDDCR_SOC_P1_EN_RC
   2    GND      B @T6G_MB_LIB.T6G(SCH_1):GND

Q_RES_0402LF-49.9,1%,1/16W,CHIP,CS04992FB07  I36  PR164
   1 VSENSE_VSS_SENSE_A_P1      A @T6G_MB_LIB.T6G(SCH_1):VSENSE_VSS_SENSE_A_P1
   2    GND      B @T6G_MB_LIB.T6G(SCH_1):GND

Q_RES_0402LF-49.9,1%,1/16W,CHIP,CS04992FB07  I42  R8182
   1 PVDDCR_CPU0_P1_RESET_N      A @T6G_MB_LIB.T6G(SCH_1):PVDDCR_CPU0_P1_RESET_N
   2 PVDDCR_CPU0_P1_RESET_N_R      B @T6G_MB_LIB.T6G(SCH_1):PVDDCR_CPU0_P1_RESET_N_R

Q_RES_0402LF-0,5%,1/16W,CHIP,CS00002JB13  I43  R8168
   1 PVDDCR_CPU0_P1_OCP_N      A @T6G_MB_LIB.T6G(SCH_1):PVDDCR_CPU0_P1_OCP_N
   2 PVDDCR_CPU0_P1_OCP_N_R      B @T6G_MB_LIB.T6G(SCH_1):PVDDCR_CPU0_P1_OCP_N_R

Q_RES_0402LF-0,5%,1/16W,CHIP,CS00002JB13  I47  PR181
   1 P12V_AUX      A @T6G_MB_LIB.T6G(SCH_1):P12V_AUX
   2 PVDDCR_CPU0_P1_VINSEN      B @T6G_MB_LIB.T6G(SCH_1):PVDDCR_CPU0_P1_VINSEN

Q_RES_0402LF-0,5%,1/16W,CHIP,CS00002JB13  I57  PR174
   1 VSENSE_PVDDCR_SOC_P1_DP      A @T6G_MB_LIB.T6G(SCH_1):VSENSE_PVDDCR_SOC_P1_DP
   2 VSENSE_PVDDCR_SOC_P1_VSEN1      B @T6G_MB_LIB.T6G(SCH_1):VSENSE_PVDDCR_SOC_P1_VSEN1

Q_CAP_0402-3300PF,50V,10%,X7R,TMP_QCH2336K1B12  I58  PC245
   1 VSENSE_PVDDCR_SOC_P1_VSEN1      A @T6G_MB_LIB.T6G(SCH_1):VSENSE_PVDDCR_SOC_P1_VSEN1
   2 VSENSE_VSS_SENSE_A_P1      B @T6G_MB_LIB.T6G(SCH_1):VSENSE_VSS_SENSE_A_P1

Q_CAP_0402-10PF,50V,5%,EMPTY,CH01006JB08  I62  C295
   1 SVID_PVDDCR_CPU0_P1_SVTO      A @T6G_MB_LIB.T6G(SCH_1):SVID_PVDDCR_CPU0_P1_SVTO
   2    GND      B @T6G_MB_LIB.T6G(SCH_1):GND

Q_RES_0402LF-1K,1%,1/16W,EMPTY,CS21002FB06  I67  R154
   1 PVDD18_S5_P1      A @T6G_MB_LIB.T6G(SCH_1):PVDD18_S5_P1
   2 SVID_PVDDCR_CPU0_P1_SVTO      B @T6G_MB_LIB.T6G(SCH_1):SVID_PVDDCR_CPU0_P1_SVTO

Q_RES_0402LF-1K,1%,1/16W,EMPTY,CS21002FB06  I68  R8156
   1 PVDD18_S5_P1      A @T6G_MB_LIB.T6G(SCH_1):PVDD18_S5_P1
   2 SVID_PVDDCR_CPU0_P1_SVD_R      B @T6G_MB_LIB.T6G(SCH_1):SVID_PVDDCR_CPU0_P1_SVD_R

Q_RES_0402LF-0,5%,1/16W,CHIP,CS00002JB13  I81  R175
   1 SMB_VR_3V3STBY_SCL      A @T6G_MB_LIB.T6G(SCH_1):SMB_VR_3V3STBY_SCL
   2 PVDDCR_CPU0_P1_PMSCL_R      B @T6G_MB_LIB.T6G(SCH_1):PVDDCR_CPU0_P1_PMSCL_R

Q_RES_0402LF-0,5%,1/16W,CHIP,CS00002JB13  I82  PR172
   1 SVID_PVDDCR_CPU0_P1_SVTI      A @T6G_MB_LIB.T6G(SCH_1):SVID_PVDDCR_CPU0_P1_SVTI
   2 SVID_PVDDCR_CPU0_P1_SVTI_R      B @T6G_MB_LIB.T6G(SCH_1):SVID_PVDDCR_CPU0_P1_SVTI_R

Q_CAP_0402-1000PF,50V,5%,X7R,TMP_QCH21006JB10  I86  C249
   1 PVDDCR_CPU0_P1_EN_R      A @T6G_MB_LIB.T6G(SCH_1):PVDDCR_CPU0_P1_EN_R
   2    GND      B @T6G_MB_LIB.T6G(SCH_1):GND

Q_CAP_0402-1000PF,50V,5%,EMPTY,TMP_QCH21006JB10  I88  C248
   1 PWRGD_PVDDCR_CPU0_P1_R      A @T6G_MB_LIB.T6G(SCH_1):PWRGD_PVDDCR_CPU0_P1_R
   2    GND      B @T6G_MB_LIB.T6G(SCH_1):GND

Q_CAP_0402-0.1UF,25V,10%,X7R,CH4104K1B00  I114  PC11
   1 PVDDCR_CPU0_P1_VCCS      A @T6G_MB_LIB.T6G(SCH_1):PVDDCR_CPU0_P1_VCCS
   2    GND      B @T6G_MB_LIB.T6G(SCH_1):GND

Q_RES_0402LF-0,5%,1/16W,CHIP,CS00002JB13  I2  R149
   1 PVDDCR_SOC_P1_EN      A @T6G_MB_LIB.T6G(SCH_1):PVDDCR_SOC_P1_EN
   2 PVDDCR_SOC_P1_EN_RC      B @T6G_MB_LIB.T6G(SCH_1):PVDDCR_SOC_P1_EN_RC

Q_RES_0402LF-1K,1%,1/16W,EMPTY,CS21002FB06  I6  R8153
   1 SVID_PVDDCR_CPU0_P1_SVTO      A @T6G_MB_LIB.T6G(SCH_1):SVID_PVDDCR_CPU0_P1_SVTO
   2    GND      B @T6G_MB_LIB.T6G(SCH_1):GND

Q_RES_0402LF-1K,1%,1/16W,EMPTY,CS21002FB06  I10  PR151
   1 PVDD18_S5_P1      A @T6G_MB_LIB.T6G(SCH_1):PVDD18_S5_P1
   2 SVID_PVDDCR_CPU0_P1_SVTI      B @T6G_MB_LIB.T6G(SCH_1):SVID_PVDDCR_CPU0_P1_SVTI

Q_RES_0402LF-40.2K,1%,1/16W,CHIP,CS34022FB04  I14  PR157
   1 P5V_AUX      A @T6G_MB_LIB.T6G(SCH_1):P5V_AUX
   2 PVDDCR_CPU0_P1_VMON      B @T6G_MB_LIB.T6G(SCH_1):PVDDCR_CPU0_P1_VMON

MOSFET_N_SMLF-BSS138K,BSS138K,IC,BAM138K0000  I16  PQ15
   G PVDDCR_SOC_P1_EN_RC   GATE @T6G_MB_LIB.T6G(SCH_1):PVDDCR_SOC_P1_EN_RC
   D PVDDCR_SOC_P1_EN_GD  DRAIN @T6G_MB_LIB.T6G(SCH_1):PVDDCR_SOC_P1_EN_GD
   S    GND SOURCE @T6G_MB_LIB.T6G(SCH_1):GND

Q_RES_0402LF-1K,1%,1/16W,CHIP,CS21002FB06  I17  PR152
   1 P3V3_AUX      A @T6G_MB_LIB.T6G(SCH_1):P3V3_AUX
   2 PVDDCR_SOC_P1_EN_GD      B @T6G_MB_LIB.T6G(SCH_1):PVDDCR_SOC_P1_EN_GD

MOSFET_PCH_GDS_ESD_PROTECTED-PJA3415AE,SMLF,IC,BAMA  I18  PQ11
   D PVDDCR_SOC_P1_EN//ADDR_CFG      D @T6G_MB_LIB.T6G(SCH_1):PVDDCR_SOC_P1_EN//ADDR_CFG
   G PVDDCR_SOC_P1_EN_GD      G @T6G_MB_LIB.T6G(SCH_1):PVDDCR_SOC_P1_EN_GD
   S P3V3_AUX      S @T6G_MB_LIB.T6G(SCH_1):P3V3_AUX

Q_RES_0402LF-10K,1%,1/16W,CHIP,CS31002FB08  I20  PR4
   1 PVDDCR_CPU0_P1_VMON      A @T6G_MB_LIB.T6G(SCH_1):PVDDCR_CPU0_P1_VMON
   2    GND      B @T6G_MB_LIB.T6G(SCH_1):GND

Q_CAP_0402-0.1UF,25V,10%,X7R,CH4104K1B00  I22  PC243
   1 PVDDCR_CPU0_P1_VMON      A @T6G_MB_LIB.T6G(SCH_1):PVDDCR_CPU0_P1_VMON
   2    GND      B @T6G_MB_LIB.T6G(SCH_1):GND

Q_RES_0402LF-33,5%,1/16W,CHIP,CS03302JB10  I23  R8166
   1 PWRGD_PVDDCR_SOC_P1      A @T6G_MB_LIB.T6G(SCH_1):PWRGD_PVDDCR_SOC_P1
   2 PWRGD_PVDDCR_SOC_P1_R      B @T6G_MB_LIB.T6G(SCH_1):PWRGD_PVDDCR_SOC_P1_R

Q_RES_0402LF-1K,1%,1/16W,CHIP,CS21002FB06  I27  R8165
   1 P3V3_AUX      A @T6G_MB_LIB.T6G(SCH_1):P3V3_AUX
   2 PWRGD_PVDDCR_SOC_P1_R      B @T6G_MB_LIB.T6G(SCH_1):PWRGD_PVDDCR_SOC_P1_R

Q_RES_0402LF-49.9,1%,1/16W,CHIP,CS04992FB07  I39  PR163
   1 PVDDCR_SOC_P1      A @T6G_MB_LIB.T6G(SCH_1):PVDDCR_SOC_P1
   2 VSENSE_PVDDCR_SOC_P1_DP      B @T6G_MB_LIB.T6G(SCH_1):VSENSE_PVDDCR_SOC_P1_DP

Q_RES_0402LF-1K,1%,1/16W,CHIP,CS21002FB06  I41  R8184
   1 PVDD18_S5_P1      A @T6G_MB_LIB.T6G(SCH_1):PVDD18_S5_P1
   2 PVDDCR_CPU0_P1_RESET_N_R      B @T6G_MB_LIB.T6G(SCH_1):PVDDCR_CPU0_P1_RESET_N_R

Q_RES_0402LF-49.9,1%,1/16W,CHIP,CS04992FB07  I45  PR162
   1 VSENSE_VSS_SENSE_A_P1      A @T6G_MB_LIB.T6G(SCH_1):VSENSE_VSS_SENSE_A_P1
   2    GND      B @T6G_MB_LIB.T6G(SCH_1):GND

Q_RES_0402LF-4.99K,1%,1/16W,EMPTY,CS24992FB07  I48  PR602
   1 PVDDCR_CPU0_P1_VINSEN      A @T6G_MB_LIB.T6G(SCH_1):PVDDCR_CPU0_P1_VINSEN
   2    GND      B @T6G_MB_LIB.T6G(SCH_1):GND

Q_CAP_0402-0.1UF,25V,10%,X7R,CH4104K1B00  I51  PC6
   1 PVDDCR_CPU0_P1_VINSEN      A @T6G_MB_LIB.T6G(SCH_1):PVDDCR_CPU0_P1_VINSEN
   2    GND      B @T6G_MB_LIB.T6G(SCH_1):GND

Q_CAP_0402-1000PF,50V,5%,EMPTY,TMP_QCH21006JB10  I52  C8246
   1 PWRGD_PVDDCR_SOC_P1_R      A @T6G_MB_LIB.T6G(SCH_1):PWRGD_PVDDCR_SOC_P1_R
   2    GND      B @T6G_MB_LIB.T6G(SCH_1):GND

Q_RES_0402LF-1K,1%,1/16W,CHIP,CS21002FB06  I54  R8180
   1 PVDD18_S5_P1      A @T6G_MB_LIB.T6G(SCH_1):PVDD18_S5_P1
   2 PVDDCR_CPU0_P1_OCP_N_R      B @T6G_MB_LIB.T6G(SCH_1):PVDDCR_CPU0_P1_OCP_N_R

Q_RES_0402LF-0,5%,1/16W,CHIP,CS00002JB13  I59  PR173
   1 VSENSE_PVDDCR_CPU0_P1_DP      A @T6G_MB_LIB.T6G(SCH_1):VSENSE_PVDDCR_CPU0_P1_DP
   2 VSENSE_PVDDCR_CPU0_P1_VSEN0      B @T6G_MB_LIB.T6G(SCH_1):VSENSE_PVDDCR_CPU0_P1_VSEN0

Q_CAP_0402-3300PF,50V,10%,X7R,TMP_QCH2336K1B12  I60  PC244
   1 VSENSE_PVDDCR_CPU0_P1_VSEN0      A @T6G_MB_LIB.T6G(SCH_1):VSENSE_PVDDCR_CPU0_P1_VSEN0
   2 VSENSE_VSS_SENSE_A_P1      B @T6G_MB_LIB.T6G(SCH_1):VSENSE_VSS_SENSE_A_P1

Q_CAP_0402-10PF,50V,5%,EMPTY,CH01006JB08  I64  C296
   1 SVID_PVDDCR_CPU0_P1_SVD_R      A @T6G_MB_LIB.T6G(SCH_1):SVID_PVDDCR_CPU0_P1_SVD_R
   2    GND      B @T6G_MB_LIB.T6G(SCH_1):GND

Q_CAP_0402-10PF,50V,5%,EMPTY,CH01006JB08  I66  C297
   1 SVID_PVDDCR_CPU0_P1_SVC_R      A @T6G_MB_LIB.T6G(SCH_1):SVID_PVDDCR_CPU0_P1_SVC_R
   2    GND      B @T6G_MB_LIB.T6G(SCH_1):GND

Q_RES_0402LF-1K,1%,1/16W,EMPTY,CS21002FB06  I69  R8160
   1 PVDD18_S5_P1      A @T6G_MB_LIB.T6G(SCH_1):PVDD18_S5_P1
   2 SVID_PVDDCR_CPU0_P1_SVC_R      B @T6G_MB_LIB.T6G(SCH_1):SVID_PVDDCR_CPU0_P1_SVC_R

Q_RES_0402LF-49.9,1%,1/16W,CHIP,CS04992FB07  I70  PR161
   1 PVDDCR_CPU0_P1      A @T6G_MB_LIB.T6G(SCH_1):PVDDCR_CPU0_P1
   2 VSENSE_PVDDCR_CPU0_P1_DP      B @T6G_MB_LIB.T6G(SCH_1):VSENSE_PVDDCR_CPU0_P1_DP

Q_RES_0402LF-1K,1%,1/16W,CHIP,CS21002FB06  I78  R8167
   1 P3V3_AUX      A @T6G_MB_LIB.T6G(SCH_1):P3V3_AUX
   2 PWRGD_PVDDCR_CPU0_P1_R      B @T6G_MB_LIB.T6G(SCH_1):PWRGD_PVDDCR_CPU0_P1_R

Q_RES_0402LF-33,5%,1/16W,CHIP,CS03302JB10  I79  R8177
   1 PVDDCR_CPU0_P1_PMALERT      A @T6G_MB_LIB.T6G(SCH_1):PVDDCR_CPU0_P1_PMALERT
   2 PVDDCR_CPU0_P1_PMALERT_R      B @T6G_MB_LIB.T6G(SCH_1):PVDDCR_CPU0_P1_PMALERT_R

Q_RES_0402LF-0,5%,1/16W,CHIP,CS00002JB13  I80  R8176
   1 SMB_VR_3V3STBY_SDA      A @T6G_MB_LIB.T6G(SCH_1):SMB_VR_3V3STBY_SDA
   2 PVDDCR_CPU0_P1_PMSDA_R      B @T6G_MB_LIB.T6G(SCH_1):PVDDCR_CPU0_P1_PMSDA_R

Q_RES_0402LF-49.9,1%,1/16W,CHIP,CS04992FB07  I83  R8171
   1 SVID_PVDDCR_CPU0_P1_SVTO      A @T6G_MB_LIB.T6G(SCH_1):SVID_PVDDCR_CPU0_P1_SVTO
   2 SVID_PVDDCR_CPU0_P1_SVTO_R      B @T6G_MB_LIB.T6G(SCH_1):SVID_PVDDCR_CPU0_P1_SVTO_R

Q_RES_0402LF-0,5%,1/16W,CHIP,CS00002JB13  I84  R8179
   1 PVDDCR_CPU0_P1_EN      A @T6G_MB_LIB.T6G(SCH_1):PVDDCR_CPU0_P1_EN
   2 PVDDCR_CPU0_P1_EN_R      B @T6G_MB_LIB.T6G(SCH_1):PVDDCR_CPU0_P1_EN_R

Q_RES_0402LF-33,5%,1/16W,CHIP,CS03302JB10  I85  R8178
   1 PWRGD_PVDDCR_CPU0_P1      A @T6G_MB_LIB.T6G(SCH_1):PWRGD_PVDDCR_CPU0_P1
   2 PWRGD_PVDDCR_CPU0_P1_R      B @T6G_MB_LIB.T6G(SCH_1):PWRGD_PVDDCR_CPU0_P1_R

Q_CAP_0402-470PF,50V,10%,X7R,TMP_QCH14706KB18  I91  PC250
   1 PVDDCR_CPU0_P1_TEMP0      A @T6G_MB_LIB.T6G(SCH_1):PVDDCR_CPU0_P1_TEMP0
   2    GND      B @T6G_MB_LIB.T6G(SCH_1):GND

Q_CAP_0402-470PF,50V,10%,X7R,TMP_QCH14706KB18  I94  PC253
   1 PVDDCR_SOC_P1_TEMP1      A @T6G_MB_LIB.T6G(SCH_1):PVDDCR_SOC_P1_TEMP1
   2    GND      B @T6G_MB_LIB.T6G(SCH_1):GND

Q_RES_0402LF-0,5%,1/16W,CHIP,CS00002JB13  I102  PR437
   1 NC_PVDDCR_CPU0_P1_IMON9      A @T6G_MB_LIB.T6G(SCH_1):NC_PVDDCR_CPU0_P1_IMON9
   2    GND      B @T6G_MB_LIB.T6G(SCH_1):GND

Q_RES_0402LF-0,5%,1/16W,CHIP,CS00002JB13  I103  PR436
   1 NC_PVDDCR_CPU0_P1_IMON8      A @T6G_MB_LIB.T6G(SCH_1):NC_PVDDCR_CPU0_P1_IMON8
   2    GND      B @T6G_MB_LIB.T6G(SCH_1):GND

Q_RES_0402LF-0,5%,1/16W,CHIP,CS00002JB13  I107  PR530
   1 NC_PVDDCR_CPU0_P1_IMON7      A @T6G_MB_LIB.T6G(SCH_1):NC_PVDDCR_CPU0_P1_IMON7
   2    GND      B @T6G_MB_LIB.T6G(SCH_1):GND

Q_CAP_0402-0.1UF,25V,10%,X7R,CH4104K1B00  I116  PC10
   1 PVDDCR_CPU0_P1_VCC      A @T6G_MB_LIB.T6G(SCH_1):PVDDCR_CPU0_P1_VCC
   2    GND      B @T6G_MB_LIB.T6G(SCH_1):GND

Q_CAP_C0402-10UF,6.3V,20%,X6S,CH6101MEB03  I125  PC251
   1 PVDDCR_CPU0_P1_VCCS      A @T6G_MB_LIB.T6G(SCH_1):PVDDCR_CPU0_P1_VCCS
   2    GND      B @T6G_MB_LIB.T6G(SCH_1):GND

Q_CAP_C0402-1UF,16V,10%,X6S,CH5103KEB01  I127  PC252
   1 PVDDCR_CPU0_P1_VCC      A @T6G_MB_LIB.T6G(SCH_1):PVDDCR_CPU0_P1_VCC
   2    GND      B @T6G_MB_LIB.T6G(SCH_1):GND

Q_RES_0402LF-1,1%,1/16W,CHIP,CS-1002FB04  I129  PR183
   1 PVDDCR_CPU0_P1_VCC      A @T6G_MB_LIB.T6G(SCH_1):PVDDCR_CPU0_P1_VCC
   2 P3V3_AUX      B @T6G_MB_LIB.T6G(SCH_1):P3V3_AUX

Q_CAP_0402-1UF,6.3V,10%,X7R,CH5101K1B01  I132  PC247
   1 PVDD18_S5_P1      A @T6G_MB_LIB.T6G(SCH_1):PVDD18_S5_P1
   2    GND      B @T6G_MB_LIB.T6G(SCH_1):GND

RAA229620GNPHA0-RAA229620GNP#HA0,SMLF,IC,ARF0TGP40A  I133  PU25
  27 PVDDCR_CPU0_P1_IMON1   CS11 @T6G_MB_LIB.T6G(SCH_1):PVDDCR_CPU0_P1_IMON1
  47 PVDDCR_CPU0_P1_VCC    VCC @T6G_MB_LIB.T6G(SCH_1):PVDDCR_CPU0_P1_VCC
  24 SVID_PVDDCR_CPU0_P1_SVTI_R   SVTI @T6G_MB_LIB.T6G(SCH_1):SVID_PVDDCR_CPU0_P1_SVTI_R
  14 PVDDCR_CPU0_P1_PMSCL_R  PMSCL @T6G_MB_LIB.T6G(SCH_1):PVDDCR_CPU0_P1_PMSCL_R
  22 SVID_PVDDCR_CPU0_P1_SVC_R1    SVC @T6G_MB_LIB.T6G(SCH_1):SVID_PVDDCR_CPU0_P1_SVC_R1
  32 PVDDCR_CPU0_P1_IMON6    CS6 @T6G_MB_LIB.T6G(SCH_1):PVDDCR_CPU0_P1_IMON6
  23 SVID_PVDDCR_CPU0_P1_SVTO_R   SVTO @T6G_MB_LIB.T6G(SCH_1):SVID_PVDDCR_CPU0_P1_SVTO_R
  18 PVDDCR_CPU0_P1_RESET_N_R RESET_L @T6G_MB_LIB.T6G(SCH_1):PVDDCR_CPU0_P1_RESET_N_R
  33 NC_PVDDCR_CPU0_P1_IMON7    CS5 @T6G_MB_LIB.T6G(SCH_1):NC_PVDDCR_CPU0_P1_IMON7
  34 NC_PVDDCR_CPU0_P1_IMON8    CS4 @T6G_MB_LIB.T6G(SCH_1):NC_PVDDCR_CPU0_P1_IMON8
  20 PWRGD_PVDDCR_SOC_P1_R    PG1 @T6G_MB_LIB.T6G(SCH_1):PWRGD_PVDDCR_SOC_P1_R
  21 SVID_PVDDCR_CPU0_P1_SVD_R1    SVD @T6G_MB_LIB.T6G(SCH_1):SVID_PVDDCR_CPU0_P1_SVD_R1
  15 PVDDCR_CPU0_P1_PMALERT_R NPMALERT @T6G_MB_LIB.T6G(SCH_1):PVDDCR_CPU0_P1_PMALERT_R
  17 PVDDCR_CPU0_P1_EN_R    EN0 @T6G_MB_LIB.T6G(SCH_1):PVDDCR_CPU0_P1_EN_R
  26 VSENSE_VSS_SENSE_A_P1  RGND0 @T6G_MB_LIB.T6G(SCH_1):VSENSE_VSS_SENSE_A_P1
  13 PVDDCR_CPU0_P1_PMSDA_R  PMSDA @T6G_MB_LIB.T6G(SCH_1):PVDDCR_CPU0_P1_PMSDA_R
   5 NC_PVDDCR_CPU0_P1_PWM8   PWM4 @T6G_MB_LIB.T6G(SCH_1):NC_PVDDCR_CPU0_P1_PWM8
   6 NC_PVDDCR_CPU0_P1_PWM7   PWM5 @T6G_MB_LIB.T6G(SCH_1):NC_PVDDCR_CPU0_P1_PWM7
  25 VSENSE_PVDDCR_CPU0_P1_VSEN0  VSEN0 @T6G_MB_LIB.T6G(SCH_1):VSENSE_PVDDCR_CPU0_P1_VSEN0
   2 PVDDCR_SOC_P1_PWM2   PWM1 @T6G_MB_LIB.T6G(SCH_1):PVDDCR_SOC_P1_PWM2
  16 PWRGD_PVDDCR_CPU0_P1_R    PG0 @T6G_MB_LIB.T6G(SCH_1):PWRGD_PVDDCR_CPU0_P1_R
   7 PVDDCR_CPU0_P1_PWM6   PWM6 @T6G_MB_LIB.T6G(SCH_1):PVDDCR_CPU0_P1_PWM6
  48 PVDDCR_CPU0_P1_VCCS   VCCS @T6G_MB_LIB.T6G(SCH_1):PVDDCR_CPU0_P1_VCCS
  45 PVDDCR_CPU0_P1_VMON VMON||IINSEN @T6G_MB_LIB.T6G(SCH_1):PVDDCR_CPU0_P1_VMON
  46 PVDDCR_CPU0_P1_VINSEN VINSEN @T6G_MB_LIB.T6G(SCH_1):PVDDCR_CPU0_P1_VINSEN
  44 PVDDCR_CPU0_P1_TEMP0  TEMP0 @T6G_MB_LIB.T6G(SCH_1):PVDDCR_CPU0_P1_TEMP0
  19 PVDD18_S5_P1  VDDIO @T6G_MB_LIB.T6G(SCH_1):PVDD18_S5_P1
  40 VSENSE_PVDDCR_SOC_P1_VSEN1  VSEN1 @T6G_MB_LIB.T6G(SCH_1):VSENSE_PVDDCR_SOC_P1_VSEN1
  39 VSENSE_VSS_SENSE_A_P1  RGND1 @T6G_MB_LIB.T6G(SCH_1):VSENSE_VSS_SENSE_A_P1
  37 PVDDCR_SOC_P1_IMON2    CS1 @T6G_MB_LIB.T6G(SCH_1):PVDDCR_SOC_P1_IMON2
  12 PVDDCR_CPU0_P1_PWM1  PWM11 @T6G_MB_LIB.T6G(SCH_1):PVDDCR_CPU0_P1_PWM1
   4 NC_PVDDCR_CPU0_P1_PWM9   PWM3 @T6G_MB_LIB.T6G(SCH_1):NC_PVDDCR_CPU0_P1_PWM9
  35 NC_PVDDCR_CPU0_P1_IMON9    CS3 @T6G_MB_LIB.T6G(SCH_1):NC_PVDDCR_CPU0_P1_IMON9
   3 PVDDCR_SOC_P1_PWM3   PWM2 @T6G_MB_LIB.T6G(SCH_1):PVDDCR_SOC_P1_PWM3
  36 PVDDCR_SOC_P1_IMON3    CS2 @T6G_MB_LIB.T6G(SCH_1):PVDDCR_SOC_P1_IMON3
  41 PVDDCR_CPU0_P1_OCP_N_R  OCP_L @T6G_MB_LIB.T6G(SCH_1):PVDDCR_CPU0_P1_OCP_N_R
  TH    GND TH_GND @T6G_MB_LIB.T6G(SCH_1):GND
  42 PVDDCR_SOC_P1_EN//ADDR_CFG EN1||ADDR_CFG @T6G_MB_LIB.T6G(SCH_1):PVDDCR_SOC_P1_EN//ADDR_CFG
  43 PVDDCR_SOC_P1_TEMP1  TEMP1 @T6G_MB_LIB.T6G(SCH_1):PVDDCR_SOC_P1_TEMP1
   1 PVDDCR_SOC_P1_PWM1   PWM0 @T6G_MB_LIB.T6G(SCH_1):PVDDCR_SOC_P1_PWM1
  38 PVDDCR_SOC_P1_IMON1    CS0 @T6G_MB_LIB.T6G(SCH_1):PVDDCR_SOC_P1_IMON1
   8 PVDDCR_CPU0_P1_PWM5   PWM7 @T6G_MB_LIB.T6G(SCH_1):PVDDCR_CPU0_P1_PWM5
  31 PVDDCR_CPU0_P1_IMON5    CS7 @T6G_MB_LIB.T6G(SCH_1):PVDDCR_CPU0_P1_IMON5
   9 PVDDCR_CPU0_P1_PWM4   PWM8 @T6G_MB_LIB.T6G(SCH_1):PVDDCR_CPU0_P1_PWM4
  30 PVDDCR_CPU0_P1_IMON4    CS8 @T6G_MB_LIB.T6G(SCH_1):PVDDCR_CPU0_P1_IMON4
  10 PVDDCR_CPU0_P1_PWM3   PWM9 @T6G_MB_LIB.T6G(SCH_1):PVDDCR_CPU0_P1_PWM3
  29 PVDDCR_CPU0_P1_IMON3    CS9 @T6G_MB_LIB.T6G(SCH_1):PVDDCR_CPU0_P1_IMON3
  11 PVDDCR_CPU0_P1_PWM2  PWM10 @T6G_MB_LIB.T6G(SCH_1):PVDDCR_CPU0_P1_PWM2
  28 PVDDCR_CPU0_P1_IMON2   CS10 @T6G_MB_LIB.T6G(SCH_1):PVDDCR_CPU0_P1_IMON2

Q_RES_0402LF-10K,1%,1/16W,EMPTY,CS31002FB08  I135  R6087
   1 PVDDCR_SOC_P1_EN_RC      A @T6G_MB_LIB.T6G(SCH_1):PVDDCR_SOC_P1_EN_RC
   2    GND      B @T6G_MB_LIB.T6G(SCH_1):GND

Q_CAP_0402-1000PF,50V,5%,X7R,TMP_QCH21006JB10  I137  C5019
   1    GND      A @T6G_MB_LIB.T6G(SCH_1):GND
   2 PWRGD_PVDDCR_SOC_P1      B @T6G_MB_LIB.T6G(SCH_1):PWRGD_PVDDCR_SOC_P1

Q_CAP_0402-1000PF,50V,5%,X7R,TMP_QCH21006JB10  I139  C5012
   1 PVDDCR_CPU0_P1_PMALERT      A @T6G_MB_LIB.T6G(SCH_1):PVDDCR_CPU0_P1_PMALERT
   2    GND      B @T6G_MB_LIB.T6G(SCH_1):GND

Q_CAP_0402-1000PF,50V,5%,X7R,TMP_QCH21006JB10  I141  C5003
   1    GND      A @T6G_MB_LIB.T6G(SCH_1):GND
   2 PWRGD_PVDDCR_CPU0_P1      B @T6G_MB_LIB.T6G(SCH_1):PWRGD_PVDDCR_CPU0_P1

Q_RES_0402LF-5.23K,1%,1/16W,CHIP,CS25232FB08  I142  PR159
   1 PVDDCR_SOC_P1_EN//ADDR_CFG      A @T6G_MB_LIB.T6G(SCH_1):PVDDCR_SOC_P1_EN//ADDR_CFG
   2    GND      B @T6G_MB_LIB.T6G(SCH_1):GND

Q_RES_0402LF-0,5%,1/16W,CHIP,CS00002JB13  I143  PR8009
   1 SVID_PVDDCR_CPU0_P1_SVC_R      A @T6G_MB_LIB.T6G(SCH_1):SVID_PVDDCR_CPU0_P1_SVC_R
   2 SVID_PVDDCR_CPU0_P1_SVC_R1      B @T6G_MB_LIB.T6G(SCH_1):SVID_PVDDCR_CPU0_P1_SVC_R1

Q_RES_0402LF-0,5%,1/16W,CHIP,CS00002JB13  I144  PR8010
   1 SVID_PVDDCR_CPU0_P1_SVD_R      A @T6G_MB_LIB.T6G(SCH_1):SVID_PVDDCR_CPU0_P1_SVD_R
   2 SVID_PVDDCR_CPU0_P1_SVD_R1      B @T6G_MB_LIB.T6G(SCH_1):SVID_PVDDCR_CPU0_P1_SVD_R1


DRAWING: @T6G_MB_LIB.T6G(SCH_1):PAGE186 

Q_RES_0402LF-0,5%,1/16W,CHIP,CS00002JB13  I3  PR335
   1 PVDDCR_CPU0_P1_PVCC      A @T6G_MB_LIB.T6G(SCH_1):PVDDCR_CPU0_P1_PVCC
   2 P5V_AUX      B @T6G_MB_LIB.T6G(SCH_1):P5V_AUX

Q_RES_0402LF-2.2,1%,1/16W,CHIP,CS-2202FB01  I11  PR186
   1 PVDDCR_CPU0_P1_PVCC      A @T6G_MB_LIB.T6G(SCH_1):PVDDCR_CPU0_P1_PVCC
   2 PVDDCR_CPU0_P1_VCC2      B @T6G_MB_LIB.T6G(SCH_1):PVDDCR_CPU0_P1_VCC2

Q_CAP_C0402-2.2UF,10V,10%,X6S,CH5222KEB01  I13  PC259_C0P1_2
   1 PVDDCR_CPU0_P1_PVCC      A @T6G_MB_LIB.T6G(SCH_1):PVDDCR_CPU0_P1_PVCC
   2    GND      B @T6G_MB_LIB.T6G(SCH_1):GND

Q_CAP_0402-0.1UF,25V,10%,X7R,CH4104K1B00  I16  PC254_1
   1 PVDDCR_CPU0_P1_VCCS      A @T6G_MB_LIB.T6G(SCH_1):PVDDCR_CPU0_P1_VCCS
   2    GND      B @T6G_MB_LIB.T6G(SCH_1):GND

Q_CAP_C0402-560PF,50V,10%,EMPTY,CH1566K1B09  I24  PC173
   1 SW_PVDDCR_CPU0_P1_SW2      A @T6G_MB_LIB.T6G(SCH_1):SW_PVDDCR_CPU0_P1_SW2
   2 SW_PVDDCR_CPU0_P1_SW2_RC      B @T6G_MB_LIB.T6G(SCH_1):SW_PVDDCR_CPU0_P1_SW2_RC

Q_CAP_C0402-1UF,25V,10%,X6S,CH5104KEB02  I26  PC263_2
   1 SW_P12V_AUX_PVDDCR_CPU0_P1_FLT      A @T6G_MB_LIB.T6G(SCH_1):SW_P12V_AUX_PVDDCR_CPU0_P1_FLT
   2    GND      B @T6G_MB_LIB.T6G(SCH_1):GND

Q_CAP_C0805-22UF,16V,20%,X6S,CH6223MEA01  I31  PC269_2
   1 SW_P12V_AUX_PVDDCR_CPU0_P1_FLT      A @T6G_MB_LIB.T6G(SCH_1):SW_P12V_AUX_PVDDCR_CPU0_P1_FLT
   2    GND      B @T6G_MB_LIB.T6G(SCH_1):GND

Q_RES_0402LF-0,5%,1/16W,CHIP,CS00002JB13  I35  PR191
   1 PVDDCR_CPU0_P1_VOS1      A @T6G_MB_LIB.T6G(SCH_1):PVDDCR_CPU0_P1_VOS1
   2 PVDDCR_CPU0_P1      B @T6G_MB_LIB.T6G(SCH_1):PVDDCR_CPU0_P1

Q_CAP_0402-0.1UF,25V,10%,X7R,CH4104K1B00  I46  PC260_1
   1 SW_P12V_AUX_PVDDCR_CPU0_P1_FLT      A @T6G_MB_LIB.T6G(SCH_1):SW_P12V_AUX_PVDDCR_CPU0_P1_FLT
   2    GND      B @T6G_MB_LIB.T6G(SCH_1):GND

Q_CAP_C0402-560PF,50V,10%,EMPTY,CH1566K1B09  I48  PC170
   1 SW_PVDDCR_CPU0_P1_SW1      A @T6G_MB_LIB.T6G(SCH_1):SW_PVDDCR_CPU0_P1_SW1
   2 SW_PVDDCR_CPU0_P1_SW1_RC      B @T6G_MB_LIB.T6G(SCH_1):SW_PVDDCR_CPU0_P1_SW1_RC

Q_CAP_C0805-22UF,4V,20%,X6S,CH622KMEA03  I63  PC282_2
   1 PVDDCR_CPU0_P1      A @T6G_MB_LIB.T6G(SCH_1):PVDDCR_CPU0_P1
   2    GND      B @T6G_MB_LIB.T6G(SCH_1):GND

Q_CAPP_SMLF-220UF,4V,20%,SPCAP,CH122KM8801  I66  PC279
   1 PVDDCR_CPU0_P1      A @T6G_MB_LIB.T6G(SCH_1):PVDDCR_CPU0_P1
   2    GND      B @T6G_MB_LIB.T6G(SCH_1):GND

Q_CAPP_THLF-270UF,16V,20%,OSCON,CC72703MD38  I71  PC273
   1 SW_P12V_AUX_PVDDCR_CPU0_P1_FLT      A @T6G_MB_LIB.T6G(SCH_1):SW_P12V_AUX_PVDDCR_CPU0_P1_FLT
   2    GND      B @T6G_MB_LIB.T6G(SCH_1):GND

Q_CAP_0402-0.1UF,25V,10%,X7R,CH4104K1B00  I5  PC255_2
   1 PVDDCR_CPU0_P1_VCCS      A @T6G_MB_LIB.T6G(SCH_1):PVDDCR_CPU0_P1_VCCS
   2    GND      B @T6G_MB_LIB.T6G(SCH_1):GND

Q_CAP_C0402-2.2UF,10V,10%,X6S,CH5222KEB01  I9  PC257
   1 PVDDCR_CPU0_P1_VCC2      A @T6G_MB_LIB.T6G(SCH_1):PVDDCR_CPU0_P1_VCC2
   2    GND      B @T6G_MB_LIB.T6G(SCH_1):GND

Q_RES_0402LF-1.5,1%,1/8W,EMPTY,CS-1504FB00  I22  PR486
   1 SW_PVDDCR_CPU0_P1_SW2_RC      A @T6G_MB_LIB.T6G(SCH_1):SW_PVDDCR_CPU0_P1_SW2_RC
   2    GND      B @T6G_MB_LIB.T6G(SCH_1):GND

Q_RES_0402LF-0,5%,1/16W,CHIP,CS00002JB13  I23  PR192
   1 PVDDCR_CPU0_P1_VOS2      A @T6G_MB_LIB.T6G(SCH_1):PVDDCR_CPU0_P1_VOS2
   2 PVDDCR_CPU0_P1      B @T6G_MB_LIB.T6G(SCH_1):PVDDCR_CPU0_P1

Q_CAP_0402-0.1UF,25V,10%,X7R,CH4104K1B00  I25  PC261_2
   1 SW_P12V_AUX_PVDDCR_CPU0_P1_FLT      A @T6G_MB_LIB.T6G(SCH_1):SW_P12V_AUX_PVDDCR_CPU0_P1_FLT
   2    GND      B @T6G_MB_LIB.T6G(SCH_1):GND

Q_CAP_C0805-22UF,16V,20%,X6S,CH6223MEA01  I28  PC265_2
   1 SW_P12V_AUX_PVDDCR_CPU0_P1_FLT      A @T6G_MB_LIB.T6G(SCH_1):SW_P12V_AUX_PVDDCR_CPU0_P1_FLT
   2    GND      B @T6G_MB_LIB.T6G(SCH_1):GND

Q_CAP_C0805-22UF,16V,20%,X6S,CH6223MEA01  I29  PC267_2
   1 SW_P12V_AUX_PVDDCR_CPU0_P1_FLT      A @T6G_MB_LIB.T6G(SCH_1):SW_P12V_AUX_PVDDCR_CPU0_P1_FLT
   2    GND      B @T6G_MB_LIB.T6G(SCH_1):GND

Q_RES_0402LF-1.5,1%,1/8W,EMPTY,CS-1504FB00  I34  PR485
   1 SW_PVDDCR_CPU0_P1_SW1_RC      A @T6G_MB_LIB.T6G(SCH_1):SW_PVDDCR_CPU0_P1_SW1_RC
   2    GND      B @T6G_MB_LIB.T6G(SCH_1):GND

Q_CAP_C0402-2.2UF,10V,10%,X6S,CH5222KEB01  I36  PC256
   1 PVDDCR_CPU0_P1_VCC1      A @T6G_MB_LIB.T6G(SCH_1):PVDDCR_CPU0_P1_VCC1
   2    GND      B @T6G_MB_LIB.T6G(SCH_1):GND

Q_RES_0402LF-8.87K,1%,1/16W,EMPTY,CS28872FB01  I37  PR187
   1    GND      A @T6G_MB_LIB.T6G(SCH_1):GND
   2 PVDDCR_CPU0_P1_LSET1      B @T6G_MB_LIB.T6G(SCH_1):PVDDCR_CPU0_P1_LSET1

Q_RES_0402LF-0,5%,1/16W,EMPTY,CS00002JB13  I41  PR336
   1 PVDDCR_CPU0_P1_PVCC      A @T6G_MB_LIB.T6G(SCH_1):PVDDCR_CPU0_P1_PVCC
   2 P3V3_AUX      B @T6G_MB_LIB.T6G(SCH_1):P3V3_AUX

Q_RES_0402LF-2.2,1%,1/16W,CHIP,CS-2202FB01  I43  PR185
   1 PVDDCR_CPU0_P1_PVCC      A @T6G_MB_LIB.T6G(SCH_1):PVDDCR_CPU0_P1_PVCC
   2 PVDDCR_CPU0_P1_VCC1      B @T6G_MB_LIB.T6G(SCH_1):PVDDCR_CPU0_P1_VCC1

Q_CAP_C0402-2.2UF,10V,10%,X6S,CH5222KEB01  I44  PC258_C0P1_1
   1 PVDDCR_CPU0_P1_PVCC      A @T6G_MB_LIB.T6G(SCH_1):PVDDCR_CPU0_P1_PVCC
   2    GND      B @T6G_MB_LIB.T6G(SCH_1):GND

Q_CAP_C0402-1UF,25V,10%,X6S,CH5104KEB02  I47  PC262_1
   1 SW_P12V_AUX_PVDDCR_CPU0_P1_FLT      A @T6G_MB_LIB.T6G(SCH_1):SW_P12V_AUX_PVDDCR_CPU0_P1_FLT
   2    GND      B @T6G_MB_LIB.T6G(SCH_1):GND

Q_RES_0402LF-5.6,1%,1/16W,CHIP,CS-5602FB01  I49  PR189
   1 SW_PVDDCR_CPU0_P1_BOOT1      A @T6G_MB_LIB.T6G(SCH_1):SW_PVDDCR_CPU0_P1_BOOT1
   2 SW_PVDDCR_CPU0_P1_BOOT1_RC      B @T6G_MB_LIB.T6G(SCH_1):SW_PVDDCR_CPU0_P1_BOOT1_RC

Q_CAP_C0805-22UF,16V,20%,X6S,CH6223MEA01  I51  PC264_1
   1 SW_P12V_AUX_PVDDCR_CPU0_P1_FLT      A @T6G_MB_LIB.T6G(SCH_1):SW_P12V_AUX_PVDDCR_CPU0_P1_FLT
   2    GND      B @T6G_MB_LIB.T6G(SCH_1):GND

Q_CAP_C0805-22UF,16V,20%,X6S,CH6223MEA01  I52  PC266_1
   1 SW_P12V_AUX_PVDDCR_CPU0_P1_FLT      A @T6G_MB_LIB.T6G(SCH_1):SW_P12V_AUX_PVDDCR_CPU0_P1_FLT
   2    GND      B @T6G_MB_LIB.T6G(SCH_1):GND

Q_CAP_C0805-22UF,16V,20%,X6S,CH6223MEA01  I53  PC268_1
   1 SW_P12V_AUX_PVDDCR_CPU0_P1_FLT      A @T6G_MB_LIB.T6G(SCH_1):SW_P12V_AUX_PVDDCR_CPU0_P1_FLT
   2    GND      B @T6G_MB_LIB.T6G(SCH_1):GND

Q_CAP_0402-0.22UF,16V,10%,X7R,CH4223K1B00  I55  PC271
   1 SW_PVDDCR_CPU0_P1_BOOT2_RC      A @T6G_MB_LIB.T6G(SCH_1):SW_PVDDCR_CPU0_P1_BOOT2_RC
   2 SW_PVDDCR_CPU0_P1_PH2      B @T6G_MB_LIB.T6G(SCH_1):SW_PVDDCR_CPU0_P1_PH2

Q_INDUCTOR4P_14-150NH,SMLF,IND,CV+15^0TZ04  I56  PL29
   2 IND_CPU0_P1_CPL1      2 @T6G_MB_LIB.T6G(SCH_1):IND_CPU0_P1_CPL1
   3 IND_CPU0_P1_CPL2      3 @T6G_MB_LIB.T6G(SCH_1):IND_CPU0_P1_CPL2
   4 PVDDCR_CPU0_P1      4 @T6G_MB_LIB.T6G(SCH_1):PVDDCR_CPU0_P1
   1 SW_PVDDCR_CPU0_P1_SW2      1 @T6G_MB_LIB.T6G(SCH_1):SW_PVDDCR_CPU0_P1_SW2

Q_CAPP_SMLF-220UF,4V,20%,SPCAP,CH122KM8801  I58  PC275
   1 PVDDCR_CPU0_P1      A @T6G_MB_LIB.T6G(SCH_1):PVDDCR_CPU0_P1
   2    GND      B @T6G_MB_LIB.T6G(SCH_1):GND

Q_CAPP_SMLF-220UF,4V,20%,SPCAP,CH122KM8801  I59  PC276
   1 PVDDCR_CPU0_P1      A @T6G_MB_LIB.T6G(SCH_1):PVDDCR_CPU0_P1
   2    GND      B @T6G_MB_LIB.T6G(SCH_1):GND

Q_CAPP_SMLF-220UF,4V,20%,SPCAP,CH122KM8801  I60  PC277
   1 PVDDCR_CPU0_P1      A @T6G_MB_LIB.T6G(SCH_1):PVDDCR_CPU0_P1
   2    GND      B @T6G_MB_LIB.T6G(SCH_1):GND

Q_CAP_C0805-22UF,4V,20%,X6S,CH622KMEA03  I61  PC280_2
   1 PVDDCR_CPU0_P1      A @T6G_MB_LIB.T6G(SCH_1):PVDDCR_CPU0_P1
   2    GND      B @T6G_MB_LIB.T6G(SCH_1):GND

Q_CAPP_THLF-270UF,16V,20%,OSCON,CC72703MD38  I70  PC272
   1 SW_P12V_AUX_PVDDCR_CPU0_P1_FLT      A @T6G_MB_LIB.T6G(SCH_1):SW_P12V_AUX_PVDDCR_CPU0_P1_FLT
   2    GND      B @T6G_MB_LIB.T6G(SCH_1):GND

Q_INDUCTOR_SMLF-50NH/86A,IND,CVA50^0MZ09  I73  PL30
   2 P12V_AUX      2 @T6G_MB_LIB.T6G(SCH_1):P12V_AUX
   1 SW_P12V_AUX_PVDDCR_CPU0_P1_FLT      1 @T6G_MB_LIB.T6G(SCH_1):SW_P12V_AUX_PVDDCR_CPU0_P1_FLT

Q_CAP_0402-0.1UF,25V,10%,X7R,CH4104K1B00  I74  PC6004
   1 P12V_AUX      A @T6G_MB_LIB.T6G(SCH_1):P12V_AUX
   2    GND      B @T6G_MB_LIB.T6G(SCH_1):GND

Q_CAP_C0805-22UF,4V,20%,X6S,CH622KMEA03  I76  PC281_1
   1 PVDDCR_CPU0_P1      A @T6G_MB_LIB.T6G(SCH_1):PVDDCR_CPU0_P1
   2    GND      B @T6G_MB_LIB.T6G(SCH_1):GND

Q_CAP_C0805-22UF,4V,20%,X6S,CH622KMEA03  I77  PC283_1
   1 PVDDCR_CPU0_P1      A @T6G_MB_LIB.T6G(SCH_1):PVDDCR_CPU0_P1
   2    GND      B @T6G_MB_LIB.T6G(SCH_1):GND

Q_RES_0402LF-1K,1%,1/16W,CHIP,CS21002FB06  I78  PR337
   1 PVDDCR_CPU0_P1      A @T6G_MB_LIB.T6G(SCH_1):PVDDCR_CPU0_P1
   2    GND      B @T6G_MB_LIB.T6G(SCH_1):GND

Q_RES_0402LF-8.87K,1%,1/16W,EMPTY,CS28872FB01  I80  PR188
   1    GND      A @T6G_MB_LIB.T6G(SCH_1):GND
   2 PVDDCR_CPU0_P1_LSET2      B @T6G_MB_LIB.T6G(SCH_1):PVDDCR_CPU0_P1_LSET2

Q_RES_0402LF-5.6,1%,1/16W,CHIP,CS-5602FB01  I83  PR190
   1 SW_PVDDCR_CPU0_P1_BOOT2      A @T6G_MB_LIB.T6G(SCH_1):SW_PVDDCR_CPU0_P1_BOOT2
   2 SW_PVDDCR_CPU0_P1_BOOT2_RC      B @T6G_MB_LIB.T6G(SCH_1):SW_PVDDCR_CPU0_P1_BOOT2_RC

Q_CAPP_SMLF-220UF,4V,20%,SPCAP,CH122KM8801  I84  PC105
   1 PVDDCR_CPU0_P1      A @T6G_MB_LIB.T6G(SCH_1):PVDDCR_CPU0_P1
   2    GND      B @T6G_MB_LIB.T6G(SCH_1):GND

Q_CAP_0402-0.1UF,25V,10%,X7R,CH4104K1B00  I85  PC278
   1 PVDDCR_CPU0_P1      A @T6G_MB_LIB.T6G(SCH_1):PVDDCR_CPU0_P1
   2    GND      B @T6G_MB_LIB.T6G(SCH_1):GND

ISL99390FRZTR5935-ISL99390FRZ-TR5935,SMLF,IC,AL099A  I88  PU4
  34 PVDDCR_CPU0_P1_PWM1    PWM @T6G_MB_LIB.T6G(SCH_1):PVDDCR_CPU0_P1_PWM1
  39 PVDDCR_CPU0_P1_VCCS  REFIN @T6G_MB_LIB.T6G(SCH_1):PVDDCR_CPU0_P1_VCCS
   3 PVDDCR_CPU0_P1_VCC1    VCC @T6G_MB_LIB.T6G(SCH_1):PVDDCR_CPU0_P1_VCC1
   2    GND   AGND @T6G_MB_LIB.T6G(SCH_1):GND
  33 SW_PVDDCR_CPU0_P1_BOOT1   BOOT @T6G_MB_LIB.T6G(SCH_1):SW_PVDDCR_CPU0_P1_BOOT1
25_29 SW_P12V_AUX_PVDDCR_CPU0_P1_FLT   VIN1 @T6G_MB_LIB.T6G(SCH_1):SW_P12V_AUX_PVDDCR_CPU0_P1_FLT
  32 SW_PVDDCR_CPU0_P1_PH1  PHASE @T6G_MB_LIB.T6G(SCH_1):SW_PVDDCR_CPU0_P1_PH1
   4 PVDDCR_CPU0_P1_PVCC   PVCC @T6G_MB_LIB.T6G(SCH_1):PVDDCR_CPU0_P1_PVCC
  36 PVDDCR_CPU0_P1_TEMP0 TOUT_FLT @T6G_MB_LIB.T6G(SCH_1):PVDDCR_CPU0_P1_TEMP0
  38 PVDDCR_CPU0_P1_IMON1   IOUT @T6G_MB_LIB.T6G(SCH_1):PVDDCR_CPU0_P1_IMON1
  37 PVDDCR_CPU0_P1_LSET1   LSET @T6G_MB_LIB.T6G(SCH_1):PVDDCR_CPU0_P1_LSET1
10_19 SW_PVDDCR_CPU0_P1_SW1     SW @T6G_MB_LIB.T6G(SCH_1):SW_PVDDCR_CPU0_P1_SW1
   5    GND  PGND1 @T6G_MB_LIB.T6G(SCH_1):GND
  30 SW_P12V_AUX_PVDDCR_CPU0_P1_FLT   VIN2 @T6G_MB_LIB.T6G(SCH_1):SW_P12V_AUX_PVDDCR_CPU0_P1_FLT
   1 PVDDCR_CPU0_P1_VOS1    VOS @T6G_MB_LIB.T6G(SCH_1):PVDDCR_CPU0_P1_VOS1
  40    GND  PGND3 @T6G_MB_LIB.T6G(SCH_1):GND
  35 PVDDCR_CPU0_P1_VCC1     EN @T6G_MB_LIB.T6G(SCH_1):PVDDCR_CPU0_P1_VCC1
  31 NC_PVDDCR_CPU0_P1_DNC1    DNC @T6G_MB_LIB.T6G(SCH_1):NC_PVDDCR_CPU0_P1_DNC1
   6 NC_PVDDCR_CPU0_P1_GL1_1    GL1 @T6G_MB_LIB.T6G(SCH_1):NC_PVDDCR_CPU0_P1_GL1_1
  41 NC_PVDDCR_CPU0_P1_GL2_1    GL2 @T6G_MB_LIB.T6G(SCH_1):NC_PVDDCR_CPU0_P1_GL2_1
7_9-20_24    GND  PGND2 @T6G_MB_LIB.T6G(SCH_1):GND

Q_CAP_0402-0.22UF,16V,10%,X7R,CH4223K1B00  I89  PC270
   1 SW_PVDDCR_CPU0_P1_BOOT1_RC      A @T6G_MB_LIB.T6G(SCH_1):SW_PVDDCR_CPU0_P1_BOOT1_RC
   2 SW_PVDDCR_CPU0_P1_PH1      B @T6G_MB_LIB.T6G(SCH_1):SW_PVDDCR_CPU0_P1_PH1

Q_INDUCTOR4P_14-150NH,SMLF,IND,CV+15^0TZ04  I90  PL28
   2 IND_CPU0_P1_CPL5      2 @T6G_MB_LIB.T6G(SCH_1):IND_CPU0_P1_CPL5
   3 IND_CPU0_P1_CPL1      3 @T6G_MB_LIB.T6G(SCH_1):IND_CPU0_P1_CPL1
   4 PVDDCR_CPU0_P1      4 @T6G_MB_LIB.T6G(SCH_1):PVDDCR_CPU0_P1
   1 SW_PVDDCR_CPU0_P1_SW1      1 @T6G_MB_LIB.T6G(SCH_1):SW_PVDDCR_CPU0_P1_SW1

ISL99390FRZTR5935-ISL99390FRZ-TR5935,SMLF,IC,AL099A  I91  PU26
  34 PVDDCR_CPU0_P1_PWM2    PWM @T6G_MB_LIB.T6G(SCH_1):PVDDCR_CPU0_P1_PWM2
  39 PVDDCR_CPU0_P1_VCCS  REFIN @T6G_MB_LIB.T6G(SCH_1):PVDDCR_CPU0_P1_VCCS
   3 PVDDCR_CPU0_P1_VCC2    VCC @T6G_MB_LIB.T6G(SCH_1):PVDDCR_CPU0_P1_VCC2
   2    GND   AGND @T6G_MB_LIB.T6G(SCH_1):GND
  33 SW_PVDDCR_CPU0_P1_BOOT2   BOOT @T6G_MB_LIB.T6G(SCH_1):SW_PVDDCR_CPU0_P1_BOOT2
25_29 SW_P12V_AUX_PVDDCR_CPU0_P1_FLT   VIN1 @T6G_MB_LIB.T6G(SCH_1):SW_P12V_AUX_PVDDCR_CPU0_P1_FLT
  32 SW_PVDDCR_CPU0_P1_PH2  PHASE @T6G_MB_LIB.T6G(SCH_1):SW_PVDDCR_CPU0_P1_PH2
   4 PVDDCR_CPU0_P1_PVCC   PVCC @T6G_MB_LIB.T6G(SCH_1):PVDDCR_CPU0_P1_PVCC
  36 PVDDCR_CPU0_P1_TEMP0 TOUT_FLT @T6G_MB_LIB.T6G(SCH_1):PVDDCR_CPU0_P1_TEMP0
  38 PVDDCR_CPU0_P1_IMON2   IOUT @T6G_MB_LIB.T6G(SCH_1):PVDDCR_CPU0_P1_IMON2
  37 PVDDCR_CPU0_P1_LSET2   LSET @T6G_MB_LIB.T6G(SCH_1):PVDDCR_CPU0_P1_LSET2
10_19 SW_PVDDCR_CPU0_P1_SW2     SW @T6G_MB_LIB.T6G(SCH_1):SW_PVDDCR_CPU0_P1_SW2
   5    GND  PGND1 @T6G_MB_LIB.T6G(SCH_1):GND
  30 SW_P12V_AUX_PVDDCR_CPU0_P1_FLT   VIN2 @T6G_MB_LIB.T6G(SCH_1):SW_P12V_AUX_PVDDCR_CPU0_P1_FLT
   1 PVDDCR_CPU0_P1_VOS2    VOS @T6G_MB_LIB.T6G(SCH_1):PVDDCR_CPU0_P1_VOS2
  40    GND  PGND3 @T6G_MB_LIB.T6G(SCH_1):GND
  35 PVDDCR_CPU0_P1_VCC2     EN @T6G_MB_LIB.T6G(SCH_1):PVDDCR_CPU0_P1_VCC2
  31 NC_PVDDCR_CPU0_P1_DNC2    DNC @T6G_MB_LIB.T6G(SCH_1):NC_PVDDCR_CPU0_P1_DNC2
   6 NC_PVDDCR_CPU0_P1_GL1_2    GL1 @T6G_MB_LIB.T6G(SCH_1):NC_PVDDCR_CPU0_P1_GL1_2
  41 NC_PVDDCR_CPU0_P1_GL2_2    GL2 @T6G_MB_LIB.T6G(SCH_1):NC_PVDDCR_CPU0_P1_GL2_2
7_9-20_24    GND  PGND2 @T6G_MB_LIB.T6G(SCH_1):GND


DRAWING: @T6G_MB_LIB.T6G(SCH_1):PAGE190 

Q_CAP_0402-0.1UF,25V,10%,X7R,CH4104K1B00  I4  PC318_8
   1 PVDDCR_CPU0_P1_VCCS      A @T6G_MB_LIB.T6G(SCH_1):PVDDCR_CPU0_P1_VCCS
   2    GND      B @T6G_MB_LIB.T6G(SCH_1):GND

Q_CAP_0402-0.1UF,25V,10%,X7R,CH4104K1B00  I22  PC326_2
   1 SW_P12V_AUX_PVDDCR_SOC_P1_FLT      A @T6G_MB_LIB.T6G(SCH_1):SW_P12V_AUX_PVDDCR_SOC_P1_FLT
   2    GND      B @T6G_MB_LIB.T6G(SCH_1):GND

Q_RES_0402LF-5.6,1%,1/16W,CHIP,CS-5602FB01  I24  PR210
   1 SW_PVDDCR_SOC_P1_BOOT2      A @T6G_MB_LIB.T6G(SCH_1):SW_PVDDCR_SOC_P1_BOOT2
   2 SW_PVDDCR_SOC_P1_BOOT2_RC      B @T6G_MB_LIB.T6G(SCH_1):SW_PVDDCR_SOC_P1_BOOT2_RC

Q_CAP_C0402-1UF,25V,10%,X6S,CH5104KEB02  I25  PC324_2
   1 SW_P12V_AUX_PVDDCR_SOC_P1_FLT      A @T6G_MB_LIB.T6G(SCH_1):SW_P12V_AUX_PVDDCR_SOC_P1_FLT
   2    GND      B @T6G_MB_LIB.T6G(SCH_1):GND

Q_CAP_C0805-22UF,16V,20%,X6S,CH6223MEA01  I26  PC328_2
   1 SW_P12V_AUX_PVDDCR_SOC_P1_FLT      A @T6G_MB_LIB.T6G(SCH_1):SW_P12V_AUX_PVDDCR_SOC_P1_FLT
   2    GND      B @T6G_MB_LIB.T6G(SCH_1):GND

Q_RES_0402LF-1.5,1%,1/8W,EMPTY,CS-1504FB00  I29  PR525
   1 SW_PVDDCR_SOC_P1_SW1_RC      A @T6G_MB_LIB.T6G(SCH_1):SW_PVDDCR_SOC_P1_SW1_RC
   2    GND      B @T6G_MB_LIB.T6G(SCH_1):GND

Q_RES_0402LF-2.2,1%,1/16W,CHIP,CS-2202FB01  I39  PR205
   1 PVDDCR_CPU0_P1_PVCC      A @T6G_MB_LIB.T6G(SCH_1):PVDDCR_CPU0_P1_PVCC
   2 PVDDCR_SOC_P1_VCC1      B @T6G_MB_LIB.T6G(SCH_1):PVDDCR_SOC_P1_VCC1

Q_CAP_0402-0.1UF,25V,10%,X7R,CH4104K1B00  I43  PC325_1
   1 SW_P12V_AUX_PVDDCR_SOC_P1_FLT      A @T6G_MB_LIB.T6G(SCH_1):SW_P12V_AUX_PVDDCR_SOC_P1_FLT
   2    GND      B @T6G_MB_LIB.T6G(SCH_1):GND

Q_CAP_C0402-1UF,25V,10%,X6S,CH5104KEB02  I44  PC323_1
   1 SW_P12V_AUX_PVDDCR_SOC_P1_FLT      A @T6G_MB_LIB.T6G(SCH_1):SW_P12V_AUX_PVDDCR_SOC_P1_FLT
   2    GND      B @T6G_MB_LIB.T6G(SCH_1):GND

Q_CAP_C0805-22UF,16V,20%,X6S,CH6223MEA01  I48  PC327_1
   1 SW_P12V_AUX_PVDDCR_SOC_P1_FLT      A @T6G_MB_LIB.T6G(SCH_1):SW_P12V_AUX_PVDDCR_SOC_P1_FLT
   2    GND      B @T6G_MB_LIB.T6G(SCH_1):GND

Q_INDUCTOR4P_14-150NH,SMLF,IND,CV+15^0TZ04  I52  PL36
   2 IND_SOC_P1_CPL3      2 @T6G_MB_LIB.T6G(SCH_1):IND_SOC_P1_CPL3
   3 IND_SOC_P1_CPL2      3 @T6G_MB_LIB.T6G(SCH_1):IND_SOC_P1_CPL2
   4 PVDDCR_SOC_P1      4 @T6G_MB_LIB.T6G(SCH_1):PVDDCR_SOC_P1
   1 SW_PVDDCR_SOC_P1_SW2      1 @T6G_MB_LIB.T6G(SCH_1):SW_PVDDCR_SOC_P1_SW2

Q_CAPP_SMLF-470UF,2.5V,20%,EMPTY,CH747LM8825  I63  PC340
   1 PVDDCR_SOC_P1      A @T6G_MB_LIB.T6G(SCH_1):PVDDCR_SOC_P1
   2    GND      B @T6G_MB_LIB.T6G(SCH_1):GND

Q_CAPP_SMLF-470UF,2.5V,20%,SPCAP,CH747LM8825  I66  PC343
   1 PVDDCR_SOC_P1      A @T6G_MB_LIB.T6G(SCH_1):PVDDCR_SOC_P1
   2    GND      B @T6G_MB_LIB.T6G(SCH_1):GND

Q_CAP_0402-0.22UF,16V,10%,X7R,CH4223K1B00  I68  PC333
   1 SW_PVDDCR_SOC_P1_BOOT1_RC      A @T6G_MB_LIB.T6G(SCH_1):SW_PVDDCR_SOC_P1_BOOT1_RC
   2 SW_PVDDCR_SOC_P1_PH1      B @T6G_MB_LIB.T6G(SCH_1):SW_PVDDCR_SOC_P1_PH1

Q_INDUCTOR4P_14-150NH,SMLF,IND,CV+15^0TZ04  I69  PL35
   2 IND_SOC_P1_CPL2      2 @T6G_MB_LIB.T6G(SCH_1):IND_SOC_P1_CPL2
   3    GND      3 @T6G_MB_LIB.T6G(SCH_1):GND
   4 PVDDCR_SOC_P1      4 @T6G_MB_LIB.T6G(SCH_1):PVDDCR_SOC_P1
   1 SW_PVDDCR_SOC_P1_SW1      1 @T6G_MB_LIB.T6G(SCH_1):SW_PVDDCR_SOC_P1_SW1

Q_CAP_0402-0.1UF,25V,10%,X7R,CH4104K1B00  I79  PC338
   1 PVDDCR_SOC_P1      A @T6G_MB_LIB.T6G(SCH_1):PVDDCR_SOC_P1
   2    GND      B @T6G_MB_LIB.T6G(SCH_1):GND

Q_CAP_C0805-22UF,4V,20%,X6S,CH622KMEA03  I81  PC344_1
   1 PVDDCR_SOC_P1      A @T6G_MB_LIB.T6G(SCH_1):PVDDCR_SOC_P1
   2    GND      B @T6G_MB_LIB.T6G(SCH_1):GND

Q_RES_0402LF-1K,1%,1/16W,CHIP,CS21002FB06  I83  PR339
   1 PVDDCR_SOC_P1      A @T6G_MB_LIB.T6G(SCH_1):PVDDCR_SOC_P1
   2    GND      B @T6G_MB_LIB.T6G(SCH_1):GND

Q_RES_0402LF-8.87K,1%,1/16W,EMPTY,CS28872FB01  I8  PR208
   1    GND      A @T6G_MB_LIB.T6G(SCH_1):GND
   2 PVDDCR_SOC_P1_LSET2      B @T6G_MB_LIB.T6G(SCH_1):PVDDCR_SOC_P1_LSET2

Q_CAP_C0402-2.2UF,10V,10%,X6S,CH5222KEB01  I11  PC320
   1 PVDDCR_SOC_P1_VCC2      A @T6G_MB_LIB.T6G(SCH_1):PVDDCR_SOC_P1_VCC2
   2    GND      B @T6G_MB_LIB.T6G(SCH_1):GND

Q_RES_0402LF-2.2,1%,1/16W,CHIP,CS-2202FB01  I12  PR206
   1 PVDDCR_CPU0_P1_PVCC      A @T6G_MB_LIB.T6G(SCH_1):PVDDCR_CPU0_P1_PVCC
   2 PVDDCR_SOC_P1_VCC2      B @T6G_MB_LIB.T6G(SCH_1):PVDDCR_SOC_P1_VCC2

Q_CAP_C0402-2.2UF,10V,10%,X6S,CH5222KEB01  I14  PC322_SOP1_2
   1 PVDDCR_CPU0_P1_PVCC      A @T6G_MB_LIB.T6G(SCH_1):PVDDCR_CPU0_P1_PVCC
   2    GND      B @T6G_MB_LIB.T6G(SCH_1):GND

ISL99390FRZTR5935-ISL99390FRZ-TR5935,SMLF,IC,AL099A  I17  PU30
  34 PVDDCR_SOC_P1_PWM1    PWM @T6G_MB_LIB.T6G(SCH_1):PVDDCR_SOC_P1_PWM1
  39 PVDDCR_CPU0_P1_VCCS  REFIN @T6G_MB_LIB.T6G(SCH_1):PVDDCR_CPU0_P1_VCCS
   3 PVDDCR_SOC_P1_VCC1    VCC @T6G_MB_LIB.T6G(SCH_1):PVDDCR_SOC_P1_VCC1
   2    GND   AGND @T6G_MB_LIB.T6G(SCH_1):GND
  33 SW_PVDDCR_SOC_P1_BOOT1   BOOT @T6G_MB_LIB.T6G(SCH_1):SW_PVDDCR_SOC_P1_BOOT1
25_29 SW_P12V_AUX_PVDDCR_SOC_P1_FLT   VIN1 @T6G_MB_LIB.T6G(SCH_1):SW_P12V_AUX_PVDDCR_SOC_P1_FLT
  32 SW_PVDDCR_SOC_P1_PH1  PHASE @T6G_MB_LIB.T6G(SCH_1):SW_PVDDCR_SOC_P1_PH1
   4 PVDDCR_CPU0_P1_PVCC   PVCC @T6G_MB_LIB.T6G(SCH_1):PVDDCR_CPU0_P1_PVCC
  36 PVDDCR_SOC_P1_TEMP1 TOUT_FLT @T6G_MB_LIB.T6G(SCH_1):PVDDCR_SOC_P1_TEMP1
  38 PVDDCR_SOC_P1_IMON1   IOUT @T6G_MB_LIB.T6G(SCH_1):PVDDCR_SOC_P1_IMON1
  37 PVDDCR_SOC_P1_LSET1   LSET @T6G_MB_LIB.T6G(SCH_1):PVDDCR_SOC_P1_LSET1
10_19 SW_PVDDCR_SOC_P1_SW1     SW @T6G_MB_LIB.T6G(SCH_1):SW_PVDDCR_SOC_P1_SW1
   5    GND  PGND1 @T6G_MB_LIB.T6G(SCH_1):GND
  30 SW_P12V_AUX_PVDDCR_SOC_P1_FLT   VIN2 @T6G_MB_LIB.T6G(SCH_1):SW_P12V_AUX_PVDDCR_SOC_P1_FLT
   1 PVDDCR_SOC_P1_VOS1    VOS @T6G_MB_LIB.T6G(SCH_1):PVDDCR_SOC_P1_VOS1
  40    GND  PGND3 @T6G_MB_LIB.T6G(SCH_1):GND
  35 PVDDCR_SOC_P1_VCC1     EN @T6G_MB_LIB.T6G(SCH_1):PVDDCR_SOC_P1_VCC1
  31 NC_PVDDCR_SOC_P1_DNC1    DNC @T6G_MB_LIB.T6G(SCH_1):NC_PVDDCR_SOC_P1_DNC1
   6 NC_PVDDCR_SOC_P1_GL1_1    GL1 @T6G_MB_LIB.T6G(SCH_1):NC_PVDDCR_SOC_P1_GL1_1
  41 NC_PVDDCR_SOC_P1_GL2_1    GL2 @T6G_MB_LIB.T6G(SCH_1):NC_PVDDCR_SOC_P1_GL2_1
7_9-20_24    GND  PGND2 @T6G_MB_LIB.T6G(SCH_1):GND

Q_CAP_C0402-560PF,50V,10%,EMPTY,CH1566K1B09  I20  PC149
   1 SW_PVDDCR_SOC_P1_SW2      A @T6G_MB_LIB.T6G(SCH_1):SW_PVDDCR_SOC_P1_SW2
   2 SW_PVDDCR_SOC_P1_SW2_RC      B @T6G_MB_LIB.T6G(SCH_1):SW_PVDDCR_SOC_P1_SW2_RC

Q_RES_0402LF-1.5,1%,1/8W,EMPTY,CS-1504FB00  I21  PR526
   1 SW_PVDDCR_SOC_P1_SW2_RC      A @T6G_MB_LIB.T6G(SCH_1):SW_PVDDCR_SOC_P1_SW2_RC
   2    GND      B @T6G_MB_LIB.T6G(SCH_1):GND

Q_CAP_C0805-22UF,16V,20%,X6S,CH6223MEA01  I27  PC330_2
   1 SW_P12V_AUX_PVDDCR_SOC_P1_FLT      A @T6G_MB_LIB.T6G(SCH_1):SW_P12V_AUX_PVDDCR_SOC_P1_FLT
   2    GND      B @T6G_MB_LIB.T6G(SCH_1):GND

Q_RES_0402LF-0,5%,1/16W,CHIP,CS00002JB13  I30  PR211
   1 PVDDCR_SOC_P1_VOS1      A @T6G_MB_LIB.T6G(SCH_1):PVDDCR_SOC_P1_VOS1
   2 PVDDCR_SOC_P1      B @T6G_MB_LIB.T6G(SCH_1):PVDDCR_SOC_P1

Q_CAP_0402-0.1UF,25V,10%,X7R,CH4104K1B00  I32  PC317_7
   1 PVDDCR_CPU0_P1_VCCS      A @T6G_MB_LIB.T6G(SCH_1):PVDDCR_CPU0_P1_VCCS
   2    GND      B @T6G_MB_LIB.T6G(SCH_1):GND

Q_RES_0402LF-8.87K,1%,1/16W,EMPTY,CS28872FB01  I35  PR207
   1    GND      A @T6G_MB_LIB.T6G(SCH_1):GND
   2 PVDDCR_SOC_P1_LSET1      B @T6G_MB_LIB.T6G(SCH_1):PVDDCR_SOC_P1_LSET1

Q_CAP_C0402-2.2UF,10V,10%,X6S,CH5222KEB01  I36  PC319
   1 PVDDCR_SOC_P1_VCC1      A @T6G_MB_LIB.T6G(SCH_1):PVDDCR_SOC_P1_VCC1
   2    GND      B @T6G_MB_LIB.T6G(SCH_1):GND

Q_CAP_C0402-2.2UF,10V,10%,X6S,CH5222KEB01  I41  PC321_SOP1_1
   1 PVDDCR_CPU0_P1_PVCC      A @T6G_MB_LIB.T6G(SCH_1):PVDDCR_CPU0_P1_PVCC
   2    GND      B @T6G_MB_LIB.T6G(SCH_1):GND

Q_CAP_C0402-560PF,50V,10%,EMPTY,CH1566K1B09  I45  PC141
   1 SW_PVDDCR_SOC_P1_SW1      A @T6G_MB_LIB.T6G(SCH_1):SW_PVDDCR_SOC_P1_SW1
   2 SW_PVDDCR_SOC_P1_SW1_RC      B @T6G_MB_LIB.T6G(SCH_1):SW_PVDDCR_SOC_P1_SW1_RC

Q_RES_0402LF-5.6,1%,1/16W,CHIP,CS-5602FB01  I46  PR209
   1 SW_PVDDCR_SOC_P1_BOOT1      A @T6G_MB_LIB.T6G(SCH_1):SW_PVDDCR_SOC_P1_BOOT1
   2 SW_PVDDCR_SOC_P1_BOOT1_RC      B @T6G_MB_LIB.T6G(SCH_1):SW_PVDDCR_SOC_P1_BOOT1_RC

Q_CAP_C0805-22UF,16V,20%,X6S,CH6223MEA01  I49  PC329_1
   1 SW_P12V_AUX_PVDDCR_SOC_P1_FLT      A @T6G_MB_LIB.T6G(SCH_1):SW_P12V_AUX_PVDDCR_SOC_P1_FLT
   2    GND      B @T6G_MB_LIB.T6G(SCH_1):GND

Q_CAP_C0805-22UF,16V,20%,X6S,CH6223MEA01  I50  PC331_1
   1 SW_P12V_AUX_PVDDCR_SOC_P1_FLT      A @T6G_MB_LIB.T6G(SCH_1):SW_P12V_AUX_PVDDCR_SOC_P1_FLT
   2    GND      B @T6G_MB_LIB.T6G(SCH_1):GND

Q_CAP_0402-0.22UF,16V,10%,X7R,CH4223K1B00  I54  PC334
   1 SW_PVDDCR_SOC_P1_BOOT2_RC      A @T6G_MB_LIB.T6G(SCH_1):SW_PVDDCR_SOC_P1_BOOT2_RC
   2 SW_PVDDCR_SOC_P1_PH2      B @T6G_MB_LIB.T6G(SCH_1):SW_PVDDCR_SOC_P1_PH2

Q_CAP_C0805-22UF,16V,20%,X6S,CH6223MEA01  I56  PC332_2
   1 SW_P12V_AUX_PVDDCR_SOC_P1_FLT      A @T6G_MB_LIB.T6G(SCH_1):SW_P12V_AUX_PVDDCR_SOC_P1_FLT
   2    GND      B @T6G_MB_LIB.T6G(SCH_1):GND

Q_CAP_C0805-22UF,16V,20%,X6S,CH6223MEA01  I57  PC335_2
   1 SW_P12V_AUX_PVDDCR_SOC_P1_FLT      A @T6G_MB_LIB.T6G(SCH_1):SW_P12V_AUX_PVDDCR_SOC_P1_FLT
   2    GND      B @T6G_MB_LIB.T6G(SCH_1):GND

Q_CAPP_SMLF-470UF,2.5V,20%,SPCAP,CH747LM8825  I59  PC337
   1 PVDDCR_SOC_P1      A @T6G_MB_LIB.T6G(SCH_1):PVDDCR_SOC_P1
   2    GND      B @T6G_MB_LIB.T6G(SCH_1):GND

Q_CAP_C0805-22UF,4V,20%,X6S,CH622KMEA03  I60  PC339_2
   1 PVDDCR_SOC_P1      A @T6G_MB_LIB.T6G(SCH_1):PVDDCR_SOC_P1
   2    GND      B @T6G_MB_LIB.T6G(SCH_1):GND

Q_CAP_C0805-22UF,4V,20%,X6S,CH622KMEA03  I62  PC342_2
   1 PVDDCR_SOC_P1      A @T6G_MB_LIB.T6G(SCH_1):PVDDCR_SOC_P1
   2    GND      B @T6G_MB_LIB.T6G(SCH_1):GND

Q_CAP_C0805-22UF,16V,20%,X6S,CH6223MEA01  I71  PC334_1
   1 SW_P12V_AUX_PVDDCR_SOC_P1_FLT      A @T6G_MB_LIB.T6G(SCH_1):SW_P12V_AUX_PVDDCR_SOC_P1_FLT
   2    GND      B @T6G_MB_LIB.T6G(SCH_1):GND

Q_CAPP_THLF-270UF,16V,20%,OSCON,CC72703MD38  I73  PC336
   1 SW_P12V_AUX_PVDDCR_SOC_P1_FLT      A @T6G_MB_LIB.T6G(SCH_1):SW_P12V_AUX_PVDDCR_SOC_P1_FLT
   2    GND      B @T6G_MB_LIB.T6G(SCH_1):GND

Q_INDUCTOR_SMLF-50NH/86A,IND,CVA50^0MZ09  I74  PL37
   2 P12V_AUX      2 @T6G_MB_LIB.T6G(SCH_1):P12V_AUX
   1 SW_P12V_AUX_PVDDCR_SOC_P1_FLT      1 @T6G_MB_LIB.T6G(SCH_1):SW_P12V_AUX_PVDDCR_SOC_P1_FLT

Q_CAP_0402-0.1UF,25V,10%,X7R,CH4104K1B00  I77  PC6007
   1 P12V_AUX      A @T6G_MB_LIB.T6G(SCH_1):P12V_AUX
   2    GND      B @T6G_MB_LIB.T6G(SCH_1):GND

Q_CAP_C0805-22UF,4V,20%,X6S,CH622KMEA03  I80  PC341_1
   1 PVDDCR_SOC_P1      A @T6G_MB_LIB.T6G(SCH_1):PVDDCR_SOC_P1
   2    GND      B @T6G_MB_LIB.T6G(SCH_1):GND

Q_RES_0402LF-0,5%,1/16W,CHIP,CS00002JB13  I85  PR212
   1 PVDDCR_SOC_P1_VOS2      A @T6G_MB_LIB.T6G(SCH_1):PVDDCR_SOC_P1_VOS2
   2 PVDDCR_SOC_P1      B @T6G_MB_LIB.T6G(SCH_1):PVDDCR_SOC_P1

ISL99390FRZTR5935-ISL99390FRZ-TR5935,SMLF,IC,AL099A  I86  PU31
  34 PVDDCR_SOC_P1_PWM2    PWM @T6G_MB_LIB.T6G(SCH_1):PVDDCR_SOC_P1_PWM2
  39 PVDDCR_CPU0_P1_VCCS  REFIN @T6G_MB_LIB.T6G(SCH_1):PVDDCR_CPU0_P1_VCCS
   3 PVDDCR_SOC_P1_VCC2    VCC @T6G_MB_LIB.T6G(SCH_1):PVDDCR_SOC_P1_VCC2
   2    GND   AGND @T6G_MB_LIB.T6G(SCH_1):GND
  33 SW_PVDDCR_SOC_P1_BOOT2   BOOT @T6G_MB_LIB.T6G(SCH_1):SW_PVDDCR_SOC_P1_BOOT2
25_29 SW_P12V_AUX_PVDDCR_SOC_P1_FLT   VIN1 @T6G_MB_LIB.T6G(SCH_1):SW_P12V_AUX_PVDDCR_SOC_P1_FLT
  32 SW_PVDDCR_SOC_P1_PH2  PHASE @T6G_MB_LIB.T6G(SCH_1):SW_PVDDCR_SOC_P1_PH2
   4 PVDDCR_CPU0_P1_PVCC   PVCC @T6G_MB_LIB.T6G(SCH_1):PVDDCR_CPU0_P1_PVCC
  36 PVDDCR_SOC_P1_TEMP1 TOUT_FLT @T6G_MB_LIB.T6G(SCH_1):PVDDCR_SOC_P1_TEMP1
  38 PVDDCR_SOC_P1_IMON2   IOUT @T6G_MB_LIB.T6G(SCH_1):PVDDCR_SOC_P1_IMON2
  37 PVDDCR_SOC_P1_LSET2   LSET @T6G_MB_LIB.T6G(SCH_1):PVDDCR_SOC_P1_LSET2
10_19 SW_PVDDCR_SOC_P1_SW2     SW @T6G_MB_LIB.T6G(SCH_1):SW_PVDDCR_SOC_P1_SW2
   5    GND  PGND1 @T6G_MB_LIB.T6G(SCH_1):GND
  30 SW_P12V_AUX_PVDDCR_SOC_P1_FLT   VIN2 @T6G_MB_LIB.T6G(SCH_1):SW_P12V_AUX_PVDDCR_SOC_P1_FLT
   1 PVDDCR_SOC_P1_VOS2    VOS @T6G_MB_LIB.T6G(SCH_1):PVDDCR_SOC_P1_VOS2
  40    GND  PGND3 @T6G_MB_LIB.T6G(SCH_1):GND
  35 PVDDCR_SOC_P1_VCC2     EN @T6G_MB_LIB.T6G(SCH_1):PVDDCR_SOC_P1_VCC2
  31 NC_PVDDCR_SOC_P1_DNC2    DNC @T6G_MB_LIB.T6G(SCH_1):NC_PVDDCR_SOC_P1_DNC2
   6 NC_PVDDCR_SOC_P1_GL1_2    GL1 @T6G_MB_LIB.T6G(SCH_1):NC_PVDDCR_SOC_P1_GL1_2
  41 NC_PVDDCR_SOC_P1_GL2_2    GL2 @T6G_MB_LIB.T6G(SCH_1):NC_PVDDCR_SOC_P1_GL2_2
7_9-20_24    GND  PGND2 @T6G_MB_LIB.T6G(SCH_1):GND

Q_CAP_C0805-22UF,16V,20%,X6S,CH6223MEA01  I87  PC8011
   1 SW_P12V_AUX_PVDDCR_SOC_P1_FLT      A @T6G_MB_LIB.T6G(SCH_1):SW_P12V_AUX_PVDDCR_SOC_P1_FLT
   2    GND      B @T6G_MB_LIB.T6G(SCH_1):GND

Q_CAP_C0805-22UF,16V,20%,X6S,CH6223MEA01  I88  PC8012
   1 SW_P12V_AUX_PVDDCR_SOC_P1_FLT      A @T6G_MB_LIB.T6G(SCH_1):SW_P12V_AUX_PVDDCR_SOC_P1_FLT
   2    GND      B @T6G_MB_LIB.T6G(SCH_1):GND


DRAWING: @T6G_MB_LIB.T6G(SCH_1):PAGE191 

Q_RES_0402LF-8.87K,1%,1/16W,EMPTY,CS28872FB01  I7  PR214
   1    GND      A @T6G_MB_LIB.T6G(SCH_1):GND
   2 PVDDCR_SOC_P1_LSET3      B @T6G_MB_LIB.T6G(SCH_1):PVDDCR_SOC_P1_LSET3

Q_CAP_C0402-2.2UF,10V,10%,X6S,CH5222KEB01  I18  PC347_SOP1_3
   1 PVDDCR_CPU0_P1_PVCC      A @T6G_MB_LIB.T6G(SCH_1):PVDDCR_CPU0_P1_PVCC
   2    GND      B @T6G_MB_LIB.T6G(SCH_1):GND

Q_CAP_C0402-1UF,25V,10%,X6S,CH5104KEB02  I20  PC349_3
   1 SW_P12V_AUX_PVDDCR_SOC_P1_FLT      A @T6G_MB_LIB.T6G(SCH_1):SW_P12V_AUX_PVDDCR_SOC_P1_FLT
   2    GND      B @T6G_MB_LIB.T6G(SCH_1):GND

Q_RES_0402LF-5.6,1%,1/16W,CHIP,CS-5602FB01  I21  PR215
   1 SW_PVDDCR_SOC_P1_BOOT3      A @T6G_MB_LIB.T6G(SCH_1):SW_PVDDCR_SOC_P1_BOOT3
   2 SW_PVDDCR_SOC_P1_BOOT3_RC      B @T6G_MB_LIB.T6G(SCH_1):SW_PVDDCR_SOC_P1_BOOT3_RC

Q_CAP_C0805-22UF,16V,20%,X6S,CH6223MEA01  I22  PC350_3
   1 SW_P12V_AUX_PVDDCR_SOC_P1_FLT      A @T6G_MB_LIB.T6G(SCH_1):SW_P12V_AUX_PVDDCR_SOC_P1_FLT
   2    GND      B @T6G_MB_LIB.T6G(SCH_1):GND

Q_INDUCTOR_SMLF-0.22UH/33A,IND,CV+22Y0EZ00  I25  PL34
   2 IND_SOC_P1_CPL0      2 @T6G_MB_LIB.T6G(SCH_1):IND_SOC_P1_CPL0
   1    GND      1 @T6G_MB_LIB.T6G(SCH_1):GND

Q_INDUCTOR4P_14-150NH,SMLF,IND,CV+15^0TZ04  I26  PL38
   2 IND_SOC_P1_CPL0      2 @T6G_MB_LIB.T6G(SCH_1):IND_SOC_P1_CPL0
   3 IND_SOC_P1_CPL3      3 @T6G_MB_LIB.T6G(SCH_1):IND_SOC_P1_CPL3
   4 PVDDCR_SOC_P1      4 @T6G_MB_LIB.T6G(SCH_1):PVDDCR_SOC_P1
   1 SW_PVDDCR_SOC_P1_SW3      1 @T6G_MB_LIB.T6G(SCH_1):SW_PVDDCR_SOC_P1_SW3

Q_CAP_C0805-22UF,16V,20%,X6S,CH6223MEA01  I31  PC351_3
   1 SW_P12V_AUX_PVDDCR_SOC_P1_FLT      A @T6G_MB_LIB.T6G(SCH_1):SW_P12V_AUX_PVDDCR_SOC_P1_FLT
   2    GND      B @T6G_MB_LIB.T6G(SCH_1):GND

Q_CAP_C0805-22UF,16V,20%,X6S,CH6223MEA01  I32  PC352_3
   1 SW_P12V_AUX_PVDDCR_SOC_P1_FLT      A @T6G_MB_LIB.T6G(SCH_1):SW_P12V_AUX_PVDDCR_SOC_P1_FLT
   2    GND      B @T6G_MB_LIB.T6G(SCH_1):GND

Q_CAP_C0805-22UF,16V,20%,X6S,CH6223MEA01  I34  PC353_3
   1 SW_P12V_AUX_PVDDCR_SOC_P1_FLT      A @T6G_MB_LIB.T6G(SCH_1):SW_P12V_AUX_PVDDCR_SOC_P1_FLT
   2    GND      B @T6G_MB_LIB.T6G(SCH_1):GND

ISL99390FRZTR5935-ISL99390FRZ-TR5935,SMLF,IC,AL099A  I38  PU32
  34 PVDDCR_SOC_P1_PWM3    PWM @T6G_MB_LIB.T6G(SCH_1):PVDDCR_SOC_P1_PWM3
  39 PVDDCR_CPU0_P1_VCCS  REFIN @T6G_MB_LIB.T6G(SCH_1):PVDDCR_CPU0_P1_VCCS
   3 PVDDCR_SOC_P1_VCC3    VCC @T6G_MB_LIB.T6G(SCH_1):PVDDCR_SOC_P1_VCC3
   2    GND   AGND @T6G_MB_LIB.T6G(SCH_1):GND
  33 SW_PVDDCR_SOC_P1_BOOT3   BOOT @T6G_MB_LIB.T6G(SCH_1):SW_PVDDCR_SOC_P1_BOOT3
25_29 SW_P12V_AUX_PVDDCR_SOC_P1_FLT   VIN1 @T6G_MB_LIB.T6G(SCH_1):SW_P12V_AUX_PVDDCR_SOC_P1_FLT
  32 SW_PVDDCR_SOC_P1_PH3  PHASE @T6G_MB_LIB.T6G(SCH_1):SW_PVDDCR_SOC_P1_PH3
   4 PVDDCR_CPU0_P1_PVCC   PVCC @T6G_MB_LIB.T6G(SCH_1):PVDDCR_CPU0_P1_PVCC
  36 PVDDCR_SOC_P1_TEMP1 TOUT_FLT @T6G_MB_LIB.T6G(SCH_1):PVDDCR_SOC_P1_TEMP1
  38 PVDDCR_SOC_P1_IMON3   IOUT @T6G_MB_LIB.T6G(SCH_1):PVDDCR_SOC_P1_IMON3
  37 PVDDCR_SOC_P1_LSET3   LSET @T6G_MB_LIB.T6G(SCH_1):PVDDCR_SOC_P1_LSET3
10_19 SW_PVDDCR_SOC_P1_SW3     SW @T6G_MB_LIB.T6G(SCH_1):SW_PVDDCR_SOC_P1_SW3
   5    GND  PGND1 @T6G_MB_LIB.T6G(SCH_1):GND
  30 SW_P12V_AUX_PVDDCR_SOC_P1_FLT   VIN2 @T6G_MB_LIB.T6G(SCH_1):SW_P12V_AUX_PVDDCR_SOC_P1_FLT
   1 PVDDCR_SOC_P1_VOS3    VOS @T6G_MB_LIB.T6G(SCH_1):PVDDCR_SOC_P1_VOS3
  40    GND  PGND3 @T6G_MB_LIB.T6G(SCH_1):GND
  35 PVDDCR_SOC_P1_VCC3     EN @T6G_MB_LIB.T6G(SCH_1):PVDDCR_SOC_P1_VCC3
  31 NC_PVDDCR_SOC_P1_DNC3    DNC @T6G_MB_LIB.T6G(SCH_1):NC_PVDDCR_SOC_P1_DNC3
   6 NC_PVDDCR_SOC_P1_GL1_3    GL1 @T6G_MB_LIB.T6G(SCH_1):NC_PVDDCR_SOC_P1_GL1_3
  41 NC_PVDDCR_SOC_P1_GL2_3    GL2 @T6G_MB_LIB.T6G(SCH_1):NC_PVDDCR_SOC_P1_GL2_3
7_9-20_24    GND  PGND2 @T6G_MB_LIB.T6G(SCH_1):GND

Q_CAP_0402-0.1UF,25V,10%,X7R,CH4104K1B00  I2  PC345_9
   1 PVDDCR_CPU0_P1_VCCS      A @T6G_MB_LIB.T6G(SCH_1):PVDDCR_CPU0_P1_VCCS
   2    GND      B @T6G_MB_LIB.T6G(SCH_1):GND

Q_RES_0402LF-1.5,1%,1/8W,EMPTY,CS-1504FB00  I10  PR511
   1 SW_PVDDCR_SOC_P1_SW3_RC      A @T6G_MB_LIB.T6G(SCH_1):SW_PVDDCR_SOC_P1_SW3_RC
   2    GND      B @T6G_MB_LIB.T6G(SCH_1):GND

Q_CAP_C0402-560PF,50V,10%,EMPTY,CH1566K1B09  I11  PC195
   1 SW_PVDDCR_SOC_P1_SW3      A @T6G_MB_LIB.T6G(SCH_1):SW_PVDDCR_SOC_P1_SW3
   2 SW_PVDDCR_SOC_P1_SW3_RC      B @T6G_MB_LIB.T6G(SCH_1):SW_PVDDCR_SOC_P1_SW3_RC

Q_CAP_C0402-2.2UF,10V,10%,X6S,CH5222KEB01  I13  PC346
   1 PVDDCR_SOC_P1_VCC3      A @T6G_MB_LIB.T6G(SCH_1):PVDDCR_SOC_P1_VCC3
   2    GND      B @T6G_MB_LIB.T6G(SCH_1):GND

Q_RES_0402LF-2.2,1%,1/16W,CHIP,CS-2202FB01  I14  PR213
   1 PVDDCR_CPU0_P1_PVCC      A @T6G_MB_LIB.T6G(SCH_1):PVDDCR_CPU0_P1_PVCC
   2 PVDDCR_SOC_P1_VCC3      B @T6G_MB_LIB.T6G(SCH_1):PVDDCR_SOC_P1_VCC3

Q_CAP_0402-0.1UF,25V,10%,X7R,CH4104K1B00  I19  PC348_3
   1 SW_P12V_AUX_PVDDCR_SOC_P1_FLT      A @T6G_MB_LIB.T6G(SCH_1):SW_P12V_AUX_PVDDCR_SOC_P1_FLT
   2    GND      B @T6G_MB_LIB.T6G(SCH_1):GND

Q_RES_0402LF-0,5%,1/16W,CHIP,CS00002JB13  I23  PR216
   1 PVDDCR_SOC_P1_VOS3      A @T6G_MB_LIB.T6G(SCH_1):PVDDCR_SOC_P1_VOS3
   2 PVDDCR_SOC_P1      B @T6G_MB_LIB.T6G(SCH_1):PVDDCR_SOC_P1

Q_CAP_C0805-22UF,4V,20%,X6S,CH622KMEA03  I28  PC354_3
   1 PVDDCR_SOC_P1      A @T6G_MB_LIB.T6G(SCH_1):PVDDCR_SOC_P1
   2    GND      B @T6G_MB_LIB.T6G(SCH_1):GND

Q_CAP_C0805-22UF,4V,20%,X6S,CH622KMEA03  I30  PC355_3
   1 PVDDCR_SOC_P1      A @T6G_MB_LIB.T6G(SCH_1):PVDDCR_SOC_P1
   2    GND      B @T6G_MB_LIB.T6G(SCH_1):GND

Q_CAP_0402-0.22UF,16V,10%,X7R,CH4223K1B00  I33  PC353
   1 SW_PVDDCR_SOC_P1_BOOT3_RC      A @T6G_MB_LIB.T6G(SCH_1):SW_PVDDCR_SOC_P1_BOOT3_RC
   2 SW_PVDDCR_SOC_P1_PH3      B @T6G_MB_LIB.T6G(SCH_1):SW_PVDDCR_SOC_P1_PH3


DRAWING: @T6G_MB_LIB.T6G(SCH_1):PAGE193 

Q_CAP_0402-0.1UF,25V,10%,X7R,CH4104K1B00  I2  PC373_2
   1 PVDDCR_CPU1_P1_VCCS      A @T6G_MB_LIB.T6G(SCH_1):PVDDCR_CPU1_P1_VCCS
   2    GND      B @T6G_MB_LIB.T6G(SCH_1):GND

Q_RES_0402LF-2.2,1%,1/16W,CHIP,CS-2202FB01  I14  PR257
   1 PVDDCR_CPU1_P1_PVCC      A @T6G_MB_LIB.T6G(SCH_1):PVDDCR_CPU1_P1_PVCC
   2 PVDDCR_CPU1_P1_VCC2      B @T6G_MB_LIB.T6G(SCH_1):PVDDCR_CPU1_P1_VCC2

Q_CAP_C0402-2.2UF,10V,10%,X6S,CH5222KEB01  I23  PC369
   1 PVDDCR_CPU1_P1_VCC1      A @T6G_MB_LIB.T6G(SCH_1):PVDDCR_CPU1_P1_VCC1
   2    GND      B @T6G_MB_LIB.T6G(SCH_1):GND

Q_RES_0402LF-5.6,1%,1/16W,CHIP,CS-5602FB01  I41  PR259
   1 SW_PVDDCR_CPU1_P1_BOOT2      A @T6G_MB_LIB.T6G(SCH_1):SW_PVDDCR_CPU1_P1_BOOT2
   2 SW_PVDDCR_CPU1_P1_BOOT2_R      B @T6G_MB_LIB.T6G(SCH_1):SW_PVDDCR_CPU1_P1_BOOT2_R

Q_CAP_C0805-22UF,16V,20%,X6S,CH6223MEA01  I46  PC382_2
   1 SW_P12V_AUX_PVDDCR_CPU1_P1_FLT      A @T6G_MB_LIB.T6G(SCH_1):SW_P12V_AUX_PVDDCR_CPU1_P1_FLT
   2    GND      B @T6G_MB_LIB.T6G(SCH_1):GND

Q_CAPP_SMLF-220UF,4V,20%,SPCAP,CH122KM8801  I65  PC106
   1 PVDDCR_CPU1_P1      A @T6G_MB_LIB.T6G(SCH_1):PVDDCR_CPU1_P1
   2    GND      B @T6G_MB_LIB.T6G(SCH_1):GND

Q_CAPP_SMLF-220UF,4V,20%,SPCAP,CH122KM8801  I66  PC387
   1 PVDDCR_CPU1_P1      A @T6G_MB_LIB.T6G(SCH_1):PVDDCR_CPU1_P1
   2    GND      B @T6G_MB_LIB.T6G(SCH_1):GND

Q_CAPP_SMLF-220UF,4V,20%,SPCAP,CH122KM8801  I67  PC388
   1 PVDDCR_CPU1_P1      A @T6G_MB_LIB.T6G(SCH_1):PVDDCR_CPU1_P1
   2    GND      B @T6G_MB_LIB.T6G(SCH_1):GND

Q_CAPP_SMLF-220UF,4V,20%,SPCAP,CH122KM8801  I74  PC391
   1 PVDDCR_CPU1_P1      A @T6G_MB_LIB.T6G(SCH_1):PVDDCR_CPU1_P1
   2    GND      B @T6G_MB_LIB.T6G(SCH_1):GND

Q_RES_0402LF-1K,1%,1/16W,CHIP,CS21002FB06  I87  PR342
   1 PVDDCR_CPU1_P1      A @T6G_MB_LIB.T6G(SCH_1):PVDDCR_CPU1_P1
   2    GND      B @T6G_MB_LIB.T6G(SCH_1):GND

Q_RES_0402LF-8.87K,1%,1/16W,EMPTY,CS28872FB01  I4  PR254
   1 PVDDCR_CPU1_P1_LSET2      A @T6G_MB_LIB.T6G(SCH_1):PVDDCR_CPU1_P1_LSET2
   2    GND      B @T6G_MB_LIB.T6G(SCH_1):GND

Q_CAP_0402-0.1UF,25V,10%,X7R,CH4104K1B00  I11  PC374_1
   1 PVDDCR_CPU1_P1_VCCS      A @T6G_MB_LIB.T6G(SCH_1):PVDDCR_CPU1_P1_VCCS
   2    GND      B @T6G_MB_LIB.T6G(SCH_1):GND

Q_CAP_C0402-2.2UF,10V,10%,X6S,CH5222KEB01  I12  PC370
   1 PVDDCR_CPU1_P1_VCC2      A @T6G_MB_LIB.T6G(SCH_1):PVDDCR_CPU1_P1_VCC2
   2    GND      B @T6G_MB_LIB.T6G(SCH_1):GND

Q_CAP_C0402-2.2UF,10V,10%,X6S,CH5222KEB01  I15  PC372_C1P1_2
   1 PVDDCR_CPU1_P1_PVCC      A @T6G_MB_LIB.T6G(SCH_1):PVDDCR_CPU1_P1_PVCC
   2    GND      B @T6G_MB_LIB.T6G(SCH_1):GND

Q_RES_0402LF-8.87K,1%,1/16W,EMPTY,CS28872FB01  I17  PR255
   1 PVDDCR_CPU1_P1_LSET1      A @T6G_MB_LIB.T6G(SCH_1):PVDDCR_CPU1_P1_LSET1
   2    GND      B @T6G_MB_LIB.T6G(SCH_1):GND

Q_RES_0402LF-2.2,1%,1/16W,CHIP,CS-2202FB01  I27  PR256
   1 PVDDCR_CPU1_P1_PVCC      A @T6G_MB_LIB.T6G(SCH_1):PVDDCR_CPU1_P1_PVCC
   2 PVDDCR_CPU1_P1_VCC1      B @T6G_MB_LIB.T6G(SCH_1):PVDDCR_CPU1_P1_VCC1

Q_CAP_C0402-2.2UF,10V,10%,X6S,CH5222KEB01  I29  PC371_C1P1_1
   1 PVDDCR_CPU1_P1_PVCC      A @T6G_MB_LIB.T6G(SCH_1):PVDDCR_CPU1_P1_PVCC
   2    GND      B @T6G_MB_LIB.T6G(SCH_1):GND

ISL99390FRZTR5935-ISL99390FRZ-TR5935,SMLF,IC,AL099A  I31  PU5
  34 PVDDCR_CPU1_P1_PWM2    PWM @T6G_MB_LIB.T6G(SCH_1):PVDDCR_CPU1_P1_PWM2
  39 PVDDCR_CPU1_P1_VCCS  REFIN @T6G_MB_LIB.T6G(SCH_1):PVDDCR_CPU1_P1_VCCS
   3 PVDDCR_CPU1_P1_VCC2    VCC @T6G_MB_LIB.T6G(SCH_1):PVDDCR_CPU1_P1_VCC2
   2    GND   AGND @T6G_MB_LIB.T6G(SCH_1):GND
  33 SW_PVDDCR_CPU1_P1_BOOT2   BOOT @T6G_MB_LIB.T6G(SCH_1):SW_PVDDCR_CPU1_P1_BOOT2
25_29 SW_P12V_AUX_PVDDCR_CPU1_P1_FLT   VIN1 @T6G_MB_LIB.T6G(SCH_1):SW_P12V_AUX_PVDDCR_CPU1_P1_FLT
  32 SW_PVDDCR_CPU1_P1_BOOTR2  PHASE @T6G_MB_LIB.T6G(SCH_1):SW_PVDDCR_CPU1_P1_BOOTR2
   4 PVDDCR_CPU1_P1_PVCC   PVCC @T6G_MB_LIB.T6G(SCH_1):PVDDCR_CPU1_P1_PVCC
  36 PVDDCR_CPU1_P1_TEMP0 TOUT_FLT @T6G_MB_LIB.T6G(SCH_1):PVDDCR_CPU1_P1_TEMP0
  38 PVDDCR_CPU1_P1_IMON2   IOUT @T6G_MB_LIB.T6G(SCH_1):PVDDCR_CPU1_P1_IMON2
  37 PVDDCR_CPU1_P1_LSET2   LSET @T6G_MB_LIB.T6G(SCH_1):PVDDCR_CPU1_P1_LSET2
10_19 SW_PVDDCR_CPU1_P1_SW2     SW @T6G_MB_LIB.T6G(SCH_1):SW_PVDDCR_CPU1_P1_SW2
   5    GND  PGND1 @T6G_MB_LIB.T6G(SCH_1):GND
  30 SW_P12V_AUX_PVDDCR_CPU1_P1_FLT   VIN2 @T6G_MB_LIB.T6G(SCH_1):SW_P12V_AUX_PVDDCR_CPU1_P1_FLT
   1 PVDDCR_CPU1_P1_VOS2    VOS @T6G_MB_LIB.T6G(SCH_1):PVDDCR_CPU1_P1_VOS2
  40    GND  PGND3 @T6G_MB_LIB.T6G(SCH_1):GND
  35 PVDDCR_CPU1_P1_VCC2     EN @T6G_MB_LIB.T6G(SCH_1):PVDDCR_CPU1_P1_VCC2
  31 NC_PVDDCR_CPU1_P1_DNC2    DNC @T6G_MB_LIB.T6G(SCH_1):NC_PVDDCR_CPU1_P1_DNC2
   6 NC_PVDDCR_CPU1_P1_GL1_2    GL1 @T6G_MB_LIB.T6G(SCH_1):NC_PVDDCR_CPU1_P1_GL1_2
  41 NC_PVDDCR_CPU1_P1_GL2_2    GL2 @T6G_MB_LIB.T6G(SCH_1):NC_PVDDCR_CPU1_P1_GL2_2
7_9-20_24    GND  PGND2 @T6G_MB_LIB.T6G(SCH_1):GND

Q_CAP_0402-0.1UF,25V,10%,X7R,CH4104K1B00  I34  PC376_2
   1 SW_P12V_AUX_PVDDCR_CPU1_P1_FLT      A @T6G_MB_LIB.T6G(SCH_1):SW_P12V_AUX_PVDDCR_CPU1_P1_FLT
   2    GND      B @T6G_MB_LIB.T6G(SCH_1):GND

Q_RES_0402LF-1.5,1%,1/8W,EMPTY,CS-1504FB00  I36  PR513
   1 SW_PVDDCR_CPU1_P1_SW2_RC      A @T6G_MB_LIB.T6G(SCH_1):SW_PVDDCR_CPU1_P1_SW2_RC
   2    GND      B @T6G_MB_LIB.T6G(SCH_1):GND

Q_CAP_C0402-560PF,50V,10%,EMPTY,CH1566K1B09  I37  PC202
   1 SW_PVDDCR_CPU1_P1_SW2      A @T6G_MB_LIB.T6G(SCH_1):SW_PVDDCR_CPU1_P1_SW2
   2 SW_PVDDCR_CPU1_P1_SW2_RC      B @T6G_MB_LIB.T6G(SCH_1):SW_PVDDCR_CPU1_P1_SW2_RC

Q_RES_0402LF-0,5%,1/16W,CHIP,CS00002JB13  I38  PR260
   1 PVDDCR_CPU1_P1_VOS2      A @T6G_MB_LIB.T6G(SCH_1):PVDDCR_CPU1_P1_VOS2
   2 PVDDCR_CPU1_P1      B @T6G_MB_LIB.T6G(SCH_1):PVDDCR_CPU1_P1

Q_CAP_0402-0.22UF,16V,10%,X7R,CH4223K1B00  I40  PC386
   1 SW_PVDDCR_CPU1_P1_BOOT2_R      A @T6G_MB_LIB.T6G(SCH_1):SW_PVDDCR_CPU1_P1_BOOT2_R
   2 SW_PVDDCR_CPU1_P1_BOOTR2      B @T6G_MB_LIB.T6G(SCH_1):SW_PVDDCR_CPU1_P1_BOOTR2

Q_CAP_C0402-1UF,25V,10%,X6S,CH5104KEB02  I42  PC378_2
   1 SW_P12V_AUX_PVDDCR_CPU1_P1_FLT      A @T6G_MB_LIB.T6G(SCH_1):SW_P12V_AUX_PVDDCR_CPU1_P1_FLT
   2    GND      B @T6G_MB_LIB.T6G(SCH_1):GND

Q_CAP_C0805-22UF,16V,20%,X6S,CH6223MEA01  I43  PC380_2
   1 SW_P12V_AUX_PVDDCR_CPU1_P1_FLT      A @T6G_MB_LIB.T6G(SCH_1):SW_P12V_AUX_PVDDCR_CPU1_P1_FLT
   2    GND      B @T6G_MB_LIB.T6G(SCH_1):GND

Q_RES_0402LF-1.5,1%,1/8W,EMPTY,CS-1504FB00  I45  PR512
   1 SW_PVDDCR_CPU1_P1_SW1_RC      A @T6G_MB_LIB.T6G(SCH_1):SW_PVDDCR_CPU1_P1_SW1_RC
   2    GND      B @T6G_MB_LIB.T6G(SCH_1):GND

Q_CAP_C0805-22UF,16V,20%,X6S,CH6223MEA01  I48  PC385_2
   1 SW_P12V_AUX_PVDDCR_CPU1_P1_FLT      A @T6G_MB_LIB.T6G(SCH_1):SW_P12V_AUX_PVDDCR_CPU1_P1_FLT
   2    GND      B @T6G_MB_LIB.T6G(SCH_1):GND

Q_CAP_0402-0.1UF,25V,10%,X7R,CH4104K1B00  I50  PC375_1
   1 SW_P12V_AUX_PVDDCR_CPU1_P1_FLT      A @T6G_MB_LIB.T6G(SCH_1):SW_P12V_AUX_PVDDCR_CPU1_P1_FLT
   2    GND      B @T6G_MB_LIB.T6G(SCH_1):GND

Q_RES_0402LF-5.6,1%,1/16W,CHIP,CS-5602FB01  I51  PR258
   1 SW_PVDDCR_CPU1_P1_BOOT1      A @T6G_MB_LIB.T6G(SCH_1):SW_PVDDCR_CPU1_P1_BOOT1
   2 SW_PVDDCR_CPU1_P1_BOOT1_R      B @T6G_MB_LIB.T6G(SCH_1):SW_PVDDCR_CPU1_P1_BOOT1_R

Q_CAP_C0402-560PF,50V,10%,EMPTY,CH1566K1B09  I52  PC201
   1 SW_PVDDCR_CPU1_P1_SW1      A @T6G_MB_LIB.T6G(SCH_1):SW_PVDDCR_CPU1_P1_SW1
   2 SW_PVDDCR_CPU1_P1_SW1_RC      B @T6G_MB_LIB.T6G(SCH_1):SW_PVDDCR_CPU1_P1_SW1_RC

Q_CAP_C0402-1UF,25V,10%,X6S,CH5104KEB02  I53  PC377_1
   1 SW_P12V_AUX_PVDDCR_CPU1_P1_FLT      A @T6G_MB_LIB.T6G(SCH_1):SW_P12V_AUX_PVDDCR_CPU1_P1_FLT
   2    GND      B @T6G_MB_LIB.T6G(SCH_1):GND

Q_CAP_C0805-22UF,16V,20%,X6S,CH6223MEA01  I54  PC379_1
   1 SW_P12V_AUX_PVDDCR_CPU1_P1_FLT      A @T6G_MB_LIB.T6G(SCH_1):SW_P12V_AUX_PVDDCR_CPU1_P1_FLT
   2    GND      B @T6G_MB_LIB.T6G(SCH_1):GND

Q_CAP_0402-0.22UF,16V,10%,X7R,CH4223K1B00  I57  PC383
   1 SW_PVDDCR_CPU1_P1_BOOT1_R      A @T6G_MB_LIB.T6G(SCH_1):SW_PVDDCR_CPU1_P1_BOOT1_R
   2 SW_PVDDCR_CPU1_P1_BOOTR1      B @T6G_MB_LIB.T6G(SCH_1):SW_PVDDCR_CPU1_P1_BOOTR1

Q_CAP_C0805-22UF,16V,20%,X6S,CH6223MEA01  I58  PC381_1
   1 SW_P12V_AUX_PVDDCR_CPU1_P1_FLT      A @T6G_MB_LIB.T6G(SCH_1):SW_P12V_AUX_PVDDCR_CPU1_P1_FLT
   2    GND      B @T6G_MB_LIB.T6G(SCH_1):GND

Q_CAP_C0805-22UF,16V,20%,X6S,CH6223MEA01  I60  PC384_1
   1 SW_P12V_AUX_PVDDCR_CPU1_P1_FLT      A @T6G_MB_LIB.T6G(SCH_1):SW_P12V_AUX_PVDDCR_CPU1_P1_FLT
   2    GND      B @T6G_MB_LIB.T6G(SCH_1):GND

Q_INDUCTOR4P_14-150NH,SMLF,IND,CV+15^0TZ04  I62  PL41
   2 IND_CPU1_P1_CPL1      2 @T6G_MB_LIB.T6G(SCH_1):IND_CPU1_P1_CPL1
   3 IND_CPU1_P1_CPL2      3 @T6G_MB_LIB.T6G(SCH_1):IND_CPU1_P1_CPL2
   4 PVDDCR_CPU1_P1      4 @T6G_MB_LIB.T6G(SCH_1):PVDDCR_CPU1_P1
   1 SW_PVDDCR_CPU1_P1_SW2      1 @T6G_MB_LIB.T6G(SCH_1):SW_PVDDCR_CPU1_P1_SW2

Q_RES_0402LF-0,5%,1/16W,CHIP,CS00002JB13  I64  PR261
   1 PVDDCR_CPU1_P1_VOS1      A @T6G_MB_LIB.T6G(SCH_1):PVDDCR_CPU1_P1_VOS1
   2 PVDDCR_CPU1_P1      B @T6G_MB_LIB.T6G(SCH_1):PVDDCR_CPU1_P1

Q_CAP_C0805-22UF,4V,20%,X6S,CH622KMEA03  I68  PC394_2
   1 PVDDCR_CPU1_P1      A @T6G_MB_LIB.T6G(SCH_1):PVDDCR_CPU1_P1
   2    GND      B @T6G_MB_LIB.T6G(SCH_1):GND

Q_CAP_C0805-22UF,4V,20%,X6S,CH622KMEA03  I70  PC397_2
   1 PVDDCR_CPU1_P1      A @T6G_MB_LIB.T6G(SCH_1):PVDDCR_CPU1_P1
   2    GND      B @T6G_MB_LIB.T6G(SCH_1):GND

Q_CAPP_SMLF-220UF,4V,20%,SPCAP,CH122KM8801  I73  PC389
   1 PVDDCR_CPU1_P1      A @T6G_MB_LIB.T6G(SCH_1):PVDDCR_CPU1_P1
   2    GND      B @T6G_MB_LIB.T6G(SCH_1):GND

Q_INDUCTOR4P_14-150NH,SMLF,IND,CV+15^0TZ04  I77  PL40
   2 IND_CPU1_P1_CPL5      2 @T6G_MB_LIB.T6G(SCH_1):IND_CPU1_P1_CPL5
   3 IND_CPU1_P1_CPL1      3 @T6G_MB_LIB.T6G(SCH_1):IND_CPU1_P1_CPL1
   4 PVDDCR_CPU1_P1      4 @T6G_MB_LIB.T6G(SCH_1):PVDDCR_CPU1_P1
   1 SW_PVDDCR_CPU1_P1_SW1      1 @T6G_MB_LIB.T6G(SCH_1):SW_PVDDCR_CPU1_P1_SW1

Q_INDUCTOR_SMLF-50NH/86A,IND,CVA50^0MZ09  I79  PL42
   2 P12V_AUX      2 @T6G_MB_LIB.T6G(SCH_1):P12V_AUX
   1 SW_P12V_AUX_PVDDCR_CPU1_P1_FLT      1 @T6G_MB_LIB.T6G(SCH_1):SW_P12V_AUX_PVDDCR_CPU1_P1_FLT

Q_CAP_0402-0.1UF,25V,10%,X7R,CH4104K1B00  I82  PC392
   1 PVDDCR_CPU1_P1      A @T6G_MB_LIB.T6G(SCH_1):PVDDCR_CPU1_P1
   2    GND      B @T6G_MB_LIB.T6G(SCH_1):GND

Q_CAP_0402-0.1UF,25V,10%,X7R,CH4104K1B00  I83  PC375
   1 P12V_AUX      A @T6G_MB_LIB.T6G(SCH_1):P12V_AUX
   2    GND      B @T6G_MB_LIB.T6G(SCH_1):GND

Q_CAP_C0805-22UF,4V,20%,X6S,CH622KMEA03  I85  PC395_1
   1 PVDDCR_CPU1_P1      A @T6G_MB_LIB.T6G(SCH_1):PVDDCR_CPU1_P1
   2    GND      B @T6G_MB_LIB.T6G(SCH_1):GND

Q_CAP_C0805-22UF,4V,20%,X6S,CH622KMEA03  I86  PC398_1
   1 PVDDCR_CPU1_P1      A @T6G_MB_LIB.T6G(SCH_1):PVDDCR_CPU1_P1
   2    GND      B @T6G_MB_LIB.T6G(SCH_1):GND

Q_RES_0402LF-0,5%,1/16W,CHIP,CS00002JB13  I89  PR340
   1 PVDDCR_CPU1_P1_PVCC      A @T6G_MB_LIB.T6G(SCH_1):PVDDCR_CPU1_P1_PVCC
   2 P5V_AUX      B @T6G_MB_LIB.T6G(SCH_1):P5V_AUX

Q_RES_0402LF-0,5%,1/16W,EMPTY,CS00002JB13  I90  PR341
   1 PVDDCR_CPU1_P1_PVCC      A @T6G_MB_LIB.T6G(SCH_1):PVDDCR_CPU1_P1_PVCC
   2 P3V3_AUX      B @T6G_MB_LIB.T6G(SCH_1):P3V3_AUX

ISL99390FRZTR5935-ISL99390FRZ-TR5935,SMLF,IC,AL099A  I91  PU35
  34 PVDDCR_CPU1_P1_PWM1    PWM @T6G_MB_LIB.T6G(SCH_1):PVDDCR_CPU1_P1_PWM1
  39 PVDDCR_CPU1_P1_VCCS  REFIN @T6G_MB_LIB.T6G(SCH_1):PVDDCR_CPU1_P1_VCCS
   3 PVDDCR_CPU1_P1_VCC1    VCC @T6G_MB_LIB.T6G(SCH_1):PVDDCR_CPU1_P1_VCC1
   2    GND   AGND @T6G_MB_LIB.T6G(SCH_1):GND
  33 SW_PVDDCR_CPU1_P1_BOOT1   BOOT @T6G_MB_LIB.T6G(SCH_1):SW_PVDDCR_CPU1_P1_BOOT1
25_29 SW_P12V_AUX_PVDDCR_CPU1_P1_FLT   VIN1 @T6G_MB_LIB.T6G(SCH_1):SW_P12V_AUX_PVDDCR_CPU1_P1_FLT
  32 SW_PVDDCR_CPU1_P1_BOOTR1  PHASE @T6G_MB_LIB.T6G(SCH_1):SW_PVDDCR_CPU1_P1_BOOTR1
   4 PVDDCR_CPU1_P1_PVCC   PVCC @T6G_MB_LIB.T6G(SCH_1):PVDDCR_CPU1_P1_PVCC
  36 PVDDCR_CPU1_P1_TEMP0 TOUT_FLT @T6G_MB_LIB.T6G(SCH_1):PVDDCR_CPU1_P1_TEMP0
  38 PVDDCR_CPU1_P1_IMON1   IOUT @T6G_MB_LIB.T6G(SCH_1):PVDDCR_CPU1_P1_IMON1
  37 PVDDCR_CPU1_P1_LSET1   LSET @T6G_MB_LIB.T6G(SCH_1):PVDDCR_CPU1_P1_LSET1
10_19 SW_PVDDCR_CPU1_P1_SW1     SW @T6G_MB_LIB.T6G(SCH_1):SW_PVDDCR_CPU1_P1_SW1
   5    GND  PGND1 @T6G_MB_LIB.T6G(SCH_1):GND
  30 SW_P12V_AUX_PVDDCR_CPU1_P1_FLT   VIN2 @T6G_MB_LIB.T6G(SCH_1):SW_P12V_AUX_PVDDCR_CPU1_P1_FLT
   1 PVDDCR_CPU1_P1_VOS1    VOS @T6G_MB_LIB.T6G(SCH_1):PVDDCR_CPU1_P1_VOS1
  40    GND  PGND3 @T6G_MB_LIB.T6G(SCH_1):GND
  35 PVDDCR_CPU1_P1_VCC1     EN @T6G_MB_LIB.T6G(SCH_1):PVDDCR_CPU1_P1_VCC1
  31 NC_PVDDCR_CPU1_P1_DNC1    DNC @T6G_MB_LIB.T6G(SCH_1):NC_PVDDCR_CPU1_P1_DNC1
   6 NC_PVDDCR_CPU1_P1_GL1_1    GL1 @T6G_MB_LIB.T6G(SCH_1):NC_PVDDCR_CPU1_P1_GL1_1
  41 NC_PVDDCR_CPU1_P1_GL2_1    GL2 @T6G_MB_LIB.T6G(SCH_1):NC_PVDDCR_CPU1_P1_GL2_1
7_9-20_24    GND  PGND2 @T6G_MB_LIB.T6G(SCH_1):GND

Q_CAPP_SMLF-270UF,16V,20%,OSCON,CC72703MZ11  I92  PC393
   1 SW_P12V_AUX_PVDDCR_CPU1_P1_FLT      A @T6G_MB_LIB.T6G(SCH_1):SW_P12V_AUX_PVDDCR_CPU1_P1_FLT
   2    GND      B @T6G_MB_LIB.T6G(SCH_1):GND

Q_CAPP_SMLF-270UF,16V,20%,OSCON,CC72703MZ11  I93  PC390
   1 SW_P12V_AUX_PVDDCR_CPU1_P1_FLT      A @T6G_MB_LIB.T6G(SCH_1):SW_P12V_AUX_PVDDCR_CPU1_P1_FLT
   2    GND      B @T6G_MB_LIB.T6G(SCH_1):GND


DRAWING: @T6G_MB_LIB.T6G(SCH_1):PAGE194 

Q_CAP_0402-0.1UF,25V,10%,X7R,CH4104K1B00  I2  PC403_4
   1 PVDDCR_CPU1_P1_VCCS      A @T6G_MB_LIB.T6G(SCH_1):PVDDCR_CPU1_P1_VCCS
   2    GND      B @T6G_MB_LIB.T6G(SCH_1):GND

Q_CAP_C0402-560PF,50V,10%,EMPTY,CH1566K1B09  I37  PC205
   1 SW_PVDDCR_CPU1_P1_SW4      A @T6G_MB_LIB.T6G(SCH_1):SW_PVDDCR_CPU1_P1_SW4
   2 SW_PVDDCR_CPU1_P1_SW4_RC      B @T6G_MB_LIB.T6G(SCH_1):SW_PVDDCR_CPU1_P1_SW4_RC

Q_RES_0402LF-0,5%,1/16W,CHIP,CS00002JB13  I38  PR268
   1 PVDDCR_CPU1_P1_VOS4      A @T6G_MB_LIB.T6G(SCH_1):PVDDCR_CPU1_P1_VOS4
   2 PVDDCR_CPU1_P1      B @T6G_MB_LIB.T6G(SCH_1):PVDDCR_CPU1_P1

Q_CAP_0402-0.22UF,16V,10%,X7R,CH4223K1B00  I40  PC413
   1 SW_PVDDCR_CPU1_P1_BOOT4_R      A @T6G_MB_LIB.T6G(SCH_1):SW_PVDDCR_CPU1_P1_BOOT4_R
   2 SW_PVDDCR_CPU1_P1_BOOTR4      B @T6G_MB_LIB.T6G(SCH_1):SW_PVDDCR_CPU1_P1_BOOTR4

Q_CAP_C0805-22UF,16V,20%,X6S,CH6223MEA01  I42  PC409_4
   1 SW_P12V_AUX_PVDDCR_CPU1_P1_FLT      A @T6G_MB_LIB.T6G(SCH_1):SW_P12V_AUX_PVDDCR_CPU1_P1_FLT
   2    GND      B @T6G_MB_LIB.T6G(SCH_1):GND

Q_INDUCTOR4P_14-150NH,SMLF,IND,CV+15^0TZ04  I50  PL43
   2 IND_CPU1_P1_CPL3      2 @T6G_MB_LIB.T6G(SCH_1):IND_CPU1_P1_CPL3
   3    GND      3 @T6G_MB_LIB.T6G(SCH_1):GND
   4 PVDDCR_CPU1_P1      4 @T6G_MB_LIB.T6G(SCH_1):PVDDCR_CPU1_P1
   1 SW_PVDDCR_CPU1_P1_SW4      1 @T6G_MB_LIB.T6G(SCH_1):SW_PVDDCR_CPU1_P1_SW4

Q_CAP_C0805-22UF,16V,20%,X6S,CH6223MEA01  I55  PC410_3
   1 SW_P12V_AUX_PVDDCR_CPU1_P1_FLT      A @T6G_MB_LIB.T6G(SCH_1):SW_P12V_AUX_PVDDCR_CPU1_P1_FLT
   2    GND      B @T6G_MB_LIB.T6G(SCH_1):GND

Q_RES_0402LF-8.87K,1%,1/16W,EMPTY,CS28872FB01  I4  PR262
   1 PVDDCR_CPU1_P1_LSET4      A @T6G_MB_LIB.T6G(SCH_1):PVDDCR_CPU1_P1_LSET4
   2    GND      B @T6G_MB_LIB.T6G(SCH_1):GND

Q_CAP_C0402-2.2UF,10V,10%,X6S,CH5222KEB01  I7  PC399
   1 PVDDCR_CPU1_P1_VCC4      A @T6G_MB_LIB.T6G(SCH_1):PVDDCR_CPU1_P1_VCC4
   2    GND      B @T6G_MB_LIB.T6G(SCH_1):GND

Q_CAP_0402-0.1UF,25V,10%,X7R,CH4104K1B00  I12  PC404_3
   1 PVDDCR_CPU1_P1_VCCS      A @T6G_MB_LIB.T6G(SCH_1):PVDDCR_CPU1_P1_VCCS
   2    GND      B @T6G_MB_LIB.T6G(SCH_1):GND

Q_RES_0402LF-2.2,1%,1/16W,CHIP,CS-2202FB01  I13  PR264
   1 PVDDCR_CPU1_P1_PVCC      A @T6G_MB_LIB.T6G(SCH_1):PVDDCR_CPU1_P1_PVCC
   2 PVDDCR_CPU1_P1_VCC4      B @T6G_MB_LIB.T6G(SCH_1):PVDDCR_CPU1_P1_VCC4

Q_CAP_C0402-2.2UF,10V,10%,X6S,CH5222KEB01  I16  PC401_C1P1_4
   1 PVDDCR_CPU1_P1_PVCC      A @T6G_MB_LIB.T6G(SCH_1):PVDDCR_CPU1_P1_PVCC
   2    GND      B @T6G_MB_LIB.T6G(SCH_1):GND

Q_RES_0402LF-8.87K,1%,1/16W,EMPTY,CS28872FB01  I18  PR263
   1 PVDDCR_CPU1_P1_LSET3      A @T6G_MB_LIB.T6G(SCH_1):PVDDCR_CPU1_P1_LSET3
   2    GND      B @T6G_MB_LIB.T6G(SCH_1):GND

ISL99390FRZTR5935-ISL99390FRZ-TR5935,SMLF,IC,AL099A  I21  PU36
  34 PVDDCR_CPU1_P1_PWM4    PWM @T6G_MB_LIB.T6G(SCH_1):PVDDCR_CPU1_P1_PWM4
  39 PVDDCR_CPU1_P1_VCCS  REFIN @T6G_MB_LIB.T6G(SCH_1):PVDDCR_CPU1_P1_VCCS
   3 PVDDCR_CPU1_P1_VCC4    VCC @T6G_MB_LIB.T6G(SCH_1):PVDDCR_CPU1_P1_VCC4
   2    GND   AGND @T6G_MB_LIB.T6G(SCH_1):GND
  33 SW_PVDDCR_CPU1_P1_BOOT4   BOOT @T6G_MB_LIB.T6G(SCH_1):SW_PVDDCR_CPU1_P1_BOOT4
25_29 SW_P12V_AUX_PVDDCR_CPU1_P1_FLT   VIN1 @T6G_MB_LIB.T6G(SCH_1):SW_P12V_AUX_PVDDCR_CPU1_P1_FLT
  32 SW_PVDDCR_CPU1_P1_BOOTR4  PHASE @T6G_MB_LIB.T6G(SCH_1):SW_PVDDCR_CPU1_P1_BOOTR4
   4 PVDDCR_CPU1_P1_PVCC   PVCC @T6G_MB_LIB.T6G(SCH_1):PVDDCR_CPU1_P1_PVCC
  36 PVDDCR_CPU1_P1_TEMP0 TOUT_FLT @T6G_MB_LIB.T6G(SCH_1):PVDDCR_CPU1_P1_TEMP0
  38 PVDDCR_CPU1_P1_IMON4   IOUT @T6G_MB_LIB.T6G(SCH_1):PVDDCR_CPU1_P1_IMON4
  37 PVDDCR_CPU1_P1_LSET4   LSET @T6G_MB_LIB.T6G(SCH_1):PVDDCR_CPU1_P1_LSET4
10_19 SW_PVDDCR_CPU1_P1_SW4     SW @T6G_MB_LIB.T6G(SCH_1):SW_PVDDCR_CPU1_P1_SW4
   5    GND  PGND1 @T6G_MB_LIB.T6G(SCH_1):GND
  30 SW_P12V_AUX_PVDDCR_CPU1_P1_FLT   VIN2 @T6G_MB_LIB.T6G(SCH_1):SW_P12V_AUX_PVDDCR_CPU1_P1_FLT
   1 PVDDCR_CPU1_P1_VOS4    VOS @T6G_MB_LIB.T6G(SCH_1):PVDDCR_CPU1_P1_VOS4
  40    GND  PGND3 @T6G_MB_LIB.T6G(SCH_1):GND
  35 PVDDCR_CPU1_P1_VCC4     EN @T6G_MB_LIB.T6G(SCH_1):PVDDCR_CPU1_P1_VCC4
  31 NC_PVDDCR_CPU1_P1_DNC4    DNC @T6G_MB_LIB.T6G(SCH_1):NC_PVDDCR_CPU1_P1_DNC4
   6 NC_PVDDCR_CPU1_P1_GL1_4    GL1 @T6G_MB_LIB.T6G(SCH_1):NC_PVDDCR_CPU1_P1_GL1_4
  41 NC_PVDDCR_CPU1_P1_GL2_4    GL2 @T6G_MB_LIB.T6G(SCH_1):NC_PVDDCR_CPU1_P1_GL2_4
7_9-20_24    GND  PGND2 @T6G_MB_LIB.T6G(SCH_1):GND

Q_CAP_0402-0.1UF,25V,10%,X7R,CH4104K1B00  I23  PC405_4
   1 SW_P12V_AUX_PVDDCR_CPU1_P1_FLT      A @T6G_MB_LIB.T6G(SCH_1):SW_P12V_AUX_PVDDCR_CPU1_P1_FLT
   2    GND      B @T6G_MB_LIB.T6G(SCH_1):GND

Q_CAP_C0402-2.2UF,10V,10%,X6S,CH5222KEB01  I27  PC400
   1 PVDDCR_CPU1_P1_VCC3      A @T6G_MB_LIB.T6G(SCH_1):PVDDCR_CPU1_P1_VCC3
   2    GND      B @T6G_MB_LIB.T6G(SCH_1):GND

Q_RES_0402LF-2.2,1%,1/16W,CHIP,CS-2202FB01  I29  PR265
   1 PVDDCR_CPU1_P1_PVCC      A @T6G_MB_LIB.T6G(SCH_1):PVDDCR_CPU1_P1_PVCC
   2 PVDDCR_CPU1_P1_VCC3      B @T6G_MB_LIB.T6G(SCH_1):PVDDCR_CPU1_P1_VCC3

Q_CAP_C0402-2.2UF,10V,10%,X6S,CH5222KEB01  I31  PC402_C1P1_3
   1 PVDDCR_CPU1_P1_PVCC      A @T6G_MB_LIB.T6G(SCH_1):PVDDCR_CPU1_P1_PVCC
   2    GND      B @T6G_MB_LIB.T6G(SCH_1):GND

Q_CAP_0402-0.1UF,25V,10%,X7R,CH4104K1B00  I33  PC408_3
   1 SW_P12V_AUX_PVDDCR_CPU1_P1_FLT      A @T6G_MB_LIB.T6G(SCH_1):SW_P12V_AUX_PVDDCR_CPU1_P1_FLT
   2    GND      B @T6G_MB_LIB.T6G(SCH_1):GND

Q_RES_0402LF-1.5,1%,1/8W,EMPTY,CS-1504FB00  I35  PR515
   1 SW_PVDDCR_CPU1_P1_SW4_RC      A @T6G_MB_LIB.T6G(SCH_1):SW_PVDDCR_CPU1_P1_SW4_RC
   2    GND      B @T6G_MB_LIB.T6G(SCH_1):GND

Q_RES_0402LF-5.6,1%,1/16W,CHIP,CS-5602FB01  I36  PR266
   1 SW_PVDDCR_CPU1_P1_BOOT4      A @T6G_MB_LIB.T6G(SCH_1):SW_PVDDCR_CPU1_P1_BOOT4
   2 SW_PVDDCR_CPU1_P1_BOOT4_R      B @T6G_MB_LIB.T6G(SCH_1):SW_PVDDCR_CPU1_P1_BOOT4_R

Q_CAP_C0402-1UF,25V,10%,X6S,CH5104KEB02  I41  PC407_4
   1 SW_P12V_AUX_PVDDCR_CPU1_P1_FLT      A @T6G_MB_LIB.T6G(SCH_1):SW_P12V_AUX_PVDDCR_CPU1_P1_FLT
   2    GND      B @T6G_MB_LIB.T6G(SCH_1):GND

Q_RES_0402LF-1.5,1%,1/8W,EMPTY,CS-1504FB00  I44  PR516
   1 SW_PVDDCR_CPU1_P1_SW3_RC      A @T6G_MB_LIB.T6G(SCH_1):SW_PVDDCR_CPU1_P1_SW3_RC
   2    GND      B @T6G_MB_LIB.T6G(SCH_1):GND

Q_CAP_C0805-22UF,16V,20%,X6S,CH6223MEA01  I45  PC411_4
   1 SW_P12V_AUX_PVDDCR_CPU1_P1_FLT      A @T6G_MB_LIB.T6G(SCH_1):SW_P12V_AUX_PVDDCR_CPU1_P1_FLT
   2    GND      B @T6G_MB_LIB.T6G(SCH_1):GND

Q_CAP_C0805-22UF,16V,20%,X6S,CH6223MEA01  I47  PC415_4
   1 SW_P12V_AUX_PVDDCR_CPU1_P1_FLT      A @T6G_MB_LIB.T6G(SCH_1):SW_P12V_AUX_PVDDCR_CPU1_P1_FLT
   2    GND      B @T6G_MB_LIB.T6G(SCH_1):GND

Q_RES_0402LF-0,5%,1/16W,CHIP,CS00002JB13  I49  PR269
   1 PVDDCR_CPU1_P1_VOS3      A @T6G_MB_LIB.T6G(SCH_1):PVDDCR_CPU1_P1_VOS3
   2 PVDDCR_CPU1_P1      B @T6G_MB_LIB.T6G(SCH_1):PVDDCR_CPU1_P1

Q_RES_0402LF-5.6,1%,1/16W,CHIP,CS-5602FB01  I52  PR267
   1 SW_PVDDCR_CPU1_P1_BOOT3      A @T6G_MB_LIB.T6G(SCH_1):SW_PVDDCR_CPU1_P1_BOOT3
   2 SW_PVDDCR_CPU1_P1_BOOT3_R      B @T6G_MB_LIB.T6G(SCH_1):SW_PVDDCR_CPU1_P1_BOOT3_R

Q_CAP_C0402-560PF,50V,10%,EMPTY,CH1566K1B09  I53  PC206
   1 SW_PVDDCR_CPU1_P1_SW3      A @T6G_MB_LIB.T6G(SCH_1):SW_PVDDCR_CPU1_P1_SW3
   2 SW_PVDDCR_CPU1_P1_SW3_RC      B @T6G_MB_LIB.T6G(SCH_1):SW_PVDDCR_CPU1_P1_SW3_RC

Q_CAP_C0402-1UF,25V,10%,X6S,CH5104KEB02  I54  PC406_3
   1 SW_P12V_AUX_PVDDCR_CPU1_P1_FLT      A @T6G_MB_LIB.T6G(SCH_1):SW_P12V_AUX_PVDDCR_CPU1_P1_FLT
   2    GND      B @T6G_MB_LIB.T6G(SCH_1):GND

Q_CAP_0402-0.22UF,16V,10%,X7R,CH4223K1B00  I57  PC414
   1 SW_PVDDCR_CPU1_P1_BOOT3_R      A @T6G_MB_LIB.T6G(SCH_1):SW_PVDDCR_CPU1_P1_BOOT3_R
   2 SW_PVDDCR_CPU1_P1_BOOTR3      B @T6G_MB_LIB.T6G(SCH_1):SW_PVDDCR_CPU1_P1_BOOTR3

Q_CAP_C0805-22UF,16V,20%,X6S,CH6223MEA01  I59  PC412_3
   1 SW_P12V_AUX_PVDDCR_CPU1_P1_FLT      A @T6G_MB_LIB.T6G(SCH_1):SW_P12V_AUX_PVDDCR_CPU1_P1_FLT
   2    GND      B @T6G_MB_LIB.T6G(SCH_1):GND

Q_CAP_C0805-22UF,16V,20%,X6S,CH6223MEA01  I60  PC416_3
   1 SW_P12V_AUX_PVDDCR_CPU1_P1_FLT      A @T6G_MB_LIB.T6G(SCH_1):SW_P12V_AUX_PVDDCR_CPU1_P1_FLT
   2    GND      B @T6G_MB_LIB.T6G(SCH_1):GND

Q_INDUCTOR4P_14-150NH,SMLF,IND,CV+15^0TZ04  I62  PL44
   2 IND_CPU1_P1_CPL2      2 @T6G_MB_LIB.T6G(SCH_1):IND_CPU1_P1_CPL2
   3 IND_CPU1_P1_CPL3      3 @T6G_MB_LIB.T6G(SCH_1):IND_CPU1_P1_CPL3
   4 PVDDCR_CPU1_P1      4 @T6G_MB_LIB.T6G(SCH_1):PVDDCR_CPU1_P1
   1 SW_PVDDCR_CPU1_P1_SW3      1 @T6G_MB_LIB.T6G(SCH_1):SW_PVDDCR_CPU1_P1_SW3

Q_CAP_C0805-22UF,4V,20%,X6S,CH622KMEA03  I64  PC417_3
   1 PVDDCR_CPU1_P1      A @T6G_MB_LIB.T6G(SCH_1):PVDDCR_CPU1_P1
   2    GND      B @T6G_MB_LIB.T6G(SCH_1):GND

Q_CAP_C0805-22UF,4V,20%,X6S,CH622KMEA03  I65  PC418_4
   1 PVDDCR_CPU1_P1      A @T6G_MB_LIB.T6G(SCH_1):PVDDCR_CPU1_P1
   2    GND      B @T6G_MB_LIB.T6G(SCH_1):GND

Q_CAP_C0805-22UF,4V,20%,X6S,CH622KMEA03  I67  PC420_4
   1 PVDDCR_CPU1_P1      A @T6G_MB_LIB.T6G(SCH_1):PVDDCR_CPU1_P1
   2    GND      B @T6G_MB_LIB.T6G(SCH_1):GND

Q_CAP_C0805-22UF,4V,20%,X6S,CH622KMEA03  I70  PC419_3
   1 PVDDCR_CPU1_P1      A @T6G_MB_LIB.T6G(SCH_1):PVDDCR_CPU1_P1
   2    GND      B @T6G_MB_LIB.T6G(SCH_1):GND

ISL99390FRZTR5935-ISL99390FRZ-TR5935,SMLF,IC,AL099A  I72  PU37
  34 PVDDCR_CPU1_P1_PWM3    PWM @T6G_MB_LIB.T6G(SCH_1):PVDDCR_CPU1_P1_PWM3
  39 PVDDCR_CPU1_P1_VCCS  REFIN @T6G_MB_LIB.T6G(SCH_1):PVDDCR_CPU1_P1_VCCS
   3 PVDDCR_CPU1_P1_VCC3    VCC @T6G_MB_LIB.T6G(SCH_1):PVDDCR_CPU1_P1_VCC3
   2    GND   AGND @T6G_MB_LIB.T6G(SCH_1):GND
  33 SW_PVDDCR_CPU1_P1_BOOT3   BOOT @T6G_MB_LIB.T6G(SCH_1):SW_PVDDCR_CPU1_P1_BOOT3
25_29 SW_P12V_AUX_PVDDCR_CPU1_P1_FLT   VIN1 @T6G_MB_LIB.T6G(SCH_1):SW_P12V_AUX_PVDDCR_CPU1_P1_FLT
  32 SW_PVDDCR_CPU1_P1_BOOTR3  PHASE @T6G_MB_LIB.T6G(SCH_1):SW_PVDDCR_CPU1_P1_BOOTR3
   4 PVDDCR_CPU1_P1_PVCC   PVCC @T6G_MB_LIB.T6G(SCH_1):PVDDCR_CPU1_P1_PVCC
  36 PVDDCR_CPU1_P1_TEMP0 TOUT_FLT @T6G_MB_LIB.T6G(SCH_1):PVDDCR_CPU1_P1_TEMP0
  38 PVDDCR_CPU1_P1_IMON3   IOUT @T6G_MB_LIB.T6G(SCH_1):PVDDCR_CPU1_P1_IMON3
  37 PVDDCR_CPU1_P1_LSET3   LSET @T6G_MB_LIB.T6G(SCH_1):PVDDCR_CPU1_P1_LSET3
10_19 SW_PVDDCR_CPU1_P1_SW3     SW @T6G_MB_LIB.T6G(SCH_1):SW_PVDDCR_CPU1_P1_SW3
   5    GND  PGND1 @T6G_MB_LIB.T6G(SCH_1):GND
  30 SW_P12V_AUX_PVDDCR_CPU1_P1_FLT   VIN2 @T6G_MB_LIB.T6G(SCH_1):SW_P12V_AUX_PVDDCR_CPU1_P1_FLT
   1 PVDDCR_CPU1_P1_VOS3    VOS @T6G_MB_LIB.T6G(SCH_1):PVDDCR_CPU1_P1_VOS3
  40    GND  PGND3 @T6G_MB_LIB.T6G(SCH_1):GND
  35 PVDDCR_CPU1_P1_VCC3     EN @T6G_MB_LIB.T6G(SCH_1):PVDDCR_CPU1_P1_VCC3
  31 NC_PVDDCR_CPU1_P1_DNC3    DNC @T6G_MB_LIB.T6G(SCH_1):NC_PVDDCR_CPU1_P1_DNC3
   6 NC_PVDDCR_CPU1_P1_GL1_3    GL1 @T6G_MB_LIB.T6G(SCH_1):NC_PVDDCR_CPU1_P1_GL1_3
  41 NC_PVDDCR_CPU1_P1_GL2_3    GL2 @T6G_MB_LIB.T6G(SCH_1):NC_PVDDCR_CPU1_P1_GL2_3
7_9-20_24    GND  PGND2 @T6G_MB_LIB.T6G(SCH_1):GND


DRAWING: @T6G_MB_LIB.T6G(SCH_1):PAGE195 

Q_CAP_C0402-2.2UF,10V,10%,X6S,CH5222KEB01  I31  PC423_C1P1_5
   1 PVDDCR_CPU1_P1_PVCC      A @T6G_MB_LIB.T6G(SCH_1):PVDDCR_CPU1_P1_PVCC
   2    GND      B @T6G_MB_LIB.T6G(SCH_1):GND

Q_RES_0402LF-5.6,1%,1/16W,CHIP,CS-5602FB01  I39  PR428
   1 SW_PVDDCR_CPU1_P1_BOOT6      A @T6G_MB_LIB.T6G(SCH_1):SW_PVDDCR_CPU1_P1_BOOT6
   2 SW_PVDDCR_CPU1_P1_BOOT6_R      B @T6G_MB_LIB.T6G(SCH_1):SW_PVDDCR_CPU1_P1_BOOT6_R

Q_CAP_C0402-1UF,25V,10%,X6S,CH5104KEB02  I40  PC140_6
   1 SW_P12V_AUX_PVDDCR_CPU1_P1_FLT      A @T6G_MB_LIB.T6G(SCH_1):SW_P12V_AUX_PVDDCR_CPU1_P1_FLT
   2    GND      B @T6G_MB_LIB.T6G(SCH_1):GND

Q_CAP_C0805-22UF,16V,20%,X6S,CH6223MEA01  I60  PC427_5
   1 SW_P12V_AUX_PVDDCR_CPU1_P1_FLT      A @T6G_MB_LIB.T6G(SCH_1):SW_P12V_AUX_PVDDCR_CPU1_P1_FLT
   2    GND      B @T6G_MB_LIB.T6G(SCH_1):GND

Q_CAP_0402-0.1UF,25V,10%,X7R,CH4104K1B00  I1  PC136_6
   1 PVDDCR_CPU1_P1_VCCS      A @T6G_MB_LIB.T6G(SCH_1):PVDDCR_CPU1_P1_VCCS
   2    GND      B @T6G_MB_LIB.T6G(SCH_1):GND

Q_RES_0402LF-8.87K,1%,1/16W,EMPTY,CS28872FB01  I4  PR426
   1 PVDDCR_CPU1_P1_LSET6      A @T6G_MB_LIB.T6G(SCH_1):PVDDCR_CPU1_P1_LSET6
   2    GND      B @T6G_MB_LIB.T6G(SCH_1):GND

Q_CAP_0402-0.1UF,25V,10%,X7R,CH4104K1B00  I10  PC422_5
   1 PVDDCR_CPU1_P1_VCCS      A @T6G_MB_LIB.T6G(SCH_1):PVDDCR_CPU1_P1_VCCS
   2    GND      B @T6G_MB_LIB.T6G(SCH_1):GND

Q_CAP_C0402-2.2UF,10V,10%,X6S,CH5222KEB01  I12  PC138
   1 PVDDCR_CPU1_P1_VCC6      A @T6G_MB_LIB.T6G(SCH_1):PVDDCR_CPU1_P1_VCC6
   2    GND      B @T6G_MB_LIB.T6G(SCH_1):GND

Q_RES_0402LF-2.2,1%,1/16W,CHIP,CS-2202FB01  I13  PR427
   1 PVDDCR_CPU1_P1_PVCC      A @T6G_MB_LIB.T6G(SCH_1):PVDDCR_CPU1_P1_PVCC
   2 PVDDCR_CPU1_P1_VCC6      B @T6G_MB_LIB.T6G(SCH_1):PVDDCR_CPU1_P1_VCC6

Q_RES_0402LF-8.87K,1%,1/16W,EMPTY,CS28872FB01  I15  PR270
   1 PVDDCR_CPU1_P1_LSET5      A @T6G_MB_LIB.T6G(SCH_1):PVDDCR_CPU1_P1_LSET5
   2    GND      B @T6G_MB_LIB.T6G(SCH_1):GND

ISL99390FRZTR5935-ISL99390FRZ-TR5935,SMLF,IC,AL099A  I19  PU33
  34 PVDDCR_CPU1_P1_PWM6    PWM @T6G_MB_LIB.T6G(SCH_1):PVDDCR_CPU1_P1_PWM6
  39 PVDDCR_CPU1_P1_VCCS  REFIN @T6G_MB_LIB.T6G(SCH_1):PVDDCR_CPU1_P1_VCCS
   3 PVDDCR_CPU1_P1_VCC6    VCC @T6G_MB_LIB.T6G(SCH_1):PVDDCR_CPU1_P1_VCC6
   2    GND   AGND @T6G_MB_LIB.T6G(SCH_1):GND
  33 SW_PVDDCR_CPU1_P1_BOOT6   BOOT @T6G_MB_LIB.T6G(SCH_1):SW_PVDDCR_CPU1_P1_BOOT6
25_29 SW_P12V_AUX_PVDDCR_CPU1_P1_FLT   VIN1 @T6G_MB_LIB.T6G(SCH_1):SW_P12V_AUX_PVDDCR_CPU1_P1_FLT
  32 SW_PVDDCR_CPU1_P1_BOOTR6  PHASE @T6G_MB_LIB.T6G(SCH_1):SW_PVDDCR_CPU1_P1_BOOTR6
   4 PVDDCR_CPU1_P1_PVCC   PVCC @T6G_MB_LIB.T6G(SCH_1):PVDDCR_CPU1_P1_PVCC
  36 PVDDCR_CPU1_P1_TEMP0 TOUT_FLT @T6G_MB_LIB.T6G(SCH_1):PVDDCR_CPU1_P1_TEMP0
  38 PVDDCR_CPU1_P1_IMON6   IOUT @T6G_MB_LIB.T6G(SCH_1):PVDDCR_CPU1_P1_IMON6
  37 PVDDCR_CPU1_P1_LSET6   LSET @T6G_MB_LIB.T6G(SCH_1):PVDDCR_CPU1_P1_LSET6
10_19 SW_PVDDCR_CPU1_P1_SW6     SW @T6G_MB_LIB.T6G(SCH_1):SW_PVDDCR_CPU1_P1_SW6
   5    GND  PGND1 @T6G_MB_LIB.T6G(SCH_1):GND
  30 SW_P12V_AUX_PVDDCR_CPU1_P1_FLT   VIN2 @T6G_MB_LIB.T6G(SCH_1):SW_P12V_AUX_PVDDCR_CPU1_P1_FLT
   1 PVDDCR_CPU1_P1_VOS6    VOS @T6G_MB_LIB.T6G(SCH_1):PVDDCR_CPU1_P1_VOS6
  40    GND  PGND3 @T6G_MB_LIB.T6G(SCH_1):GND
  35 PVDDCR_CPU1_P1_VCC6     EN @T6G_MB_LIB.T6G(SCH_1):PVDDCR_CPU1_P1_VCC6
  31 NC_PVDDCR_CPU1_P1_DNC6    DNC @T6G_MB_LIB.T6G(SCH_1):NC_PVDDCR_CPU1_P1_DNC6
   6 NC_PVDDCR_CPU1_P1_GL1_6    GL1 @T6G_MB_LIB.T6G(SCH_1):NC_PVDDCR_CPU1_P1_GL1_6
  41 NC_PVDDCR_CPU1_P1_GL2_6    GL2 @T6G_MB_LIB.T6G(SCH_1):NC_PVDDCR_CPU1_P1_GL2_6
7_9-20_24    GND  PGND2 @T6G_MB_LIB.T6G(SCH_1):GND

Q_CAP_C0402-2.2UF,10V,10%,X6S,CH5222KEB01  I22  PC139_C1P1_6
   1 PVDDCR_CPU1_P1_PVCC      A @T6G_MB_LIB.T6G(SCH_1):PVDDCR_CPU1_P1_PVCC
   2    GND      B @T6G_MB_LIB.T6G(SCH_1):GND

Q_CAP_C0402-2.2UF,10V,10%,X6S,CH5222KEB01  I27  PC421
   1 PVDDCR_CPU1_P1_VCC5      A @T6G_MB_LIB.T6G(SCH_1):PVDDCR_CPU1_P1_VCC5
   2    GND      B @T6G_MB_LIB.T6G(SCH_1):GND

Q_RES_0402LF-2.2,1%,1/16W,CHIP,CS-2202FB01  I28  PR271
   1 PVDDCR_CPU1_P1_PVCC      A @T6G_MB_LIB.T6G(SCH_1):PVDDCR_CPU1_P1_PVCC
   2 PVDDCR_CPU1_P1_VCC5      B @T6G_MB_LIB.T6G(SCH_1):PVDDCR_CPU1_P1_VCC5

Q_RES_0402LF-1.5,1%,1/8W,EMPTY,CS-1504FB00  I33  PR518
   1 SW_PVDDCR_CPU1_P1_SW6_RC      A @T6G_MB_LIB.T6G(SCH_1):SW_PVDDCR_CPU1_P1_SW6_RC
   2    GND      B @T6G_MB_LIB.T6G(SCH_1):GND

Q_CAP_C0402-560PF,50V,10%,EMPTY,CH1566K1B09  I34  PC208
   1 SW_PVDDCR_CPU1_P1_SW6      A @T6G_MB_LIB.T6G(SCH_1):SW_PVDDCR_CPU1_P1_SW6
   2 SW_PVDDCR_CPU1_P1_SW6_RC      B @T6G_MB_LIB.T6G(SCH_1):SW_PVDDCR_CPU1_P1_SW6_RC

Q_RES_0402LF-0,5%,1/16W,CHIP,CS00002JB13  I35  PR429
   1 PVDDCR_CPU1_P1_VOS6      A @T6G_MB_LIB.T6G(SCH_1):PVDDCR_CPU1_P1_VOS6
   2 PVDDCR_CPU1_P1      B @T6G_MB_LIB.T6G(SCH_1):PVDDCR_CPU1_P1

Q_INDUCTOR_SMLF-120NH/69A,IND,CV+12^0EZ03  I37  PL39
   2    GND      2 @T6G_MB_LIB.T6G(SCH_1):GND
   1 IND_CPU1_P1_CPL0      1 @T6G_MB_LIB.T6G(SCH_1):IND_CPU1_P1_CPL0

Q_CAP_0402-0.1UF,25V,10%,X7R,CH4104K1B00  I38  PC141_6
   1 SW_P12V_AUX_PVDDCR_CPU1_P1_FLT      A @T6G_MB_LIB.T6G(SCH_1):SW_P12V_AUX_PVDDCR_CPU1_P1_FLT
   2    GND      B @T6G_MB_LIB.T6G(SCH_1):GND

Q_CAP_C0805-22UF,16V,20%,X6S,CH6223MEA01  I41  PC144_6
   1 SW_P12V_AUX_PVDDCR_CPU1_P1_FLT      A @T6G_MB_LIB.T6G(SCH_1):SW_P12V_AUX_PVDDCR_CPU1_P1_FLT
   2    GND      B @T6G_MB_LIB.T6G(SCH_1):GND

Q_RES_0402LF-1.5,1%,1/8W,EMPTY,CS-1504FB00  I43  PR517
   1 SW_PVDDCR_CPU1_P1_SW5_RC      A @T6G_MB_LIB.T6G(SCH_1):SW_PVDDCR_CPU1_P1_SW5_RC
   2    GND      B @T6G_MB_LIB.T6G(SCH_1):GND

Q_CAP_C0805-22UF,16V,20%,X6S,CH6223MEA01  I44  PC145_6
   1 SW_P12V_AUX_PVDDCR_CPU1_P1_FLT      A @T6G_MB_LIB.T6G(SCH_1):SW_P12V_AUX_PVDDCR_CPU1_P1_FLT
   2    GND      B @T6G_MB_LIB.T6G(SCH_1):GND

Q_CAP_0402-0.22UF,16V,10%,X7R,CH4223K1B00  I45  PC146
   1 SW_PVDDCR_CPU1_P1_BOOT6_R      A @T6G_MB_LIB.T6G(SCH_1):SW_PVDDCR_CPU1_P1_BOOT6_R
   2 SW_PVDDCR_CPU1_P1_BOOTR6      B @T6G_MB_LIB.T6G(SCH_1):SW_PVDDCR_CPU1_P1_BOOTR6

Q_CAP_C0805-22UF,16V,20%,X6S,CH6223MEA01  I47  PC147_6
   1 SW_P12V_AUX_PVDDCR_CPU1_P1_FLT      A @T6G_MB_LIB.T6G(SCH_1):SW_P12V_AUX_PVDDCR_CPU1_P1_FLT
   2    GND      B @T6G_MB_LIB.T6G(SCH_1):GND

Q_RES_0402LF-0,5%,1/16W,CHIP,CS00002JB13  I49  PR273
   1 PVDDCR_CPU1_P1_VOS5      A @T6G_MB_LIB.T6G(SCH_1):PVDDCR_CPU1_P1_VOS5
   2 PVDDCR_CPU1_P1      B @T6G_MB_LIB.T6G(SCH_1):PVDDCR_CPU1_P1

Q_INDUCTOR4P_14-150NH,SMLF,IND,CV+15^0TZ04  I50  PL69
   2 IND_CPU1_P1_CPL0      2 @T6G_MB_LIB.T6G(SCH_1):IND_CPU1_P1_CPL0
   3 IND_CPU1_P1_CPL6      3 @T6G_MB_LIB.T6G(SCH_1):IND_CPU1_P1_CPL6
   4 PVDDCR_CPU1_P1      4 @T6G_MB_LIB.T6G(SCH_1):PVDDCR_CPU1_P1
   1 SW_PVDDCR_CPU1_P1_SW6      1 @T6G_MB_LIB.T6G(SCH_1):SW_PVDDCR_CPU1_P1_SW6

Q_RES_0402LF-5.6,1%,1/16W,CHIP,CS-5602FB01  I52  PR272
   1 SW_PVDDCR_CPU1_P1_BOOT5      A @T6G_MB_LIB.T6G(SCH_1):SW_PVDDCR_CPU1_P1_BOOT5
   2 SW_PVDDCR_CPU1_P1_BOOT5_R      B @T6G_MB_LIB.T6G(SCH_1):SW_PVDDCR_CPU1_P1_BOOT5_R

Q_CAP_C0402-560PF,50V,10%,EMPTY,CH1566K1B09  I53  PC207
   1 SW_PVDDCR_CPU1_P1_SW5      A @T6G_MB_LIB.T6G(SCH_1):SW_PVDDCR_CPU1_P1_SW5
   2 SW_PVDDCR_CPU1_P1_SW5_RC      B @T6G_MB_LIB.T6G(SCH_1):SW_PVDDCR_CPU1_P1_SW5_RC

Q_CAP_0402-0.1UF,25V,10%,X7R,CH4104K1B00  I54  PC425_5
   1 SW_P12V_AUX_PVDDCR_CPU1_P1_FLT      A @T6G_MB_LIB.T6G(SCH_1):SW_P12V_AUX_PVDDCR_CPU1_P1_FLT
   2    GND      B @T6G_MB_LIB.T6G(SCH_1):GND

Q_CAP_C0402-1UF,25V,10%,X6S,CH5104KEB02  I55  PC424_5
   1 SW_P12V_AUX_PVDDCR_CPU1_P1_FLT      A @T6G_MB_LIB.T6G(SCH_1):SW_P12V_AUX_PVDDCR_CPU1_P1_FLT
   2    GND      B @T6G_MB_LIB.T6G(SCH_1):GND

Q_CAP_C0805-22UF,16V,20%,X6S,CH6223MEA01  I56  PC426_5
   1 SW_P12V_AUX_PVDDCR_CPU1_P1_FLT      A @T6G_MB_LIB.T6G(SCH_1):SW_P12V_AUX_PVDDCR_CPU1_P1_FLT
   2    GND      B @T6G_MB_LIB.T6G(SCH_1):GND

Q_CAP_0402-0.22UF,16V,10%,X7R,CH4223K1B00  I57  PC428
   1 SW_PVDDCR_CPU1_P1_BOOT5_R      A @T6G_MB_LIB.T6G(SCH_1):SW_PVDDCR_CPU1_P1_BOOT5_R
   2 SW_PVDDCR_CPU1_P1_BOOTR5      B @T6G_MB_LIB.T6G(SCH_1):SW_PVDDCR_CPU1_P1_BOOTR5

Q_CAP_C0805-22UF,16V,20%,X6S,CH6223MEA01  I61  PC429_5
   1 SW_P12V_AUX_PVDDCR_CPU1_P1_FLT      A @T6G_MB_LIB.T6G(SCH_1):SW_P12V_AUX_PVDDCR_CPU1_P1_FLT
   2    GND      B @T6G_MB_LIB.T6G(SCH_1):GND

Q_INDUCTOR4P_14-150NH,SMLF,IND,CV+15^0TZ04  I63  PL45
   2 IND_CPU1_P1_CPL6      2 @T6G_MB_LIB.T6G(SCH_1):IND_CPU1_P1_CPL6
   3 IND_CPU1_P1_CPL5      3 @T6G_MB_LIB.T6G(SCH_1):IND_CPU1_P1_CPL5
   4 PVDDCR_CPU1_P1      4 @T6G_MB_LIB.T6G(SCH_1):PVDDCR_CPU1_P1
   1 SW_PVDDCR_CPU1_P1_SW5      1 @T6G_MB_LIB.T6G(SCH_1):SW_PVDDCR_CPU1_P1_SW5

Q_CAP_C0805-22UF,4V,20%,X6S,CH622KMEA03  I65  PC148_6
   1 PVDDCR_CPU1_P1      A @T6G_MB_LIB.T6G(SCH_1):PVDDCR_CPU1_P1
   2    GND      B @T6G_MB_LIB.T6G(SCH_1):GND

Q_CAP_C0805-22UF,4V,20%,X6S,CH622KMEA03  I67  PC149_6
   1 PVDDCR_CPU1_P1      A @T6G_MB_LIB.T6G(SCH_1):PVDDCR_CPU1_P1
   2    GND      B @T6G_MB_LIB.T6G(SCH_1):GND

Q_CAP_C0805-22UF,4V,20%,X6S,CH622KMEA03  I70  PC430_5
   1 PVDDCR_CPU1_P1      A @T6G_MB_LIB.T6G(SCH_1):PVDDCR_CPU1_P1
   2    GND      B @T6G_MB_LIB.T6G(SCH_1):GND

Q_CAP_C0805-22UF,4V,20%,X6S,CH622KMEA03  I71  PC431_5
   1 PVDDCR_CPU1_P1      A @T6G_MB_LIB.T6G(SCH_1):PVDDCR_CPU1_P1
   2    GND      B @T6G_MB_LIB.T6G(SCH_1):GND

ISL99390FRZTR5935-ISL99390FRZ-TR5935,SMLF,IC,AL099A  I73  PU38
  34 PVDDCR_CPU1_P1_PWM5    PWM @T6G_MB_LIB.T6G(SCH_1):PVDDCR_CPU1_P1_PWM5
  39 PVDDCR_CPU1_P1_VCCS  REFIN @T6G_MB_LIB.T6G(SCH_1):PVDDCR_CPU1_P1_VCCS
   3 PVDDCR_CPU1_P1_VCC5    VCC @T6G_MB_LIB.T6G(SCH_1):PVDDCR_CPU1_P1_VCC5
   2    GND   AGND @T6G_MB_LIB.T6G(SCH_1):GND
  33 SW_PVDDCR_CPU1_P1_BOOT5   BOOT @T6G_MB_LIB.T6G(SCH_1):SW_PVDDCR_CPU1_P1_BOOT5
25_29 SW_P12V_AUX_PVDDCR_CPU1_P1_FLT   VIN1 @T6G_MB_LIB.T6G(SCH_1):SW_P12V_AUX_PVDDCR_CPU1_P1_FLT
  32 SW_PVDDCR_CPU1_P1_BOOTR5  PHASE @T6G_MB_LIB.T6G(SCH_1):SW_PVDDCR_CPU1_P1_BOOTR5
   4 PVDDCR_CPU1_P1_PVCC   PVCC @T6G_MB_LIB.T6G(SCH_1):PVDDCR_CPU1_P1_PVCC
  36 PVDDCR_CPU1_P1_TEMP0 TOUT_FLT @T6G_MB_LIB.T6G(SCH_1):PVDDCR_CPU1_P1_TEMP0
  38 PVDDCR_CPU1_P1_IMON5   IOUT @T6G_MB_LIB.T6G(SCH_1):PVDDCR_CPU1_P1_IMON5
  37 PVDDCR_CPU1_P1_LSET5   LSET @T6G_MB_LIB.T6G(SCH_1):PVDDCR_CPU1_P1_LSET5
10_19 SW_PVDDCR_CPU1_P1_SW5     SW @T6G_MB_LIB.T6G(SCH_1):SW_PVDDCR_CPU1_P1_SW5
   5    GND  PGND1 @T6G_MB_LIB.T6G(SCH_1):GND
  30 SW_P12V_AUX_PVDDCR_CPU1_P1_FLT   VIN2 @T6G_MB_LIB.T6G(SCH_1):SW_P12V_AUX_PVDDCR_CPU1_P1_FLT
   1 PVDDCR_CPU1_P1_VOS5    VOS @T6G_MB_LIB.T6G(SCH_1):PVDDCR_CPU1_P1_VOS5
  40    GND  PGND3 @T6G_MB_LIB.T6G(SCH_1):GND
  35 PVDDCR_CPU1_P1_VCC5     EN @T6G_MB_LIB.T6G(SCH_1):PVDDCR_CPU1_P1_VCC5
  31 NC_PVDDCR_CPU1_P1_DNC5    DNC @T6G_MB_LIB.T6G(SCH_1):NC_PVDDCR_CPU1_P1_DNC5
   6 NC_PVDDCR_CPU1_P1_GL1_5    GL1 @T6G_MB_LIB.T6G(SCH_1):NC_PVDDCR_CPU1_P1_GL1_5
  41 NC_PVDDCR_CPU1_P1_GL2_5    GL2 @T6G_MB_LIB.T6G(SCH_1):NC_PVDDCR_CPU1_P1_GL2_5
7_9-20_24    GND  PGND2 @T6G_MB_LIB.T6G(SCH_1):GND


DRAWING: @T6G_MB_LIB.T6G(SCH_1):PAGE198 

Q_CAP_0402-0.1UF,25V,10%,X7R,CH4104K1B00  I2  PC621_10
   1 PVDDCR_CPU1_P1_VCCS      A @T6G_MB_LIB.T6G(SCH_1):PVDDCR_CPU1_P1_VCCS
   2    GND      B @T6G_MB_LIB.T6G(SCH_1):GND

ISL99390FRZTR5935-ISL99390FRZ-TR5935,SMLF,IC,AL099A  I15  PU53
  34 PVDDIO_P1_PWM4    PWM @T6G_MB_LIB.T6G(SCH_1):PVDDIO_P1_PWM4
  39 PVDDCR_CPU1_P1_VCCS  REFIN @T6G_MB_LIB.T6G(SCH_1):PVDDCR_CPU1_P1_VCCS
   3 PVDDIO_P1_VCC4    VCC @T6G_MB_LIB.T6G(SCH_1):PVDDIO_P1_VCC4
   2    GND   AGND @T6G_MB_LIB.T6G(SCH_1):GND
  33 SW_PVDDIO_P1_BOOT4   BOOT @T6G_MB_LIB.T6G(SCH_1):SW_PVDDIO_P1_BOOT4
25_29 SW_P12V_AUX_PVDDIO_P1_FLT   VIN1 @T6G_MB_LIB.T6G(SCH_1):SW_P12V_AUX_PVDDIO_P1_FLT
  32 SW_PVDDIO_P1_BOOTR4  PHASE @T6G_MB_LIB.T6G(SCH_1):SW_PVDDIO_P1_BOOTR4
   4 PVDDCR_CPU1_P1_PVCC   PVCC @T6G_MB_LIB.T6G(SCH_1):PVDDCR_CPU1_P1_PVCC
  36 PVDDIO_P1_TEMP1 TOUT_FLT @T6G_MB_LIB.T6G(SCH_1):PVDDIO_P1_TEMP1
  38 PVDDIO_P1_IMON4   IOUT @T6G_MB_LIB.T6G(SCH_1):PVDDIO_P1_IMON4
  37 PVDDIO_P1_LSET4   LSET @T6G_MB_LIB.T6G(SCH_1):PVDDIO_P1_LSET4
10_19 SW_PVDDIO_P1_SW4     SW @T6G_MB_LIB.T6G(SCH_1):SW_PVDDIO_P1_SW4
   5    GND  PGND1 @T6G_MB_LIB.T6G(SCH_1):GND
  30 SW_P12V_AUX_PVDDIO_P1_FLT   VIN2 @T6G_MB_LIB.T6G(SCH_1):SW_P12V_AUX_PVDDIO_P1_FLT
   1 PVDDIO_P1_VOS4    VOS @T6G_MB_LIB.T6G(SCH_1):PVDDIO_P1_VOS4
  40    GND  PGND3 @T6G_MB_LIB.T6G(SCH_1):GND
  35 PVDDIO_P1_VCC4     EN @T6G_MB_LIB.T6G(SCH_1):PVDDIO_P1_VCC4
  31 NC_PVDDIO_P1_DNC4    DNC @T6G_MB_LIB.T6G(SCH_1):NC_PVDDIO_P1_DNC4
   6 NC_PVDDIO_P1_GL1_4    GL1 @T6G_MB_LIB.T6G(SCH_1):NC_PVDDIO_P1_GL1_4
  41 NC_PVDDIO_P1_GL2_4    GL2 @T6G_MB_LIB.T6G(SCH_1):NC_PVDDIO_P1_GL2_4
7_9-20_24    GND  PGND2 @T6G_MB_LIB.T6G(SCH_1):GND

Q_CAP_C0402-2.2UF,10V,10%,X6S,CH5222KEB01  I28  PC617
   1 PVDDIO_P1_VCC3      A @T6G_MB_LIB.T6G(SCH_1):PVDDIO_P1_VCC3
   2    GND      B @T6G_MB_LIB.T6G(SCH_1):GND

Q_CAP_0402-0.22UF,16V,10%,X7R,CH4223K1B00  I44  PC630
   1 SW_PVDDIO_P1_BOOT4_R      A @T6G_MB_LIB.T6G(SCH_1):SW_PVDDIO_P1_BOOT4_R
   2 SW_PVDDIO_P1_BOOTR4      B @T6G_MB_LIB.T6G(SCH_1):SW_PVDDIO_P1_BOOTR4

Q_CAP_C0805-22UF,16V,20%,X6S,CH6223MEA01  I46  PC629_4
   1 SW_P12V_AUX_PVDDIO_P1_FLT      A @T6G_MB_LIB.T6G(SCH_1):SW_P12V_AUX_PVDDIO_P1_FLT
   2    GND      B @T6G_MB_LIB.T6G(SCH_1):GND

Q_CAP_C0805-22UF,4V,20%,X6S,CH622KMEA03  I51  PC634_4
   1 PVDDIO_P1      A @T6G_MB_LIB.T6G(SCH_1):PVDDIO_P1
   2    GND      B @T6G_MB_LIB.T6G(SCH_1):GND

Q_RES_0402LF-0,5%,1/16W,CHIP,CS00002JB13  I55  PR374
   1 PVDDIO_P1_VOS3      A @T6G_MB_LIB.T6G(SCH_1):PVDDIO_P1_VOS3
   2 PVDDIO_P1      B @T6G_MB_LIB.T6G(SCH_1):PVDDIO_P1

Q_RES_0402LF-1.5,1%,1/8W,EMPTY,CS-1504FB00  I57  PR492
   1 SW_PVDDIO_P1_SW3_RC      A @T6G_MB_LIB.T6G(SCH_1):SW_PVDDIO_P1_SW3_RC
   2    GND      B @T6G_MB_LIB.T6G(SCH_1):GND

Q_CAP_C0805-22UF,16V,20%,X6S,CH6223MEA01  I65  PC632_3
   1 SW_P12V_AUX_PVDDIO_P1_FLT      A @T6G_MB_LIB.T6G(SCH_1):SW_P12V_AUX_PVDDIO_P1_FLT
   2    GND      B @T6G_MB_LIB.T6G(SCH_1):GND

Q_CAP_C0805-22UF,4V,20%,X6S,CH622KMEA03  I68  PC635_3
   1 PVDDIO_P1      A @T6G_MB_LIB.T6G(SCH_1):PVDDIO_P1
   2    GND      B @T6G_MB_LIB.T6G(SCH_1):GND

Q_RES_0402LF-8.87K,1%,1/16W,EMPTY,CS28872FB01  I4  PR368
   1 PVDDIO_P1_LSET4      A @T6G_MB_LIB.T6G(SCH_1):PVDDIO_P1_LSET4
   2    GND      B @T6G_MB_LIB.T6G(SCH_1):GND

Q_CAP_C0402-2.2UF,10V,10%,X6S,CH5222KEB01  I10  PC616
   1 PVDDIO_P1_VCC4      A @T6G_MB_LIB.T6G(SCH_1):PVDDIO_P1_VCC4
   2    GND      B @T6G_MB_LIB.T6G(SCH_1):GND

Q_RES_0402LF-2.2,1%,1/16W,CHIP,CS-2202FB01  I12  PR370
   1 PVDDCR_CPU1_P1_PVCC      A @T6G_MB_LIB.T6G(SCH_1):PVDDCR_CPU1_P1_PVCC
   2 PVDDIO_P1_VCC4      B @T6G_MB_LIB.T6G(SCH_1):PVDDIO_P1_VCC4

Q_CAP_C0402-2.2UF,10V,10%,X6S,CH5222KEB01  I13  PC618_IOP1_4
   1 PVDDCR_CPU1_P1_PVCC      A @T6G_MB_LIB.T6G(SCH_1):PVDDCR_CPU1_P1_PVCC
   2    GND      B @T6G_MB_LIB.T6G(SCH_1):GND

Q_RES_0402LF-5.6,1%,1/16W,CHIP,CS-5602FB01  I17  PR372
   1 SW_PVDDIO_P1_BOOT4      A @T6G_MB_LIB.T6G(SCH_1):SW_PVDDIO_P1_BOOT4
   2 SW_PVDDIO_P1_BOOT4_R      B @T6G_MB_LIB.T6G(SCH_1):SW_PVDDIO_P1_BOOT4_R

Q_CAP_0402-0.1UF,25V,10%,X7R,CH4104K1B00  I18  PC623_4
   1 SW_P12V_AUX_PVDDIO_P1_FLT      A @T6G_MB_LIB.T6G(SCH_1):SW_P12V_AUX_PVDDIO_P1_FLT
   2    GND      B @T6G_MB_LIB.T6G(SCH_1):GND

Q_CAP_0402-0.1UF,25V,10%,X7R,CH4104K1B00  I20  PC620_9
   1 PVDDCR_CPU1_P1_VCCS      A @T6G_MB_LIB.T6G(SCH_1):PVDDCR_CPU1_P1_VCCS
   2    GND      B @T6G_MB_LIB.T6G(SCH_1):GND

Q_RES_0402LF-8.87K,1%,1/16W,EMPTY,CS28872FB01  I22  PR369
   1 PVDDIO_P1_LSET3      A @T6G_MB_LIB.T6G(SCH_1):PVDDIO_P1_LSET3
   2    GND      B @T6G_MB_LIB.T6G(SCH_1):GND

Q_RES_0402LF-2.2,1%,1/16W,CHIP,CS-2202FB01  I29  PR371
   1 PVDDCR_CPU1_P1_PVCC      A @T6G_MB_LIB.T6G(SCH_1):PVDDCR_CPU1_P1_PVCC
   2 PVDDIO_P1_VCC3      B @T6G_MB_LIB.T6G(SCH_1):PVDDIO_P1_VCC3

Q_CAP_C0402-2.2UF,10V,10%,X6S,CH5222KEB01  I31  PC619_IOP1_3
   1 PVDDCR_CPU1_P1_PVCC      A @T6G_MB_LIB.T6G(SCH_1):PVDDCR_CPU1_P1_PVCC
   2    GND      B @T6G_MB_LIB.T6G(SCH_1):GND

Q_RES_0402LF-5.6,1%,1/16W,CHIP,CS-5602FB01  I34  PR373
   1 SW_PVDDIO_P1_BOOT3      A @T6G_MB_LIB.T6G(SCH_1):SW_PVDDIO_P1_BOOT3
   2 SW_PVDDIO_P1_BOOT3_R      B @T6G_MB_LIB.T6G(SCH_1):SW_PVDDIO_P1_BOOT3_R

Q_CAP_0402-0.1UF,25V,10%,X7R,CH4104K1B00  I35  PC622_3
   1 SW_P12V_AUX_PVDDIO_P1_FLT      A @T6G_MB_LIB.T6G(SCH_1):SW_P12V_AUX_PVDDIO_P1_FLT
   2    GND      B @T6G_MB_LIB.T6G(SCH_1):GND

Q_CAP_C0402-1UF,25V,10%,X6S,CH5104KEB02  I36  PC624_3
   1 SW_P12V_AUX_PVDDIO_P1_FLT      A @T6G_MB_LIB.T6G(SCH_1):SW_P12V_AUX_PVDDIO_P1_FLT
   2    GND      B @T6G_MB_LIB.T6G(SCH_1):GND

Q_CAP_C0402-560PF,50V,10%,EMPTY,CH1566K1B09  I37  PC176
   1 SW_PVDDIO_P1_SW4      A @T6G_MB_LIB.T6G(SCH_1):SW_PVDDIO_P1_SW4
   2 SW_PVDDIO_P1_SW4_RC      B @T6G_MB_LIB.T6G(SCH_1):SW_PVDDIO_P1_SW4_RC

Q_RES_0402LF-1.5,1%,1/8W,EMPTY,CS-1504FB00  I39  PR491
   1 SW_PVDDIO_P1_SW4_RC      A @T6G_MB_LIB.T6G(SCH_1):SW_PVDDIO_P1_SW4_RC
   2    GND      B @T6G_MB_LIB.T6G(SCH_1):GND

Q_RES_0402LF-0,5%,1/16W,CHIP,CS00002JB13  I41  PR375
   1 PVDDIO_P1_VOS4      A @T6G_MB_LIB.T6G(SCH_1):PVDDIO_P1_VOS4
   2 PVDDIO_P1      B @T6G_MB_LIB.T6G(SCH_1):PVDDIO_P1

Q_INDUCTOR4P_14-150NH,SMLF,IND,CV+15^0TZ04  I42  PL67
   2 IND_PVDDIO_P1_CPL0      2 @T6G_MB_LIB.T6G(SCH_1):IND_PVDDIO_P1_CPL0
   3 IND_PVDDIO_P1_CPL4      3 @T6G_MB_LIB.T6G(SCH_1):IND_PVDDIO_P1_CPL4
   4 PVDDIO_P1      4 @T6G_MB_LIB.T6G(SCH_1):PVDDIO_P1
   1 SW_PVDDIO_P1_SW4      1 @T6G_MB_LIB.T6G(SCH_1):SW_PVDDIO_P1_SW4

Q_INDUCTOR_SMLF-0.22UH/33A,IND,CV+22Y0EZ00  I43  PL46
   2    GND      2 @T6G_MB_LIB.T6G(SCH_1):GND
   1 IND_PVDDIO_P1_CPL0      1 @T6G_MB_LIB.T6G(SCH_1):IND_PVDDIO_P1_CPL0

Q_CAP_C0402-1UF,25V,10%,X6S,CH5104KEB02  I45  PC625_4
   1 SW_P12V_AUX_PVDDIO_P1_FLT      A @T6G_MB_LIB.T6G(SCH_1):SW_P12V_AUX_PVDDIO_P1_FLT
   2    GND      B @T6G_MB_LIB.T6G(SCH_1):GND

Q_CAP_C0805-22UF,16V,20%,X6S,CH6223MEA01  I48  PC633_4
   1 SW_P12V_AUX_PVDDIO_P1_FLT      A @T6G_MB_LIB.T6G(SCH_1):SW_P12V_AUX_PVDDIO_P1_FLT
   2    GND      B @T6G_MB_LIB.T6G(SCH_1):GND

Q_CAP_C0805-22UF,4V,20%,X6S,CH622KMEA03  I53  PC636_4
   1 PVDDIO_P1      A @T6G_MB_LIB.T6G(SCH_1):PVDDIO_P1
   2    GND      B @T6G_MB_LIB.T6G(SCH_1):GND

Q_CAP_C0402-560PF,50V,10%,EMPTY,CH1566K1B09  I58  PC177
   1 SW_PVDDIO_P1_SW3      A @T6G_MB_LIB.T6G(SCH_1):SW_PVDDIO_P1_SW3
   2 SW_PVDDIO_P1_SW3_RC      B @T6G_MB_LIB.T6G(SCH_1):SW_PVDDIO_P1_SW3_RC

Q_CAP_C0805-22UF,16V,20%,X6S,CH6223MEA01  I60  PC626_3
   1 SW_P12V_AUX_PVDDIO_P1_FLT      A @T6G_MB_LIB.T6G(SCH_1):SW_P12V_AUX_PVDDIO_P1_FLT
   2    GND      B @T6G_MB_LIB.T6G(SCH_1):GND

Q_CAP_C0805-22UF,16V,20%,X6S,CH6223MEA01  I61  PC628_3
   1 SW_P12V_AUX_PVDDIO_P1_FLT      A @T6G_MB_LIB.T6G(SCH_1):SW_P12V_AUX_PVDDIO_P1_FLT
   2    GND      B @T6G_MB_LIB.T6G(SCH_1):GND

Q_INDUCTOR4P_14-150NH,SMLF,IND,CV+15^0TZ04  I62  PL68
   2 IND_PVDDIO_P1_CPL4      2 @T6G_MB_LIB.T6G(SCH_1):IND_PVDDIO_P1_CPL4
   3 IND_PVDDIO_P1_CPL3      3 @T6G_MB_LIB.T6G(SCH_1):IND_PVDDIO_P1_CPL3
   4 PVDDIO_P1      4 @T6G_MB_LIB.T6G(SCH_1):PVDDIO_P1
   1 SW_PVDDIO_P1_SW3      1 @T6G_MB_LIB.T6G(SCH_1):SW_PVDDIO_P1_SW3

Q_CAP_0402-0.22UF,16V,10%,X7R,CH4223K1B00  I63  PC631
   1 SW_PVDDIO_P1_BOOT3_R      A @T6G_MB_LIB.T6G(SCH_1):SW_PVDDIO_P1_BOOT3_R
   2 SW_PVDDIO_P1_BOOTR3      B @T6G_MB_LIB.T6G(SCH_1):SW_PVDDIO_P1_BOOTR3

Q_CAP_C0805-22UF,4V,20%,X6S,CH622KMEA03  I70  PC637_3
   1 PVDDIO_P1      A @T6G_MB_LIB.T6G(SCH_1):PVDDIO_P1
   2    GND      B @T6G_MB_LIB.T6G(SCH_1):GND

Q_CAP_C0805-22UF,16V,20%,X6S,CH6223MEA01  I72  PC627_4
   1 SW_P12V_AUX_PVDDIO_P1_FLT      A @T6G_MB_LIB.T6G(SCH_1):SW_P12V_AUX_PVDDIO_P1_FLT
   2    GND      B @T6G_MB_LIB.T6G(SCH_1):GND

ISL99390FRZTR5935-ISL99390FRZ-TR5935,SMLF,IC,AL099A  I73  PU52
  34 PVDDIO_P1_PWM3    PWM @T6G_MB_LIB.T6G(SCH_1):PVDDIO_P1_PWM3
  39 PVDDCR_CPU1_P1_VCCS  REFIN @T6G_MB_LIB.T6G(SCH_1):PVDDCR_CPU1_P1_VCCS
   3 PVDDIO_P1_VCC3    VCC @T6G_MB_LIB.T6G(SCH_1):PVDDIO_P1_VCC3
   2    GND   AGND @T6G_MB_LIB.T6G(SCH_1):GND
  33 SW_PVDDIO_P1_BOOT3   BOOT @T6G_MB_LIB.T6G(SCH_1):SW_PVDDIO_P1_BOOT3
25_29 SW_P12V_AUX_PVDDIO_P1_FLT   VIN1 @T6G_MB_LIB.T6G(SCH_1):SW_P12V_AUX_PVDDIO_P1_FLT
  32 SW_PVDDIO_P1_BOOTR3  PHASE @T6G_MB_LIB.T6G(SCH_1):SW_PVDDIO_P1_BOOTR3
   4 PVDDCR_CPU1_P1_PVCC   PVCC @T6G_MB_LIB.T6G(SCH_1):PVDDCR_CPU1_P1_PVCC
  36 PVDDIO_P1_TEMP1 TOUT_FLT @T6G_MB_LIB.T6G(SCH_1):PVDDIO_P1_TEMP1
  38 PVDDIO_P1_IMON3   IOUT @T6G_MB_LIB.T6G(SCH_1):PVDDIO_P1_IMON3
  37 PVDDIO_P1_LSET3   LSET @T6G_MB_LIB.T6G(SCH_1):PVDDIO_P1_LSET3
10_19 SW_PVDDIO_P1_SW3     SW @T6G_MB_LIB.T6G(SCH_1):SW_PVDDIO_P1_SW3
   5    GND  PGND1 @T6G_MB_LIB.T6G(SCH_1):GND
  30 SW_P12V_AUX_PVDDIO_P1_FLT   VIN2 @T6G_MB_LIB.T6G(SCH_1):SW_P12V_AUX_PVDDIO_P1_FLT
   1 PVDDIO_P1_VOS3    VOS @T6G_MB_LIB.T6G(SCH_1):PVDDIO_P1_VOS3
  40    GND  PGND3 @T6G_MB_LIB.T6G(SCH_1):GND
  35 PVDDIO_P1_VCC3     EN @T6G_MB_LIB.T6G(SCH_1):PVDDIO_P1_VCC3
  31 NC_PVDDIO_P1_DNC3    DNC @T6G_MB_LIB.T6G(SCH_1):NC_PVDDIO_P1_DNC3
   6 NC_PVDDIO_P1_GL1_3    GL1 @T6G_MB_LIB.T6G(SCH_1):NC_PVDDIO_P1_GL1_3
  41 NC_PVDDIO_P1_GL2_3    GL2 @T6G_MB_LIB.T6G(SCH_1):NC_PVDDIO_P1_GL2_3
7_9-20_24    GND  PGND2 @T6G_MB_LIB.T6G(SCH_1):GND


DRAWING: @T6G_MB_LIB.T6G(SCH_1):PAGE245 

Q_RES_0402LF-86.6K,1%,1/16W,EMPTY,CS38662FB05  I2  R3118
   1 P3V3_AUX_EN      A @T6G_MB_LIB.T6G(SCH_1):P3V3_AUX_EN
   2    GND      B @T6G_MB_LIB.T6G(SCH_1):GND

Q_RES_0402LF-510K,5%,1/16W,EMPTY,CS45102JB03  I4  R3117
   1 P12V_AUX      A @T6G_MB_LIB.T6G(SCH_1):P12V_AUX
   2 P3V3_AUX_EN      B @T6G_MB_LIB.T6G(SCH_1):P3V3_AUX_EN

Q_CAP_0402-0.1UF,25V,10%,EMPTY,CH4104K1B00  I8  PC1870
   1 P3V3_AUX_EN      A @T6G_MB_LIB.T6G(SCH_1):P3V3_AUX_EN
   2    GND      B @T6G_MB_LIB.T6G(SCH_1):GND

Q_RES_0402LF-0,5%,1/16W,CHIP,CS00002JB13  I11  R1571
   1 PWRGD_P5V_AUX      A @T6G_MB_LIB.T6G(SCH_1):PWRGD_P5V_AUX
   2 P3V3_AUX_EN      B @T6G_MB_LIB.T6G(SCH_1):P3V3_AUX_EN

Q_RES_0402LF-1.5K,1%,1/16W,EMPTY,CS21502FB07  I15  PR833
   1 P3V3_AUX_SS      A @T6G_MB_LIB.T6G(SCH_1):P3V3_AUX_SS
   2    GND      B @T6G_MB_LIB.T6G(SCH_1):GND

Q_RES_0402LF-21.5K,1%,1/16W,CHIP,CS32152FB04  I17  PR834
   1 P3V3_AUX_ILIM      A @T6G_MB_LIB.T6G(SCH_1):P3V3_AUX_ILIM
   2    GND      B @T6G_MB_LIB.T6G(SCH_1):GND

Q_RES_0402LF-1,1%,1/16W,CHIP,CS-1002FB04  I20  PR8389
   1 P3V3_AUX_VDRV      A @T6G_MB_LIB.T6G(SCH_1):P3V3_AUX_VDRV
   2 P3V3_AUX_VCC      B @T6G_MB_LIB.T6G(SCH_1):P3V3_AUX_VCC

NCP3284AMNTXG-NCP3284AMNTXG,SMLF,IC,AL003284002  I21  PU9
  34 NC_PU9_2    NC2 @T6G_MB_LIB.T6G(SCH_1):NC_PU9_2
  36 P3V3_AUX_MODE MODE||FSET @T6G_MB_LIB.T6G(SCH_1):P3V3_AUX_MODE
   3 P12V_AUX    VIN @T6G_MB_LIB.T6G(SCH_1):P12V_AUX
  30 P3V3_AUX_FB     FB @T6G_MB_LIB.T6G(SCH_1):P3V3_AUX_FB
  26 SW_P3V3_AUX_BOOT   BOOT @T6G_MB_LIB.T6G(SCH_1):SW_P3V3_AUX_BOOT
   1 P3V3_AUX_ILIM   ILIM @T6G_MB_LIB.T6G(SCH_1):P3V3_AUX_ILIM
  25 SW_P3V3_AUX_BOOTR  PHASE @T6G_MB_LIB.T6G(SCH_1):SW_P3V3_AUX_BOOTR
   4 P3V3_AUX_VCC    VCC @T6G_MB_LIB.T6G(SCH_1):P3V3_AUX_VCC
  31    GND  VSNS- @T6G_MB_LIB.T6G(SCH_1):GND
  35 NC_HICCUP HICCUP# @T6G_MB_LIB.T6G(SCH_1):NC_HICCUP
7_10-19    GND   PGND @T6G_MB_LIB.T6G(SCH_1):GND
  33 NC_PU9_1    NC1 @T6G_MB_LIB.T6G(SCH_1):NC_PU9_1
11_18 SW_P3V3_AUX_SW     SW @T6G_MB_LIB.T6G(SCH_1):SW_P3V3_AUX_SW
20_24 SW_P3V3_AUX_FLT   PVIN @T6G_MB_LIB.T6G(SCH_1):SW_P3V3_AUX_FLT
   2 PWRGD_P3V3_AUX_R1  PGOOD @T6G_MB_LIB.T6G(SCH_1):PWRGD_P3V3_AUX_R1
  28 P3V3_AUX_VOS    VOS @T6G_MB_LIB.T6G(SCH_1):P3V3_AUX_VOS
  32    GND   AGND @T6G_MB_LIB.T6G(SCH_1):GND
  27 P3V3_AUX_EN     EN @T6G_MB_LIB.T6G(SCH_1):P3V3_AUX_EN
   5 P3V3_AUX_VDRV   VDRV @T6G_MB_LIB.T6G(SCH_1):P3V3_AUX_VDRV
   6 NC_PU9_3    GL1 @T6G_MB_LIB.T6G(SCH_1):NC_PU9_3
  29 P3V3_AUX_SS     SS @T6G_MB_LIB.T6G(SCH_1):P3V3_AUX_SS
  37 NC_PU9_4    GL2 @T6G_MB_LIB.T6G(SCH_1):NC_PU9_4

Q_CAP_C0402-0.1UF,25V,10%,X6S,CH4104KEB00  I23  PC1649
   1 P12V_AUX      A @T6G_MB_LIB.T6G(SCH_1):P12V_AUX
   2    GND      B @T6G_MB_LIB.T6G(SCH_1):GND

Q_CAP_C0805-22UF,16V,20%,X6S,CH6223MEA01  I26  PC2260
   1 SW_P3V3_AUX_FLT      A @T6G_MB_LIB.T6G(SCH_1):SW_P3V3_AUX_FLT
   2    GND      B @T6G_MB_LIB.T6G(SCH_1):GND

Q_CAPP_THLF-270UF,16V,20%,OSCON,CC72703MD38  I29  PC3
   1 SW_P3V3_AUX_FLT      A @T6G_MB_LIB.T6G(SCH_1):SW_P3V3_AUX_FLT
   2    GND      B @T6G_MB_LIB.T6G(SCH_1):GND

Q_CAPP_THLF-270UF,16V,20%,OSCON,CC72703MD38  I30  PC566
   1 SW_P3V3_AUX_FLT      A @T6G_MB_LIB.T6G(SCH_1):SW_P3V3_AUX_FLT
   2    GND      B @T6G_MB_LIB.T6G(SCH_1):GND

Q_CAP_C0805-22UF,16V,20%,X6S,CH6223MEA01  I31  PC2262
   1 SW_P3V3_AUX_FLT      A @T6G_MB_LIB.T6G(SCH_1):SW_P3V3_AUX_FLT
   2    GND      B @T6G_MB_LIB.T6G(SCH_1):GND

Q_CAP_C0805-22UF,16V,20%,X6S,CH6223MEA01  I32  PC8567
   1 SW_P3V3_AUX_FLT      A @T6G_MB_LIB.T6G(SCH_1):SW_P3V3_AUX_FLT
   2    GND      B @T6G_MB_LIB.T6G(SCH_1):GND

Q_CAP_C0805-22UF,16V,20%,X6S,CH6223MEA01  I33  PC2263
   1 SW_P3V3_AUX_FLT      A @T6G_MB_LIB.T6G(SCH_1):SW_P3V3_AUX_FLT
   2    GND      B @T6G_MB_LIB.T6G(SCH_1):GND

Q_CAP_C0805-22UF,16V,20%,X6S,CH6223MEA01  I34  PC2342
   1 SW_P3V3_AUX_FLT      A @T6G_MB_LIB.T6G(SCH_1):SW_P3V3_AUX_FLT
   2    GND      B @T6G_MB_LIB.T6G(SCH_1):GND

Q_CAP_C0805-22UF,16V,20%,X6S,CH6223MEA01  I35  PC570
   1 SW_P3V3_AUX_FLT      A @T6G_MB_LIB.T6G(SCH_1):SW_P3V3_AUX_FLT
   2    GND      B @T6G_MB_LIB.T6G(SCH_1):GND

Q_CAP_C0805-22UF,16V,20%,X6S,CH6223MEA01  I36  PC571
   1 SW_P3V3_AUX_FLT      A @T6G_MB_LIB.T6G(SCH_1):SW_P3V3_AUX_FLT
   2    GND      B @T6G_MB_LIB.T6G(SCH_1):GND

Q_CAP_C0805-22UF,16V,20%,X6S,CH6223MEA01  I37  PC2343
   1 SW_P3V3_AUX_FLT      A @T6G_MB_LIB.T6G(SCH_1):SW_P3V3_AUX_FLT
   2    GND      B @T6G_MB_LIB.T6G(SCH_1):GND

Q_CAP_C0805-22UF,16V,20%,X6S,CH6223MEA01  I38  PC2344
   1 SW_P3V3_AUX_FLT      A @T6G_MB_LIB.T6G(SCH_1):SW_P3V3_AUX_FLT
   2    GND      B @T6G_MB_LIB.T6G(SCH_1):GND

Q_CAP_C0805-22UF,16V,20%,X6S,CH6223MEA01  I39  PC576
   1 SW_P3V3_AUX_FLT      A @T6G_MB_LIB.T6G(SCH_1):SW_P3V3_AUX_FLT
   2    GND      B @T6G_MB_LIB.T6G(SCH_1):GND

Q_CAP_C0805-22UF,16V,20%,X6S,CH6223MEA01  I40  PC8071
   1 SW_P3V3_AUX_FLT      A @T6G_MB_LIB.T6G(SCH_1):SW_P3V3_AUX_FLT
   2    GND      B @T6G_MB_LIB.T6G(SCH_1):GND

Q_CAP_0402-0.1UF,25V,10%,X7R,CH4104K1B00  I41  PC577
   1 SW_P3V3_AUX_FLT      A @T6G_MB_LIB.T6G(SCH_1):SW_P3V3_AUX_FLT
   2    GND      B @T6G_MB_LIB.T6G(SCH_1):GND

Q_CAP_C0402-0.22UF,25V,10%,X7R,CH4224K1B01  I48  PC568
   1 SW_P3V3_AUX_BOOTR      A @T6G_MB_LIB.T6G(SCH_1):SW_P3V3_AUX_BOOTR
   2 SW_P3V3_AUX_BOOT_R      B @T6G_MB_LIB.T6G(SCH_1):SW_P3V3_AUX_BOOT_R

Q_RES_0402LF-0,5%,1/16W,CHIP,CS00002JB13  I49  PR835
   1 SW_P3V3_AUX_BOOT      A @T6G_MB_LIB.T6G(SCH_1):SW_P3V3_AUX_BOOT
   2 SW_P3V3_AUX_BOOT_R      B @T6G_MB_LIB.T6G(SCH_1):SW_P3V3_AUX_BOOT_R

Q_RES_0402LF-15K,0.1%,1/16W,CHIP,CS31502BB03  I51  PR830
   1 P3V3_AUX_FB      A @T6G_MB_LIB.T6G(SCH_1):P3V3_AUX_FB
   2    GND      B @T6G_MB_LIB.T6G(SCH_1):GND

Q_CAP_0402-10PF,50V,1%,NPO,TMP_QCH0106F0B00  I53  PC569
   1 P3V3_AUX_FB      A @T6G_MB_LIB.T6G(SCH_1):P3V3_AUX_FB
   2 P3V3_AUX      B @T6G_MB_LIB.T6G(SCH_1):P3V3_AUX

Q_INDUCTOR_SMLF-1.5UH/53A,IND,CV-15^0MZ02  I55  PL8066
   2 P3V3_AUX      2 @T6G_MB_LIB.T6G(SCH_1):P3V3_AUX
   1 SW_P3V3_AUX_SW      1 @T6G_MB_LIB.T6G(SCH_1):SW_P3V3_AUX_SW

Q_CAPP_THLF-560UF,6.3V,20%,OSCON,CC75601MD16  I57  PC1866
   1 P3V3_AUX      A @T6G_MB_LIB.T6G(SCH_1):P3V3_AUX
   2    GND      B @T6G_MB_LIB.T6G(SCH_1):GND

Q_CAPP_THLF-560UF,6.3V,20%,OSCON,CC75601MD16  I58  PC1867
   1 P3V3_AUX      A @T6G_MB_LIB.T6G(SCH_1):P3V3_AUX
   2    GND      B @T6G_MB_LIB.T6G(SCH_1):GND

Q_CAP_C0805-22UF,10V,20%,X6S,CH6222MEA01  I59  PC1868
   1 P3V3_AUX      A @T6G_MB_LIB.T6G(SCH_1):P3V3_AUX
   2    GND      B @T6G_MB_LIB.T6G(SCH_1):GND

Q_CAP_C0805-22UF,10V,20%,X6S,CH6222MEA01  I62  PC1600
   1 P3V3_AUX      A @T6G_MB_LIB.T6G(SCH_1):P3V3_AUX
   2    GND      B @T6G_MB_LIB.T6G(SCH_1):GND

Q_CAP_0402-0.1UF,25V,10%,X7R,CH4104K1B00  I63  PC1869
   1 P3V3_AUX      A @T6G_MB_LIB.T6G(SCH_1):P3V3_AUX
   2    GND      B @T6G_MB_LIB.T6G(SCH_1):GND

Q_RES_0402LF-1K,1%,1/16W,CHIP,CS21002FB06  I65  PR8073
   1 P3V3_AUX      A @T6G_MB_LIB.T6G(SCH_1):P3V3_AUX
   2 PWRGD_P3V3_AUX_R1      B @T6G_MB_LIB.T6G(SCH_1):PWRGD_P3V3_AUX_R1

Q_RES_0402LF-0,5%,1/16W,CHIP,CS00002JB13  I10  PR832
   1 P3V3_AUX_MODE      A @T6G_MB_LIB.T6G(SCH_1):P3V3_AUX_MODE
   2    GND      B @T6G_MB_LIB.T6G(SCH_1):GND

Q_CAP_C0603-4.7UF,16V,10%,X6S,CH5473KE902  I12  PC581
   1 P3V3_AUX_VDRV      A @T6G_MB_LIB.T6G(SCH_1):P3V3_AUX_VDRV
   2    GND      B @T6G_MB_LIB.T6G(SCH_1):GND

Q_CAP_C0603-2.2UF,16V,10%,X6S,CH5223KE901  I19  PC591
   1 P3V3_AUX_VCC      A @T6G_MB_LIB.T6G(SCH_1):P3V3_AUX_VCC
   2    GND      B @T6G_MB_LIB.T6G(SCH_1):GND

Q_INDUCTOR_SMLF-100NH/16A,IND,CV+10G0MZ04  I24  PL8045
   2 SW_P3V3_AUX_FLT      2 @T6G_MB_LIB.T6G(SCH_1):SW_P3V3_AUX_FLT
   1 P12V_AUX      1 @T6G_MB_LIB.T6G(SCH_1):P12V_AUX

Q_CAP_C0805-22UF,16V,20%,X6S,CH6223MEA01  I27  PC2261
   1 SW_P3V3_AUX_FLT      A @T6G_MB_LIB.T6G(SCH_1):SW_P3V3_AUX_FLT
   2    GND      B @T6G_MB_LIB.T6G(SCH_1):GND

Q_CAP_0603-1UF,16V,10%,X7R,TMP_QCH5103K1900  I44  PC8008
   1 P12V_AUX      A @T6G_MB_LIB.T6G(SCH_1):P12V_AUX
   2    GND      B @T6G_MB_LIB.T6G(SCH_1):GND

Q_RES_0402LF-1K,1%,1/16W,CHIP,CS21002FB06  I46  PR836
   1 P3V3_AUX_VOS      A @T6G_MB_LIB.T6G(SCH_1):P3V3_AUX_VOS
   2 P3V3_AUX      B @T6G_MB_LIB.T6G(SCH_1):P3V3_AUX

Q_RES_0402LF-47K,0.1%,1/16W,CHIP,CS34702BB05  I54  PR831
   1 P3V3_AUX_FB      A @T6G_MB_LIB.T6G(SCH_1):P3V3_AUX_FB
   2 P3V3_AUX      B @T6G_MB_LIB.T6G(SCH_1):P3V3_AUX

Q_CAP_C0805-22UF,10V,20%,X6S,CH6222MEA01  I60  PC1599
   1 P3V3_AUX      A @T6G_MB_LIB.T6G(SCH_1):P3V3_AUX
   2    GND      B @T6G_MB_LIB.T6G(SCH_1):GND

Q_RES_0402LF-0,5%,1/16W,CHIP,CS00002JB13  I67  R6099
   1 PWRGD_P3V3_AUX_R1      A @T6G_MB_LIB.T6G(SCH_1):PWRGD_P3V3_AUX_R1
   2 PWRGD_P3V3_AUX      B @T6G_MB_LIB.T6G(SCH_1):PWRGD_P3V3_AUX

Q_CAP_0402-1000PF,50V,5%,EMPTY,TMP_QCH21006JB10  I68  C5015
   1 PWRGD_P3V3_AUX      A @T6G_MB_LIB.T6G(SCH_1):PWRGD_P3V3_AUX
   2    GND      B @T6G_MB_LIB.T6G(SCH_1):GND

Q_CAP_C0805-22UF,16V,20%,X6S,CH6223MEA01  I70  PC8013
   1 SW_P3V3_AUX_FLT      A @T6G_MB_LIB.T6G(SCH_1):SW_P3V3_AUX_FLT
   2    GND      B @T6G_MB_LIB.T6G(SCH_1):GND

Q_CAP_C0805-22UF,16V,20%,X6S,CH6223MEA01  I71  PC8014
   1 SW_P3V3_AUX_FLT      A @T6G_MB_LIB.T6G(SCH_1):SW_P3V3_AUX_FLT
   2    GND      B @T6G_MB_LIB.T6G(SCH_1):GND


DRAWING: @T6G_MB_LIB.T6G(SCH_1):PAGE301 

Q_CAP_0402-220PF,50V,10%,EMPTY,TMP_QCH12206KB14  I2  PC2183
   1 HSC_ON      A @T6G_MB_LIB.T6G(SCH_1):HSC_ON
   2 AGND_HSC      B @T6G_MB_LIB.T6G(SCH_1):AGND_HSC

Q_CAP_C0402-1UF,25V,10%,X6S,CH5104KEB02  I4  PC2181
   1 HSC_VDD_R_2      A @T6G_MB_LIB.T6G(SCH_1):HSC_VDD_R_2
   2 AGND_HSC      B @T6G_MB_LIB.T6G(SCH_1):AGND_HSC

Q_RES_0402LF-0,5%,1/16W,CHIP,CS00002JB13  I5  PR3911
   1 HSC_VDD_R_2      A @T6G_MB_LIB.T6G(SCH_1):HSC_VDD_R_2
   2 HSC_VDD      B @T6G_MB_LIB.T6G(SCH_1):HSC_VDD

Q_RES_0402LF-120K,1%,1/16W,CHIP,CS41202FB05  I11  PR3912
   1 AGND_HSC      A @T6G_MB_LIB.T6G(SCH_1):AGND_HSC
   2 HSC_MODE_2      B @T6G_MB_LIB.T6G(SCH_1):HSC_MODE_2

Q_CAP_0402-1NF,50V,10%,EMPTY,CH21006KB16  I12  PC2348
   1 HSC_OCREF      A @T6G_MB_LIB.T6G(SCH_1):HSC_OCREF
   2 AGND_HSC      B @T6G_MB_LIB.T6G(SCH_1):AGND_HSC

Q_RES_0402LF-2K,0.1%,1/16W,CHIP,CS22002BB07  I13  PR3915
   1 HSC_CS_2      A @T6G_MB_LIB.T6G(SCH_1):HSC_CS_2
   2 AGND_HSC      B @T6G_MB_LIB.T6G(SCH_1):AGND_HSC

Q_RES_0402LF-2K,0.1%,1/16W,CHIP,CS22002BB07  I15  PR1101
   1 HSC_IMON      A @T6G_MB_LIB.T6G(SCH_1):HSC_IMON
   2 AGND_HSC      B @T6G_MB_LIB.T6G(SCH_1):AGND_HSC

MP5991GLUZ-MP5991GLU-Z,SMLF,IC,AL005991A00  I16  PU288
   9 P12V_PSU   VIN1 @T6G_MB_LIB.T6G(SCH_1):P12V_PSU
  10 P12V_PSU   VIN2 @T6G_MB_LIB.T6G(SCH_1):P12V_PSU
  11 P12V_PSU   VIN3 @T6G_MB_LIB.T6G(SCH_1):P12V_PSU
  12 P12V_PSU   VIN4 @T6G_MB_LIB.T6G(SCH_1):P12V_PSU
  13 P12V_PSU   VIN5 @T6G_MB_LIB.T6G(SCH_1):P12V_PSU
   4 HSC_ON     ON @T6G_MB_LIB.T6G(SCH_1):HSC_ON
  24 HSC_OCREF  OCREF @T6G_MB_LIB.T6G(SCH_1):HSC_OCREF
  23 HSC_CS_2     CS @T6G_MB_LIB.T6G(SCH_1):HSC_CS_2
  22 HSC_IMON   IMON @T6G_MB_LIB.T6G(SCH_1):HSC_IMON
  21 HSC_VDD_R_2  VDD33 @T6G_MB_LIB.T6G(SCH_1):HSC_VDD_R_2
  20 AGND_HSC    GND @T6G_MB_LIB.T6G(SCH_1):AGND_HSC
  19 HSC_SS     SS @T6G_MB_LIB.T6G(SCH_1):HSC_SS
   5 HSC_FAULT    GOK @T6G_MB_LIB.T6G(SCH_1):HSC_FAULT
  18 HSC_VTEMP  VTEMP @T6G_MB_LIB.T6G(SCH_1):HSC_VTEMP
   1 P12V_AUX  VOUT1 @T6G_MB_LIB.T6G(SCH_1):P12V_AUX
   2 P12V_AUX  VOUT2 @T6G_MB_LIB.T6G(SCH_1):P12V_AUX
  25 P12V_AUX  VOUT3 @T6G_MB_LIB.T6G(SCH_1):P12V_AUX
  26 P12V_AUX  VOUT4 @T6G_MB_LIB.T6G(SCH_1):P12V_AUX
   3 HSC_D_OC_2   D_OC @T6G_MB_LIB.T6G(SCH_1):HSC_D_OC_2
  14 P12V_PSU   VIN6 @T6G_MB_LIB.T6G(SCH_1):P12V_PSU
  15 P12V_PSU   VIN7 @T6G_MB_LIB.T6G(SCH_1):P12V_PSU
  16 P12V_PSU   VIN8 @T6G_MB_LIB.T6G(SCH_1):P12V_PSU
  33 P12V_PSU   VIN9 @T6G_MB_LIB.T6G(SCH_1):P12V_PSU
  27 P12V_AUX  VOUT5 @T6G_MB_LIB.T6G(SCH_1):P12V_AUX
  28 P12V_AUX  VOUT6 @T6G_MB_LIB.T6G(SCH_1):P12V_AUX
  29 P12V_AUX  VOUT7 @T6G_MB_LIB.T6G(SCH_1):P12V_AUX
  30 P12V_AUX  VOUT8 @T6G_MB_LIB.T6G(SCH_1):P12V_AUX
  31 P12V_AUX  VOUT9 @T6G_MB_LIB.T6G(SCH_1):P12V_AUX
  32 P12V_AUX VOUT10 @T6G_MB_LIB.T6G(SCH_1):P12V_AUX
   8 HSC_MODE_2   MODE @T6G_MB_LIB.T6G(SCH_1):HSC_MODE_2
  17 HSC_SCREF_2 SCREF_OCWREF @T6G_MB_LIB.T6G(SCH_1):HSC_SCREF_2
   6 HSC_FLT_TYPE_2 FLT_TYPE @T6G_MB_LIB.T6G(SCH_1):HSC_FLT_TYPE_2
   7 HSC_NC1_2    NC1 @T6G_MB_LIB.T6G(SCH_1):HSC_NC1_2

Q_RES_0402LF-0,5%,1/16W,CHIP,CS00002JB13  I17  PR3917
   1 HSC_SCREF      A @T6G_MB_LIB.T6G(SCH_1):HSC_SCREF
   2 HSC_SCREF_2      B @T6G_MB_LIB.T6G(SCH_1):HSC_SCREF_2

Q_CAP_C0402-1UF,25V,10%,X6S,CH5104KEB02  I20  PC1525
   1 HSC_VDD_R_1      A @T6G_MB_LIB.T6G(SCH_1):HSC_VDD_R_1
   2 AGND_HSC      B @T6G_MB_LIB.T6G(SCH_1):AGND_HSC

Q_RES_0402LF-0,5%,1/16W,CHIP,CS00002JB13  I21  PR3910
   1 HSC_VDD_R_1      A @T6G_MB_LIB.T6G(SCH_1):HSC_VDD_R_1
   2 HSC_VDD      B @T6G_MB_LIB.T6G(SCH_1):HSC_VDD

Q_CAP_0402-220PF,50V,10%,X7R,TMP_QCH12206KB14  I24  PC2182
   1 HSC_ON      A @T6G_MB_LIB.T6G(SCH_1):HSC_ON
   2 AGND_HSC      B @T6G_MB_LIB.T6G(SCH_1):AGND_HSC

Q_RES_0402LF-120K,1%,1/16W,CHIP,CS41202FB05  I29  PR1134
   1 AGND_HSC      A @T6G_MB_LIB.T6G(SCH_1):AGND_HSC
   2 HSC_MODE_1      B @T6G_MB_LIB.T6G(SCH_1):HSC_MODE_1

Q_CAP_0402-1NF,50V,10%,EMPTY,CH21006KB16  I30  PC2347
   1 HSC_OCREF      A @T6G_MB_LIB.T6G(SCH_1):HSC_OCREF
   2 AGND_HSC      B @T6G_MB_LIB.T6G(SCH_1):AGND_HSC

Q_RES_0402LF-2K,0.1%,1/16W,CHIP,CS22002BB07  I31  PR3914
   1 HSC_CS_1      A @T6G_MB_LIB.T6G(SCH_1):HSC_CS_1
   2 AGND_HSC      B @T6G_MB_LIB.T6G(SCH_1):AGND_HSC

Q_RES_0402LF-0,5%,1/16W,CHIP,CS00002JB13  I33  PR3916
   1 HSC_SCREF      A @T6G_MB_LIB.T6G(SCH_1):HSC_SCREF
   2 HSC_SCREF_1      B @T6G_MB_LIB.T6G(SCH_1):HSC_SCREF_1

Q_RES_0402LF-2K,0.1%,1/16W,CHIP,CS22002BB07  I34  PR3918
   1 HSC_IMON      A @T6G_MB_LIB.T6G(SCH_1):HSC_IMON
   2 AGND_HSC      B @T6G_MB_LIB.T6G(SCH_1):AGND_HSC

MP5991GLUZ-MP5991GLU-Z,SMLF,IC,AL005991A00  I35  PU287
   9 P12V_PSU   VIN1 @T6G_MB_LIB.T6G(SCH_1):P12V_PSU
  10 P12V_PSU   VIN2 @T6G_MB_LIB.T6G(SCH_1):P12V_PSU
  11 P12V_PSU   VIN3 @T6G_MB_LIB.T6G(SCH_1):P12V_PSU
  12 P12V_PSU   VIN4 @T6G_MB_LIB.T6G(SCH_1):P12V_PSU
  13 P12V_PSU   VIN5 @T6G_MB_LIB.T6G(SCH_1):P12V_PSU
   4 HSC_ON     ON @T6G_MB_LIB.T6G(SCH_1):HSC_ON
  24 HSC_OCREF  OCREF @T6G_MB_LIB.T6G(SCH_1):HSC_OCREF
  23 HSC_CS_1     CS @T6G_MB_LIB.T6G(SCH_1):HSC_CS_1
  22 HSC_IMON   IMON @T6G_MB_LIB.T6G(SCH_1):HSC_IMON
  21 HSC_VDD_R_1  VDD33 @T6G_MB_LIB.T6G(SCH_1):HSC_VDD_R_1
  20 AGND_HSC    GND @T6G_MB_LIB.T6G(SCH_1):AGND_HSC
  19 HSC_SS     SS @T6G_MB_LIB.T6G(SCH_1):HSC_SS
   5 HSC_FAULT    GOK @T6G_MB_LIB.T6G(SCH_1):HSC_FAULT
  18 HSC_VTEMP  VTEMP @T6G_MB_LIB.T6G(SCH_1):HSC_VTEMP
   1 P12V_AUX  VOUT1 @T6G_MB_LIB.T6G(SCH_1):P12V_AUX
   2 P12V_AUX  VOUT2 @T6G_MB_LIB.T6G(SCH_1):P12V_AUX
  25 P12V_AUX  VOUT3 @T6G_MB_LIB.T6G(SCH_1):P12V_AUX
  26 P12V_AUX  VOUT4 @T6G_MB_LIB.T6G(SCH_1):P12V_AUX
   3 HSC_D_OC_1   D_OC @T6G_MB_LIB.T6G(SCH_1):HSC_D_OC_1
  14 P12V_PSU   VIN6 @T6G_MB_LIB.T6G(SCH_1):P12V_PSU
  15 P12V_PSU   VIN7 @T6G_MB_LIB.T6G(SCH_1):P12V_PSU
  16 P12V_PSU   VIN8 @T6G_MB_LIB.T6G(SCH_1):P12V_PSU
  33 P12V_PSU   VIN9 @T6G_MB_LIB.T6G(SCH_1):P12V_PSU
  27 P12V_AUX  VOUT5 @T6G_MB_LIB.T6G(SCH_1):P12V_AUX
  28 P12V_AUX  VOUT6 @T6G_MB_LIB.T6G(SCH_1):P12V_AUX
  29 P12V_AUX  VOUT7 @T6G_MB_LIB.T6G(SCH_1):P12V_AUX
  30 P12V_AUX  VOUT8 @T6G_MB_LIB.T6G(SCH_1):P12V_AUX
  31 P12V_AUX  VOUT9 @T6G_MB_LIB.T6G(SCH_1):P12V_AUX
  32 P12V_AUX VOUT10 @T6G_MB_LIB.T6G(SCH_1):P12V_AUX
   8 HSC_MODE_1   MODE @T6G_MB_LIB.T6G(SCH_1):HSC_MODE_1
  17 HSC_SCREF_1 SCREF_OCWREF @T6G_MB_LIB.T6G(SCH_1):HSC_SCREF_1
   6 HSC_FLT_TYPE_1 FLT_TYPE @T6G_MB_LIB.T6G(SCH_1):HSC_FLT_TYPE_1
   7 HSC_NC1_1    NC1 @T6G_MB_LIB.T6G(SCH_1):HSC_NC1_1

Q_CAP_0402-0.068UF,16V,10%,X7R,CH3683K1B09  I38  PC2185
   1 HSC_SS      A @T6G_MB_LIB.T6G(SCH_1):HSC_SS
   2 AGND_HSC      B @T6G_MB_LIB.T6G(SCH_1):AGND_HSC

Q_RES_0402LF-0,5%,1/16W,CHIP,CS00002JB13  I39  PR3922
   1 HSC_FLT_TYPE_2      A @T6G_MB_LIB.T6G(SCH_1):HSC_FLT_TYPE_2
   2 HSC_FLT_TYPE      B @T6G_MB_LIB.T6G(SCH_1):HSC_FLT_TYPE

Q_RES_0402LF-0,5%,1/16W,CHIP,CS00002JB13  I40  PR3921
   1 HSC_D_OC_2      A @T6G_MB_LIB.T6G(SCH_1):HSC_D_OC_2
   2 HSC_D_OC_R      B @T6G_MB_LIB.T6G(SCH_1):HSC_D_OC_R

Q_CAP_0402-0.068UF,16V,10%,X7R,CH3683K1B09  I47  PC2184
   1 HSC_SS      A @T6G_MB_LIB.T6G(SCH_1):HSC_SS
   2 AGND_HSC      B @T6G_MB_LIB.T6G(SCH_1):AGND_HSC

Q_RES_0402LF-0,5%,1/16W,CHIP,CS00002JB13  I49  PR3920
   1 HSC_FLT_TYPE_1      A @T6G_MB_LIB.T6G(SCH_1):HSC_FLT_TYPE_1
   2 HSC_FLT_TYPE      B @T6G_MB_LIB.T6G(SCH_1):HSC_FLT_TYPE

Q_RES_0402LF-0,5%,1/16W,CHIP,CS00002JB13  I50  PR3919
   1 HSC_D_OC_1      A @T6G_MB_LIB.T6G(SCH_1):HSC_D_OC_1
   2 HSC_D_OC_R      B @T6G_MB_LIB.T6G(SCH_1):HSC_D_OC_R


DRAWING: @T6G_MB_LIB.T6G(SCH_1):PAGE325 

Q_CAP_0402-220PF,50V,10%,EMPTY,TMP_QCH12206KB14  I2  PC2225
   1 HSC_ON      A @T6G_MB_LIB.T6G(SCH_1):HSC_ON
   2 AGND_HSC      B @T6G_MB_LIB.T6G(SCH_1):AGND_HSC

Q_CAP_C0402-1UF,25V,10%,X6S,CH5104KEB02  I4  PC2223
   1 HSC_VDD_R_4      A @T6G_MB_LIB.T6G(SCH_1):HSC_VDD_R_4
   2 AGND_HSC      B @T6G_MB_LIB.T6G(SCH_1):AGND_HSC

Q_RES_0402LF-0,5%,1/16W,CHIP,CS00002JB13  I6  PR3981
   1 HSC_VDD_R_4      A @T6G_MB_LIB.T6G(SCH_1):HSC_VDD_R_4
   2 HSC_VDD      B @T6G_MB_LIB.T6G(SCH_1):HSC_VDD

Q_RES_0402LF-120K,1%,1/16W,CHIP,CS41202FB05  I11  PR3984
   1 AGND_HSC      A @T6G_MB_LIB.T6G(SCH_1):AGND_HSC
   2 HSC_MODE_4      B @T6G_MB_LIB.T6G(SCH_1):HSC_MODE_4

Q_CAP_0402-1NF,50V,10%,EMPTY,CH21006KB16  I12  PC2349
   1 HSC_OCREF      A @T6G_MB_LIB.T6G(SCH_1):HSC_OCREF
   2 AGND_HSC      B @T6G_MB_LIB.T6G(SCH_1):AGND_HSC

Q_RES_0402LF-2K,0.1%,1/16W,CHIP,CS22002BB07  I13  PR3987
   1 HSC_CS_4      A @T6G_MB_LIB.T6G(SCH_1):HSC_CS_4
   2 AGND_HSC      B @T6G_MB_LIB.T6G(SCH_1):AGND_HSC

Q_RES_0402LF-2K,0.1%,1/16W,CHIP,CS22002BB07  I14  PR3991
   1 HSC_IMON      A @T6G_MB_LIB.T6G(SCH_1):HSC_IMON
   2 AGND_HSC      B @T6G_MB_LIB.T6G(SCH_1):AGND_HSC

Q_RES_0402LF-0,5%,1/16W,CHIP,CS00002JB13  I16  PR3989
   1 HSC_SCREF      A @T6G_MB_LIB.T6G(SCH_1):HSC_SCREF
   2 HSC_SCREF_4      B @T6G_MB_LIB.T6G(SCH_1):HSC_SCREF_4

MP5991GLUZ-MP5991GLU-Z,SMLF,IC,AL005991A00  I17  PU297
   9 P12V_PSU   VIN1 @T6G_MB_LIB.T6G(SCH_1):P12V_PSU
  10 P12V_PSU   VIN2 @T6G_MB_LIB.T6G(SCH_1):P12V_PSU
  11 P12V_PSU   VIN3 @T6G_MB_LIB.T6G(SCH_1):P12V_PSU
  12 P12V_PSU   VIN4 @T6G_MB_LIB.T6G(SCH_1):P12V_PSU
  13 P12V_PSU   VIN5 @T6G_MB_LIB.T6G(SCH_1):P12V_PSU
   4 HSC_ON     ON @T6G_MB_LIB.T6G(SCH_1):HSC_ON
  24 HSC_OCREF  OCREF @T6G_MB_LIB.T6G(SCH_1):HSC_OCREF
  23 HSC_CS_4     CS @T6G_MB_LIB.T6G(SCH_1):HSC_CS_4
  22 HSC_IMON   IMON @T6G_MB_LIB.T6G(SCH_1):HSC_IMON
  21 HSC_VDD_R_4  VDD33 @T6G_MB_LIB.T6G(SCH_1):HSC_VDD_R_4
  20 AGND_HSC    GND @T6G_MB_LIB.T6G(SCH_1):AGND_HSC
  19 HSC_SS     SS @T6G_MB_LIB.T6G(SCH_1):HSC_SS
   5 HSC_FAULT    GOK @T6G_MB_LIB.T6G(SCH_1):HSC_FAULT
  18 HSC_VTEMP  VTEMP @T6G_MB_LIB.T6G(SCH_1):HSC_VTEMP
   1 P12V_AUX  VOUT1 @T6G_MB_LIB.T6G(SCH_1):P12V_AUX
   2 P12V_AUX  VOUT2 @T6G_MB_LIB.T6G(SCH_1):P12V_AUX
  25 P12V_AUX  VOUT3 @T6G_MB_LIB.T6G(SCH_1):P12V_AUX
  26 P12V_AUX  VOUT4 @T6G_MB_LIB.T6G(SCH_1):P12V_AUX
   3 HSC_D_OC_4   D_OC @T6G_MB_LIB.T6G(SCH_1):HSC_D_OC_4
  14 P12V_PSU   VIN6 @T6G_MB_LIB.T6G(SCH_1):P12V_PSU
  15 P12V_PSU   VIN7 @T6G_MB_LIB.T6G(SCH_1):P12V_PSU
  16 P12V_PSU   VIN8 @T6G_MB_LIB.T6G(SCH_1):P12V_PSU
  33 P12V_PSU   VIN9 @T6G_MB_LIB.T6G(SCH_1):P12V_PSU
  27 P12V_AUX  VOUT5 @T6G_MB_LIB.T6G(SCH_1):P12V_AUX
  28 P12V_AUX  VOUT6 @T6G_MB_LIB.T6G(SCH_1):P12V_AUX
  29 P12V_AUX  VOUT7 @T6G_MB_LIB.T6G(SCH_1):P12V_AUX
  30 P12V_AUX  VOUT8 @T6G_MB_LIB.T6G(SCH_1):P12V_AUX
  31 P12V_AUX  VOUT9 @T6G_MB_LIB.T6G(SCH_1):P12V_AUX
  32 P12V_AUX VOUT10 @T6G_MB_LIB.T6G(SCH_1):P12V_AUX
   8 HSC_MODE_4   MODE @T6G_MB_LIB.T6G(SCH_1):HSC_MODE_4
  17 HSC_SCREF_4 SCREF_OCWREF @T6G_MB_LIB.T6G(SCH_1):HSC_SCREF_4
   6 HSC_FLT_TYPE_4 FLT_TYPE @T6G_MB_LIB.T6G(SCH_1):HSC_FLT_TYPE_4
   7 HSC_NC1_4    NC1 @T6G_MB_LIB.T6G(SCH_1):HSC_NC1_4

Q_CAP_C0402-1UF,25V,10%,X6S,CH5104KEB02  I20  PC3272
   1 HSC_VDD_R_3      A @T6G_MB_LIB.T6G(SCH_1):HSC_VDD_R_3
   2 AGND_HSC      B @T6G_MB_LIB.T6G(SCH_1):AGND_HSC

Q_RES_0402LF-0,5%,1/16W,CHIP,CS00002JB13  I21  PR3980
   1 HSC_VDD_R_3      A @T6G_MB_LIB.T6G(SCH_1):HSC_VDD_R_3
   2 HSC_VDD      B @T6G_MB_LIB.T6G(SCH_1):HSC_VDD

Q_CAP_0402-220PF,50V,10%,EMPTY,TMP_QCH12206KB14  I24  PC2224
   1 HSC_ON      A @T6G_MB_LIB.T6G(SCH_1):HSC_ON
   2 AGND_HSC      B @T6G_MB_LIB.T6G(SCH_1):AGND_HSC

Q_RES_0402LF-120K,1%,1/16W,CHIP,CS41202FB05  I28  PR3982
   1 AGND_HSC      A @T6G_MB_LIB.T6G(SCH_1):AGND_HSC
   2 HSC_MODE_3      B @T6G_MB_LIB.T6G(SCH_1):HSC_MODE_3

Q_CAP_0402-1NF,50V,10%,EMPTY,CH21006KB16  I30  PC2350
   1 HSC_OCREF      A @T6G_MB_LIB.T6G(SCH_1):HSC_OCREF
   2 AGND_HSC      B @T6G_MB_LIB.T6G(SCH_1):AGND_HSC

Q_RES_0402LF-2K,0.1%,1/16W,CHIP,CS22002BB07  I31  PR3986
   1 HSC_CS_3      A @T6G_MB_LIB.T6G(SCH_1):HSC_CS_3
   2 AGND_HSC      B @T6G_MB_LIB.T6G(SCH_1):AGND_HSC

Q_RES_0402LF-0,5%,1/16W,CHIP,CS00002JB13  I33  PR3988
   1 HSC_SCREF      A @T6G_MB_LIB.T6G(SCH_1):HSC_SCREF
   2 HSC_SCREF_3      B @T6G_MB_LIB.T6G(SCH_1):HSC_SCREF_3

Q_RES_0402LF-2K,0.1%,1/16W,CHIP,CS22002BB07  I34  PR3990
   1 HSC_IMON      A @T6G_MB_LIB.T6G(SCH_1):HSC_IMON
   2 AGND_HSC      B @T6G_MB_LIB.T6G(SCH_1):AGND_HSC

MP5991GLUZ-MP5991GLU-Z,SMLF,IC,AL005991A00  I35  PU296
   9 P12V_PSU   VIN1 @T6G_MB_LIB.T6G(SCH_1):P12V_PSU
  10 P12V_PSU   VIN2 @T6G_MB_LIB.T6G(SCH_1):P12V_PSU
  11 P12V_PSU   VIN3 @T6G_MB_LIB.T6G(SCH_1):P12V_PSU
  12 P12V_PSU   VIN4 @T6G_MB_LIB.T6G(SCH_1):P12V_PSU
  13 P12V_PSU   VIN5 @T6G_MB_LIB.T6G(SCH_1):P12V_PSU
   4 HSC_ON     ON @T6G_MB_LIB.T6G(SCH_1):HSC_ON
  24 HSC_OCREF  OCREF @T6G_MB_LIB.T6G(SCH_1):HSC_OCREF
  23 HSC_CS_3     CS @T6G_MB_LIB.T6G(SCH_1):HSC_CS_3
  22 HSC_IMON   IMON @T6G_MB_LIB.T6G(SCH_1):HSC_IMON
  21 HSC_VDD_R_3  VDD33 @T6G_MB_LIB.T6G(SCH_1):HSC_VDD_R_3
  20 AGND_HSC    GND @T6G_MB_LIB.T6G(SCH_1):AGND_HSC
  19 HSC_SS     SS @T6G_MB_LIB.T6G(SCH_1):HSC_SS
   5 HSC_FAULT    GOK @T6G_MB_LIB.T6G(SCH_1):HSC_FAULT
  18 HSC_VTEMP  VTEMP @T6G_MB_LIB.T6G(SCH_1):HSC_VTEMP
   1 P12V_AUX  VOUT1 @T6G_MB_LIB.T6G(SCH_1):P12V_AUX
   2 P12V_AUX  VOUT2 @T6G_MB_LIB.T6G(SCH_1):P12V_AUX
  25 P12V_AUX  VOUT3 @T6G_MB_LIB.T6G(SCH_1):P12V_AUX
  26 P12V_AUX  VOUT4 @T6G_MB_LIB.T6G(SCH_1):P12V_AUX
   3 HSC_D_OC_3   D_OC @T6G_MB_LIB.T6G(SCH_1):HSC_D_OC_3
  14 P12V_PSU   VIN6 @T6G_MB_LIB.T6G(SCH_1):P12V_PSU
  15 P12V_PSU   VIN7 @T6G_MB_LIB.T6G(SCH_1):P12V_PSU
  16 P12V_PSU   VIN8 @T6G_MB_LIB.T6G(SCH_1):P12V_PSU
  33 P12V_PSU   VIN9 @T6G_MB_LIB.T6G(SCH_1):P12V_PSU
  27 P12V_AUX  VOUT5 @T6G_MB_LIB.T6G(SCH_1):P12V_AUX
  28 P12V_AUX  VOUT6 @T6G_MB_LIB.T6G(SCH_1):P12V_AUX
  29 P12V_AUX  VOUT7 @T6G_MB_LIB.T6G(SCH_1):P12V_AUX
  30 P12V_AUX  VOUT8 @T6G_MB_LIB.T6G(SCH_1):P12V_AUX
  31 P12V_AUX  VOUT9 @T6G_MB_LIB.T6G(SCH_1):P12V_AUX
  32 P12V_AUX VOUT10 @T6G_MB_LIB.T6G(SCH_1):P12V_AUX
   8 HSC_MODE_3   MODE @T6G_MB_LIB.T6G(SCH_1):HSC_MODE_3
  17 HSC_SCREF_3 SCREF_OCWREF @T6G_MB_LIB.T6G(SCH_1):HSC_SCREF_3
   6 HSC_FLT_TYPE_3 FLT_TYPE @T6G_MB_LIB.T6G(SCH_1):HSC_FLT_TYPE_3
   7 HSC_NC1_3    NC1 @T6G_MB_LIB.T6G(SCH_1):HSC_NC1_3

Q_CAP_0402-0.068UF,16V,10%,X7R,CH3683K1B09  I38  PC2227
   1 HSC_SS      A @T6G_MB_LIB.T6G(SCH_1):HSC_SS
   2 AGND_HSC      B @T6G_MB_LIB.T6G(SCH_1):AGND_HSC

Q_RES_0402LF-0,5%,1/16W,CHIP,CS00002JB13  I39  PR3995
   1 HSC_FLT_TYPE_4      A @T6G_MB_LIB.T6G(SCH_1):HSC_FLT_TYPE_4
   2 HSC_FLT_TYPE      B @T6G_MB_LIB.T6G(SCH_1):HSC_FLT_TYPE

Q_RES_0402LF-0,5%,1/16W,CHIP,CS00002JB13  I40  PR3994
   1 HSC_D_OC_4      A @T6G_MB_LIB.T6G(SCH_1):HSC_D_OC_4
   2 HSC_D_OC_R      B @T6G_MB_LIB.T6G(SCH_1):HSC_D_OC_R

Q_CAP_0402-0.068UF,16V,10%,X7R,CH3683K1B09  I47  PC2226
   1 HSC_SS      A @T6G_MB_LIB.T6G(SCH_1):HSC_SS
   2 AGND_HSC      B @T6G_MB_LIB.T6G(SCH_1):AGND_HSC

Q_RES_0402LF-0,5%,1/16W,CHIP,CS00002JB13  I49  PR3993
   1 HSC_FLT_TYPE_3      A @T6G_MB_LIB.T6G(SCH_1):HSC_FLT_TYPE_3
   2 HSC_FLT_TYPE      B @T6G_MB_LIB.T6G(SCH_1):HSC_FLT_TYPE

Q_RES_0402LF-0,5%,1/16W,CHIP,CS00002JB13  I50  PR3992
   1 HSC_D_OC_3      A @T6G_MB_LIB.T6G(SCH_1):HSC_D_OC_3
   2 HSC_D_OC_R      B @T6G_MB_LIB.T6G(SCH_1):HSC_D_OC_R


DRAWING: @T6G_MB_LIB.T6G(SCH_1):PAGE299 

Q_RES_0402LF-100K,1%,1/16W,EMPTY,CS41002FB09  I3  R3430
   1 GPU_FPGA_OVERT_N      A @T6G_MB_LIB.T6G(SCH_1):GPU_FPGA_OVERT_N
   2    GND      B @T6G_MB_LIB.T6G(SCH_1):GND

Q_RES_0402LF-100K,1%,1/16W,EMPTY,CS41002FB09  I17  R3428
   1 GPU_FPGA_THERM_OVERT_N      A @T6G_MB_LIB.T6G(SCH_1):GPU_FPGA_THERM_OVERT_N
   2    GND      B @T6G_MB_LIB.T6G(SCH_1):GND

MOSFET_NCH_DUAL-PJT138K,SMLF,IC,BAM138K0003  I21  Q104
   1    GND     S1 @T6G_MB_LIB.T6G(SCH_1):GND
   2 GPU_FPGA_OVERT_N     G1 @T6G_MB_LIB.T6G(SCH_1):GPU_FPGA_OVERT_N
   6 GPU_FPGA_OVERT     D1 @T6G_MB_LIB.T6G(SCH_1):GPU_FPGA_OVERT

Q_RES_0402LF-4.7K,5%,1/16W,CHIP,CS24702JB10  I23  R3435
   1 P3V3_AUX      A @T6G_MB_LIB.T6G(SCH_1):P3V3_AUX
   2 GPU_FPGA_OVERT      B @T6G_MB_LIB.T6G(SCH_1):GPU_FPGA_OVERT

MOSFET_NCH_DUAL-PJT138K,SMLF,IC,BAM138K0003  I26  Q104
   3 GPU_FPGA_OVERT_ISO_N     D2 @T6G_MB_LIB.T6G(SCH_1):GPU_FPGA_OVERT_ISO_N
   5 GPU_FPGA_OVERT     G2 @T6G_MB_LIB.T6G(SCH_1):GPU_FPGA_OVERT
   4    GND     S2 @T6G_MB_LIB.T6G(SCH_1):GND

Q_RES_0402LF-100K,1%,1/16W,CHIP,CS41002FB09  I27  R3437
   1 P3V3_AUX      A @T6G_MB_LIB.T6G(SCH_1):P3V3_AUX
   2 GPU_FPGA_OVERT_ISO_N      B @T6G_MB_LIB.T6G(SCH_1):GPU_FPGA_OVERT_ISO_N

Q_CAP_0402-0.1UF,25V,10%,X7R,CH4104K1B00  I30  C1976
   1 GPU_FPGA_OVERT_ISO_N      A @T6G_MB_LIB.T6G(SCH_1):GPU_FPGA_OVERT_ISO_N
   2    GND      B @T6G_MB_LIB.T6G(SCH_1):GND

MOSFET_NCH_DUAL-PJT138K,SMLF,IC,BAM138K0003  I37  Q103
   1    GND     S1 @T6G_MB_LIB.T6G(SCH_1):GND
   2 GPU_HMC_PRSNT_N     G1 @T6G_MB_LIB.T6G(SCH_1):GPU_HMC_PRSNT_N
   6 GPU_HMC_PRSNT     D1 @T6G_MB_LIB.T6G(SCH_1):GPU_HMC_PRSNT

Q_RES_0402LF-4.7K,5%,1/16W,CHIP,CS24702JB10  I39  R3434
   1 P3V3_AUX      A @T6G_MB_LIB.T6G(SCH_1):P3V3_AUX
   2 GPU_HMC_PRSNT      B @T6G_MB_LIB.T6G(SCH_1):GPU_HMC_PRSNT

MOSFET_NCH_DUAL-PJT138K,SMLF,IC,BAM138K0003  I40  Q102
   1    GND     S1 @T6G_MB_LIB.T6G(SCH_1):GND
   2 GPU_BASE_HMC_READY     G1 @T6G_MB_LIB.T6G(SCH_1):GPU_BASE_HMC_READY
   6 GPU_BASE_HMC_READY_N     D1 @T6G_MB_LIB.T6G(SCH_1):GPU_BASE_HMC_READY_N

MOSFET_NCH_DUAL-PJT138K,SMLF,IC,BAM138K0003  I43  Q103
   3 GPU_HMC_PRSNT_ISO_N     D2 @T6G_MB_LIB.T6G(SCH_1):GPU_HMC_PRSNT_ISO_N
   5 GPU_HMC_PRSNT     G2 @T6G_MB_LIB.T6G(SCH_1):GPU_HMC_PRSNT
   4    GND     S2 @T6G_MB_LIB.T6G(SCH_1):GND

Q_RES_0402LF-100K,1%,1/16W,CHIP,CS41002FB09  I45  R3436
   1 P3V3_AUX      A @T6G_MB_LIB.T6G(SCH_1):P3V3_AUX
   2 GPU_HMC_PRSNT_ISO_N      B @T6G_MB_LIB.T6G(SCH_1):GPU_HMC_PRSNT_ISO_N

MOSFET_NCH_DUAL-PJT138K,SMLF,IC,BAM138K0003  I48  Q102
   3 GPU_BASE_HMC_READY_ISO     D2 @T6G_MB_LIB.T6G(SCH_1):GPU_BASE_HMC_READY_ISO
   5 GPU_BASE_HMC_READY_N     G2 @T6G_MB_LIB.T6G(SCH_1):GPU_BASE_HMC_READY_N
   4    GND     S2 @T6G_MB_LIB.T6G(SCH_1):GND

Q_RES_0402LF-4.7K,5%,1/16W,CHIP,CS24702JB10  I49  R3433
   1 P3V3_AUX      A @T6G_MB_LIB.T6G(SCH_1):P3V3_AUX
   2 GPU_BASE_HMC_READY_N      B @T6G_MB_LIB.T6G(SCH_1):GPU_BASE_HMC_READY_N

MOSFET_NCH_DUAL-PJT138K,SMLF,IC,BAM138K0003  I52  Q101
   1    GND     S1 @T6G_MB_LIB.T6G(SCH_1):GND
   2 GPU_FPGA_THERM_OVERT_N     G1 @T6G_MB_LIB.T6G(SCH_1):GPU_FPGA_THERM_OVERT_N
   6 GPU_FPGA_THERM_OVERT     D1 @T6G_MB_LIB.T6G(SCH_1):GPU_FPGA_THERM_OVERT

Q_RES_0402LF-4.7K,5%,1/16W,CHIP,CS24702JB10  I53  R3432
   1 P3V3_AUX      A @T6G_MB_LIB.T6G(SCH_1):P3V3_AUX
   2 GPU_FPGA_THERM_OVERT      B @T6G_MB_LIB.T6G(SCH_1):GPU_FPGA_THERM_OVERT

Q_RES_0402LF-100K,1%,1/16W,CHIP,CS41002FB09  I55  R3438
   1 P3V3_AUX      A @T6G_MB_LIB.T6G(SCH_1):P3V3_AUX
   2 GPU_BASE_HMC_READY_ISO      B @T6G_MB_LIB.T6G(SCH_1):GPU_BASE_HMC_READY_ISO

MOSFET_NCH_DUAL-PJT138K,SMLF,IC,BAM138K0003  I57  Q101
   3 GPU_FPGA_THERM_OVERT_ISO_N     D2 @T6G_MB_LIB.T6G(SCH_1):GPU_FPGA_THERM_OVERT_ISO_N
   5 GPU_FPGA_THERM_OVERT     G2 @T6G_MB_LIB.T6G(SCH_1):GPU_FPGA_THERM_OVERT
   4    GND     S2 @T6G_MB_LIB.T6G(SCH_1):GND

Q_RES_0402LF-100K,1%,1/16W,CHIP,CS41002FB09  I59  R3439
   1 P3V3_AUX      A @T6G_MB_LIB.T6G(SCH_1):P3V3_AUX
   2 GPU_FPGA_THERM_OVERT_ISO_N      B @T6G_MB_LIB.T6G(SCH_1):GPU_FPGA_THERM_OVERT_ISO_N

Q_CAP_0402-0.1UF,25V,10%,X7R,CH4104K1B00  I71  C1973
   1 GPU_BASE_HMC_READY_ISO      A @T6G_MB_LIB.T6G(SCH_1):GPU_BASE_HMC_READY_ISO
   2    GND      B @T6G_MB_LIB.T6G(SCH_1):GND

Q_CAP_0402-0.1UF,25V,10%,X7R,CH4104K1B00  I74  C1974
   1 GPU_FPGA_THERM_OVERT_ISO_N      A @T6G_MB_LIB.T6G(SCH_1):GPU_FPGA_THERM_OVERT_ISO_N
   2    GND      B @T6G_MB_LIB.T6G(SCH_1):GND

Q_CAP_0402-0.1UF,25V,10%,X7R,CH4104K1B00  I129  C1975
   1 GPU_HMC_PRSNT_ISO_N      A @T6G_MB_LIB.T6G(SCH_1):GPU_HMC_PRSNT_ISO_N
   2    GND      B @T6G_MB_LIB.T6G(SCH_1):GND

Q_RES_0402LF-100K,1%,1/16W,EMPTY,CS41002FB09  I130  R3429
   1 P3V3_AUX      A @T6G_MB_LIB.T6G(SCH_1):P3V3_AUX
   2 GPU_BASE_HMC_READY      B @T6G_MB_LIB.T6G(SCH_1):GPU_BASE_HMC_READY

Q_RES_0402LF-54.9K,1%,1/16W,CHIP,CS35492FB03  I131  R3463
   1 GPU_BASE_HMC_READY      A @T6G_MB_LIB.T6G(SCH_1):GPU_BASE_HMC_READY
   2    GND      B @T6G_MB_LIB.T6G(SCH_1):GND

Q_RES_0402LF-10K,1%,1/16W,CHIP,CS31002FB08  I132  R3465
   1 P3V3_AUX      A @T6G_MB_LIB.T6G(SCH_1):P3V3_AUX
   2 GPU_HMC_PRSNT_N      B @T6G_MB_LIB.T6G(SCH_1):GPU_HMC_PRSNT_N

Q_RES_0402LF-100K,1%,1/16W,EMPTY,CS41002FB09  I133  R3431
   1 GPU_HMC_PRSNT_N      A @T6G_MB_LIB.T6G(SCH_1):GPU_HMC_PRSNT_N
   2    GND      B @T6G_MB_LIB.T6G(SCH_1):GND

Q_RES_0402LF-54.9K,1%,1/16W,CHIP,CS35492FB03  I134  R3464
   1 P3V3_AUX      A @T6G_MB_LIB.T6G(SCH_1):P3V3_AUX
   2 GPU_FPGA_OVERT_N      B @T6G_MB_LIB.T6G(SCH_1):GPU_FPGA_OVERT_N

Q_CAP_0402-0.1UF,25V,10%,X7R,CH4104K1B00  I152  C1978
   1 GPU_PRSNT_N_ISO      A @T6G_MB_LIB.T6G(SCH_1):GPU_PRSNT_N_ISO
   2    GND      B @T6G_MB_LIB.T6G(SCH_1):GND

Q_RES_0402LF-100K,1%,1/16W,CHIP,CS41002FB09  I154  R3475
   1 P3V3_AUX      A @T6G_MB_LIB.T6G(SCH_1):P3V3_AUX
   2 GPU_PRSNT_N_ISO      B @T6G_MB_LIB.T6G(SCH_1):GPU_PRSNT_N_ISO

MOSFET_NCH_DUAL-PJT138K,SMLF,IC,BAM138K0003  I157  Q107
   3 GPU_PRSNT_N_ISO     D2 @T6G_MB_LIB.T6G(SCH_1):GPU_PRSNT_N_ISO
   5 GPU_PRSNT     G2 @T6G_MB_LIB.T6G(SCH_1):GPU_PRSNT
   4    GND     S2 @T6G_MB_LIB.T6G(SCH_1):GND

Q_RES_0402LF-4.7K,5%,1/16W,CHIP,CS24702JB10  I158  R3474
   1 P3V3_AUX      A @T6G_MB_LIB.T6G(SCH_1):P3V3_AUX
   2 GPU_PRSNT      B @T6G_MB_LIB.T6G(SCH_1):GPU_PRSNT

MOSFET_NCH_DUAL-PJT138K,SMLF,IC,BAM138K0003  I160  Q107
   1    GND     S1 @T6G_MB_LIB.T6G(SCH_1):GND
   2 GPU_PRSNT_N     G1 @T6G_MB_LIB.T6G(SCH_1):GPU_PRSNT_N
   6 GPU_PRSNT     D1 @T6G_MB_LIB.T6G(SCH_1):GPU_PRSNT

Q_RES_0402LF-100K,1%,1/16W,EMPTY,CS41002FB09  I163  R3473
   1 GPU_PRSNT_N      A @T6G_MB_LIB.T6G(SCH_1):GPU_PRSNT_N
   2    GND      B @T6G_MB_LIB.T6G(SCH_1):GND

Q_RES_0402LF-10K,1%,1/16W,CHIP,CS31002FB08  I166  R3487
   1 P3V3_AUX      A @T6G_MB_LIB.T6G(SCH_1):P3V3_AUX
   2 GPU_PRSNT_N      B @T6G_MB_LIB.T6G(SCH_1):GPU_PRSNT_N

Q_RES_0402LF-54.9K,1%,1/16W,CHIP,CS35492FB03  I167  R3498
   1 P3V3_AUX      A @T6G_MB_LIB.T6G(SCH_1):P3V3_AUX
   2 GPU_FPGA_THERM_OVERT_N      B @T6G_MB_LIB.T6G(SCH_1):GPU_FPGA_THERM_OVERT_N

MOSFET_NCH_DUAL-PJT138K,SMLF,IC,BAM138K0003  I168  Q108
   3 GPU_FPGA_EROT_FATALERR_ISO_N     D2 @T6G_MB_LIB.T6G(SCH_1):GPU_FPGA_EROT_FATALERR_ISO_N
   5 GPU_FPGA_EROT_FATALERR     G2 @T6G_MB_LIB.T6G(SCH_1):GPU_FPGA_EROT_FATALERR
   4    GND     S2 @T6G_MB_LIB.T6G(SCH_1):GND

MOSFET_NCH_DUAL-PJT138K,SMLF,IC,BAM138K0003  I169  Q108
   1    GND     S1 @T6G_MB_LIB.T6G(SCH_1):GND
   2 GPU_FPGA_EROT_FATALERR_N     G1 @T6G_MB_LIB.T6G(SCH_1):GPU_FPGA_EROT_FATALERR_N
   6 GPU_FPGA_EROT_FATALERR     D1 @T6G_MB_LIB.T6G(SCH_1):GPU_FPGA_EROT_FATALERR

Q_CAP_0402-0.1UF,25V,10%,X7R,CH4104K1B00  I171  C1988
   1 GPU_FPGA_EROT_FATALERR_ISO_N      A @T6G_MB_LIB.T6G(SCH_1):GPU_FPGA_EROT_FATALERR_ISO_N
   2    GND      B @T6G_MB_LIB.T6G(SCH_1):GND

Q_RES_0402LF-100K,1%,1/16W,CHIP,CS41002FB09  I174  R3504
   1 P3V3_AUX      A @T6G_MB_LIB.T6G(SCH_1):P3V3_AUX
   2 GPU_FPGA_EROT_FATALERR_ISO_N      B @T6G_MB_LIB.T6G(SCH_1):GPU_FPGA_EROT_FATALERR_ISO_N

Q_RES_0402LF-4.7K,5%,1/16W,CHIP,CS24702JB10  I177  R3503
   1 P3V3_AUX      A @T6G_MB_LIB.T6G(SCH_1):P3V3_AUX
   2 GPU_FPGA_EROT_FATALERR      B @T6G_MB_LIB.T6G(SCH_1):GPU_FPGA_EROT_FATALERR

Q_RES_0402LF-100K,1%,1/16W,EMPTY,CS41002FB09  I181  R3502
   1 GPU_FPGA_EROT_FATALERR_N      A @T6G_MB_LIB.T6G(SCH_1):GPU_FPGA_EROT_FATALERR_N
   2    GND      B @T6G_MB_LIB.T6G(SCH_1):GND

Q_RES_0402LF-54.9K,1%,1/16W,CHIP,CS35492FB03  I184  R3525
   1 P3V3_AUX      A @T6G_MB_LIB.T6G(SCH_1):P3V3_AUX
   2 GPU_FPGA_EROT_FATALERR_N      B @T6G_MB_LIB.T6G(SCH_1):GPU_FPGA_EROT_FATALERR_N

Q_RES_0402LF-10K,1%,1/16W,EMPTY,CS31002FB08  I187  R3471
   1 GPU_WP_HW_CTRL_N      A @T6G_MB_LIB.T6G(SCH_1):GPU_WP_HW_CTRL_N
   2    GND      B @T6G_MB_LIB.T6G(SCH_1):GND

Q_RES_0402LF-4.7K,5%,1/16W,CHIP,CS24702JB10  I192  R9043
   1 P3V3_AUX      A @T6G_MB_LIB.T6G(SCH_1):P3V3_AUX
   2 GPU_WP_HW_CTRL_ISO      B @T6G_MB_LIB.T6G(SCH_1):GPU_WP_HW_CTRL_ISO

Q_RES_0402LF-4.7K,1%,1/16W,EMPTY,CS24702FB06  I195  R9044
   1 P3V3_AUX      A @T6G_MB_LIB.T6G(SCH_1):P3V3_AUX
   2 GPU_WP_HW_CTRL_ISO_N      B @T6G_MB_LIB.T6G(SCH_1):GPU_WP_HW_CTRL_ISO_N

Q_RES_0402LF-0,5%,1/16W,EMPTY,CS00002JB13  I198  R3472
   1    GND      A @T6G_MB_LIB.T6G(SCH_1):GND
   2 GPU_WP_HW_CTRL_ISO_N      B @T6G_MB_LIB.T6G(SCH_1):GPU_WP_HW_CTRL_ISO_N

MOSFET_NCH_DUAL-PJT138K,SMLF,IC,BAM138K0003  I200  Q106
   3 GPU_WP_HW_CTRL_ISO_N     D2 @T6G_MB_LIB.T6G(SCH_1):GPU_WP_HW_CTRL_ISO_N
   5 GPU_WP_HW_CTRL_ISO     G2 @T6G_MB_LIB.T6G(SCH_1):GPU_WP_HW_CTRL_ISO
   4    GND     S2 @T6G_MB_LIB.T6G(SCH_1):GND

MOSFET_NCH_DUAL-PJT138K,SMLF,IC,BAM138K0003  I201  Q106
   1    GND     S1 @T6G_MB_LIB.T6G(SCH_1):GND
   2 GPU_WP_HW_CTRL_N     G1 @T6G_MB_LIB.T6G(SCH_1):GPU_WP_HW_CTRL_N
   6 GPU_WP_HW_CTRL_ISO     D1 @T6G_MB_LIB.T6G(SCH_1):GPU_WP_HW_CTRL_ISO

Q_RES_0402LF-1K,1%,1/16W,CHIP,CS21002FB06  I202  R3470
   1 P3V3_AUX      A @T6G_MB_LIB.T6G(SCH_1):P3V3_AUX
   2 GPU_WP_HW_CTRL_N      B @T6G_MB_LIB.T6G(SCH_1):GPU_WP_HW_CTRL_N


DRAWING: @T6G_MB_LIB.T6G(SCH_1):PAGE330 

Q_RES_0402LF-10K,1%,1/16W,CHIP,CS31002FB08  I8  R9002
   1 P3V3_AUX      A @T6G_MB_LIB.T6G(SCH_1):P3V3_AUX
   2 PRSNT_CABLE_SWB_B1_N      B @T6G_MB_LIB.T6G(SCH_1):PRSNT_CABLE_SWB_B1_N

Q_RES_0402LF-4.7K,5%,1/16W,CHIP,CS24702JB10  I17  R9008
   1 P3V3_AUX      A @T6G_MB_LIB.T6G(SCH_1):P3V3_AUX
   2 PRSNT_CABLE_SWB_B2      B @T6G_MB_LIB.T6G(SCH_1):PRSNT_CABLE_SWB_B2

MOSFET_NCH_DUAL-PJT138K,SMLF,IC,BAM138K0003  I21  Q9000
   1    GND     S1 @T6G_MB_LIB.T6G(SCH_1):GND
   2 PRSNT_CABLE_SWB_B1_N     G1 @T6G_MB_LIB.T6G(SCH_1):PRSNT_CABLE_SWB_B1_N
   6 PRSNT_CABLE_SWB_B1     D1 @T6G_MB_LIB.T6G(SCH_1):PRSNT_CABLE_SWB_B1

Q_RES_0402LF-4.7K,5%,1/16W,CHIP,CS24702JB10  I23  R9009
   1 P3V3_AUX      A @T6G_MB_LIB.T6G(SCH_1):P3V3_AUX
   2 PRSNT_CABLE_SWB_B2_ISO_N      B @T6G_MB_LIB.T6G(SCH_1):PRSNT_CABLE_SWB_B2_ISO_N

Q_RES_0402LF-4.7K,5%,1/16W,CHIP,CS24702JB10  I26  R9004
   1 P3V3_AUX      A @T6G_MB_LIB.T6G(SCH_1):P3V3_AUX
   2 PRSNT_CABLE_SWB_B1      B @T6G_MB_LIB.T6G(SCH_1):PRSNT_CABLE_SWB_B1

MOSFET_NCH_DUAL-PJT138K,SMLF,IC,BAM138K0003  I30  Q8000
   3 PRSNT_SWB_ISO_N     D2 @T6G_MB_LIB.T6G(SCH_1):PRSNT_SWB_ISO_N
   5 PRSNT_SWB     G2 @T6G_MB_LIB.T6G(SCH_1):PRSNT_SWB
   4    GND     S2 @T6G_MB_LIB.T6G(SCH_1):GND

Q_RES_0402LF-100K,1%,1/16W,EMPTY,CS41002FB09  I2  R9007
   1 PRSNT_CABLE_SWB_B2_N      A @T6G_MB_LIB.T6G(SCH_1):PRSNT_CABLE_SWB_B2_N
   2    GND      B @T6G_MB_LIB.T6G(SCH_1):GND

MOSFET_NCH_DUAL-PJT138K,SMLF,IC,BAM138K0003  I3  Q9001
   1    GND     S1 @T6G_MB_LIB.T6G(SCH_1):GND
   2 PRSNT_CABLE_SWB_B2_N     G1 @T6G_MB_LIB.T6G(SCH_1):PRSNT_CABLE_SWB_B2_N
   6 PRSNT_CABLE_SWB_B2     D1 @T6G_MB_LIB.T6G(SCH_1):PRSNT_CABLE_SWB_B2

Q_RES_0402LF-100K,1%,1/16W,EMPTY,CS41002FB09  I12  R8001
   1 PRSNT_SWB_N      A @T6G_MB_LIB.T6G(SCH_1):PRSNT_SWB_N
   2    GND      B @T6G_MB_LIB.T6G(SCH_1):GND

Q_RES_0402LF-10K,1%,1/16W,CHIP,CS31002FB08  I13  R4058
   1 P3V3_AUX      A @T6G_MB_LIB.T6G(SCH_1):P3V3_AUX
   2 PRSNT_SWB_N      B @T6G_MB_LIB.T6G(SCH_1):PRSNT_SWB_N

Q_RES_0402LF-10K,1%,1/16W,CHIP,CS31002FB08  I15  R9006
   1 P3V3_AUX      A @T6G_MB_LIB.T6G(SCH_1):P3V3_AUX
   2 PRSNT_CABLE_SWB_B2_N      B @T6G_MB_LIB.T6G(SCH_1):PRSNT_CABLE_SWB_B2_N

Q_RES_0402LF-100K,1%,1/16W,EMPTY,CS41002FB09  I20  R9003
   1 PRSNT_CABLE_SWB_B1_N      A @T6G_MB_LIB.T6G(SCH_1):PRSNT_CABLE_SWB_B1_N
   2    GND      B @T6G_MB_LIB.T6G(SCH_1):GND

MOSFET_NCH_DUAL-PJT138K,SMLF,IC,BAM138K0003  I22  Q9001
   3 PRSNT_CABLE_SWB_B2_ISO_N     D2 @T6G_MB_LIB.T6G(SCH_1):PRSNT_CABLE_SWB_B2_ISO_N
   5 PRSNT_CABLE_SWB_B2     G2 @T6G_MB_LIB.T6G(SCH_1):PRSNT_CABLE_SWB_B2
   4    GND     S2 @T6G_MB_LIB.T6G(SCH_1):GND

MOSFET_NCH_DUAL-PJT138K,SMLF,IC,BAM138K0003  I29  Q8000
   1    GND     S1 @T6G_MB_LIB.T6G(SCH_1):GND
   2 PRSNT_SWB_N     G1 @T6G_MB_LIB.T6G(SCH_1):PRSNT_SWB_N
   6 PRSNT_SWB     D1 @T6G_MB_LIB.T6G(SCH_1):PRSNT_SWB

MOSFET_NCH_DUAL-PJT138K,SMLF,IC,BAM138K0003  I31  Q9000
   3 PRSNT_CABLE_SWB_B1_ISO_N     D2 @T6G_MB_LIB.T6G(SCH_1):PRSNT_CABLE_SWB_B1_ISO_N
   5 PRSNT_CABLE_SWB_B1     G2 @T6G_MB_LIB.T6G(SCH_1):PRSNT_CABLE_SWB_B1
   4    GND     S2 @T6G_MB_LIB.T6G(SCH_1):GND

Q_RES_0402LF-4.7K,5%,1/16W,CHIP,CS24702JB10  I32  R9005
   1 P3V3_AUX      A @T6G_MB_LIB.T6G(SCH_1):P3V3_AUX
   2 PRSNT_CABLE_SWB_B1_ISO_N      B @T6G_MB_LIB.T6G(SCH_1):PRSNT_CABLE_SWB_B1_ISO_N

Q_CAP_0402-1000PF,50V,5%,EMPTY,TMP_QCH21006JB10  I36  C8000
   1 PRSNT_SWB_ISO_N      A @T6G_MB_LIB.T6G(SCH_1):PRSNT_SWB_ISO_N
   2    GND      B @T6G_MB_LIB.T6G(SCH_1):GND

Q_CAP_0402-1000PF,50V,5%,EMPTY,TMP_QCH21006JB10  I42  C9001
   1 PRSNT_CABLE_SWB_B2_ISO_N      A @T6G_MB_LIB.T6G(SCH_1):PRSNT_CABLE_SWB_B2_ISO_N
   2    GND      B @T6G_MB_LIB.T6G(SCH_1):GND

Q_CAP_0402-1000PF,50V,5%,EMPTY,TMP_QCH21006JB10  I45  C9000
   1 PRSNT_CABLE_SWB_B1_ISO_N      A @T6G_MB_LIB.T6G(SCH_1):PRSNT_CABLE_SWB_B1_ISO_N
   2    GND      B @T6G_MB_LIB.T6G(SCH_1):GND

Q_RES_0402LF-100K,1%,1/16W,EMPTY,CS41002FB09  I50  R9015
   1 PRSNT_CABLE_GPU_A3_N      A @T6G_MB_LIB.T6G(SCH_1):PRSNT_CABLE_GPU_A3_N
   2    GND      B @T6G_MB_LIB.T6G(SCH_1):GND

Q_RES_0402LF-10K,1%,1/16W,CHIP,CS31002FB08  I51  R9014
   1 P3V3_AUX      A @T6G_MB_LIB.T6G(SCH_1):P3V3_AUX
   2 PRSNT_CABLE_GPU_A3_N      B @T6G_MB_LIB.T6G(SCH_1):PRSNT_CABLE_GPU_A3_N

MOSFET_NCH_DUAL-PJT138K,SMLF,IC,BAM138K0003  I52  Q9002
   1    GND     S1 @T6G_MB_LIB.T6G(SCH_1):GND
   2 PRSNT_CABLE_GPU_A3_N     G1 @T6G_MB_LIB.T6G(SCH_1):PRSNT_CABLE_GPU_A3_N
   6 PRSNT_CABLE_GPU_A3     D1 @T6G_MB_LIB.T6G(SCH_1):PRSNT_CABLE_GPU_A3

Q_RES_0402LF-4.7K,5%,1/16W,CHIP,CS24702JB10  I55  R8002
   1 P3V3_AUX      A @T6G_MB_LIB.T6G(SCH_1):P3V3_AUX
   2 PRSNT_SWB      B @T6G_MB_LIB.T6G(SCH_1):PRSNT_SWB

Q_RES_0402LF-4.7K,5%,1/16W,CHIP,CS24702JB10  I57  R8003
   1 P3V3_AUX      A @T6G_MB_LIB.T6G(SCH_1):P3V3_AUX
   2 PRSNT_SWB_ISO_N      B @T6G_MB_LIB.T6G(SCH_1):PRSNT_SWB_ISO_N

Q_RES_0402LF-4.7K,5%,1/16W,CHIP,CS24702JB10  I61  R9016
   1 P3V3_AUX      A @T6G_MB_LIB.T6G(SCH_1):P3V3_AUX
   2 PRSNT_CABLE_GPU_A3      B @T6G_MB_LIB.T6G(SCH_1):PRSNT_CABLE_GPU_A3

Q_RES_0402LF-0,5%,1/16W,CHIP,CS00002JB13  I64  R3441
   1 GPU_BASE_ID1      A @T6G_MB_LIB.T6G(SCH_1):GPU_BASE_ID1
   2    GND      B @T6G_MB_LIB.T6G(SCH_1):GND

Q_RES_0402LF-0,5%,1/16W,EMPTY,CS00002JB13  I65  R3440
   1 GPU_BASE_ID0      A @T6G_MB_LIB.T6G(SCH_1):GPU_BASE_ID0
   2    GND      B @T6G_MB_LIB.T6G(SCH_1):GND

Q_RES_0402LF-0,5%,1/16W,CHIP,CS00002JB13  I66  R3443
   1 GPU_PEX_STRAP1      A @T6G_MB_LIB.T6G(SCH_1):GPU_PEX_STRAP1
   2    GND      B @T6G_MB_LIB.T6G(SCH_1):GND

Q_RES_0402LF-0,5%,1/16W,CHIP,CS00002JB13  I67  R3442
   1 GPU_PEX_STRAP0      A @T6G_MB_LIB.T6G(SCH_1):GPU_PEX_STRAP0
   2    GND      B @T6G_MB_LIB.T6G(SCH_1):GND

Q_RES_0402LF-100,1%,1/16W,EMPTY,CS11002FB07  I69  R2656
   1 HGX_DETECT_N_ISO      A @T6G_MB_LIB.T6G(SCH_1):HGX_DETECT_N_ISO
   2    GND      B @T6G_MB_LIB.T6G(SCH_1):GND

Q_CAP_0402-1000PF,50V,5%,EMPTY,TMP_QCH21006JB10  I71  C9002
   1 PRSNT_CABLE_GPU_A3_ISO_N      A @T6G_MB_LIB.T6G(SCH_1):PRSNT_CABLE_GPU_A3_ISO_N
   2    GND      B @T6G_MB_LIB.T6G(SCH_1):GND

Q_RES_0402LF-4.7K,5%,1/16W,CHIP,CS24702JB10  I72  R9017
   1 P3V3_AUX      A @T6G_MB_LIB.T6G(SCH_1):P3V3_AUX
   2 PRSNT_CABLE_GPU_A3_ISO_N      B @T6G_MB_LIB.T6G(SCH_1):PRSNT_CABLE_GPU_A3_ISO_N

MOSFET_NCH_DUAL-PJT138K,SMLF,IC,BAM138K0003  I75  Q9002
   3 PRSNT_CABLE_GPU_A3_ISO_N     D2 @T6G_MB_LIB.T6G(SCH_1):PRSNT_CABLE_GPU_A3_ISO_N
   5 PRSNT_CABLE_GPU_A3     G2 @T6G_MB_LIB.T6G(SCH_1):PRSNT_CABLE_GPU_A3
   4    GND     S2 @T6G_MB_LIB.T6G(SCH_1):GND


DRAWING: @T6G_MB_LIB.T6G(SCH_1):PAGE331 

Q_RES_0402LF-100K,1%,1/16W,EMPTY,CS41002FB09  I2  R4161
   1 GPU_3V3IO_RSVD4      A @T6G_MB_LIB.T6G(SCH_1):GPU_3V3IO_RSVD4
   2    GND      B @T6G_MB_LIB.T6G(SCH_1):GND

Q_RES_0402LF-54.9K,1%,1/16W,EMPTY,CS35492FB03  I4  R4160
   1 P3V3_AUX      A @T6G_MB_LIB.T6G(SCH_1):P3V3_AUX
   2 GPU_3V3IO_RSVD4      B @T6G_MB_LIB.T6G(SCH_1):GPU_3V3IO_RSVD4

Q_RES_0402LF-100K,1%,1/16W,EMPTY,CS41002FB09  I8  R4163
   1 GPU_3V3IO_RSVD3      A @T6G_MB_LIB.T6G(SCH_1):GPU_3V3IO_RSVD3
   2    GND      B @T6G_MB_LIB.T6G(SCH_1):GND

Q_RES_0402LF-54.9K,1%,1/16W,EMPTY,CS35492FB03  I9  R4162
   1 P3V3_AUX      A @T6G_MB_LIB.T6G(SCH_1):P3V3_AUX
   2 GPU_3V3IO_RSVD3      B @T6G_MB_LIB.T6G(SCH_1):GPU_3V3IO_RSVD3

Q_RES_0402LF-100K,1%,1/16W,EMPTY,CS41002FB09  I13  R4159
   1 GPU_3V3IO_RSVD1      A @T6G_MB_LIB.T6G(SCH_1):GPU_3V3IO_RSVD1
   2    GND      B @T6G_MB_LIB.T6G(SCH_1):GND

Q_RES_0402LF-54.9K,1%,1/16W,EMPTY,CS35492FB03  I14  R4158
   1 P3V3_AUX      A @T6G_MB_LIB.T6G(SCH_1):P3V3_AUX
   2 GPU_3V3IO_RSVD1      B @T6G_MB_LIB.T6G(SCH_1):GPU_3V3IO_RSVD1

MOSFET_NCH_DUAL-PJT138K,SMLF,IC,BAM138K0003  I17  Q136
   1    GND     S1 @T6G_MB_LIB.T6G(SCH_1):GND
   2 GPU_3V3IO_RSVD4     G1 @T6G_MB_LIB.T6G(SCH_1):GPU_3V3IO_RSVD4
   6 GPU_3V3IO_RSVD4_N     D1 @T6G_MB_LIB.T6G(SCH_1):GPU_3V3IO_RSVD4_N

Q_RES_0402LF-4.7K,5%,1/16W,CHIP,CS24702JB10  I18  R4165
   1 P3V3_AUX      A @T6G_MB_LIB.T6G(SCH_1):P3V3_AUX
   2 GPU_3V3IO_RSVD4_N      B @T6G_MB_LIB.T6G(SCH_1):GPU_3V3IO_RSVD4_N

MOSFET_NCH_DUAL-PJT138K,SMLF,IC,BAM138K0003  I21  Q137
   1    GND     S1 @T6G_MB_LIB.T6G(SCH_1):GND
   2 GPU_3V3IO_RSVD3     G1 @T6G_MB_LIB.T6G(SCH_1):GPU_3V3IO_RSVD3
   6 GPU_3V3IO_RSVD3_N     D1 @T6G_MB_LIB.T6G(SCH_1):GPU_3V3IO_RSVD3_N

MOSFET_NCH_DUAL-PJT138K,SMLF,IC,BAM138K0003  I22  Q136
   3 GPU_3V3IO_RSVD4_ISO     D2 @T6G_MB_LIB.T6G(SCH_1):GPU_3V3IO_RSVD4_ISO
   5 GPU_3V3IO_RSVD4_N     G2 @T6G_MB_LIB.T6G(SCH_1):GPU_3V3IO_RSVD4_N
   4    GND     S2 @T6G_MB_LIB.T6G(SCH_1):GND

Q_RES_0402LF-4.7K,5%,1/16W,CHIP,CS24702JB10  I23  R4166
   1 P3V3_AUX      A @T6G_MB_LIB.T6G(SCH_1):P3V3_AUX
   2 GPU_3V3IO_RSVD3_N      B @T6G_MB_LIB.T6G(SCH_1):GPU_3V3IO_RSVD3_N

MOSFET_NCH_DUAL-PJT138K,SMLF,IC,BAM138K0003  I25  Q135
   1    GND     S1 @T6G_MB_LIB.T6G(SCH_1):GND
   2 GPU_3V3IO_RSVD1     G1 @T6G_MB_LIB.T6G(SCH_1):GPU_3V3IO_RSVD1
   6 GPU_3V3IO_RSVD1_N     D1 @T6G_MB_LIB.T6G(SCH_1):GPU_3V3IO_RSVD1_N

Q_RES_0402LF-4.7K,5%,1/16W,CHIP,CS24702JB10  I27  R4164
   1 P3V3_AUX      A @T6G_MB_LIB.T6G(SCH_1):P3V3_AUX
   2 GPU_3V3IO_RSVD1_N      B @T6G_MB_LIB.T6G(SCH_1):GPU_3V3IO_RSVD1_N

MOSFET_NCH_DUAL-PJT138K,SMLF,IC,BAM138K0003  I28  Q137
   3 GPU_3V3IO_RSVD3_ISO     D2 @T6G_MB_LIB.T6G(SCH_1):GPU_3V3IO_RSVD3_ISO
   5 GPU_3V3IO_RSVD3_N     G2 @T6G_MB_LIB.T6G(SCH_1):GPU_3V3IO_RSVD3_N
   4    GND     S2 @T6G_MB_LIB.T6G(SCH_1):GND

MOSFET_NCH_DUAL-PJT138K,SMLF,IC,BAM138K0003  I29  Q135
   3 GPU_3V3IO_RSVD1_ISO     D2 @T6G_MB_LIB.T6G(SCH_1):GPU_3V3IO_RSVD1_ISO
   5 GPU_3V3IO_RSVD1_N     G2 @T6G_MB_LIB.T6G(SCH_1):GPU_3V3IO_RSVD1_N
   4    GND     S2 @T6G_MB_LIB.T6G(SCH_1):GND

Q_CAP_0402-0.1UF,25V,10%,X7R,CH4104K1B00  I33  C5
   1 GPU_3V3IO_RSVD4_ISO      A @T6G_MB_LIB.T6G(SCH_1):GPU_3V3IO_RSVD4_ISO
   2    GND      B @T6G_MB_LIB.T6G(SCH_1):GND

Q_RES_0402LF-100K,1%,1/16W,CHIP,CS41002FB09  I35  R4168
   1 P3V3_AUX      A @T6G_MB_LIB.T6G(SCH_1):P3V3_AUX
   2 GPU_3V3IO_RSVD4_ISO      B @T6G_MB_LIB.T6G(SCH_1):GPU_3V3IO_RSVD4_ISO

Q_RES_0402LF-100K,1%,1/16W,CHIP,CS41002FB09  I39  R4169
   1 P3V3_AUX      A @T6G_MB_LIB.T6G(SCH_1):P3V3_AUX
   2 GPU_3V3IO_RSVD3_ISO      B @T6G_MB_LIB.T6G(SCH_1):GPU_3V3IO_RSVD3_ISO

Q_CAP_0402-0.1UF,25V,10%,X7R,CH4104K1B00  I42  C7
   1 GPU_3V3IO_RSVD3_ISO      A @T6G_MB_LIB.T6G(SCH_1):GPU_3V3IO_RSVD3_ISO
   2    GND      B @T6G_MB_LIB.T6G(SCH_1):GND

Q_CAP_0402-0.1UF,25V,10%,X7R,CH4104K1B00  I44  C4
   1 GPU_3V3IO_RSVD1_ISO      A @T6G_MB_LIB.T6G(SCH_1):GPU_3V3IO_RSVD1_ISO
   2    GND      B @T6G_MB_LIB.T6G(SCH_1):GND

Q_RES_0402LF-100K,1%,1/16W,CHIP,CS41002FB09  I47  R4167
   1 P3V3_AUX      A @T6G_MB_LIB.T6G(SCH_1):P3V3_AUX
   2 GPU_3V3IO_RSVD1_ISO      B @T6G_MB_LIB.T6G(SCH_1):GPU_3V3IO_RSVD1_ISO

MOSFET_NCH_DUAL-PJT138K,SMLF,IC,BAM138K0003  I55  Q148
   3 HGX_DETECT_N_ISO     D2 @T6G_MB_LIB.T6G(SCH_1):HGX_DETECT_N_ISO
   5 HGX_DETECT     G2 @T6G_MB_LIB.T6G(SCH_1):HGX_DETECT
   4    GND     S2 @T6G_MB_LIB.T6G(SCH_1):GND

Q_RES_0402LF-4.7K,5%,1/16W,CHIP,CS24702JB10  I57  R4545
   1 P3V3_AUX      A @T6G_MB_LIB.T6G(SCH_1):P3V3_AUX
   2 HGX_DETECT      B @T6G_MB_LIB.T6G(SCH_1):HGX_DETECT

MOSFET_NCH_DUAL-PJT138K,SMLF,IC,BAM138K0003  I61  Q148
   1    GND     S1 @T6G_MB_LIB.T6G(SCH_1):GND
   2 HGX_DETECT_N     G1 @T6G_MB_LIB.T6G(SCH_1):HGX_DETECT_N
   6 HGX_DETECT     D1 @T6G_MB_LIB.T6G(SCH_1):HGX_DETECT

Q_RES_0402LF-100K,1%,1/16W,EMPTY,CS41002FB09  I62  R4544
   1 HGX_DETECT_N      A @T6G_MB_LIB.T6G(SCH_1):HGX_DETECT_N
   2    GND      B @T6G_MB_LIB.T6G(SCH_1):GND

Q_RES_0402LF-1K,1%,1/16W,CHIP,CS21002FB06  I85  R4543
   1 P3V3_AUX      A @T6G_MB_LIB.T6G(SCH_1):P3V3_AUX
   2 HGX_DETECT_N      B @T6G_MB_LIB.T6G(SCH_1):HGX_DETECT_N

74LVC2G17GW-74LVC2G17GW,SMLF,IC,AL2G0017005  I86  U316
   5 P3V3_AUX    VCC @T6G_MB_LIB.T6G(SCH_1):P3V3_AUX
   4 NC_U316_2Y     B1 @T6G_MB_LIB.T6G(SCH_1):NC_U316_2Y
   2    GND    GND @T6G_MB_LIB.T6G(SCH_1):GND
   1 SWB_HSC_EN     A0 @T6G_MB_LIB.T6G(SCH_1):SWB_HSC_EN
   3    GND     A1 @T6G_MB_LIB.T6G(SCH_1):GND
   6 SWB_HSC_EN_BUF_R     B0 @T6G_MB_LIB.T6G(SCH_1):SWB_HSC_EN_BUF_R

Q_RES_0402LF-100K,1%,1/16W,CHIP,CS41002FB09  I87  R4548
   1 SWB_HSC_EN      A @T6G_MB_LIB.T6G(SCH_1):SWB_HSC_EN
   2    GND      B @T6G_MB_LIB.T6G(SCH_1):GND

Q_RES_0402LF-100K,1%,1/16W,EMPTY,CS41002FB09  I89  R4547
   1 P3V3_AUX      A @T6G_MB_LIB.T6G(SCH_1):P3V3_AUX
   2 SWB_HSC_EN      B @T6G_MB_LIB.T6G(SCH_1):SWB_HSC_EN

Q_CAP_0402-0.1UF,25V,10%,X7R,CH4104K1B00  I93  C8
   1 P3V3_AUX      A @T6G_MB_LIB.T6G(SCH_1):P3V3_AUX
   2    GND      B @T6G_MB_LIB.T6G(SCH_1):GND

Q_RES_0402LF-49.9,1%,1/16W,CHIP,CS04992FB07  I97  R4550
   1 SWB_HSC_EN_BUF_R      A @T6G_MB_LIB.T6G(SCH_1):SWB_HSC_EN_BUF_R
   2 SWB_HSC_EN_BUF      B @T6G_MB_LIB.T6G(SCH_1):SWB_HSC_EN_BUF

Q_RES_0402LF-4.7K,5%,1/16W,EMPTY,CS24702JB10  I98  R4549
   1 P3V3_AUX      A @T6G_MB_LIB.T6G(SCH_1):P3V3_AUX
   2 SWB_HSC_EN_BUF_R      B @T6G_MB_LIB.T6G(SCH_1):SWB_HSC_EN_BUF_R

Q_RES_0402LF-4.7K,5%,1/16W,EMPTY,CS24702JB10  I99  R4555
   1 SWB_HSC_EN_BUF_R      A @T6G_MB_LIB.T6G(SCH_1):SWB_HSC_EN_BUF_R
   2    GND      B @T6G_MB_LIB.T6G(SCH_1):GND

Q_RES_0402LF-0,5%,1/16W,EMPTY,CS00002JB13  I107  R4569
   1 GPU_3V3IO_RSVD1      A @T6G_MB_LIB.T6G(SCH_1):GPU_3V3IO_RSVD1
   2 GPU_3V3IO_RSVD1_ISO      B @T6G_MB_LIB.T6G(SCH_1):GPU_3V3IO_RSVD1_ISO

Q_RES_0402LF-0,5%,1/16W,EMPTY,CS00002JB13  I108  R4571
   1 GPU_3V3IO_RSVD4      A @T6G_MB_LIB.T6G(SCH_1):GPU_3V3IO_RSVD4
   2 GPU_3V3IO_RSVD4_ISO      B @T6G_MB_LIB.T6G(SCH_1):GPU_3V3IO_RSVD4_ISO

Q_RES_0402LF-0,5%,1/16W,EMPTY,CS00002JB13  I109  R4570
   1 GPU_3V3IO_RSVD3      A @T6G_MB_LIB.T6G(SCH_1):GPU_3V3IO_RSVD3
   2 GPU_3V3IO_RSVD3_ISO      B @T6G_MB_LIB.T6G(SCH_1):GPU_3V3IO_RSVD3_ISO

Q_RES_0402LF-100K,1%,1/16W,EMPTY,CS41002FB09  I110  R4546
   1 P3V3_AUX      A @T6G_MB_LIB.T6G(SCH_1):P3V3_AUX
   2 HGX_DETECT_N_ISO      B @T6G_MB_LIB.T6G(SCH_1):HGX_DETECT_N_ISO

Q_CAP_0402-0.1UF,25V,10%,EMPTY,CH4104K1B00  I111  C6
   1 HGX_DETECT_N_ISO      A @T6G_MB_LIB.T6G(SCH_1):HGX_DETECT_N_ISO
   2    GND      B @T6G_MB_LIB.T6G(SCH_1):GND


DRAWING: @T6G_MB_LIB.T6G(SCH_1):PAGE333 

Q_RES_0402LF-4.7K,5%,1/16W,CHIP,CS24702JB10  I14  R2835
   1 P3V3_AUX      A @T6G_MB_LIB.T6G(SCH_1):P3V3_AUX
   2 BIC_MONITER_N      B @T6G_MB_LIB.T6G(SCH_1):BIC_MONITER_N

Q_RES_0402LF-4.7K,5%,1/16W,CHIP,CS24702JB10  I18  R2834
   1 P3V3_AUX      A @T6G_MB_LIB.T6G(SCH_1):P3V3_AUX
   2 RST_BMC_FROM_SWB      B @T6G_MB_LIB.T6G(SCH_1):RST_BMC_FROM_SWB

Q_RES_0402LF-4.7K,5%,1/16W,CHIP,CS24702JB10  I19  R2836
   1 P3V3_AUX      A @T6G_MB_LIB.T6G(SCH_1):P3V3_AUX
   2 FM_SWB_BIC_READY      B @T6G_MB_LIB.T6G(SCH_1):FM_SWB_BIC_READY

Q_RES_0402LF-4.7K,5%,1/16W,CHIP,CS24702JB10  I24  R2841
   1 P3V3_AUX      A @T6G_MB_LIB.T6G(SCH_1):P3V3_AUX
   2 FM_SWB_PWRGD_N      B @T6G_MB_LIB.T6G(SCH_1):FM_SWB_PWRGD_N

Q_RES_0402LF-4.7K,5%,1/16W,CHIP,CS24702JB10  I30  R2842
   1 P3V3_AUX      A @T6G_MB_LIB.T6G(SCH_1):P3V3_AUX
   2 FM_GPU_PWRGD_N      B @T6G_MB_LIB.T6G(SCH_1):FM_GPU_PWRGD_N

MOSFET_NCH_DUAL-PJT138K,SMLF,IC,BAM138K0003  I33  Q67
   1    GND     S1 @T6G_MB_LIB.T6G(SCH_1):GND
   2 BIC_MONITER     G1 @T6G_MB_LIB.T6G(SCH_1):BIC_MONITER
   6 BIC_MONITER_N     D1 @T6G_MB_LIB.T6G(SCH_1):BIC_MONITER_N

MOSFET_NCH_DUAL-PJT138K,SMLF,IC,BAM138K0003  I35  Q70
   1    GND     S1 @T6G_MB_LIB.T6G(SCH_1):GND
   2 FM_SWB_BIC_READY_N     G1 @T6G_MB_LIB.T6G(SCH_1):FM_SWB_BIC_READY_N
   6 FM_SWB_BIC_READY     D1 @T6G_MB_LIB.T6G(SCH_1):FM_SWB_BIC_READY

MOSFET_NCH_DUAL-PJT138K,SMLF,IC,BAM138K0003  I37  Q72
   1    GND     S1 @T6G_MB_LIB.T6G(SCH_1):GND
   2 FM_GPU_PWRGD     G1 @T6G_MB_LIB.T6G(SCH_1):FM_GPU_PWRGD
   6 FM_GPU_PWRGD_N     D1 @T6G_MB_LIB.T6G(SCH_1):FM_GPU_PWRGD_N

Q_RES_0402LF-100K,1%,1/16W,EMPTY,CS41002FB09  I56  R2831
   1 BIC_MONITER      A @T6G_MB_LIB.T6G(SCH_1):BIC_MONITER
   2    GND      B @T6G_MB_LIB.T6G(SCH_1):GND

Q_RES_0402LF-100K,1%,1/16W,EMPTY,CS41002FB09  I58  R2829
   1 RST_BMC_FROM_SWB_N      A @T6G_MB_LIB.T6G(SCH_1):RST_BMC_FROM_SWB_N
   2    GND      B @T6G_MB_LIB.T6G(SCH_1):GND

Q_RES_0402LF-100K,1%,1/16W,EMPTY,CS41002FB09  I60  R2833
   1 FM_SWB_BIC_READY_N      A @T6G_MB_LIB.T6G(SCH_1):FM_SWB_BIC_READY_N
   2    GND      B @T6G_MB_LIB.T6G(SCH_1):GND

Q_RES_0402LF-100K,1%,1/16W,CHIP,CS41002FB09  I62  R2838
   1 FM_SWB_PWRGD      A @T6G_MB_LIB.T6G(SCH_1):FM_SWB_PWRGD
   2    GND      B @T6G_MB_LIB.T6G(SCH_1):GND

Q_RES_0402LF-100K,1%,1/16W,CHIP,CS41002FB09  I66  R2828
   1 P3V3_AUX      A @T6G_MB_LIB.T6G(SCH_1):P3V3_AUX
   2 RST_BMC_FROM_SWB_N      B @T6G_MB_LIB.T6G(SCH_1):RST_BMC_FROM_SWB_N

Q_RES_0402LF-100K,1%,1/16W,CHIP,CS41002FB09  I67  R2832
   1 P3V3_AUX      A @T6G_MB_LIB.T6G(SCH_1):P3V3_AUX
   2 FM_SWB_BIC_READY_N      B @T6G_MB_LIB.T6G(SCH_1):FM_SWB_BIC_READY_N

Q_RES_0402LF-100K,1%,1/16W,CHIP,CS41002FB09  I68  R2830
   1 P3V3_AUX      A @T6G_MB_LIB.T6G(SCH_1):P3V3_AUX
   2 BIC_MONITER      B @T6G_MB_LIB.T6G(SCH_1):BIC_MONITER

Q_RES_0402LF-100K,1%,1/16W,EMPTY,CS41002FB09  I80  R2837
   1 P3V3_AUX      A @T6G_MB_LIB.T6G(SCH_1):P3V3_AUX
   2 FM_SWB_PWRGD      B @T6G_MB_LIB.T6G(SCH_1):FM_SWB_PWRGD

MOSFET_NCH_DUAL-PJT138K,SMLF,IC,BAM138K0003  I82  Q67
   3 BIC_MONITER_ISO     D2 @T6G_MB_LIB.T6G(SCH_1):BIC_MONITER_ISO
   5 BIC_MONITER_N     G2 @T6G_MB_LIB.T6G(SCH_1):BIC_MONITER_N
   4    GND     S2 @T6G_MB_LIB.T6G(SCH_1):GND

MOSFET_NCH_DUAL-PJT138K,SMLF,IC,BAM138K0003  I88  Q69
   3 RST_BMC_FROM_SWB_ISO_N     D2 @T6G_MB_LIB.T6G(SCH_1):RST_BMC_FROM_SWB_ISO_N
   5 RST_BMC_FROM_SWB     G2 @T6G_MB_LIB.T6G(SCH_1):RST_BMC_FROM_SWB
   4    GND     S2 @T6G_MB_LIB.T6G(SCH_1):GND

Q_RES_0402LF-100K,1%,1/16W,CHIP,CS41002FB09  I91  R2919
   1 P3V3_AUX      A @T6G_MB_LIB.T6G(SCH_1):P3V3_AUX
   2 RST_BMC_FROM_SWB_ISO_N      B @T6G_MB_LIB.T6G(SCH_1):RST_BMC_FROM_SWB_ISO_N

Q_CAP_0402-0.1UF,25V,10%,X7R,CH4104K1B00  I92  C1754
   1 FM_SWB_BIC_READY_ISO_N      A @T6G_MB_LIB.T6G(SCH_1):FM_SWB_BIC_READY_ISO_N
   2    GND      B @T6G_MB_LIB.T6G(SCH_1):GND

MOSFET_NCH_DUAL-PJT138K,SMLF,IC,BAM138K0003  I100  Q71
   3 FM_SWB_PWRGD_ISO     D2 @T6G_MB_LIB.T6G(SCH_1):FM_SWB_PWRGD_ISO
   5 FM_SWB_PWRGD_N     G2 @T6G_MB_LIB.T6G(SCH_1):FM_SWB_PWRGD_N
   4    GND     S2 @T6G_MB_LIB.T6G(SCH_1):GND

Q_RES_0402LF-100K,1%,1/16W,CHIP,CS41002FB09  I101  R2934
   1 P3V3_AUX      A @T6G_MB_LIB.T6G(SCH_1):P3V3_AUX
   2 FM_SWB_PWRGD_ISO      B @T6G_MB_LIB.T6G(SCH_1):FM_SWB_PWRGD_ISO

Q_CAP_0402-0.1UF,25V,10%,X7R,CH4104K1B00  I105  C1756
   1 FM_GPU_PWRGD_ISO      A @T6G_MB_LIB.T6G(SCH_1):FM_GPU_PWRGD_ISO
   2    GND      B @T6G_MB_LIB.T6G(SCH_1):GND

Q_RES_0402LF-100K,1%,1/16W,CHIP,CS41002FB09  I109  R2935
   1 P3V3_AUX      A @T6G_MB_LIB.T6G(SCH_1):P3V3_AUX
   2 FM_GPU_PWRGD_ISO      B @T6G_MB_LIB.T6G(SCH_1):FM_GPU_PWRGD_ISO

Q_CAP_0402-0.1UF,25V,10%,X7R,CH4104K1B00  I111  C1774
   1 FM_SWB_PWRGD_ISO      A @T6G_MB_LIB.T6G(SCH_1):FM_SWB_PWRGD_ISO
   2    GND      B @T6G_MB_LIB.T6G(SCH_1):GND

Q_CAP_0402-0.1UF,25V,10%,X7R,CH4104K1B00  I114  C1773
   1 BIC_MONITER_ISO      A @T6G_MB_LIB.T6G(SCH_1):BIC_MONITER_ISO
   2    GND      B @T6G_MB_LIB.T6G(SCH_1):GND

Q_CAP_0402-0.1UF,25V,10%,X7R,CH4104K1B00  I116  C1772
   1 RST_BMC_FROM_SWB_ISO_N      A @T6G_MB_LIB.T6G(SCH_1):RST_BMC_FROM_SWB_ISO_N
   2    GND      B @T6G_MB_LIB.T6G(SCH_1):GND

MOSFET_NCH_DUAL-PJT138K,SMLF,IC,BAM138K0003  I117  Q69
   1    GND     S1 @T6G_MB_LIB.T6G(SCH_1):GND
   2 RST_BMC_FROM_SWB_N     G1 @T6G_MB_LIB.T6G(SCH_1):RST_BMC_FROM_SWB_N
   6 RST_BMC_FROM_SWB     D1 @T6G_MB_LIB.T6G(SCH_1):RST_BMC_FROM_SWB

MOSFET_NCH_DUAL-PJT138K,SMLF,IC,BAM138K0003  I118  Q71
   1    GND     S1 @T6G_MB_LIB.T6G(SCH_1):GND
   2 FM_SWB_PWRGD     G1 @T6G_MB_LIB.T6G(SCH_1):FM_SWB_PWRGD
   6 FM_SWB_PWRGD_N     D1 @T6G_MB_LIB.T6G(SCH_1):FM_SWB_PWRGD_N

MOSFET_NCH_DUAL-PJT138K,SMLF,IC,BAM138K0003  I119  Q72
   3 FM_GPU_PWRGD_ISO     D2 @T6G_MB_LIB.T6G(SCH_1):FM_GPU_PWRGD_ISO
   5 FM_GPU_PWRGD_N     G2 @T6G_MB_LIB.T6G(SCH_1):FM_GPU_PWRGD_N
   4    GND     S2 @T6G_MB_LIB.T6G(SCH_1):GND

MOSFET_NCH_DUAL-PJT138K,SMLF,IC,BAM138K0003  I120  Q70
   3 FM_SWB_BIC_READY_ISO_N     D2 @T6G_MB_LIB.T6G(SCH_1):FM_SWB_BIC_READY_ISO_N
   5 FM_SWB_BIC_READY     G2 @T6G_MB_LIB.T6G(SCH_1):FM_SWB_BIC_READY
   4    GND     S2 @T6G_MB_LIB.T6G(SCH_1):GND

MOSFET_NCH_DUAL-PJT138K,SMLF,IC,BAM138K0003  I121  Q74
   1    GND     S1 @T6G_MB_LIB.T6G(SCH_1):GND
   2 FM_SMB_2_ALERT_GPU_N     G1 @T6G_MB_LIB.T6G(SCH_1):FM_SMB_2_ALERT_GPU_N
   6 FM_SMB_2_ALERT_GPU     D1 @T6G_MB_LIB.T6G(SCH_1):FM_SMB_2_ALERT_GPU

MOSFET_NCH_DUAL-PJT138K,SMLF,IC,BAM138K0003  I122  Q74
   3 FM_SMB_2_ALERT_GPU_ISO_N     D2 @T6G_MB_LIB.T6G(SCH_1):FM_SMB_2_ALERT_GPU_ISO_N
   5 FM_SMB_2_ALERT_GPU     G2 @T6G_MB_LIB.T6G(SCH_1):FM_SMB_2_ALERT_GPU
   4    GND     S2 @T6G_MB_LIB.T6G(SCH_1):GND

Q_CAP_0402-0.1UF,25V,10%,X7R,CH4104K1B00  I125  C1804
   1 FM_SMB_2_ALERT_GPU_ISO_N      A @T6G_MB_LIB.T6G(SCH_1):FM_SMB_2_ALERT_GPU_ISO_N
   2    GND      B @T6G_MB_LIB.T6G(SCH_1):GND

Q_RES_0402LF-4.7K,5%,1/16W,CHIP,CS24702JB10  I129  R3034
   1 P3V3_AUX      A @T6G_MB_LIB.T6G(SCH_1):P3V3_AUX
   2 FM_SMB_2_ALERT_GPU      B @T6G_MB_LIB.T6G(SCH_1):FM_SMB_2_ALERT_GPU

Q_RES_0402LF-100K,1%,1/16W,EMPTY,CS41002FB09  I134  R3032
   1 FM_SMB_2_ALERT_GPU_N      A @T6G_MB_LIB.T6G(SCH_1):FM_SMB_2_ALERT_GPU_N
   2    GND      B @T6G_MB_LIB.T6G(SCH_1):GND

Q_RES_0402LF-100K,1%,1/16W,EMPTY,CS41002FB09  I139  R3028
   1 FM_SMB_1_ALERT_GPU_N      A @T6G_MB_LIB.T6G(SCH_1):FM_SMB_1_ALERT_GPU_N
   2    GND      B @T6G_MB_LIB.T6G(SCH_1):GND

Q_RES_0402LF-4.7K,5%,1/16W,CHIP,CS24702JB10  I144  R3029
   1 P3V3_AUX      A @T6G_MB_LIB.T6G(SCH_1):P3V3_AUX
   2 FM_SMB_1_ALERT_GPU      B @T6G_MB_LIB.T6G(SCH_1):FM_SMB_1_ALERT_GPU

Q_CAP_0402-0.1UF,25V,10%,X7R,CH4104K1B00  I148  C1802
   1 FM_SMB_1_ALERT_GPU_ISO_N      A @T6G_MB_LIB.T6G(SCH_1):FM_SMB_1_ALERT_GPU_ISO_N
   2    GND      B @T6G_MB_LIB.T6G(SCH_1):GND

MOSFET_NCH_DUAL-PJT138K,SMLF,IC,BAM138K0003  I151  Q75
   3 FM_SMB_1_ALERT_GPU_ISO_N     D2 @T6G_MB_LIB.T6G(SCH_1):FM_SMB_1_ALERT_GPU_ISO_N
   5 FM_SMB_1_ALERT_GPU     G2 @T6G_MB_LIB.T6G(SCH_1):FM_SMB_1_ALERT_GPU
   4    GND     S2 @T6G_MB_LIB.T6G(SCH_1):GND

MOSFET_NCH_DUAL-PJT138K,SMLF,IC,BAM138K0003  I152  Q75
   1    GND     S1 @T6G_MB_LIB.T6G(SCH_1):GND
   2 FM_SMB_1_ALERT_GPU_N     G1 @T6G_MB_LIB.T6G(SCH_1):FM_SMB_1_ALERT_GPU_N
   6 FM_SMB_1_ALERT_GPU     D1 @T6G_MB_LIB.T6G(SCH_1):FM_SMB_1_ALERT_GPU

MOSFET_NCH_DUAL-PJT138K,SMLF,IC,BAM138K0003  I154  Q96
   1    GND     S1 @T6G_MB_LIB.T6G(SCH_1):GND
   2 GPU_FPGA_READY     G1 @T6G_MB_LIB.T6G(SCH_1):GPU_FPGA_READY
   6 GPU_FPGA_READY_N     D1 @T6G_MB_LIB.T6G(SCH_1):GPU_FPGA_READY_N

Q_CAP_0402-0.1UF,25V,10%,X7R,CH4104K1B00  I156  C1881
   1 GPU_FPGA_READY_ISO      A @T6G_MB_LIB.T6G(SCH_1):GPU_FPGA_READY_ISO
   2    GND      B @T6G_MB_LIB.T6G(SCH_1):GND

Q_RES_0402LF-100K,1%,1/16W,CHIP,CS41002FB09  I158  R3321
   1 P3V3_AUX      A @T6G_MB_LIB.T6G(SCH_1):P3V3_AUX
   2 GPU_FPGA_READY_ISO      B @T6G_MB_LIB.T6G(SCH_1):GPU_FPGA_READY_ISO

MOSFET_NCH_DUAL-PJT138K,SMLF,IC,BAM138K0003  I159  Q96
   3 GPU_FPGA_READY_ISO     D2 @T6G_MB_LIB.T6G(SCH_1):GPU_FPGA_READY_ISO
   5 GPU_FPGA_READY_N     G2 @T6G_MB_LIB.T6G(SCH_1):GPU_FPGA_READY_N
   4    GND     S2 @T6G_MB_LIB.T6G(SCH_1):GND

Q_RES_0402LF-4.7K,5%,1/16W,CHIP,CS24702JB10  I162  R3320
   1 P3V3_AUX      A @T6G_MB_LIB.T6G(SCH_1):P3V3_AUX
   2 GPU_FPGA_READY_N      B @T6G_MB_LIB.T6G(SCH_1):GPU_FPGA_READY_N

Q_RES_0402LF-100K,1%,1/16W,EMPTY,CS41002FB09  I171  R3318
   1 P3V3_AUX      A @T6G_MB_LIB.T6G(SCH_1):P3V3_AUX
   2 GPU_FPGA_READY      B @T6G_MB_LIB.T6G(SCH_1):GPU_FPGA_READY

Q_RES_0402LF-54.9K,1%,1/16W,CHIP,CS35492FB03  I172  R3511
   1 GPU_FPGA_READY      A @T6G_MB_LIB.T6G(SCH_1):GPU_FPGA_READY
   2    GND      B @T6G_MB_LIB.T6G(SCH_1):GND

Q_RES_0402LF-54.9K,1%,1/16W,CHIP,CS35492FB03  I173  R3513
   1 FM_GPU_PWRGD      A @T6G_MB_LIB.T6G(SCH_1):FM_GPU_PWRGD
   2    GND      B @T6G_MB_LIB.T6G(SCH_1):GND

Q_RES_0402LF-100K,1%,1/16W,EMPTY,CS41002FB09  I174  R3512
   1 P3V3_AUX      A @T6G_MB_LIB.T6G(SCH_1):P3V3_AUX
   2 FM_GPU_PWRGD      B @T6G_MB_LIB.T6G(SCH_1):FM_GPU_PWRGD

Q_RES_0402LF-54.9K,1%,1/16W,CHIP,CS35492FB03  I175  R3514
   1 P3V3_AUX      A @T6G_MB_LIB.T6G(SCH_1):P3V3_AUX
   2 FM_SMB_2_ALERT_GPU_N      B @T6G_MB_LIB.T6G(SCH_1):FM_SMB_2_ALERT_GPU_N

Q_RES_0402LF-54.9K,1%,1/16W,CHIP,CS35492FB03  I176  R3510
   1 P3V3_AUX      A @T6G_MB_LIB.T6G(SCH_1):P3V3_AUX
   2 FM_SMB_1_ALERT_GPU_N      B @T6G_MB_LIB.T6G(SCH_1):FM_SMB_1_ALERT_GPU_N

Q_RES_0402LF-100K,1%,1/16W,CHIP,CS41002FB09  I177  R2920
   1 P3V3_AUX      A @T6G_MB_LIB.T6G(SCH_1):P3V3_AUX
   2 BIC_MONITER_ISO      B @T6G_MB_LIB.T6G(SCH_1):BIC_MONITER_ISO

Q_RES_0402LF-100K,1%,1/16W,CHIP,CS41002FB09  I178  R3030
   1 P3V3_AUX      A @T6G_MB_LIB.T6G(SCH_1):P3V3_AUX
   2 FM_SMB_1_ALERT_GPU_ISO_N      B @T6G_MB_LIB.T6G(SCH_1):FM_SMB_1_ALERT_GPU_ISO_N

Q_RES_0402LF-100K,1%,1/16W,CHIP,CS41002FB09  I179  R3035
   1 P3V3_AUX      A @T6G_MB_LIB.T6G(SCH_1):P3V3_AUX
   2 FM_SMB_2_ALERT_GPU_ISO_N      B @T6G_MB_LIB.T6G(SCH_1):FM_SMB_2_ALERT_GPU_ISO_N

Q_RES_0402LF-100K,1%,1/16W,CHIP,CS41002FB09  I180  R2933
   1 P3V3_AUX      A @T6G_MB_LIB.T6G(SCH_1):P3V3_AUX
   2 FM_SWB_BIC_READY_ISO_N      B @T6G_MB_LIB.T6G(SCH_1):FM_SWB_BIC_READY_ISO_N


DRAWING: @T6G_MB_LIB.T6G(SCH_1):PAGE334 

74LVC2G17GW-74LVC2G17GW,SMLF,IC,AL2G0017005  I26  U253
   5 P3V3_AUX    VCC @T6G_MB_LIB.T6G(SCH_1):P3V3_AUX
   4 GPU_BASE_STBY_EN_BUF_R     B1 @T6G_MB_LIB.T6G(SCH_1):GPU_BASE_STBY_EN_BUF_R
   2    GND    GND @T6G_MB_LIB.T6G(SCH_1):GND
   1 GPU_FPGA_BOOT_EN     A0 @T6G_MB_LIB.T6G(SCH_1):GPU_FPGA_BOOT_EN
   3 GPU_BASE_STBY_EN     A1 @T6G_MB_LIB.T6G(SCH_1):GPU_BASE_STBY_EN
   6 GPU_FPGA_BOOT_EN_BUF_R     B0 @T6G_MB_LIB.T6G(SCH_1):GPU_FPGA_BOOT_EN_BUF_R

Q_CAP_0402-0.1UF,25V,10%,X7R,CH4104K1B00  I29  C1958
   1 P3V3_AUX      A @T6G_MB_LIB.T6G(SCH_1):P3V3_AUX
   2    GND      B @T6G_MB_LIB.T6G(SCH_1):GND

Q_RES_0402LF-49.9,1%,1/16W,CHIP,CS04992FB07  I62  R3392
   1 GPU_BASE_STBY_EN_BUF_R      A @T6G_MB_LIB.T6G(SCH_1):GPU_BASE_STBY_EN_BUF_R
   2 GPU_BASE_STBY_EN_BUF      B @T6G_MB_LIB.T6G(SCH_1):GPU_BASE_STBY_EN_BUF

Q_RES_0402LF-100K,1%,1/16W,CHIP,CS41002FB09  I95  R3452
   1 GPU_BASE_STBY_EN      A @T6G_MB_LIB.T6G(SCH_1):GPU_BASE_STBY_EN
   2    GND      B @T6G_MB_LIB.T6G(SCH_1):GND

Q_RES_0402LF-10K,1%,1/16W,CHIP,CS31002FB08  I123  R3457
   1 GPU_BASE_STBY_EN_BUF_R      A @T6G_MB_LIB.T6G(SCH_1):GPU_BASE_STBY_EN_BUF_R
   2    GND      B @T6G_MB_LIB.T6G(SCH_1):GND

Q_RES_0402LF-100K,1%,1/16W,EMPTY,CS41002FB09  I124  R3456
   1 P3V3_AUX      A @T6G_MB_LIB.T6G(SCH_1):P3V3_AUX
   2 GPU_BASE_STBY_EN_BUF_R      B @T6G_MB_LIB.T6G(SCH_1):GPU_BASE_STBY_EN_BUF_R

Q_RES_0402LF-4.7K,5%,1/16W,EMPTY,CS24702JB10  I127  R3451
   1 P3V3_AUX      A @T6G_MB_LIB.T6G(SCH_1):P3V3_AUX
   2 GPU_BASE_STBY_EN      B @T6G_MB_LIB.T6G(SCH_1):GPU_BASE_STBY_EN

Q_RES_0402LF-10K,1%,1/16W,CHIP,CS31002FB08  I139  R3455
   1 RST_PERST_2_SWB_BUF_R_N      A @T6G_MB_LIB.T6G(SCH_1):RST_PERST_2_SWB_BUF_R_N
   2    GND      B @T6G_MB_LIB.T6G(SCH_1):GND

Q_RES_0402LF-49.9,1%,1/16W,CHIP,CS04992FB07  I140  R3391
   1 RST_PERST_2_SWB_BUF_R_N      A @T6G_MB_LIB.T6G(SCH_1):RST_PERST_2_SWB_BUF_R_N
   2 RST_PERST_2_SWB_BUF_N      B @T6G_MB_LIB.T6G(SCH_1):RST_PERST_2_SWB_BUF_N

Q_CAP_0402-0.1UF,25V,10%,X7R,CH4104K1B00  I148  C1957
   1 P3V3_AUX      A @T6G_MB_LIB.T6G(SCH_1):P3V3_AUX
   2    GND      B @T6G_MB_LIB.T6G(SCH_1):GND

74LVC2G17GW-74LVC2G17GW,SMLF,IC,AL2G0017005  I153  U252
   5 P3V3_AUX    VCC @T6G_MB_LIB.T6G(SCH_1):P3V3_AUX
   4 RST_PERST_2_SWB_BUF_R_N     B1 @T6G_MB_LIB.T6G(SCH_1):RST_PERST_2_SWB_BUF_R_N
   2    GND    GND @T6G_MB_LIB.T6G(SCH_1):GND
   1 RST_PERST_CPU1_SWB_R_N     A0 @T6G_MB_LIB.T6G(SCH_1):RST_PERST_CPU1_SWB_R_N
   3 RST_PERST_CPU1_SWB_1_R_N     A1 @T6G_MB_LIB.T6G(SCH_1):RST_PERST_CPU1_SWB_1_R_N
   6 RST_PERST_0_SWB_BUF_R_N     B0 @T6G_MB_LIB.T6G(SCH_1):RST_PERST_0_SWB_BUF_R_N

Q_RES_0402LF-49.9,1%,1/16W,CHIP,CS04992FB07  I162  R3390
   1 GPU_FPGA_BOOT_EN_BUF_R      A @T6G_MB_LIB.T6G(SCH_1):GPU_FPGA_BOOT_EN_BUF_R
   2 GPU_FPGA_BOOT_EN_BUF      B @T6G_MB_LIB.T6G(SCH_1):GPU_FPGA_BOOT_EN_BUF

Q_RES_0402LF-100K,1%,1/16W,EMPTY,CS41002FB09  I164  R3453
   1 P3V3_AUX      A @T6G_MB_LIB.T6G(SCH_1):P3V3_AUX
   2 GPU_FPGA_BOOT_EN_BUF_R      B @T6G_MB_LIB.T6G(SCH_1):GPU_FPGA_BOOT_EN_BUF_R

Q_RES_0402LF-1K,1%,1/16W,CHIP,CS21002FB06  I165  R3454
   1 GPU_FPGA_BOOT_EN_BUF_R      A @T6G_MB_LIB.T6G(SCH_1):GPU_FPGA_BOOT_EN_BUF_R
   2    GND      B @T6G_MB_LIB.T6G(SCH_1):GND

Q_RES_0402LF-4.7K,5%,1/16W,EMPTY,CS24702JB10  I168  R3448
   1 P3V3_AUX      A @T6G_MB_LIB.T6G(SCH_1):P3V3_AUX
   2 GPU_FPGA_BOOT_EN      B @T6G_MB_LIB.T6G(SCH_1):GPU_FPGA_BOOT_EN

Q_RES_0402LF-100K,1%,1/16W,CHIP,CS41002FB09  I170  R3449
   1 GPU_FPGA_BOOT_EN      A @T6G_MB_LIB.T6G(SCH_1):GPU_FPGA_BOOT_EN
   2    GND      B @T6G_MB_LIB.T6G(SCH_1):GND

74LVC2G17GW-74LVC2G17GW,SMLF,IC,AL2G0017005  I173  U256
   5 P3V3_AUX    VCC @T6G_MB_LIB.T6G(SCH_1):P3V3_AUX
   4 FM_SWB_PWR_EN_R1_BUF     B1 @T6G_MB_LIB.T6G(SCH_1):FM_SWB_PWR_EN_R1_BUF
   2    GND    GND @T6G_MB_LIB.T6G(SCH_1):GND
   1 RST_PERST_CPU0_SWB_R_N     A0 @T6G_MB_LIB.T6G(SCH_1):RST_PERST_CPU0_SWB_R_N
   3 FM_SWB_PWR_EN_R     A1 @T6G_MB_LIB.T6G(SCH_1):FM_SWB_PWR_EN_R
   6 RST_PERST_1_SWB_BUF_R_N     B0 @T6G_MB_LIB.T6G(SCH_1):RST_PERST_1_SWB_BUF_R_N

Q_CAP_0402-0.1UF,25V,10%,X7R,CH4104K1B00  I175  C1977
   1 P3V3_AUX      A @T6G_MB_LIB.T6G(SCH_1):P3V3_AUX
   2    GND      B @T6G_MB_LIB.T6G(SCH_1):GND

Q_RES_0402LF-49.9,1%,1/16W,CHIP,CS04992FB07  I180  R3469
   1 RST_PERST_0_SWB_BUF_R_N      A @T6G_MB_LIB.T6G(SCH_1):RST_PERST_0_SWB_BUF_R_N
   2 RST_PERST_0_SWB_BUF_N      B @T6G_MB_LIB.T6G(SCH_1):RST_PERST_0_SWB_BUF_N

Q_RES_0402LF-10K,1%,1/16W,CHIP,CS31002FB08  I181  R3467
   1 RST_PERST_0_SWB_BUF_R_N      A @T6G_MB_LIB.T6G(SCH_1):RST_PERST_0_SWB_BUF_R_N
   2    GND      B @T6G_MB_LIB.T6G(SCH_1):GND

Q_RES_0402LF-49.9,1%,1/16W,CHIP,CS04992FB07  I183  R3468
   1 RST_PERST_1_SWB_BUF_R_N      A @T6G_MB_LIB.T6G(SCH_1):RST_PERST_1_SWB_BUF_R_N
   2 RST_PERST_1_SWB_BUF_N      B @T6G_MB_LIB.T6G(SCH_1):RST_PERST_1_SWB_BUF_N

Q_RES_0402LF-10K,1%,1/16W,CHIP,CS31002FB08  I184  R3466
   1 RST_PERST_1_SWB_BUF_R_N      A @T6G_MB_LIB.T6G(SCH_1):RST_PERST_1_SWB_BUF_R_N
   2    GND      B @T6G_MB_LIB.T6G(SCH_1):GND

Q_RES_0402LF-100K,1%,1/16W,EMPTY,CS41002FB09  I187  R2910
   1 P3V3_AUX      A @T6G_MB_LIB.T6G(SCH_1):P3V3_AUX
   2 FM_SWB_PWR_EN_R      B @T6G_MB_LIB.T6G(SCH_1):FM_SWB_PWR_EN_R

Q_RES_0402LF-4.7K,5%,1/16W,CHIP,CS24702JB10  I188  R2918
   1 FM_SWB_PWR_EN_R      A @T6G_MB_LIB.T6G(SCH_1):FM_SWB_PWR_EN_R
   2    GND      B @T6G_MB_LIB.T6G(SCH_1):GND

Q_RES_0402LF-4.7K,5%,1/16W,EMPTY,CS24702JB10  I192  R2914
   1 P3V3_AUX      A @T6G_MB_LIB.T6G(SCH_1):P3V3_AUX
   2 FM_SWB_PWR_EN_R1_BUF      B @T6G_MB_LIB.T6G(SCH_1):FM_SWB_PWR_EN_R1_BUF

Q_RES_0402LF-49.9,1%,1/16W,CHIP,CS04992FB07  I193  R3515
   1 FM_SWB_PWR_EN_R1_BUF      A @T6G_MB_LIB.T6G(SCH_1):FM_SWB_PWR_EN_R1_BUF
   2 FM_SWB_PWR_EN_R_BUF      B @T6G_MB_LIB.T6G(SCH_1):FM_SWB_PWR_EN_R_BUF

Q_RES_0402LF-4.7K,5%,1/16W,CHIP,CS24702JB10  I195  R2932
   1 FM_SWB_PWR_EN_R1_BUF      A @T6G_MB_LIB.T6G(SCH_1):FM_SWB_PWR_EN_R1_BUF
   2    GND      B @T6G_MB_LIB.T6G(SCH_1):GND


DRAWING: @T6G_MB_LIB.T6G(SCH_1):PAGE255 

Q_CAP_0402-0.1UF,25V,10%,X7R,CH4104K1B00  I13  C1963
   1 P3V3_AUX      A @T6G_MB_LIB.T6G(SCH_1):P3V3_AUX
   2    GND      B @T6G_MB_LIB.T6G(SCH_1):GND

74LVC2G07DW7-74LVC2G07DW-7,SMLF,IC,AL002G07003  I16  U255
   1 GPU_NVS_PWR_BRAKE_N     1A @T6G_MB_LIB.T6G(SCH_1):GPU_NVS_PWR_BRAKE_N
   3 GPU_FPGA_EROT_RST_N     2A @T6G_MB_LIB.T6G(SCH_1):GPU_FPGA_EROT_RST_N
   6 GPU_NVS_PWR_BRAKE_N_R     1Y @T6G_MB_LIB.T6G(SCH_1):GPU_NVS_PWR_BRAKE_N_R
   4 GPU_FPGA_EROT_RST_BUF_R_N     2Y @T6G_MB_LIB.T6G(SCH_1):GPU_FPGA_EROT_RST_BUF_R_N
   2    GND    GND @T6G_MB_LIB.T6G(SCH_1):GND
   5 P3V3_AUX    VCC @T6G_MB_LIB.T6G(SCH_1):P3V3_AUX

Q_RES_0402LF-100K,1%,1/16W,EMPTY,CS41002FB09  I31  R3460
   1 GPU_NVS_PWR_BRAKE_N      A @T6G_MB_LIB.T6G(SCH_1):GPU_NVS_PWR_BRAKE_N
   2    GND      B @T6G_MB_LIB.T6G(SCH_1):GND

Q_RES_0402LF-100K,1%,1/16W,EMPTY,CS41002FB09  I33  R3462
   1 GPU_NVS_PWR_BRAKE_N_R      A @T6G_MB_LIB.T6G(SCH_1):GPU_NVS_PWR_BRAKE_N_R
   2    GND      B @T6G_MB_LIB.T6G(SCH_1):GND

Q_RES_0402LF-54.9K,1%,1/16W,CHIP,CS35492FB03  I35  R3461
   1 P3V3_AUX      A @T6G_MB_LIB.T6G(SCH_1):P3V3_AUX
   2 GPU_NVS_PWR_BRAKE_N_R      B @T6G_MB_LIB.T6G(SCH_1):GPU_NVS_PWR_BRAKE_N_R

Q_RES_0402LF-33.2,1%,1/16W,CHIP,CS03322FB03  I37  R3397
   1 GPU_NVS_PWR_BRAKE_N_R      A @T6G_MB_LIB.T6G(SCH_1):GPU_NVS_PWR_BRAKE_N_R
   2 GPU_NVS_PWR_BRAKE_N_BUF      B @T6G_MB_LIB.T6G(SCH_1):GPU_NVS_PWR_BRAKE_N_BUF

Q_RES_0402LF-1K,1%,1/16W,CHIP,CS21002FB06  I40  R3488
   1 P3V3_AUX      A @T6G_MB_LIB.T6G(SCH_1):P3V3_AUX
   2 GPU_FPGA_EROT_RST_N      B @T6G_MB_LIB.T6G(SCH_1):GPU_FPGA_EROT_RST_N

Q_RES_0402LF-100K,1%,1/16W,EMPTY,CS41002FB09  I42  R3489
   1 GPU_FPGA_EROT_RST_N      A @T6G_MB_LIB.T6G(SCH_1):GPU_FPGA_EROT_RST_N
   2    GND      B @T6G_MB_LIB.T6G(SCH_1):GND

Q_RES_0402LF-33.2,1%,1/16W,CHIP,CS03322FB03  I45  R3496
   1 GPU_FPGA_EROT_RST_BUF_R_N      A @T6G_MB_LIB.T6G(SCH_1):GPU_FPGA_EROT_RST_BUF_R_N
   2 GPU_FPGA_EROT_RST_BUF_N      B @T6G_MB_LIB.T6G(SCH_1):GPU_FPGA_EROT_RST_BUF_N

Q_RES_0402LF-54.9K,1%,1/16W,CHIP,CS35492FB03  I47  R3492
   1 P3V3_AUX      A @T6G_MB_LIB.T6G(SCH_1):P3V3_AUX
   2 GPU_FPGA_EROT_RST_BUF_R_N      B @T6G_MB_LIB.T6G(SCH_1):GPU_FPGA_EROT_RST_BUF_R_N

Q_RES_0402LF-100K,1%,1/16W,EMPTY,CS41002FB09  I48  R3493
   1 GPU_FPGA_EROT_RST_BUF_R_N      A @T6G_MB_LIB.T6G(SCH_1):GPU_FPGA_EROT_RST_BUF_R_N
   2    GND      B @T6G_MB_LIB.T6G(SCH_1):GND

74LVC2G07DW7-74LVC2G07DW-7,SMLF,IC,AL002G07003  I50  U257
   1 GPU_FPGA_EROT_RECOV_N     1A @T6G_MB_LIB.T6G(SCH_1):GPU_FPGA_EROT_RECOV_N
   3    GND     2A @T6G_MB_LIB.T6G(SCH_1):GND
   6 GPU_FPGA_EROT_RECOV_BUF_R_N     1Y @T6G_MB_LIB.T6G(SCH_1):GPU_FPGA_EROT_RECOV_BUF_R_N
   4 NC_U257_2Y     2Y @T6G_MB_LIB.T6G(SCH_1):NC_U257_2Y
   2    GND    GND @T6G_MB_LIB.T6G(SCH_1):GND
   5 P3V3_AUX    VCC @T6G_MB_LIB.T6G(SCH_1):P3V3_AUX

Q_RES_0402LF-33.2,1%,1/16W,CHIP,CS03322FB03  I53  R3497
   1 GPU_FPGA_EROT_RECOV_BUF_R_N      A @T6G_MB_LIB.T6G(SCH_1):GPU_FPGA_EROT_RECOV_BUF_R_N
   2 GPU_FPGA_EROT_RECOV_BUF_N      B @T6G_MB_LIB.T6G(SCH_1):GPU_FPGA_EROT_RECOV_BUF_N

Q_RES_0402LF-54.9K,1%,1/16W,CHIP,CS35492FB03  I55  R3494
   1 P3V3_AUX      A @T6G_MB_LIB.T6G(SCH_1):P3V3_AUX
   2 GPU_FPGA_EROT_RECOV_BUF_R_N      B @T6G_MB_LIB.T6G(SCH_1):GPU_FPGA_EROT_RECOV_BUF_R_N

Q_RES_0402LF-1K,1%,1/16W,CHIP,CS21002FB06  I57  R3490
   1 P3V3_AUX      A @T6G_MB_LIB.T6G(SCH_1):P3V3_AUX
   2 GPU_FPGA_EROT_RECOV_N      B @T6G_MB_LIB.T6G(SCH_1):GPU_FPGA_EROT_RECOV_N

Q_RES_0402LF-100K,1%,1/16W,EMPTY,CS41002FB09  I62  R3495
   1 GPU_FPGA_EROT_RECOV_BUF_R_N      A @T6G_MB_LIB.T6G(SCH_1):GPU_FPGA_EROT_RECOV_BUF_R_N
   2    GND      B @T6G_MB_LIB.T6G(SCH_1):GND

Q_CAP_0402-0.1UF,25V,10%,X7R,CH4104K1B00  I67  C1979
   1 P3V3_AUX      A @T6G_MB_LIB.T6G(SCH_1):P3V3_AUX
   2    GND      B @T6G_MB_LIB.T6G(SCH_1):GND

Q_RES_0402LF-100K,1%,1/16W,EMPTY,CS41002FB09  I70  R3491
   1 GPU_FPGA_EROT_RECOV_N      A @T6G_MB_LIB.T6G(SCH_1):GPU_FPGA_EROT_RECOV_N
   2    GND      B @T6G_MB_LIB.T6G(SCH_1):GND

Q_RES_0402LF-1K,1%,1/16W,CHIP,CS21002FB06  I75  R3459
   1 P3V3_AUX      A @T6G_MB_LIB.T6G(SCH_1):P3V3_AUX
   2 GPU_NVS_PWR_BRAKE_N      B @T6G_MB_LIB.T6G(SCH_1):GPU_NVS_PWR_BRAKE_N


DRAWING: @T6G_MB_LIB.T6G(SCH_1):PAGE256 

74LVC2G17GW-74LVC2G17GW,SMLF,IC,AL2G0017005  I65  U195
   5 P3V3_AUX    VCC @T6G_MB_LIB.T6G(SCH_1):P3V3_AUX
   4 RST_SWB_BIC_BUF_R_N     B1 @T6G_MB_LIB.T6G(SCH_1):RST_SWB_BIC_BUF_R_N
   2    GND    GND @T6G_MB_LIB.T6G(SCH_1):GND
   1 BMC_MONITER_R     A0 @T6G_MB_LIB.T6G(SCH_1):BMC_MONITER_R
   3 RST_SWB_BIC_R_N     A1 @T6G_MB_LIB.T6G(SCH_1):RST_SWB_BIC_R_N
   6 BMC_MONITER_BUF_R     B0 @T6G_MB_LIB.T6G(SCH_1):BMC_MONITER_BUF_R

Q_RES_0402LF-100K,1%,1/16W,EMPTY,CS41002FB09  I68  R2815
   1 P3V3_AUX      A @T6G_MB_LIB.T6G(SCH_1):P3V3_AUX
   2 BMC_MONITER_R      B @T6G_MB_LIB.T6G(SCH_1):BMC_MONITER_R

Q_RES_0402LF-4.7K,5%,1/16W,EMPTY,CS24702JB10  I78  R2820
   1 P3V3_AUX      A @T6G_MB_LIB.T6G(SCH_1):P3V3_AUX
   2 BMC_MONITER_BUF_R      B @T6G_MB_LIB.T6G(SCH_1):BMC_MONITER_BUF_R

Q_CAP_0402-0.1UF,25V,10%,X7R,CH4104K1B00  I89  C1769
   1 P3V3_AUX      A @T6G_MB_LIB.T6G(SCH_1):P3V3_AUX
   2    GND      B @T6G_MB_LIB.T6G(SCH_1):GND

Q_RES_0402LF-4.7K,5%,1/16W,CHIP,CS24702JB10  I92  R2915
   1 BMC_MONITER_R      A @T6G_MB_LIB.T6G(SCH_1):BMC_MONITER_R
   2    GND      B @T6G_MB_LIB.T6G(SCH_1):GND

Q_RES_0402LF-4.7K,5%,1/16W,EMPTY,CS24702JB10  I93  R2916
   1 RST_SWB_BIC_R_N      A @T6G_MB_LIB.T6G(SCH_1):RST_SWB_BIC_R_N
   2    GND      B @T6G_MB_LIB.T6G(SCH_1):GND

Q_RES_0402LF-4.7K,5%,1/16W,CHIP,CS24702JB10  I121  R2926
   1 BMC_MONITER_BUF_R      A @T6G_MB_LIB.T6G(SCH_1):BMC_MONITER_BUF_R
   2    GND      B @T6G_MB_LIB.T6G(SCH_1):GND

74LVC2G17GW-74LVC2G17GW,SMLF,IC,AL2G0017005  I127  U196
   5 P3V3_AUX    VCC @T6G_MB_LIB.T6G(SCH_1):P3V3_AUX
   4 GPU_FPGA_RST_R1_BUF_N     B1 @T6G_MB_LIB.T6G(SCH_1):GPU_FPGA_RST_R1_BUF_N
   2    GND    GND @T6G_MB_LIB.T6G(SCH_1):GND
   1 FM_GPU_PWR_EN_R     A0 @T6G_MB_LIB.T6G(SCH_1):FM_GPU_PWR_EN_R
   3 GPU_FPGA_RST_R_N     A1 @T6G_MB_LIB.T6G(SCH_1):GPU_FPGA_RST_R_N
   6 FM_GPU_PWR_EN_R1     B0 @T6G_MB_LIB.T6G(SCH_1):FM_GPU_PWR_EN_R1

Q_CAP_0402-0.1UF,25V,10%,X7R,CH4104K1B00  I140  C1770
   1 P3V3_AUX      A @T6G_MB_LIB.T6G(SCH_1):P3V3_AUX
   2    GND      B @T6G_MB_LIB.T6G(SCH_1):GND

Q_RES_0402LF-4.7K,5%,1/16W,EMPTY,CS24702JB10  I147  R2912
   1 P3V3_AUX      A @T6G_MB_LIB.T6G(SCH_1):P3V3_AUX
   2 FM_GPU_PWR_EN_R1      B @T6G_MB_LIB.T6G(SCH_1):FM_GPU_PWR_EN_R1

Q_RES_0402LF-4.7K,5%,1/16W,EMPTY,CS24702JB10  I153  R2911
   1 P3V3_AUX      A @T6G_MB_LIB.T6G(SCH_1):P3V3_AUX
   2 RST_SWB_BIC_BUF_R_N      B @T6G_MB_LIB.T6G(SCH_1):RST_SWB_BIC_BUF_R_N

Q_RES_0402LF-49.9,1%,1/16W,CHIP,CS04992FB07  I154  R2917
   1 BMC_MONITER_BUF_R      A @T6G_MB_LIB.T6G(SCH_1):BMC_MONITER_BUF_R
   2 BMC_MONITER_BUF      B @T6G_MB_LIB.T6G(SCH_1):BMC_MONITER_BUF

Q_RES_0402LF-49.9,1%,1/16W,CHIP,CS04992FB07  I155  R2924
   1 RST_SWB_BIC_BUF_R_N      A @T6G_MB_LIB.T6G(SCH_1):RST_SWB_BIC_BUF_R_N
   2 RST_SWB_BIC_BUF_N      B @T6G_MB_LIB.T6G(SCH_1):RST_SWB_BIC_BUF_N

Q_RES_0402LF-49.9,1%,1/16W,CHIP,CS04992FB07  I156  R2925
   1 FM_GPU_PWR_EN_R1      A @T6G_MB_LIB.T6G(SCH_1):FM_GPU_PWR_EN_R1
   2 FM_GPU_PWR_EN_R_BUF      B @T6G_MB_LIB.T6G(SCH_1):FM_GPU_PWR_EN_R_BUF

Q_RES_0402LF-4.7K,5%,1/16W,CHIP,CS24702JB10  I160  R2937
   1 FM_GPU_PWR_EN_R      A @T6G_MB_LIB.T6G(SCH_1):FM_GPU_PWR_EN_R
   2    GND      B @T6G_MB_LIB.T6G(SCH_1):GND

Q_RES_0402LF-100K,1%,1/16W,EMPTY,CS41002FB09  I162  R2936
   1 P3V3_AUX      A @T6G_MB_LIB.T6G(SCH_1):P3V3_AUX
   2 FM_GPU_PWR_EN_R      B @T6G_MB_LIB.T6G(SCH_1):FM_GPU_PWR_EN_R

Q_CAP_0402-0.1UF,25V,10%,X7R,CH4104K1B00  I166  C1803
   1 P3V3_AUX      A @T6G_MB_LIB.T6G(SCH_1):P3V3_AUX
   2    GND      B @T6G_MB_LIB.T6G(SCH_1):GND

Q_RES_0402LF-0,5%,1/16W,CHIP,CS00002JB13  I170  R3033
   1 UART_BMC_BIC_RX      A @T6G_MB_LIB.T6G(SCH_1):UART_BMC_BIC_RX
   2 UART_BMC_BIC_R_RX      B @T6G_MB_LIB.T6G(SCH_1):UART_BMC_BIC_R_RX

Q_RES_0402LF-0,5%,1/16W,CHIP,CS00002JB13  I171  R3063
   1 FM_PDB_BUF_EN_R1      A @T6G_MB_LIB.T6G(SCH_1):FM_PDB_BUF_EN_R1
   2 FM_UART_EN      B @T6G_MB_LIB.T6G(SCH_1):FM_UART_EN

Q_RES_0402LF-33.2,1%,1/16W,CHIP,CS03322FB03  I181  R3315
   1 GPU_FPGA_RST_R1_BUF_N      A @T6G_MB_LIB.T6G(SCH_1):GPU_FPGA_RST_R1_BUF_N
   2 GPU_FPGA_RST_R_BUF_N      B @T6G_MB_LIB.T6G(SCH_1):GPU_FPGA_RST_R_BUF_N

Q_RES_0402LF-4.7K,5%,1/16W,EMPTY,CS24702JB10  I190  R3317
   1 P3V3_AUX      A @T6G_MB_LIB.T6G(SCH_1):P3V3_AUX
   2 GPU_FPGA_RST_R1_BUF_N      B @T6G_MB_LIB.T6G(SCH_1):GPU_FPGA_RST_R1_BUF_N

Q_RES_0402LF-10K,1%,1/16W,CHIP,CS31002FB08  I191  R3509
   1 GPU_FPGA_RST_R1_BUF_N      A @T6G_MB_LIB.T6G(SCH_1):GPU_FPGA_RST_R1_BUF_N
   2    GND      B @T6G_MB_LIB.T6G(SCH_1):GND

Q_RES_0402LF-10K,1%,1/16W,CHIP,CS31002FB08  I192  R3507
   1 GPU_FPGA_RST_R_N      A @T6G_MB_LIB.T6G(SCH_1):GPU_FPGA_RST_R_N
   2    GND      B @T6G_MB_LIB.T6G(SCH_1):GND

Q_RES_0402LF-4.7K,5%,1/16W,EMPTY,CS24702JB10  I193  R3506
   1 P3V3_AUX      A @T6G_MB_LIB.T6G(SCH_1):P3V3_AUX
   2 GPU_FPGA_RST_R_N      B @T6G_MB_LIB.T6G(SCH_1):GPU_FPGA_RST_R_N

Q_RES_0402LF-54.9K,1%,1/16W,CHIP,CS35492FB03  I194  R3508
   1 FM_GPU_PWR_EN_R1      A @T6G_MB_LIB.T6G(SCH_1):FM_GPU_PWR_EN_R1
   2    GND      B @T6G_MB_LIB.T6G(SCH_1):GND

74LVC1G126SE7-74LVC1G126SE-7,SMLF,IC,AL1G0126009  I195  U204
   2 UART_BMC_BIC_R_RX      A @T6G_MB_LIB.T6G(SCH_1):UART_BMC_BIC_R_RX
   4 UART_BMC_BIC_R_BUF_RX      Y @T6G_MB_LIB.T6G(SCH_1):UART_BMC_BIC_R_BUF_RX
   5 P3V3_AUX    VCC @T6G_MB_LIB.T6G(SCH_1):P3V3_AUX
   3    GND    GND @T6G_MB_LIB.T6G(SCH_1):GND
   1 FM_UART_EN     OE @T6G_MB_LIB.T6G(SCH_1):FM_UART_EN

Q_RES_0402LF-33.2,1%,1/16W,CHIP,CS03322FB03  I197  R3036
   1 UART_BMC_BIC_R_BUF_RX      A @T6G_MB_LIB.T6G(SCH_1):UART_BMC_BIC_R_BUF_RX
   2 UART_BMC_BIC_BUF_RX      B @T6G_MB_LIB.T6G(SCH_1):UART_BMC_BIC_BUF_RX

Q_RES_0402LF-4.7K,5%,1/16W,CHIP,CS24702JB10  I198  R2909
   1 P3V3_AUX      A @T6G_MB_LIB.T6G(SCH_1):P3V3_AUX
   2 RST_SWB_BIC_R_N      B @T6G_MB_LIB.T6G(SCH_1):RST_SWB_BIC_R_N

Q_RES_0402LF-100K,1%,1/16W,CHIP,CS41002FB09  I200  R4515
   1 P3V3_AUX      A @T6G_MB_LIB.T6G(SCH_1):P3V3_AUX
   2 UART_BMC_BIC_RX      B @T6G_MB_LIB.T6G(SCH_1):UART_BMC_BIC_RX

Q_RES_0402LF-100K,1%,1/16W,CHIP,CS41002FB09  I203  R2927
   1 RST_SWB_BIC_BUF_R_N      A @T6G_MB_LIB.T6G(SCH_1):RST_SWB_BIC_BUF_R_N
   2    GND      B @T6G_MB_LIB.T6G(SCH_1):GND

Q_RES_0402LF-100K,1%,1/16W,EMPTY,CS41002FB09  I204  R4173
   1 P3V3_AUX      A @T6G_MB_LIB.T6G(SCH_1):P3V3_AUX
   2 UART_BMC_BIC_R_BUF_RX      B @T6G_MB_LIB.T6G(SCH_1):UART_BMC_BIC_R_BUF_RX


DRAWING: @T6G_MB_LIB.T6G(SCH_1):PAGE307 

Q_RES_0402LF-100K,1%,1/16W,CHIP,CS41002FB09  I15  R3207
   1 FB_BMC_ISOLATE1      A @T6G_MB_LIB.T6G(SCH_1):FB_BMC_ISOLATE1
   2    GND      B @T6G_MB_LIB.T6G(SCH_1):GND

Q_CAP_0402-0.1UF,25V,10%,X7R,CH4104K1B00  I17  C1825
   1 P3V3_AUX      A @T6G_MB_LIB.T6G(SCH_1):P3V3_AUX
   2    GND      B @T6G_MB_LIB.T6G(SCH_1):GND

74CBTLV3126PW-74CBTLV3126PW,SMLF,IC,AL003126K08  I32  U222
   5 NCSI_BMC_RXD0_R1     2A @T6G_MB_LIB.T6G(SCH_1):NCSI_BMC_RXD0_R1
   8 NCSI_OCP_V3_2_CRS_DV     3B @T6G_MB_LIB.T6G(SCH_1):NCSI_OCP_V3_2_CRS_DV
   1 FB_BMC_ISOLATE1    1OE @T6G_MB_LIB.T6G(SCH_1):FB_BMC_ISOLATE1
   4 FB_BMC_ISOLATE1    2OE @T6G_MB_LIB.T6G(SCH_1):FB_BMC_ISOLATE1
   3 NCSI_OCP_V3_2_RXD1     1B @T6G_MB_LIB.T6G(SCH_1):NCSI_OCP_V3_2_RXD1
   6 NCSI_OCP_V3_2_RXD0     2B @T6G_MB_LIB.T6G(SCH_1):NCSI_OCP_V3_2_RXD0
   2 NCSI_BMC_RXD1_R1     1A @T6G_MB_LIB.T6G(SCH_1):NCSI_BMC_RXD1_R1
   7    GND    GND @T6G_MB_LIB.T6G(SCH_1):GND
   9 NCSI_BMC_CRS_DV_R1     3A @T6G_MB_LIB.T6G(SCH_1):NCSI_BMC_CRS_DV_R1
  10 FB_BMC_ISOLATE1    3OE @T6G_MB_LIB.T6G(SCH_1):FB_BMC_ISOLATE1
  11 OCP_V3_2_ISO1_RBT_ARB_IN     4B @T6G_MB_LIB.T6G(SCH_1):OCP_V3_2_ISO1_RBT_ARB_IN
  12 OCP_V3_2_RBT_ARB_IN_R     4A @T6G_MB_LIB.T6G(SCH_1):OCP_V3_2_RBT_ARB_IN_R
  13 FB_BMC_ISOLATE1    4OE @T6G_MB_LIB.T6G(SCH_1):FB_BMC_ISOLATE1
  14 P3V3_AUX    VCC @T6G_MB_LIB.T6G(SCH_1):P3V3_AUX

Q_CAP_0402-0.1UF,25V,10%,X7R,CH4104K1B00  I33  C1826
   1 P3V3_AUX      A @T6G_MB_LIB.T6G(SCH_1):P3V3_AUX
   2    GND      B @T6G_MB_LIB.T6G(SCH_1):GND

Q_RES_0402LF-100,1%,1/16W,CHIP,CS11002FB07  I37  R3208
   1 OCP_V3_2_ISO_BIF0_EN      A @T6G_MB_LIB.T6G(SCH_1):OCP_V3_2_ISO_BIF0_EN
   2    GND      B @T6G_MB_LIB.T6G(SCH_1):GND

Q_RES_0402LF-100,1%,1/16W,CHIP,CS11002FB07  I38  R3216
   1 OCP_V3_2_ISO_BIF1_EN      A @T6G_MB_LIB.T6G(SCH_1):OCP_V3_2_ISO_BIF1_EN
   2    GND      B @T6G_MB_LIB.T6G(SCH_1):GND

Q_RES_0402LF-100,1%,1/16W,CHIP,CS11002FB07  I40  R3217
   1 OCP_V3_2_ISO_BIF2_EN      A @T6G_MB_LIB.T6G(SCH_1):OCP_V3_2_ISO_BIF2_EN
   2    GND      B @T6G_MB_LIB.T6G(SCH_1):GND

Q_RES_0402LF-0,5%,1/16W,EMPTY,CS00002JB13  I56  R3215
   1 NCSI_BMC_TXD1_R1      A @T6G_MB_LIB.T6G(SCH_1):NCSI_BMC_TXD1_R1
   2 RMII_BMC_OCP_TXD_1      B @T6G_MB_LIB.T6G(SCH_1):RMII_BMC_OCP_TXD_1

Q_RES_0402LF-0,5%,1/16W,EMPTY,CS00002JB13  I60  R3214
   1 NCSI_BMC_TXD0_R1      A @T6G_MB_LIB.T6G(SCH_1):NCSI_BMC_TXD0_R1
   2 RMII_BMC_OCP_TXD_0      B @T6G_MB_LIB.T6G(SCH_1):RMII_BMC_OCP_TXD_0

Q_RES_0402LF-0,5%,1/16W,EMPTY,CS00002JB13  I61  R3213
   1 NCSI_BMC_TX_EN_R1      A @T6G_MB_LIB.T6G(SCH_1):NCSI_BMC_TX_EN_R1
   2 RMII_BMC_OCP_TX_EN      B @T6G_MB_LIB.T6G(SCH_1):RMII_BMC_OCP_TX_EN

Q_RES_0402LF-22,1%,1/16W,EMPTY,CS02202FB02  I62  R3212
   1 NCSI_BMC_RXD1_R1      A @T6G_MB_LIB.T6G(SCH_1):NCSI_BMC_RXD1_R1
   2 RMII_OCP_BMC_RXD_1      B @T6G_MB_LIB.T6G(SCH_1):RMII_OCP_BMC_RXD_1

Q_RES_0402LF-22,1%,1/16W,EMPTY,CS02202FB02  I63  R3211
   1 NCSI_BMC_RXD0_R1      A @T6G_MB_LIB.T6G(SCH_1):NCSI_BMC_RXD0_R1
   2 RMII_OCP_BMC_RXD_0      B @T6G_MB_LIB.T6G(SCH_1):RMII_OCP_BMC_RXD_0

Q_RES_0402LF-22,1%,1/16W,EMPTY,CS02202FB02  I64  R3209
   1 OCP_V3_2_RBT_ARB_IN_R      A @T6G_MB_LIB.T6G(SCH_1):OCP_V3_2_RBT_ARB_IN_R
   2 OCP_V3_2_RBT_ARB_IN      B @T6G_MB_LIB.T6G(SCH_1):OCP_V3_2_RBT_ARB_IN

Q_RES_0402LF-22,1%,1/16W,EMPTY,CS02202FB02  I65  R3210
   1 NCSI_BMC_CRS_DV_R1      A @T6G_MB_LIB.T6G(SCH_1):NCSI_BMC_CRS_DV_R1
   2 RMII_OCP_BMC_CRSDV      B @T6G_MB_LIB.T6G(SCH_1):RMII_OCP_BMC_CRSDV

Q_CAP_0402-0.1UF,25V,10%,X7R,CH4104K1B00  I77  C1827
   1 P3V3_AUX      A @T6G_MB_LIB.T6G(SCH_1):P3V3_AUX
   2    GND      B @T6G_MB_LIB.T6G(SCH_1):GND

74CBTLV3126PW-74CBTLV3126PW,SMLF,IC,AL003126K08  I78  U223
   5 NCSI_BMC_TXD0_R1     2A @T6G_MB_LIB.T6G(SCH_1):NCSI_BMC_TXD0_R1
   8 NCSI_OCP_V3_2_TX_EN     3B @T6G_MB_LIB.T6G(SCH_1):NCSI_OCP_V3_2_TX_EN
   1 FB_BMC_ISOLATE1    1OE @T6G_MB_LIB.T6G(SCH_1):FB_BMC_ISOLATE1
   4 FB_BMC_ISOLATE1    2OE @T6G_MB_LIB.T6G(SCH_1):FB_BMC_ISOLATE1
   3 NCSI_OCP_V3_2_TXD1     1B @T6G_MB_LIB.T6G(SCH_1):NCSI_OCP_V3_2_TXD1
   6 NCSI_OCP_V3_2_TXD0     2B @T6G_MB_LIB.T6G(SCH_1):NCSI_OCP_V3_2_TXD0
   2 NCSI_BMC_TXD1_R1     1A @T6G_MB_LIB.T6G(SCH_1):NCSI_BMC_TXD1_R1
   7    GND    GND @T6G_MB_LIB.T6G(SCH_1):GND
   9 NCSI_BMC_TX_EN_R1     3A @T6G_MB_LIB.T6G(SCH_1):NCSI_BMC_TX_EN_R1
  10 FB_BMC_ISOLATE1    3OE @T6G_MB_LIB.T6G(SCH_1):FB_BMC_ISOLATE1
  11 OCP_V3_2_ISO2_RBT_ARB_OUT     4B @T6G_MB_LIB.T6G(SCH_1):OCP_V3_2_ISO2_RBT_ARB_OUT
  12 OCP_V3_2_RBT_ARB_OUT     4A @T6G_MB_LIB.T6G(SCH_1):OCP_V3_2_RBT_ARB_OUT
  13 FB_BMC_ISOLATE1    4OE @T6G_MB_LIB.T6G(SCH_1):FB_BMC_ISOLATE1
  14 P3V3_AUX    VCC @T6G_MB_LIB.T6G(SCH_1):P3V3_AUX

Q_RES_0402LF-0,5%,1/16W,CHIP,CS00002JB13  I79  R3244
   1 OCP_V3_2_RBT_ARB_OUT      A @T6G_MB_LIB.T6G(SCH_1):OCP_V3_2_RBT_ARB_OUT
   2 OCP_V3_2_RBT_ARB_IN_R      B @T6G_MB_LIB.T6G(SCH_1):OCP_V3_2_RBT_ARB_IN_R

74LVC1G126SE7-74LVC1G126SE-7,SMLF,IC,AL1G0126009  I80  U286
   2 FM_OCP_V3_2_PWR_GOOD      A @T6G_MB_LIB.T6G(SCH_1):FM_OCP_V3_2_PWR_GOOD
   4 FB_BMC_ISOLATE_R2      Y @T6G_MB_LIB.T6G(SCH_1):FB_BMC_ISOLATE_R2
   5 P3V3_AUX    VCC @T6G_MB_LIB.T6G(SCH_1):P3V3_AUX
   3    GND    GND @T6G_MB_LIB.T6G(SCH_1):GND
   1 OCP_V3_2_AUX_PWR_EN_R1     OE @T6G_MB_LIB.T6G(SCH_1):OCP_V3_2_AUX_PWR_EN_R1

Q_RES_0402LF-33.2,1%,1/16W,CHIP,CS03322FB03  I81  R3203
   1 OCP_V3_2_AUX_PWR_EN      A @T6G_MB_LIB.T6G(SCH_1):OCP_V3_2_AUX_PWR_EN
   2 OCP_V3_2_AUX_PWR_EN_R1      B @T6G_MB_LIB.T6G(SCH_1):OCP_V3_2_AUX_PWR_EN_R1

Q_RES_0402LF-0,5%,1/16W,EMPTY,CS00002JB13  I85  R3206
   1 FM_NCSI_OCP_V3_2_R_OE      A @T6G_MB_LIB.T6G(SCH_1):FM_NCSI_OCP_V3_2_R_OE
   2 FB_BMC_ISOLATE1      B @T6G_MB_LIB.T6G(SCH_1):FB_BMC_ISOLATE1

Q_RES_0402LF-0,5%,1/16W,CHIP,CS00002JB13  I86  R3205
   1 FB_BMC_ISOLATE_R2      A @T6G_MB_LIB.T6G(SCH_1):FB_BMC_ISOLATE_R2
   2 FB_BMC_ISOLATE1      B @T6G_MB_LIB.T6G(SCH_1):FB_BMC_ISOLATE1


DRAWING: @T6G_MB_LIB.T6G(SCH_1):PAGE335 

Q_RES_0402LF-4.7K,1%,1/16W,CHIP,CS24702FB06  I2  R32
   1 OCP_SFF_ID0      A @T6G_MB_LIB.T6G(SCH_1):OCP_SFF_ID0
   2    GND      B @T6G_MB_LIB.T6G(SCH_1):GND

Q_RES_0402LF-100K,1%,1/16W,CHIP,CS41002FB09  I6  R3132
   1    GND      A @T6G_MB_LIB.T6G(SCH_1):GND
   2 FM_OCP_SFF_PWR_GOOD      B @T6G_MB_LIB.T6G(SCH_1):FM_OCP_SFF_PWR_GOOD

Q_RES_0402LF-0,5%,1/16W,CHIP,CS00002JB13  I54  R1671
   1 OCP_SFF_AUX_PWR_EN      A @T6G_MB_LIB.T6G(SCH_1):OCP_SFF_AUX_PWR_EN
   2 OCP_SFF_AUX_PWR_EN_R      B @T6G_MB_LIB.T6G(SCH_1):OCP_SFF_AUX_PWR_EN_R

Q_CAP_0402-0.1UF,25V,10%,X7R,CH4104K1B00  I89  C21
   1 P12V_OCP_SFF_R      A @T6G_MB_LIB.T6G(SCH_1):P12V_OCP_SFF_R
   2    GND      B @T6G_MB_LIB.T6G(SCH_1):GND

Q_CAP_0402-0.1UF,25V,10%,X7R,CH4104K1B00  I90  C1235
   1 P12V_OCP_SFF_R      A @T6G_MB_LIB.T6G(SCH_1):P12V_OCP_SFF_R
   2    GND      B @T6G_MB_LIB.T6G(SCH_1):GND

Q_CAP_0402-0.1UF,25V,10%,X7R,CH4104K1B00  I110  C1237
   1 P3V3_OCP_SFF      A @T6G_MB_LIB.T6G(SCH_1):P3V3_OCP_SFF
   2    GND      B @T6G_MB_LIB.T6G(SCH_1):GND

Q_CAP_0402-0.1UF,25V,10%,X7R,CH4104K1B00  I111  C1238
   1 P3V3_OCP_SFF      A @T6G_MB_LIB.T6G(SCH_1):P3V3_OCP_SFF
   2    GND      B @T6G_MB_LIB.T6G(SCH_1):GND

Q_CAP_0402-0.1UF,25V,10%,X7R,CH4104K1B00  I114  C1240
   1 P3V3_OCP_SFF      A @T6G_MB_LIB.T6G(SCH_1):P3V3_OCP_SFF
   2    GND      B @T6G_MB_LIB.T6G(SCH_1):GND

SCONN168_ME1016810202011-SCONN168_ME1016810202011,A  I168  J38
 OB1 FM_OCP_SFF_PWR_GOOD NIC_PWR_GOOD @T6G_MB_LIB.T6G(SCH_1):FM_OCP_SFF_PWR_GOOD
 OB2 OCP_SFF_MAIN_PWR_EN_R MAIN_PWR_EN @T6G_MB_LIB.T6G(SCH_1):OCP_SFF_MAIN_PWR_EN_R
 OB3 SGPIO_OCP_SFF_LD_N    LD# @T6G_MB_LIB.T6G(SCH_1):SGPIO_OCP_SFF_LD_N
 OB4 SGPIO_OCP_SFF_DATAIN DATA_IN @T6G_MB_LIB.T6G(SCH_1):SGPIO_OCP_SFF_DATAIN
 OB5 SGPIO_OCP_SFF_DATAOUT DATA_OUT @T6G_MB_LIB.T6G(SCH_1):SGPIO_OCP_SFF_DATAOUT
 OB6 SGPIO_OCP_SFF_CLK    CLK @T6G_MB_LIB.T6G(SCH_1):SGPIO_OCP_SFF_CLK
 OB7 OCP_SFF_ID0 SLOT_ID0 @T6G_MB_LIB.T6G(SCH_1):OCP_SFF_ID0
 OB8 NCSI_OCP_SFF_RXD1 RBT_RXD1 @T6G_MB_LIB.T6G(SCH_1):NCSI_OCP_SFF_RXD1
 OB9 NCSI_OCP_SFF_RXD0 RBT_RXD0 @T6G_MB_LIB.T6G(SCH_1):NCSI_OCP_SFF_RXD0
OB10    GND GND_OB10 @T6G_MB_LIB.T6G(SCH_1):GND
OB11 CLK_100M_CPU0_CLK04_DN REFCLKN2 @T6G_MB_LIB.T6G(SCH_1):CLK_100M_CPU0_CLK04_DN
OB12 CLK_100M_CPU0_CLK04_DP REFCLKP2 @T6G_MB_LIB.T6G(SCH_1):CLK_100M_CPU0_CLK04_DP
OB13    GND GND_OB13 @T6G_MB_LIB.T6G(SCH_1):GND
OB14 NCSI_OCP_SFF_CRS_DV RBT_CRS_DV @T6G_MB_LIB.T6G(SCH_1):NCSI_OCP_SFF_CRS_DV
  B1 P12V_OCP_SFF_R +12V_EDGE_B1 @T6G_MB_LIB.T6G(SCH_1):P12V_OCP_SFF_R
  B2 P12V_OCP_SFF_R +12V_EDGE_B2 @T6G_MB_LIB.T6G(SCH_1):P12V_OCP_SFF_R
  B3 P12V_OCP_SFF_R +12V_EDGE_B3 @T6G_MB_LIB.T6G(SCH_1):P12V_OCP_SFF_R
  B4 P12V_OCP_SFF_R +12V_EDGE_B4 @T6G_MB_LIB.T6G(SCH_1):P12V_OCP_SFF_R
  B5 P12V_OCP_SFF_R +12V_EDGE_B5 @T6G_MB_LIB.T6G(SCH_1):P12V_OCP_SFF_R
  B6 P12V_OCP_SFF_R +12V_EDGE_B6 @T6G_MB_LIB.T6G(SCH_1):P12V_OCP_SFF_R
  B7 OCP_SFF_BIF0_R_N  BIF0# @T6G_MB_LIB.T6G(SCH_1):OCP_SFF_BIF0_R_N
  B8 OCP_SFF_BIF1_R_N  BIF1# @T6G_MB_LIB.T6G(SCH_1):OCP_SFF_BIF1_R_N
  B9 OCP_SFF_BIF2_R_N  BIF2# @T6G_MB_LIB.T6G(SCH_1):OCP_SFF_BIF2_R_N
 B10 RST_PERST0_OCP_SFF_N PERST0# @T6G_MB_LIB.T6G(SCH_1):RST_PERST0_OCP_SFF_N
 B11 P3V3_OCP_SFF +3.3V_EDGE @T6G_MB_LIB.T6G(SCH_1):P3V3_OCP_SFF
 B12 OCP_SFF_AUX_PWR_EN_R AUX_PWR_EN @T6G_MB_LIB.T6G(SCH_1):OCP_SFF_AUX_PWR_EN_R
 B13    GND GND_B13 @T6G_MB_LIB.T6G(SCH_1):GND
 B14 CLK_100M_CPU0_CLK02_DN REFCLKN0 @T6G_MB_LIB.T6G(SCH_1):CLK_100M_CPU0_CLK02_DN
 B15 CLK_100M_CPU0_CLK02_DP REFCLKP0 @T6G_MB_LIB.T6G(SCH_1):CLK_100M_CPU0_CLK02_DP
 B16    GND GND_B16 @T6G_MB_LIB.T6G(SCH_1):GND
 B17 P5E_CPU0_G3_TX_C_DP<0>  PETN0 @T6G_MB_LIB.T6G(SCH_1):P5E_CPU0_G3_TX_C_DP(0)
 B18 P5E_CPU0_G3_TX_C_DN<0>  PETP0 @T6G_MB_LIB.T6G(SCH_1):P5E_CPU0_G3_TX_C_DN(0)
 B19    GND GND_B19 @T6G_MB_LIB.T6G(SCH_1):GND
 B20 P5E_CPU0_G3_TX_C_DP<1>  PETN1 @T6G_MB_LIB.T6G(SCH_1):P5E_CPU0_G3_TX_C_DP(1)
 B21 P5E_CPU0_G3_TX_C_DN<1>  PETP1 @T6G_MB_LIB.T6G(SCH_1):P5E_CPU0_G3_TX_C_DN(1)
 B22    GND GND_B22 @T6G_MB_LIB.T6G(SCH_1):GND
 B23 P5E_CPU0_G3_TX_C_DP<2>  PETN2 @T6G_MB_LIB.T6G(SCH_1):P5E_CPU0_G3_TX_C_DP(2)
 B24 P5E_CPU0_G3_TX_C_DN<2>  PETP2 @T6G_MB_LIB.T6G(SCH_1):P5E_CPU0_G3_TX_C_DN(2)
 B25    GND GND_B25 @T6G_MB_LIB.T6G(SCH_1):GND
 B26 P5E_CPU0_G3_TX_C_DP<3>  PETN3 @T6G_MB_LIB.T6G(SCH_1):P5E_CPU0_G3_TX_C_DP(3)
 B27 P5E_CPU0_G3_TX_C_DN<3>  PETP3 @T6G_MB_LIB.T6G(SCH_1):P5E_CPU0_G3_TX_C_DN(3)
 B28    GND GND_B28 @T6G_MB_LIB.T6G(SCH_1):GND
 B29    GND GND_B29 @T6G_MB_LIB.T6G(SCH_1):GND
 B30 P5E_CPU0_G3_TX_C_DP<4>  PETN4 @T6G_MB_LIB.T6G(SCH_1):P5E_CPU0_G3_TX_C_DP(4)
 B31 P5E_CPU0_G3_TX_C_DN<4>  PETP4 @T6G_MB_LIB.T6G(SCH_1):P5E_CPU0_G3_TX_C_DN(4)
 B32    GND GND_B32 @T6G_MB_LIB.T6G(SCH_1):GND
 B33 P5E_CPU0_G3_TX_C_DP<5>  PETN5 @T6G_MB_LIB.T6G(SCH_1):P5E_CPU0_G3_TX_C_DP(5)
 B34 P5E_CPU0_G3_TX_C_DN<5>  PETP5 @T6G_MB_LIB.T6G(SCH_1):P5E_CPU0_G3_TX_C_DN(5)
 B35    GND GND_B35 @T6G_MB_LIB.T6G(SCH_1):GND
 B36 P5E_CPU0_G3_TX_C_DP<6>  PETN6 @T6G_MB_LIB.T6G(SCH_1):P5E_CPU0_G3_TX_C_DP(6)
 B37 P5E_CPU0_G3_TX_C_DN<6>  PETP6 @T6G_MB_LIB.T6G(SCH_1):P5E_CPU0_G3_TX_C_DN(6)
 B38    GND GND_B38 @T6G_MB_LIB.T6G(SCH_1):GND
 B39 P5E_CPU0_G3_TX_C_DP<7>  PETN7 @T6G_MB_LIB.T6G(SCH_1):P5E_CPU0_G3_TX_C_DP(7)
 B40 P5E_CPU0_G3_TX_C_DN<7>  PETP7 @T6G_MB_LIB.T6G(SCH_1):P5E_CPU0_G3_TX_C_DN(7)
 B41    GND GND_B41 @T6G_MB_LIB.T6G(SCH_1):GND
 B42 OCP_SFF_PRSNT0_R_N PRSNTB0# @T6G_MB_LIB.T6G(SCH_1):OCP_SFF_PRSNT0_R_N
 B43    GND GND_B43 @T6G_MB_LIB.T6G(SCH_1):GND
 B44 P5E_CPU0_G3_TX_C_DP<8>  PETN8 @T6G_MB_LIB.T6G(SCH_1):P5E_CPU0_G3_TX_C_DP(8)
 B45 P5E_CPU0_G3_TX_C_DN<8>  PETP8 @T6G_MB_LIB.T6G(SCH_1):P5E_CPU0_G3_TX_C_DN(8)
 B46    GND GND_B46 @T6G_MB_LIB.T6G(SCH_1):GND
 B47 P5E_CPU0_G3_TX_C_DP<9>  PETN9 @T6G_MB_LIB.T6G(SCH_1):P5E_CPU0_G3_TX_C_DP(9)
 B48 P5E_CPU0_G3_TX_C_DN<9>  PETP9 @T6G_MB_LIB.T6G(SCH_1):P5E_CPU0_G3_TX_C_DN(9)
 B49    GND GND_B49 @T6G_MB_LIB.T6G(SCH_1):GND
 B50 P5E_CPU0_G3_TX_C_DP<10> PETN10 @T6G_MB_LIB.T6G(SCH_1):P5E_CPU0_G3_TX_C_DP(10)
 B51 P5E_CPU0_G3_TX_C_DN<10> PETP10 @T6G_MB_LIB.T6G(SCH_1):P5E_CPU0_G3_TX_C_DN(10)
 B52    GND GND_B52 @T6G_MB_LIB.T6G(SCH_1):GND
 B53 P5E_CPU0_G3_TX_C_DP<11> PETN11 @T6G_MB_LIB.T6G(SCH_1):P5E_CPU0_G3_TX_C_DP(11)
 B54 P5E_CPU0_G3_TX_C_DN<11> PETP11 @T6G_MB_LIB.T6G(SCH_1):P5E_CPU0_G3_TX_C_DN(11)
 B55    GND GND_B55 @T6G_MB_LIB.T6G(SCH_1):GND
 B56 P5E_CPU0_G3_TX_C_DP<12> PETN12 @T6G_MB_LIB.T6G(SCH_1):P5E_CPU0_G3_TX_C_DP(12)
 OA1 RST_PERST2_OCP_SFF_N PERST2# @T6G_MB_LIB.T6G(SCH_1):RST_PERST2_OCP_SFF_N
 OA2 RST_PERST3_OCP_SFF_N PERST3# @T6G_MB_LIB.T6G(SCH_1):RST_PERST3_OCP_SFF_N
 OA3 IRQ_LVC3_OCP_SFF_WAKE_N  WAKE# @T6G_MB_LIB.T6G(SCH_1):IRQ_LVC3_OCP_SFF_WAKE_N
 OA4 OCP_SFF_ISO1_RBT_ARB_IN RBT_ARB_IN @T6G_MB_LIB.T6G(SCH_1):OCP_SFF_ISO1_RBT_ARB_IN
 OA5 OCP_SFF_ISO2_RBT_ARB_OUT RBT_ARB_OUT @T6G_MB_LIB.T6G(SCH_1):OCP_SFF_ISO2_RBT_ARB_OUT
 OA6 OCP_SFF_ID1 SLOT_ID1 @T6G_MB_LIB.T6G(SCH_1):OCP_SFF_ID1
 OA7 NCSI_OCP_SFF_TX_EN RBT_TX_EN @T6G_MB_LIB.T6G(SCH_1):NCSI_OCP_SFF_TX_EN
 OA8 NCSI_OCP_SFF_TXD1 RBT_TXD1 @T6G_MB_LIB.T6G(SCH_1):NCSI_OCP_SFF_TXD1
 OA9 NCSI_OCP_SFF_TXD0 RBT_TXD0 @T6G_MB_LIB.T6G(SCH_1):NCSI_OCP_SFF_TXD0
OA10    GND GND_OA10 @T6G_MB_LIB.T6G(SCH_1):GND
OA11 CLK_100M_CPU0_CLK05_DN REFCLKN3 @T6G_MB_LIB.T6G(SCH_1):CLK_100M_CPU0_CLK05_DN
OA12 CLK_100M_CPU0_CLK05_DP REFCLKP3 @T6G_MB_LIB.T6G(SCH_1):CLK_100M_CPU0_CLK05_DP
OA13    GND GND_OA13 @T6G_MB_LIB.T6G(SCH_1):GND
OA14 CLK_50M_NCSI_OCP_SFF_ISO RBT_CLK_IN @T6G_MB_LIB.T6G(SCH_1):CLK_50M_NCSI_OCP_SFF_ISO
  A1    GND GND_A1 @T6G_MB_LIB.T6G(SCH_1):GND
  A2    GND GND_A2 @T6G_MB_LIB.T6G(SCH_1):GND
  A3    GND GND_A3 @T6G_MB_LIB.T6G(SCH_1):GND
  A4    GND GND_A4 @T6G_MB_LIB.T6G(SCH_1):GND
  A5    GND GND_A5 @T6G_MB_LIB.T6G(SCH_1):GND
  A6    GND GND_A6 @T6G_MB_LIB.T6G(SCH_1):GND
  A7 SMB_OCP_SFF_3V3AUX_BUF_R_SCL  SMCLK @T6G_MB_LIB.T6G(SCH_1):SMB_OCP_SFF_3V3AUX_BUF_R_SCL
  A8 SMB_OCP_SFF_3V3AUX_BUF_R_SDA  SMDAT @T6G_MB_LIB.T6G(SCH_1):SMB_OCP_SFF_3V3AUX_BUF_R_SDA
  A9 RST_SMB_OCP_SFF_N SMRST# @T6G_MB_LIB.T6G(SCH_1):RST_SMB_OCP_SFF_N
 A10 OCP_SFF_PRSNTA_R_N PRSNTA# @T6G_MB_LIB.T6G(SCH_1):OCP_SFF_PRSNTA_R_N
 A11 RST_PERST1_OCP_SFF_N PERST1# @T6G_MB_LIB.T6G(SCH_1):RST_PERST1_OCP_SFF_N
 A12 OCP_SFF_PRSNT2_R_N PRSNTB2# @T6G_MB_LIB.T6G(SCH_1):OCP_SFF_PRSNT2_R_N
 A13    GND GND_A13 @T6G_MB_LIB.T6G(SCH_1):GND
 A14 CLK_100M_CPU0_CLK03_DN REFCLKN1 @T6G_MB_LIB.T6G(SCH_1):CLK_100M_CPU0_CLK03_DN
 A15 CLK_100M_CPU0_CLK03_DP REFCLKP1 @T6G_MB_LIB.T6G(SCH_1):CLK_100M_CPU0_CLK03_DP
 A16    GND GND_A16 @T6G_MB_LIB.T6G(SCH_1):GND
 A17 P5E_CPU0_G3_RX_DN<0>  PERN0 @T6G_MB_LIB.T6G(SCH_1):P5E_CPU0_G3_RX_DN(0)
 A18 P5E_CPU0_G3_RX_DP<0>  PERP0 @T6G_MB_LIB.T6G(SCH_1):P5E_CPU0_G3_RX_DP(0)
 A19    GND GND_A19 @T6G_MB_LIB.T6G(SCH_1):GND
 A20 P5E_CPU0_G3_RX_DN<1>  PERN1 @T6G_MB_LIB.T6G(SCH_1):P5E_CPU0_G3_RX_DN(1)
 A21 P5E_CPU0_G3_RX_DP<1>  PERP1 @T6G_MB_LIB.T6G(SCH_1):P5E_CPU0_G3_RX_DP(1)
 A22    GND GND_A22 @T6G_MB_LIB.T6G(SCH_1):GND
 A23 P5E_CPU0_G3_RX_DN<2>  PERN2 @T6G_MB_LIB.T6G(SCH_1):P5E_CPU0_G3_RX_DN(2)
 A24 P5E_CPU0_G3_RX_DP<2>  PERP2 @T6G_MB_LIB.T6G(SCH_1):P5E_CPU0_G3_RX_DP(2)
 A25    GND GND_A25 @T6G_MB_LIB.T6G(SCH_1):GND
 A26 P5E_CPU0_G3_RX_DN<3>  PERN3 @T6G_MB_LIB.T6G(SCH_1):P5E_CPU0_G3_RX_DN(3)
 A27 P5E_CPU0_G3_RX_DP<3>  PERP3 @T6G_MB_LIB.T6G(SCH_1):P5E_CPU0_G3_RX_DP(3)
 A28    GND GND_A28 @T6G_MB_LIB.T6G(SCH_1):GND
 A29    GND GND_A29 @T6G_MB_LIB.T6G(SCH_1):GND
 A30 P5E_CPU0_G3_RX_DN<4>  PERN4 @T6G_MB_LIB.T6G(SCH_1):P5E_CPU0_G3_RX_DN(4)
 A31 P5E_CPU0_G3_RX_DP<4>  PERP4 @T6G_MB_LIB.T6G(SCH_1):P5E_CPU0_G3_RX_DP(4)
 A32    GND GND_A32 @T6G_MB_LIB.T6G(SCH_1):GND
 A33 P5E_CPU0_G3_RX_DN<5>  PERN5 @T6G_MB_LIB.T6G(SCH_1):P5E_CPU0_G3_RX_DN(5)
 A34 P5E_CPU0_G3_RX_DP<5>  PERP5 @T6G_MB_LIB.T6G(SCH_1):P5E_CPU0_G3_RX_DP(5)
 A35    GND GND_A35 @T6G_MB_LIB.T6G(SCH_1):GND
 A36 P5E_CPU0_G3_RX_DN<6>  PERN6 @T6G_MB_LIB.T6G(SCH_1):P5E_CPU0_G3_RX_DN(6)
 A37 P5E_CPU0_G3_RX_DP<6>  PERP6 @T6G_MB_LIB.T6G(SCH_1):P5E_CPU0_G3_RX_DP(6)
 A38    GND GND_A38 @T6G_MB_LIB.T6G(SCH_1):GND
 A39 P5E_CPU0_G3_RX_DN<7>  PERN7 @T6G_MB_LIB.T6G(SCH_1):P5E_CPU0_G3_RX_DN(7)
 A40 P5E_CPU0_G3_RX_DP<7>  PERP7 @T6G_MB_LIB.T6G(SCH_1):P5E_CPU0_G3_RX_DP(7)
 A41    GND GND_A41 @T6G_MB_LIB.T6G(SCH_1):GND
 A42 OCP_SFF_PRSNT1_R_N PRSNTB1# @T6G_MB_LIB.T6G(SCH_1):OCP_SFF_PRSNT1_R_N
 A43    GND GND_A43 @T6G_MB_LIB.T6G(SCH_1):GND
 A44 P5E_CPU0_G3_RX_DN<8>  PERN8 @T6G_MB_LIB.T6G(SCH_1):P5E_CPU0_G3_RX_DN(8)
 A45 P5E_CPU0_G3_RX_DP<8>  PERP8 @T6G_MB_LIB.T6G(SCH_1):P5E_CPU0_G3_RX_DP(8)
 A46    GND GND_A46 @T6G_MB_LIB.T6G(SCH_1):GND
 A47 P5E_CPU0_G3_RX_DN<9>  PERN9 @T6G_MB_LIB.T6G(SCH_1):P5E_CPU0_G3_RX_DN(9)
 A48 P5E_CPU0_G3_RX_DP<9>  PERP9 @T6G_MB_LIB.T6G(SCH_1):P5E_CPU0_G3_RX_DP(9)
 A49    GND GND_A49 @T6G_MB_LIB.T6G(SCH_1):GND
 A50 P5E_CPU0_G3_RX_DN<10> PERN10 @T6G_MB_LIB.T6G(SCH_1):P5E_CPU0_G3_RX_DN(10)
 A51 P5E_CPU0_G3_RX_DP<10> PERP10 @T6G_MB_LIB.T6G(SCH_1):P5E_CPU0_G3_RX_DP(10)
 A52    GND GND_A52 @T6G_MB_LIB.T6G(SCH_1):GND
 A53 P5E_CPU0_G3_RX_DN<11> PERN11 @T6G_MB_LIB.T6G(SCH_1):P5E_CPU0_G3_RX_DN(11)
 A54 P5E_CPU0_G3_RX_DP<11> PERP11 @T6G_MB_LIB.T6G(SCH_1):P5E_CPU0_G3_RX_DP(11)
 A55    GND GND_A55 @T6G_MB_LIB.T6G(SCH_1):GND
 A56 P5E_CPU0_G3_RX_DN<12> PERN12 @T6G_MB_LIB.T6G(SCH_1):P5E_CPU0_G3_RX_DN(12)
 A57 P5E_CPU0_G3_RX_DP<12> PERP12 @T6G_MB_LIB.T6G(SCH_1):P5E_CPU0_G3_RX_DP(12)
 A58    GND GND_A58 @T6G_MB_LIB.T6G(SCH_1):GND
 A59 P5E_CPU0_G3_RX_DN<13> PERN13 @T6G_MB_LIB.T6G(SCH_1):P5E_CPU0_G3_RX_DN(13)
 A60 P5E_CPU0_G3_RX_DP<13> PERP13 @T6G_MB_LIB.T6G(SCH_1):P5E_CPU0_G3_RX_DP(13)
 A61    GND GND_A61 @T6G_MB_LIB.T6G(SCH_1):GND
 A62 P5E_CPU0_G3_RX_DN<14> PERN14 @T6G_MB_LIB.T6G(SCH_1):P5E_CPU0_G3_RX_DN(14)
 A63 P5E_CPU0_G3_RX_DP<14> PERP14 @T6G_MB_LIB.T6G(SCH_1):P5E_CPU0_G3_RX_DP(14)
 A64    GND GND_A64 @T6G_MB_LIB.T6G(SCH_1):GND
 A65 P5E_CPU0_G3_RX_DN<15> PERN15 @T6G_MB_LIB.T6G(SCH_1):P5E_CPU0_G3_RX_DN(15)
 A66 P5E_CPU0_G3_RX_DP<15> PERP15 @T6G_MB_LIB.T6G(SCH_1):P5E_CPU0_G3_RX_DP(15)
 A67    GND GND_A67 @T6G_MB_LIB.T6G(SCH_1):GND
 A68 USB2_P11_DN USB_DATN @T6G_MB_LIB.T6G(SCH_1):USB2_P11_DN
 A69 USB2_P11_DP USB_DATP @T6G_MB_LIB.T6G(SCH_1):USB2_P11_DP
 A70 OCP_SFF_PWRBRK_N PWRBRK0# @T6G_MB_LIB.T6G(SCH_1):OCP_SFF_PWRBRK_N
 B57 P5E_CPU0_G3_TX_C_DN<12> PETP12 @T6G_MB_LIB.T6G(SCH_1):P5E_CPU0_G3_TX_C_DN(12)
 B58    GND GND_B58 @T6G_MB_LIB.T6G(SCH_1):GND
 B59 P5E_CPU0_G3_TX_C_DP<13> PETN13 @T6G_MB_LIB.T6G(SCH_1):P5E_CPU0_G3_TX_C_DP(13)
 B60 P5E_CPU0_G3_TX_C_DN<13> PETP13 @T6G_MB_LIB.T6G(SCH_1):P5E_CPU0_G3_TX_C_DN(13)
 B61    GND GND_B61 @T6G_MB_LIB.T6G(SCH_1):GND
 B62 P5E_CPU0_G3_TX_C_DP<14> PETN14 @T6G_MB_LIB.T6G(SCH_1):P5E_CPU0_G3_TX_C_DP(14)
 B63 P5E_CPU0_G3_TX_C_DN<14> PETP14 @T6G_MB_LIB.T6G(SCH_1):P5E_CPU0_G3_TX_C_DN(14)
 B64    GND GND_B64 @T6G_MB_LIB.T6G(SCH_1):GND
 B65 P5E_CPU0_G3_TX_C_DP<15> PETN15 @T6G_MB_LIB.T6G(SCH_1):P5E_CPU0_G3_TX_C_DP(15)
 B66 P5E_CPU0_G3_TX_C_DN<15> PETP15 @T6G_MB_LIB.T6G(SCH_1):P5E_CPU0_G3_TX_C_DN(15)
 B67    GND GND_B67 @T6G_MB_LIB.T6G(SCH_1):GND
 B68 TP_OCP_SFF_B68 RFU1_NC_B68 @T6G_MB_LIB.T6G(SCH_1):TP_OCP_SFF_B68
 B69 TP_OCP_SFF_B69 RFU1_NC_B69 @T6G_MB_LIB.T6G(SCH_1):TP_OCP_SFF_B69
 B70 OCP_SFF_PRSNT3_R_N PRSNTB3# @T6G_MB_LIB.T6G(SCH_1):OCP_SFF_PRSNT3_R_N
  G1    GND     G1 @T6G_MB_LIB.T6G(SCH_1):GND
  G2    GND     G2 @T6G_MB_LIB.T6G(SCH_1):GND
  G3    GND     G3 @T6G_MB_LIB.T6G(SCH_1):GND
  G4    GND     G4 @T6G_MB_LIB.T6G(SCH_1):GND
  G5    GND     G5 @T6G_MB_LIB.T6G(SCH_1):GND

Q_RES_0402LF-4.7K,1%,1/16W,EMPTY,CS24702FB06  I3  R31
   1 P3V3_OCP_SFF      A @T6G_MB_LIB.T6G(SCH_1):P3V3_OCP_SFF
   2 OCP_SFF_ID0      B @T6G_MB_LIB.T6G(SCH_1):OCP_SFF_ID0

Q_RES_0402LF-10K,1%,1/16W,CHIP,CS31002FB08  I7  R1930
   1    GND      A @T6G_MB_LIB.T6G(SCH_1):GND
   2 OCP_SFF_MAIN_PWR_EN      B @T6G_MB_LIB.T6G(SCH_1):OCP_SFF_MAIN_PWR_EN

Q_RES_0402LF-10K,1%,1/16W,CHIP,CS31002FB08  I8  R1929
   1    GND      A @T6G_MB_LIB.T6G(SCH_1):GND
   2 OCP_SFF_AUX_PWR_EN      B @T6G_MB_LIB.T6G(SCH_1):OCP_SFF_AUX_PWR_EN

Q_RES_0402LF-4.7K,1%,1/16W,CHIP,CS24702FB06  I12  R34
   1 OCP_SFF_ID1      A @T6G_MB_LIB.T6G(SCH_1):OCP_SFF_ID1
   2    GND      B @T6G_MB_LIB.T6G(SCH_1):GND

Q_RES_0402LF-4.7K,1%,1/16W,EMPTY,CS24702FB06  I17  R33
   1 P3V3_OCP_SFF      A @T6G_MB_LIB.T6G(SCH_1):P3V3_OCP_SFF
   2 OCP_SFF_ID1      B @T6G_MB_LIB.T6G(SCH_1):OCP_SFF_ID1

Q_RES_0402LF-10K,1%,1/16W,CHIP,CS31002FB08  I19  R8422
   1 SGPIO_OCP_SFF_DATAOUT      A @T6G_MB_LIB.T6G(SCH_1):SGPIO_OCP_SFF_DATAOUT
   2    GND      B @T6G_MB_LIB.T6G(SCH_1):GND

Q_RES_0402LF-1K,1%,1/16W,CHIP,CS21002FB06  I20  R8423
   1 SGPIO_OCP_SFF_CLK      A @T6G_MB_LIB.T6G(SCH_1):SGPIO_OCP_SFF_CLK
   2 P3V3_OCP_SFF      B @T6G_MB_LIB.T6G(SCH_1):P3V3_OCP_SFF

Q_RES_0402LF-10K,1%,1/16W,CHIP,CS31002FB08  I21  R8421
   1 SGPIO_OCP_SFF_DATAIN      A @T6G_MB_LIB.T6G(SCH_1):SGPIO_OCP_SFF_DATAIN
   2 P3V3_OCP_SFF      B @T6G_MB_LIB.T6G(SCH_1):P3V3_OCP_SFF

Q_RES_0402LF-1K,1%,1/16W,CHIP,CS21002FB06  I22  R8420
   1 SGPIO_OCP_SFF_LD_N      A @T6G_MB_LIB.T6G(SCH_1):SGPIO_OCP_SFF_LD_N
   2 P3V3_OCP_SFF      B @T6G_MB_LIB.T6G(SCH_1):P3V3_OCP_SFF

Q_RES_0402LF-0,5%,1/16W,CHIP,CS00002JB13  I55  R41
   1 OCP_SFF_ISO_BIF2_EN      A @T6G_MB_LIB.T6G(SCH_1):OCP_SFF_ISO_BIF2_EN
   2 OCP_SFF_BIF2_R_N      B @T6G_MB_LIB.T6G(SCH_1):OCP_SFF_BIF2_R_N

Q_RES_0402LF-0,5%,1/16W,CHIP,CS00002JB13  I56  R40
   1 OCP_SFF_ISO_BIF1_EN      A @T6G_MB_LIB.T6G(SCH_1):OCP_SFF_ISO_BIF1_EN
   2 OCP_SFF_BIF1_R_N      B @T6G_MB_LIB.T6G(SCH_1):OCP_SFF_BIF1_R_N

Q_RES_0402LF-0,5%,1/16W,CHIP,CS00002JB13  I57  R39
   1 OCP_SFF_ISO_BIF0_EN      A @T6G_MB_LIB.T6G(SCH_1):OCP_SFF_ISO_BIF0_EN
   2 OCP_SFF_BIF0_R_N      B @T6G_MB_LIB.T6G(SCH_1):OCP_SFF_BIF0_R_N

Q_RES_0402LF-0,5%,1/16W,CHIP,CS00002JB13  I59  R38
   1 OCP_SFF_MAIN_PWR_EN      A @T6G_MB_LIB.T6G(SCH_1):OCP_SFF_MAIN_PWR_EN
   2 OCP_SFF_MAIN_PWR_EN_R      B @T6G_MB_LIB.T6G(SCH_1):OCP_SFF_MAIN_PWR_EN_R

Q_CAP_C0805-22UF,16V,20%,X6S,CH6223MEA00  I87  C1213
   1 P12V_OCP_SFF_R      A @T6G_MB_LIB.T6G(SCH_1):P12V_OCP_SFF_R
   2    GND      B @T6G_MB_LIB.T6G(SCH_1):GND

Q_CAP_C0805-22UF,16V,20%,X6S,CH6223MEA00  I88  C34
   1 P12V_OCP_SFF_R      A @T6G_MB_LIB.T6G(SCH_1):P12V_OCP_SFF_R
   2    GND      B @T6G_MB_LIB.T6G(SCH_1):GND

Q_RES_0402LF-0,5%,1/16W,CHIP,CS00002JB13  I108  R46
   1 USB2_P11_DP      A @T6G_MB_LIB.T6G(SCH_1):USB2_P11_DP
   2 USB2_CPU0_P11_DP      B @T6G_MB_LIB.T6G(SCH_1):USB2_CPU0_P11_DP

Q_CAP_0402-0.1UF,25V,10%,X7R,CH4104K1B00  I112  C1239
   1 P3V3_OCP_SFF      A @T6G_MB_LIB.T6G(SCH_1):P3V3_OCP_SFF
   2    GND      B @T6G_MB_LIB.T6G(SCH_1):GND

Q_CAP_0402-0.1UF,25V,10%,X7R,CH4104K1B00  I163  C27
   1 P12V_OCP_SFF_R      A @T6G_MB_LIB.T6G(SCH_1):P12V_OCP_SFF_R
   2    GND      B @T6G_MB_LIB.T6G(SCH_1):GND

Q_CAP_0402-0.1UF,25V,10%,X7R,CH4104K1B00  I164  C1236
   1 P12V_OCP_SFF_R      A @T6G_MB_LIB.T6G(SCH_1):P12V_OCP_SFF_R
   2    GND      B @T6G_MB_LIB.T6G(SCH_1):GND

Q_RES_0402LF-0,5%,1/16W,CHIP,CS00002JB13  I166  R42
   1 USB2_P11_DN      A @T6G_MB_LIB.T6G(SCH_1):USB2_P11_DN
   2 USB2_CPU0_P11_DN      B @T6G_MB_LIB.T6G(SCH_1):USB2_CPU0_P11_DN

Q_RES_0402LF-0,5%,1/16W,CHIP,CS00002JB13  I169  R1895
   1 OCP_SFF_PRSNTA_R_N      A @T6G_MB_LIB.T6G(SCH_1):OCP_SFF_PRSNTA_R_N
   2    GND      B @T6G_MB_LIB.T6G(SCH_1):GND

Q_RES_0402LF-200,1%,1/16W,CHIP,CS12002FB06  I170  R48
   1 SMB_OCP_SFF_3V3AUX_BUF_R_SDA      A @T6G_MB_LIB.T6G(SCH_1):SMB_OCP_SFF_3V3AUX_BUF_R_SDA
   2 SMB_OCP_SFF_3V3AUX_BUF_SDA      B @T6G_MB_LIB.T6G(SCH_1):SMB_OCP_SFF_3V3AUX_BUF_SDA

Q_RES_0402LF-200,1%,1/16W,CHIP,CS12002FB06  I171  R47
   1 SMB_OCP_SFF_3V3AUX_BUF_R_SCL      A @T6G_MB_LIB.T6G(SCH_1):SMB_OCP_SFF_3V3AUX_BUF_R_SCL
   2 SMB_OCP_SFF_3V3AUX_BUF_SCL      B @T6G_MB_LIB.T6G(SCH_1):SMB_OCP_SFF_3V3AUX_BUF_SCL


DRAWING: @T6G_MB_LIB.T6G(SCH_1):PAGE336 

74CBTLV3126PW-74CBTLV3126PW,SMLF,IC,AL003126K08  I1  U67
   5 NCSI_BMC_RXD0_R     2A @T6G_MB_LIB.T6G(SCH_1):NCSI_BMC_RXD0_R
   8 NCSI_OCP_SFF_CRS_DV     3B @T6G_MB_LIB.T6G(SCH_1):NCSI_OCP_SFF_CRS_DV
   1 FB_BMC_ISOLATE    1OE @T6G_MB_LIB.T6G(SCH_1):FB_BMC_ISOLATE
   4 FB_BMC_ISOLATE    2OE @T6G_MB_LIB.T6G(SCH_1):FB_BMC_ISOLATE
   3 NCSI_OCP_SFF_RXD1     1B @T6G_MB_LIB.T6G(SCH_1):NCSI_OCP_SFF_RXD1
   6 NCSI_OCP_SFF_RXD0     2B @T6G_MB_LIB.T6G(SCH_1):NCSI_OCP_SFF_RXD0
   2 NCSI_BMC_RXD1_R     1A @T6G_MB_LIB.T6G(SCH_1):NCSI_BMC_RXD1_R
   7    GND    GND @T6G_MB_LIB.T6G(SCH_1):GND
   9 NCSI_BMC_CRS_DV_R     3A @T6G_MB_LIB.T6G(SCH_1):NCSI_BMC_CRS_DV_R
  10 FB_BMC_ISOLATE    3OE @T6G_MB_LIB.T6G(SCH_1):FB_BMC_ISOLATE
  11 OCP_SFF_ISO1_RBT_ARB_IN     4B @T6G_MB_LIB.T6G(SCH_1):OCP_SFF_ISO1_RBT_ARB_IN
  12 OCP_SFF_RBT_ARB_IN_R     4A @T6G_MB_LIB.T6G(SCH_1):OCP_SFF_RBT_ARB_IN_R
  13 FB_BMC_ISOLATE    4OE @T6G_MB_LIB.T6G(SCH_1):FB_BMC_ISOLATE
  14 P3V3_AUX    VCC @T6G_MB_LIB.T6G(SCH_1):P3V3_AUX

74CBTLV3126PW-74CBTLV3126PW,SMLF,IC,AL003126K08  I2  U7
   5 NCSI_BMC_TXD0_R     2A @T6G_MB_LIB.T6G(SCH_1):NCSI_BMC_TXD0_R
   8 NCSI_OCP_SFF_TX_EN     3B @T6G_MB_LIB.T6G(SCH_1):NCSI_OCP_SFF_TX_EN
   1 FB_BMC_ISOLATE    1OE @T6G_MB_LIB.T6G(SCH_1):FB_BMC_ISOLATE
   4 FB_BMC_ISOLATE    2OE @T6G_MB_LIB.T6G(SCH_1):FB_BMC_ISOLATE
   3 NCSI_OCP_SFF_TXD1     1B @T6G_MB_LIB.T6G(SCH_1):NCSI_OCP_SFF_TXD1
   6 NCSI_OCP_SFF_TXD0     2B @T6G_MB_LIB.T6G(SCH_1):NCSI_OCP_SFF_TXD0
   2 NCSI_BMC_TXD1_R     1A @T6G_MB_LIB.T6G(SCH_1):NCSI_BMC_TXD1_R
   7    GND    GND @T6G_MB_LIB.T6G(SCH_1):GND
   9 NCSI_BMC_TX_EN_R     3A @T6G_MB_LIB.T6G(SCH_1):NCSI_BMC_TX_EN_R
  10 FB_BMC_ISOLATE    3OE @T6G_MB_LIB.T6G(SCH_1):FB_BMC_ISOLATE
  11 OCP_SFF_ISO2_RBT_ARB_OUT     4B @T6G_MB_LIB.T6G(SCH_1):OCP_SFF_ISO2_RBT_ARB_OUT
  12 OCP_SFF_RBT_ARB_OUT     4A @T6G_MB_LIB.T6G(SCH_1):OCP_SFF_RBT_ARB_OUT
  13 FB_BMC_ISOLATE    4OE @T6G_MB_LIB.T6G(SCH_1):FB_BMC_ISOLATE
  14 P3V3_AUX    VCC @T6G_MB_LIB.T6G(SCH_1):P3V3_AUX

Q_CAP_0402-0.1UF,25V,10%,X7R,CH4104K1B00  I16  C641
   1 P3V3_AUX      A @T6G_MB_LIB.T6G(SCH_1):P3V3_AUX
   2    GND      B @T6G_MB_LIB.T6G(SCH_1):GND

Q_CAP_0402-0.1UF,25V,10%,X7R,CH4104K1B00  I47  C640
   1 P3V3_AUX      A @T6G_MB_LIB.T6G(SCH_1):P3V3_AUX
   2    GND      B @T6G_MB_LIB.T6G(SCH_1):GND

Q_RES_0402LF-100K,1%,1/16W,CHIP,CS41002FB09  I56  R1289
   1 FB_BMC_ISOLATE      A @T6G_MB_LIB.T6G(SCH_1):FB_BMC_ISOLATE
   2    GND      B @T6G_MB_LIB.T6G(SCH_1):GND

Q_CAP_0402-0.1UF,25V,10%,X7R,CH4104K1B00  I59  C639
   1 P3V3_AUX      A @T6G_MB_LIB.T6G(SCH_1):P3V3_AUX
   2    GND      B @T6G_MB_LIB.T6G(SCH_1):GND

Q_RES_0402LF-22,1%,1/16W,EMPTY,CS02202FB02  I98  R1290
   1 OCP_SFF_RBT_ARB_IN_R      A @T6G_MB_LIB.T6G(SCH_1):OCP_SFF_RBT_ARB_IN_R
   2 OCP_SFF_RBT_ARB_IN      B @T6G_MB_LIB.T6G(SCH_1):OCP_SFF_RBT_ARB_IN

Q_RES_0402LF-22,1%,1/16W,CHIP,CS02202FB02  I99  R59
   1 NCSI_BMC_CRS_DV_R      A @T6G_MB_LIB.T6G(SCH_1):NCSI_BMC_CRS_DV_R
   2 RMII_OCP_BMC_CRSDV      B @T6G_MB_LIB.T6G(SCH_1):RMII_OCP_BMC_CRSDV

Q_RES_0402LF-22,1%,1/16W,CHIP,CS02202FB02  I100  R72
   1 NCSI_BMC_RXD0_R      A @T6G_MB_LIB.T6G(SCH_1):NCSI_BMC_RXD0_R
   2 RMII_OCP_BMC_RXD_0      B @T6G_MB_LIB.T6G(SCH_1):RMII_OCP_BMC_RXD_0

Q_RES_0402LF-22,1%,1/16W,CHIP,CS02202FB02  I101  R73
   1 NCSI_BMC_RXD1_R      A @T6G_MB_LIB.T6G(SCH_1):NCSI_BMC_RXD1_R
   2 RMII_OCP_BMC_RXD_1      B @T6G_MB_LIB.T6G(SCH_1):RMII_OCP_BMC_RXD_1

Q_RES_0402LF-0,5%,1/16W,CHIP,CS00002JB13  I102  R74
   1 NCSI_BMC_TX_EN_R      A @T6G_MB_LIB.T6G(SCH_1):NCSI_BMC_TX_EN_R
   2 RMII_BMC_OCP_TX_EN      B @T6G_MB_LIB.T6G(SCH_1):RMII_BMC_OCP_TX_EN

Q_RES_0402LF-0,5%,1/16W,CHIP,CS00002JB13  I103  R75
   1 NCSI_BMC_TXD0_R      A @T6G_MB_LIB.T6G(SCH_1):NCSI_BMC_TXD0_R
   2 RMII_BMC_OCP_TXD_0      B @T6G_MB_LIB.T6G(SCH_1):RMII_BMC_OCP_TXD_0

Q_RES_0402LF-0,5%,1/16W,CHIP,CS00002JB13  I104  R76
   1 NCSI_BMC_TXD1_R      A @T6G_MB_LIB.T6G(SCH_1):NCSI_BMC_TXD1_R
   2 RMII_BMC_OCP_TXD_1      B @T6G_MB_LIB.T6G(SCH_1):RMII_BMC_OCP_TXD_1

Q_RES_0402LF-33.2,1%,1/16W,CHIP,CS03322FB03  I119  R1719
   1 OCP_SFF_AUX_PWR_EN      A @T6G_MB_LIB.T6G(SCH_1):OCP_SFF_AUX_PWR_EN
   2 OCP_SFF_AUX_PWR_EN_R1      B @T6G_MB_LIB.T6G(SCH_1):OCP_SFF_AUX_PWR_EN_R1

Q_RES_0402LF-100,1%,1/16W,CHIP,CS11002FB07  I122  R1898
   1 OCP_SFF_ISO_BIF2_EN      A @T6G_MB_LIB.T6G(SCH_1):OCP_SFF_ISO_BIF2_EN
   2    GND      B @T6G_MB_LIB.T6G(SCH_1):GND

Q_RES_0402LF-100,1%,1/16W,CHIP,CS11002FB07  I123  R1896
   1 OCP_SFF_ISO_BIF0_EN      A @T6G_MB_LIB.T6G(SCH_1):OCP_SFF_ISO_BIF0_EN
   2    GND      B @T6G_MB_LIB.T6G(SCH_1):GND

Q_RES_0402LF-100,1%,1/16W,CHIP,CS11002FB07  I124  R1897
   1 OCP_SFF_ISO_BIF1_EN      A @T6G_MB_LIB.T6G(SCH_1):OCP_SFF_ISO_BIF1_EN
   2    GND      B @T6G_MB_LIB.T6G(SCH_1):GND

Q_RES_0402LF-100K,1%,1/16W,CHIP,CS41002FB09  I129  R84
   1 RMII_BMC_OCP_TXD_1      A @T6G_MB_LIB.T6G(SCH_1):RMII_BMC_OCP_TXD_1
   2    GND      B @T6G_MB_LIB.T6G(SCH_1):GND

Q_RES_0402LF-100K,1%,1/16W,CHIP,CS41002FB09  I131  R77
   1 RMII_OCP_BMC_CRSDV      A @T6G_MB_LIB.T6G(SCH_1):RMII_OCP_BMC_CRSDV
   2    GND      B @T6G_MB_LIB.T6G(SCH_1):GND

Q_RES_0402LF-100K,1%,1/16W,CHIP,CS41002FB09  I132  R79
   1 RMII_OCP_BMC_RXD_0      A @T6G_MB_LIB.T6G(SCH_1):RMII_OCP_BMC_RXD_0
   2    GND      B @T6G_MB_LIB.T6G(SCH_1):GND

Q_RES_0402LF-100K,1%,1/16W,CHIP,CS41002FB09  I133  R80
   1 RMII_OCP_BMC_RXD_1      A @T6G_MB_LIB.T6G(SCH_1):RMII_OCP_BMC_RXD_1
   2    GND      B @T6G_MB_LIB.T6G(SCH_1):GND

Q_RES_0402LF-100K,1%,1/16W,CHIP,CS41002FB09  I134  R82
   1 RMII_BMC_OCP_TX_EN      A @T6G_MB_LIB.T6G(SCH_1):RMII_BMC_OCP_TX_EN
   2    GND      B @T6G_MB_LIB.T6G(SCH_1):GND

Q_RES_0402LF-100K,1%,1/16W,CHIP,CS41002FB09  I135  R83
   1 RMII_BMC_OCP_TXD_0      A @T6G_MB_LIB.T6G(SCH_1):RMII_BMC_OCP_TXD_0
   2    GND      B @T6G_MB_LIB.T6G(SCH_1):GND

Q_RES_0402LF-1K,1%,1/16W,CHIP,CS21002FB06  I136  R87
   1 RMII_BMC_OCP_RX_ER      A @T6G_MB_LIB.T6G(SCH_1):RMII_BMC_OCP_RX_ER
   2    GND      B @T6G_MB_LIB.T6G(SCH_1):GND

Q_CAP_0402-0.1UF,25V,10%,X7R,CH4104K1B00  I147  C1840
   1 P3V3_AUX      A @T6G_MB_LIB.T6G(SCH_1):P3V3_AUX
   2    GND      B @T6G_MB_LIB.T6G(SCH_1):GND

Q_RES_0402LF-100K,1%,1/16W,CHIP,CS41002FB09  I152  R3232
   1 RST_HP_OCP_SFF_R_N      A @T6G_MB_LIB.T6G(SCH_1):RST_HP_OCP_SFF_R_N
   2    GND      B @T6G_MB_LIB.T6G(SCH_1):GND

Q_RES_0402LF-0,5%,1/16W,CHIP,CS00002JB13  I153  R3233
   1 RST_HP_OCP_SFF_R_N      A @T6G_MB_LIB.T6G(SCH_1):RST_HP_OCP_SFF_R_N
   2 RST_SMB_OCP_SFF_N      B @T6G_MB_LIB.T6G(SCH_1):RST_SMB_OCP_SFF_N

Q_RES_0402LF-0,5%,1/16W,CHIP,CS00002JB13  I156  R3237
   1 OCP_SFF_RBT_ARB_OUT      A @T6G_MB_LIB.T6G(SCH_1):OCP_SFF_RBT_ARB_OUT
   2 OCP_SFF_RBT_ARB_IN_R      B @T6G_MB_LIB.T6G(SCH_1):OCP_SFF_RBT_ARB_IN_R

74LVC1G126SE7-74LVC1G126SE-7,SMLF,IC,AL1G0126009  I157  U66
   2 FM_OCP_SFF_PWR_GOOD      A @T6G_MB_LIB.T6G(SCH_1):FM_OCP_SFF_PWR_GOOD
   4 FB_BMC_ISOLATE_R1      Y @T6G_MB_LIB.T6G(SCH_1):FB_BMC_ISOLATE_R1
   5 P3V3_AUX    VCC @T6G_MB_LIB.T6G(SCH_1):P3V3_AUX
   3    GND    GND @T6G_MB_LIB.T6G(SCH_1):GND
   1 OCP_SFF_AUX_PWR_EN_R1     OE @T6G_MB_LIB.T6G(SCH_1):OCP_SFF_AUX_PWR_EN_R1

74LVC1G126SE7-74LVC1G126SE-7,SMLF,IC,AL1G0126009  I159  U224
   2 RST_SMB_SWITCH_N      A @T6G_MB_LIB.T6G(SCH_1):RST_SMB_SWITCH_N
   4 RST_HP_OCP_SFF_R_N      Y @T6G_MB_LIB.T6G(SCH_1):RST_HP_OCP_SFF_R_N
   5 P3V3_AUX    VCC @T6G_MB_LIB.T6G(SCH_1):P3V3_AUX
   3    GND    GND @T6G_MB_LIB.T6G(SCH_1):GND
   1 OCP_SFF_AUX_PWR_EN_R2     OE @T6G_MB_LIB.T6G(SCH_1):OCP_SFF_AUX_PWR_EN_R2

Q_RES_0402LF-33.2,1%,1/16W,CHIP,CS03322FB03  I160  R3231
   1 OCP_SFF_AUX_PWR_EN      A @T6G_MB_LIB.T6G(SCH_1):OCP_SFF_AUX_PWR_EN
   2 OCP_SFF_AUX_PWR_EN_R2      B @T6G_MB_LIB.T6G(SCH_1):OCP_SFF_AUX_PWR_EN_R2

Q_RES_0402LF-0,5%,1/16W,CHIP,CS00002JB13  I164  R2473
   1 FB_BMC_ISOLATE_R1      A @T6G_MB_LIB.T6G(SCH_1):FB_BMC_ISOLATE_R1
   2 FB_BMC_ISOLATE      B @T6G_MB_LIB.T6G(SCH_1):FB_BMC_ISOLATE

Q_RES_0402LF-0,5%,1/16W,EMPTY,CS00002JB13  I165  R2474
   1 FM_NCSI_OCP_SFF_R_OE      A @T6G_MB_LIB.T6G(SCH_1):FM_NCSI_OCP_SFF_R_OE
   2 FB_BMC_ISOLATE      B @T6G_MB_LIB.T6G(SCH_1):FB_BMC_ISOLATE


DRAWING: @T6G_MB_LIB.T6G(SCH_1):PAGE337 

Q_CAP_0402-0.1UF,25V,10%,X7R,CH4104K1B00  I40  C72
   1 P3V3_AUX      A @T6G_MB_LIB.T6G(SCH_1):P3V3_AUX
   2    GND      B @T6G_MB_LIB.T6G(SCH_1):GND

Q_RES_0402LF-4.7K,1%,1/16W,CHIP,CS24702FB06  I42  R53
   1 P3V3_AUX      A @T6G_MB_LIB.T6G(SCH_1):P3V3_AUX
   2 OCP_SFF_PWRBRK_BUFF_N      B @T6G_MB_LIB.T6G(SCH_1):OCP_SFF_PWRBRK_BUFF_N

Q_RES_0402LF-33.2,1%,1/16W,CHIP,CS03322FB03  I44  R1595
   1 OCP_SFF_PWRBRK_BUFF_N      A @T6G_MB_LIB.T6G(SCH_1):OCP_SFF_PWRBRK_BUFF_N
   2 OCP_SFF_PWRBRK_N      B @T6G_MB_LIB.T6G(SCH_1):OCP_SFF_PWRBRK_N

Q_CAP_0402-0.1UF,25V,10%,X7R,CH4104K1B00  I53  C2344
   1 P3V3_AUX      A @T6G_MB_LIB.T6G(SCH_1):P3V3_AUX
   2    GND      B @T6G_MB_LIB.T6G(SCH_1):GND

Q_RES_0402LF-4.7K,1%,1/16W,EMPTY,CS24702FB06  I56  R2487
   1 P3V3_AUX      A @T6G_MB_LIB.T6G(SCH_1):P3V3_AUX
   2 IRQ_LVC3_WAKE_BUF_N      B @T6G_MB_LIB.T6G(SCH_1):IRQ_LVC3_WAKE_BUF_N

Q_RES_0402LF-10K,1%,1/16W,CHIP,CS31002FB08  I1  R1138
   1 P3V3_AUX      A @T6G_MB_LIB.T6G(SCH_1):P3V3_AUX
   2 CLK_50M_EN      B @T6G_MB_LIB.T6G(SCH_1):CLK_50M_EN

Q_CAP_0402-0.1UF,25V,10%,X7R,CH4104K1B00  I3  C1274
   1 P3V3_AUX      A @T6G_MB_LIB.T6G(SCH_1):P3V3_AUX
   2    GND      B @T6G_MB_LIB.T6G(SCH_1):GND

Q_OSC4P_SMLF-50MHZ,OSC,BF650000032  I4  OSC1
   1 CLK_50M_EN     OE @T6G_MB_LIB.T6G(SCH_1):CLK_50M_EN
   3 CLK_50M_RMII    OUT @T6G_MB_LIB.T6G(SCH_1):CLK_50M_RMII
   2    GND    GND @T6G_MB_LIB.T6G(SCH_1):GND
   4 P3V3_AUX    VDD @T6G_MB_LIB.T6G(SCH_1):P3V3_AUX

Q_RES_0402LF-0,5%,1/16W,CHIP,CS00002JB13  I7  R1139
   1 CLK_50M_RMII      A @T6G_MB_LIB.T6G(SCH_1):CLK_50M_RMII
   2 CLK_50M_RMII_R      B @T6G_MB_LIB.T6G(SCH_1):CLK_50M_RMII_R

74LVC1G126SE7-74LVC1G126SE-7,SMLF,IC,AL1G0126009  I8  U8082
   2 IRQ_LVC3_OCP_SFF_WAKE_N      A @T6G_MB_LIB.T6G(SCH_1):IRQ_LVC3_OCP_SFF_WAKE_N
   4 OCP_SFF_WAKE_BUFF_N      Y @T6G_MB_LIB.T6G(SCH_1):OCP_SFF_WAKE_BUFF_N
   5 P3V3_AUX    VCC @T6G_MB_LIB.T6G(SCH_1):P3V3_AUX
   3    GND    GND @T6G_MB_LIB.T6G(SCH_1):GND
   1 PU_OCP_SFF_WAKE_OE     OE @T6G_MB_LIB.T6G(SCH_1):PU_OCP_SFF_WAKE_OE

Q_RES_0402LF-10K,1%,1/16W,CHIP,CS31002FB08  I11  R1824
   1 P3V3_OCP_SFF      A @T6G_MB_LIB.T6G(SCH_1):P3V3_OCP_SFF
   2 IRQ_LVC3_OCP_SFF_WAKE_N      B @T6G_MB_LIB.T6G(SCH_1):IRQ_LVC3_OCP_SFF_WAKE_N

Q_RES_0402LF-10K,1%,1/16W,CHIP,CS31002FB08  I12  R45
   1 P3V3_OCP_SFF      A @T6G_MB_LIB.T6G(SCH_1):P3V3_OCP_SFF
   2 PU_OCP_SFF_WAKE_OE      B @T6G_MB_LIB.T6G(SCH_1):PU_OCP_SFF_WAKE_OE

PI6CV304LE-PI6CV304LE,SMLF,IC,AL000304K01  I16  U90
   1 CLK_50M_RMII_R CLK_IN @T6G_MB_LIB.T6G(SCH_1):CLK_50M_RMII_R
   2 CLK_50M_EN     OE @T6G_MB_LIB.T6G(SCH_1):CLK_50M_EN
   3 CLK_50M_BMC_MAC_R     Y0 @T6G_MB_LIB.T6G(SCH_1):CLK_50M_BMC_MAC_R
   5 CLK_50M_NCSI_OCP_1     Y1 @T6G_MB_LIB.T6G(SCH_1):CLK_50M_NCSI_OCP_1
   7 CLK_50M_NCSI_OCP_2     Y2 @T6G_MB_LIB.T6G(SCH_1):CLK_50M_NCSI_OCP_2
   8 TP_CLK_50M_Y3     Y3 @T6G_MB_LIB.T6G(SCH_1):TP_CLK_50M_Y3
   6 P3V3_AUX    VDD @T6G_MB_LIB.T6G(SCH_1):P3V3_AUX
   4    GND    GND @T6G_MB_LIB.T6G(SCH_1):GND

Q_CAP_0402-0.1UF,25V,10%,X7R,CH4104K1B00  I19  C1275
   1 P3V3_AUX      A @T6G_MB_LIB.T6G(SCH_1):P3V3_AUX
   2    GND      B @T6G_MB_LIB.T6G(SCH_1):GND

Q_RES_0402LF-27.4,1%,1/16W,CHIP,CS02742FB03  I20  R3181
   1 CLK_50M_NCSI_OCP_2      A @T6G_MB_LIB.T6G(SCH_1):CLK_50M_NCSI_OCP_2
   2 CLK_50M_NCSI_OCP_V3_2      B @T6G_MB_LIB.T6G(SCH_1):CLK_50M_NCSI_OCP_V3_2

Q_RES_0402LF-27.4,1%,1/16W,CHIP,CS02742FB03  I21  R1141
   1 CLK_50M_NCSI_OCP_1      A @T6G_MB_LIB.T6G(SCH_1):CLK_50M_NCSI_OCP_1
   2 CLK_50M_NCSI_OCP_SFF      B @T6G_MB_LIB.T6G(SCH_1):CLK_50M_NCSI_OCP_SFF

Q_RES_0402LF-27.4,1%,1/16W,CHIP,CS02742FB03  I22  R1140
   1 CLK_50M_BMC_MAC_R      A @T6G_MB_LIB.T6G(SCH_1):CLK_50M_BMC_MAC_R
   2 CLK_50M_RMII_BMC_OCP      B @T6G_MB_LIB.T6G(SCH_1):CLK_50M_RMII_BMC_OCP

74LVC1G07GV-74LVC1G07GV,SMLF,IC,AL1G0007001  I25  U157
   5 P3V3_AUX    VCC @T6G_MB_LIB.T6G(SCH_1):P3V3_AUX
   2 OCP_SFF_WAKE_BUFF_R_N      A @T6G_MB_LIB.T6G(SCH_1):OCP_SFF_WAKE_BUFF_R_N
   3    GND    GND @T6G_MB_LIB.T6G(SCH_1):GND
   4 IRQ_LVC3_WAKE_BUF_N      Y @T6G_MB_LIB.T6G(SCH_1):IRQ_LVC3_WAKE_BUF_N
   1 NC_U157_NC1    NC1 @T6G_MB_LIB.T6G(SCH_1):NC_U157_NC1

Q_RES_0402LF-0,5%,1/16W,CHIP,CS00002JB13  I29  R4601
   1 CLK_50M_NCSI_OCP_SFF_ISO      A @T6G_MB_LIB.T6G(SCH_1):CLK_50M_NCSI_OCP_SFF_ISO
   2 CLK_50M_NCSI_OCP_SFF_ISO_R      B @T6G_MB_LIB.T6G(SCH_1):CLK_50M_NCSI_OCP_SFF_ISO_R

Q_RES_0402LF-33.2,1%,1/16W,CHIP,CS03322FB03  I31  R1594
   1 OCP_SFF_WAKE_BUFF_N      A @T6G_MB_LIB.T6G(SCH_1):OCP_SFF_WAKE_BUFF_N
   2 OCP_SFF_WAKE_BUFF_R_N      B @T6G_MB_LIB.T6G(SCH_1):OCP_SFF_WAKE_BUFF_R_N

Q_CAP_0402-0.1UF,25V,10%,X7R,CH4104K1B00  I33  C36
   1 P3V3_AUX      A @T6G_MB_LIB.T6G(SCH_1):P3V3_AUX
   2    GND      B @T6G_MB_LIB.T6G(SCH_1):GND

Q_RES_0402LF-4.7K,1%,1/16W,CHIP,CS24702FB06  I35  R2488
   1 P3V3_AUX      A @T6G_MB_LIB.T6G(SCH_1):P3V3_AUX
   2 OCP_SFF_WAKE_BUFF_N      B @T6G_MB_LIB.T6G(SCH_1):OCP_SFF_WAKE_BUFF_N

74LVC1G07GV-74LVC1G07GV,SMLF,IC,AL1G0007001  I38  U104
   5 P3V3_AUX    VCC @T6G_MB_LIB.T6G(SCH_1):P3V3_AUX
   2 FM_SYS_THROTTLE_N      A @T6G_MB_LIB.T6G(SCH_1):FM_SYS_THROTTLE_N
   3    GND    GND @T6G_MB_LIB.T6G(SCH_1):GND
   4 OCP_SFF_PWRBRK_BUFF_N      Y @T6G_MB_LIB.T6G(SCH_1):OCP_SFF_PWRBRK_BUFF_N
   1 NC_U104_NC1    NC1 @T6G_MB_LIB.T6G(SCH_1):NC_U104_NC1

Q_CAP_0402-0.1UF,25V,10%,X7R,CH4104K1B00  I47  C1663
   1 P3V3_AUX      A @T6G_MB_LIB.T6G(SCH_1):P3V3_AUX
   2    GND      B @T6G_MB_LIB.T6G(SCH_1):GND

Q_RES_0402LF-33.2,1%,1/16W,CHIP,CS03322FB03  I50  R2489
   1 IRQ_LVC3_WAKE_BUF_N      A @T6G_MB_LIB.T6G(SCH_1):IRQ_LVC3_WAKE_BUF_N
   2 IRQ_OCP_SFF_WAKE_BUF_N      B @T6G_MB_LIB.T6G(SCH_1):IRQ_OCP_SFF_WAKE_BUF_N

Q_CAP_0402-0.1UF,25V,10%,X7R,CH4104K1B00  I61  C10
   1 P3V3_AUX      A @T6G_MB_LIB.T6G(SCH_1):P3V3_AUX
   2    GND      B @T6G_MB_LIB.T6G(SCH_1):GND

74LVC1G17GW-74LVC1G17GW,SMLF,IC,AL1G0017K01  I64  U75
   5 P3V3_AUX    VCC @T6G_MB_LIB.T6G(SCH_1):P3V3_AUX
   2 RST_PERST_OCP_SFF_BUF_N      A @T6G_MB_LIB.T6G(SCH_1):RST_PERST_OCP_SFF_BUF_N
   3    GND    GND @T6G_MB_LIB.T6G(SCH_1):GND
   4 RST_PERST_OCP_SFF_BUF2_N      Y @T6G_MB_LIB.T6G(SCH_1):RST_PERST_OCP_SFF_BUF2_N
   1     NC     NC     NC

Q_RES_0402LF-0,5%,1/16W,CHIP,CS00002JB13  I78  R899
   1 RST_PERST_OCP_SFF_BUF2_N      A @T6G_MB_LIB.T6G(SCH_1):RST_PERST_OCP_SFF_BUF2_N
   2 RST_PERST1_OCP_SFF_N      B @T6G_MB_LIB.T6G(SCH_1):RST_PERST1_OCP_SFF_N

Q_RES_0402LF-0,5%,1/16W,CHIP,CS00002JB13  I79  R877
   1 RST_PERST_OCP_SFF_BUF2_N      A @T6G_MB_LIB.T6G(SCH_1):RST_PERST_OCP_SFF_BUF2_N
   2 RST_PERST0_OCP_SFF_N      B @T6G_MB_LIB.T6G(SCH_1):RST_PERST0_OCP_SFF_N

Q_RES_0402LF-0,5%,1/16W,CHIP,CS00002JB13  I80  R905
   1 RST_PERST_OCP_SFF_BUF2_N      A @T6G_MB_LIB.T6G(SCH_1):RST_PERST_OCP_SFF_BUF2_N
   2 RST_PERST2_OCP_SFF_N      B @T6G_MB_LIB.T6G(SCH_1):RST_PERST2_OCP_SFF_N

Q_RES_0402LF-0,5%,1/16W,CHIP,CS00002JB13  I81  R956
   1 RST_PERST_OCP_SFF_BUF2_N      A @T6G_MB_LIB.T6G(SCH_1):RST_PERST_OCP_SFF_BUF2_N
   2 RST_PERST3_OCP_SFF_N      B @T6G_MB_LIB.T6G(SCH_1):RST_PERST3_OCP_SFF_N

74LVC1G66GV-74LVC1G66GV,SMLF,IC,AL001G66000  I82  U320
   1 CLK_50M_NCSI_OCP_SFF      Y @T6G_MB_LIB.T6G(SCH_1):CLK_50M_NCSI_OCP_SFF
   2 CLK_50M_NCSI_OCP_SFF_ISO_R      Z @T6G_MB_LIB.T6G(SCH_1):CLK_50M_NCSI_OCP_SFF_ISO_R
   3    GND    GND @T6G_MB_LIB.T6G(SCH_1):GND
   4 FB_BMC_ISOLATE      E @T6G_MB_LIB.T6G(SCH_1):FB_BMC_ISOLATE
   5 P3V3_AUX    VCC @T6G_MB_LIB.T6G(SCH_1):P3V3_AUX


DRAWING: @T6G_MB_LIB.T6G(SCH_1):PAGE341 

Q_CAP_0402-0.1UF,25V,10%,X7R,CH4104K1B00  I20  C1834
   1 P12V_OCP_V3_2_R      A @T6G_MB_LIB.T6G(SCH_1):P12V_OCP_V3_2_R
   2    GND      B @T6G_MB_LIB.T6G(SCH_1):GND

Q_CAP_0402-0.1UF,25V,10%,X7R,CH4104K1B00  I23  C1837
   1 P3V3_OCP_V3_2      A @T6G_MB_LIB.T6G(SCH_1):P3V3_OCP_V3_2
   2    GND      B @T6G_MB_LIB.T6G(SCH_1):GND

Q_RES_0402LF-4.7K,1%,1/16W,CHIP,CS24702FB06  I26  R3162
   1 P3V3_OCP_V3_2      A @T6G_MB_LIB.T6G(SCH_1):P3V3_OCP_V3_2
   2 OCP_V3_2_ID0      B @T6G_MB_LIB.T6G(SCH_1):OCP_V3_2_ID0

Q_RES_0402LF-10K,1%,1/16W,CHIP,CS31002FB08  I32  R3165
   1    GND      A @T6G_MB_LIB.T6G(SCH_1):GND
   2 OCP_V3_2_MAIN_PWR_EN      B @T6G_MB_LIB.T6G(SCH_1):OCP_V3_2_MAIN_PWR_EN

Q_RES_0402LF-100K,1%,1/16W,CHIP,CS41002FB09  I33  R8413
   1    GND      A @T6G_MB_LIB.T6G(SCH_1):GND
   2 FM_OCP_V3_2_PWR_GOOD      B @T6G_MB_LIB.T6G(SCH_1):FM_OCP_V3_2_PWR_GOOD

Q_RES_0402LF-0,5%,1/16W,CHIP,CS00002JB13  I43  R3169
   1 OCP_V3_2_ISO_BIF0_EN      A @T6G_MB_LIB.T6G(SCH_1):OCP_V3_2_ISO_BIF0_EN
   2 OCP_V3_2_BIF0_R_N      B @T6G_MB_LIB.T6G(SCH_1):OCP_V3_2_BIF0_R_N

SCONN168_ME1016810202011-SCONN168_ME1016810202011,A  I168  J35
 OB1 FM_OCP_V3_2_PWR_GOOD NIC_PWR_GOOD @T6G_MB_LIB.T6G(SCH_1):FM_OCP_V3_2_PWR_GOOD
 OB2 OCP_V3_2_MAIN_PWR_EN_R MAIN_PWR_EN @T6G_MB_LIB.T6G(SCH_1):OCP_V3_2_MAIN_PWR_EN_R
 OB3 SGPIO_OCP_V3_2_LD_N    LD# @T6G_MB_LIB.T6G(SCH_1):SGPIO_OCP_V3_2_LD_N
 OB4 SGPIO_OCP_V3_2_DATAIN DATA_IN @T6G_MB_LIB.T6G(SCH_1):SGPIO_OCP_V3_2_DATAIN
 OB5 SGPIO_OCP_V3_2_DATAOUT DATA_OUT @T6G_MB_LIB.T6G(SCH_1):SGPIO_OCP_V3_2_DATAOUT
 OB6 SGPIO_OCP_V3_2_CLK    CLK @T6G_MB_LIB.T6G(SCH_1):SGPIO_OCP_V3_2_CLK
 OB7 OCP_V3_2_ID0 SLOT_ID0 @T6G_MB_LIB.T6G(SCH_1):OCP_V3_2_ID0
 OB8 NCSI_OCP_V3_2_RXD1 RBT_RXD1 @T6G_MB_LIB.T6G(SCH_1):NCSI_OCP_V3_2_RXD1
 OB9 NCSI_OCP_V3_2_RXD0 RBT_RXD0 @T6G_MB_LIB.T6G(SCH_1):NCSI_OCP_V3_2_RXD0
OB10    GND GND_OB10 @T6G_MB_LIB.T6G(SCH_1):GND
OB11 CLK_100M_CPU1_CLK04_DN REFCLKN2 @T6G_MB_LIB.T6G(SCH_1):CLK_100M_CPU1_CLK04_DN
OB12 CLK_100M_CPU1_CLK04_DP REFCLKP2 @T6G_MB_LIB.T6G(SCH_1):CLK_100M_CPU1_CLK04_DP
OB13    GND GND_OB13 @T6G_MB_LIB.T6G(SCH_1):GND
OB14 NCSI_OCP_V3_2_CRS_DV RBT_CRS_DV @T6G_MB_LIB.T6G(SCH_1):NCSI_OCP_V3_2_CRS_DV
  B1 P12V_OCP_V3_2_R +12V_EDGE_B1 @T6G_MB_LIB.T6G(SCH_1):P12V_OCP_V3_2_R
  B2 P12V_OCP_V3_2_R +12V_EDGE_B2 @T6G_MB_LIB.T6G(SCH_1):P12V_OCP_V3_2_R
  B3 P12V_OCP_V3_2_R +12V_EDGE_B3 @T6G_MB_LIB.T6G(SCH_1):P12V_OCP_V3_2_R
  B4 P12V_OCP_V3_2_R +12V_EDGE_B4 @T6G_MB_LIB.T6G(SCH_1):P12V_OCP_V3_2_R
  B5 P12V_OCP_V3_2_R +12V_EDGE_B5 @T6G_MB_LIB.T6G(SCH_1):P12V_OCP_V3_2_R
  B6 P12V_OCP_V3_2_R +12V_EDGE_B6 @T6G_MB_LIB.T6G(SCH_1):P12V_OCP_V3_2_R
  B7 OCP_V3_2_BIF0_R_N  BIF0# @T6G_MB_LIB.T6G(SCH_1):OCP_V3_2_BIF0_R_N
  B8 OCP_V3_2_BIF1_R_N  BIF1# @T6G_MB_LIB.T6G(SCH_1):OCP_V3_2_BIF1_R_N
  B9 OCP_V3_2_BIF2_R_N  BIF2# @T6G_MB_LIB.T6G(SCH_1):OCP_V3_2_BIF2_R_N
 B10 RST_PERST0_OCP_V3_2_N PERST0# @T6G_MB_LIB.T6G(SCH_1):RST_PERST0_OCP_V3_2_N
 B11 P3V3_OCP_V3_2 +3.3V_EDGE @T6G_MB_LIB.T6G(SCH_1):P3V3_OCP_V3_2
 B12 OCP_V3_2_AUX_PWR_EN_R AUX_PWR_EN @T6G_MB_LIB.T6G(SCH_1):OCP_V3_2_AUX_PWR_EN_R
 B13    GND GND_B13 @T6G_MB_LIB.T6G(SCH_1):GND
 B14 CLK_100M_CPU1_CLK02_DN REFCLKN0 @T6G_MB_LIB.T6G(SCH_1):CLK_100M_CPU1_CLK02_DN
 B15 CLK_100M_CPU1_CLK02_DP REFCLKP0 @T6G_MB_LIB.T6G(SCH_1):CLK_100M_CPU1_CLK02_DP
 B16    GND GND_B16 @T6G_MB_LIB.T6G(SCH_1):GND
 B17 P5E_CPU1_G1_TX_C_DP<0>  PETN0 @T6G_MB_LIB.T6G(SCH_1):P5E_CPU1_G1_TX_C_DP(0)
 B18 P5E_CPU1_G1_TX_C_DN<0>  PETP0 @T6G_MB_LIB.T6G(SCH_1):P5E_CPU1_G1_TX_C_DN(0)
 B19    GND GND_B19 @T6G_MB_LIB.T6G(SCH_1):GND
 B20 P5E_CPU1_G1_TX_C_DP<1>  PETN1 @T6G_MB_LIB.T6G(SCH_1):P5E_CPU1_G1_TX_C_DP(1)
 B21 P5E_CPU1_G1_TX_C_DN<1>  PETP1 @T6G_MB_LIB.T6G(SCH_1):P5E_CPU1_G1_TX_C_DN(1)
 B22    GND GND_B22 @T6G_MB_LIB.T6G(SCH_1):GND
 B23 P5E_CPU1_G1_TX_C_DP<2>  PETN2 @T6G_MB_LIB.T6G(SCH_1):P5E_CPU1_G1_TX_C_DP(2)
 B24 P5E_CPU1_G1_TX_C_DN<2>  PETP2 @T6G_MB_LIB.T6G(SCH_1):P5E_CPU1_G1_TX_C_DN(2)
 B25    GND GND_B25 @T6G_MB_LIB.T6G(SCH_1):GND
 B26 P5E_CPU1_G1_TX_C_DP<3>  PETN3 @T6G_MB_LIB.T6G(SCH_1):P5E_CPU1_G1_TX_C_DP(3)
 B27 P5E_CPU1_G1_TX_C_DN<3>  PETP3 @T6G_MB_LIB.T6G(SCH_1):P5E_CPU1_G1_TX_C_DN(3)
 B28    GND GND_B28 @T6G_MB_LIB.T6G(SCH_1):GND
 B29    GND GND_B29 @T6G_MB_LIB.T6G(SCH_1):GND
 B30 P5E_CPU1_G1_TX_C_DP<4>  PETN4 @T6G_MB_LIB.T6G(SCH_1):P5E_CPU1_G1_TX_C_DP(4)
 B31 P5E_CPU1_G1_TX_C_DN<4>  PETP4 @T6G_MB_LIB.T6G(SCH_1):P5E_CPU1_G1_TX_C_DN(4)
 B32    GND GND_B32 @T6G_MB_LIB.T6G(SCH_1):GND
 B33 P5E_CPU1_G1_TX_C_DP<5>  PETN5 @T6G_MB_LIB.T6G(SCH_1):P5E_CPU1_G1_TX_C_DP(5)
 B34 P5E_CPU1_G1_TX_C_DN<5>  PETP5 @T6G_MB_LIB.T6G(SCH_1):P5E_CPU1_G1_TX_C_DN(5)
 B35    GND GND_B35 @T6G_MB_LIB.T6G(SCH_1):GND
 B36 P5E_CPU1_G1_TX_C_DP<6>  PETN6 @T6G_MB_LIB.T6G(SCH_1):P5E_CPU1_G1_TX_C_DP(6)
 B37 P5E_CPU1_G1_TX_C_DN<6>  PETP6 @T6G_MB_LIB.T6G(SCH_1):P5E_CPU1_G1_TX_C_DN(6)
 B38    GND GND_B38 @T6G_MB_LIB.T6G(SCH_1):GND
 B39 P5E_CPU1_G1_TX_C_DP<7>  PETN7 @T6G_MB_LIB.T6G(SCH_1):P5E_CPU1_G1_TX_C_DP(7)
 B40 P5E_CPU1_G1_TX_C_DN<7>  PETP7 @T6G_MB_LIB.T6G(SCH_1):P5E_CPU1_G1_TX_C_DN(7)
 B41    GND GND_B41 @T6G_MB_LIB.T6G(SCH_1):GND
 B42 OCP_V3_2_PRSNT0_R_N PRSNTB0# @T6G_MB_LIB.T6G(SCH_1):OCP_V3_2_PRSNT0_R_N
 B43    GND GND_B43 @T6G_MB_LIB.T6G(SCH_1):GND
 B44 P5E_CPU1_G1_TX_C_DP<8>  PETN8 @T6G_MB_LIB.T6G(SCH_1):P5E_CPU1_G1_TX_C_DP(8)
 B45 P5E_CPU1_G1_TX_C_DN<8>  PETP8 @T6G_MB_LIB.T6G(SCH_1):P5E_CPU1_G1_TX_C_DN(8)
 B46    GND GND_B46 @T6G_MB_LIB.T6G(SCH_1):GND
 B47 P5E_CPU1_G1_TX_C_DP<9>  PETN9 @T6G_MB_LIB.T6G(SCH_1):P5E_CPU1_G1_TX_C_DP(9)
 B48 P5E_CPU1_G1_TX_C_DN<9>  PETP9 @T6G_MB_LIB.T6G(SCH_1):P5E_CPU1_G1_TX_C_DN(9)
 B49    GND GND_B49 @T6G_MB_LIB.T6G(SCH_1):GND
 B50 P5E_CPU1_G1_TX_C_DP<10> PETN10 @T6G_MB_LIB.T6G(SCH_1):P5E_CPU1_G1_TX_C_DP(10)
 B51 P5E_CPU1_G1_TX_C_DN<10> PETP10 @T6G_MB_LIB.T6G(SCH_1):P5E_CPU1_G1_TX_C_DN(10)
 B52    GND GND_B52 @T6G_MB_LIB.T6G(SCH_1):GND
 B53 P5E_CPU1_G1_TX_C_DP<11> PETN11 @T6G_MB_LIB.T6G(SCH_1):P5E_CPU1_G1_TX_C_DP(11)
 B54 P5E_CPU1_G1_TX_C_DN<11> PETP11 @T6G_MB_LIB.T6G(SCH_1):P5E_CPU1_G1_TX_C_DN(11)
 B55    GND GND_B55 @T6G_MB_LIB.T6G(SCH_1):GND
 B56 P5E_CPU1_G1_TX_C_DP<12> PETN12 @T6G_MB_LIB.T6G(SCH_1):P5E_CPU1_G1_TX_C_DP(12)
 OA1 RST_PERST2_OCP_V3_2_N PERST2# @T6G_MB_LIB.T6G(SCH_1):RST_PERST2_OCP_V3_2_N
 OA2 RST_PERST3_OCP_V3_2_N PERST3# @T6G_MB_LIB.T6G(SCH_1):RST_PERST3_OCP_V3_2_N
 OA3 IRQ_LVC3_OCP_V3_2_WAKE_N  WAKE# @T6G_MB_LIB.T6G(SCH_1):IRQ_LVC3_OCP_V3_2_WAKE_N
 OA4 OCP_V3_2_ISO1_RBT_ARB_IN RBT_ARB_IN @T6G_MB_LIB.T6G(SCH_1):OCP_V3_2_ISO1_RBT_ARB_IN
 OA5 OCP_V3_2_ISO2_RBT_ARB_OUT RBT_ARB_OUT @T6G_MB_LIB.T6G(SCH_1):OCP_V3_2_ISO2_RBT_ARB_OUT
 OA6 OCP_V3_2_ID1 SLOT_ID1 @T6G_MB_LIB.T6G(SCH_1):OCP_V3_2_ID1
 OA7 NCSI_OCP_V3_2_TX_EN RBT_TX_EN @T6G_MB_LIB.T6G(SCH_1):NCSI_OCP_V3_2_TX_EN
 OA8 NCSI_OCP_V3_2_TXD1 RBT_TXD1 @T6G_MB_LIB.T6G(SCH_1):NCSI_OCP_V3_2_TXD1
 OA9 NCSI_OCP_V3_2_TXD0 RBT_TXD0 @T6G_MB_LIB.T6G(SCH_1):NCSI_OCP_V3_2_TXD0
OA10    GND GND_OA10 @T6G_MB_LIB.T6G(SCH_1):GND
OA11 CLK_100M_CPU1_CLK05_DN REFCLKN3 @T6G_MB_LIB.T6G(SCH_1):CLK_100M_CPU1_CLK05_DN
OA12 CLK_100M_CPU1_CLK05_DP REFCLKP3 @T6G_MB_LIB.T6G(SCH_1):CLK_100M_CPU1_CLK05_DP
OA13    GND GND_OA13 @T6G_MB_LIB.T6G(SCH_1):GND
OA14 CLK_50M_NCSI_OCP_V3_2_ISO RBT_CLK_IN @T6G_MB_LIB.T6G(SCH_1):CLK_50M_NCSI_OCP_V3_2_ISO
  A1    GND GND_A1 @T6G_MB_LIB.T6G(SCH_1):GND
  A2    GND GND_A2 @T6G_MB_LIB.T6G(SCH_1):GND
  A3    GND GND_A3 @T6G_MB_LIB.T6G(SCH_1):GND
  A4    GND GND_A4 @T6G_MB_LIB.T6G(SCH_1):GND
  A5    GND GND_A5 @T6G_MB_LIB.T6G(SCH_1):GND
  A6    GND GND_A6 @T6G_MB_LIB.T6G(SCH_1):GND
  A7 SMB_OCP_V3_2_3V3AUX_BUF_R_SCL  SMCLK @T6G_MB_LIB.T6G(SCH_1):SMB_OCP_V3_2_3V3AUX_BUF_R_SCL
  A8 SMB_OCP_V3_2_3V3AUX_BUF_R_SDA  SMDAT @T6G_MB_LIB.T6G(SCH_1):SMB_OCP_V3_2_3V3AUX_BUF_R_SDA
  A9 RST_SMB_OCP_V3_2_N SMRST# @T6G_MB_LIB.T6G(SCH_1):RST_SMB_OCP_V3_2_N
 A10 OCP_V3_2_PRSNTA_R_N PRSNTA# @T6G_MB_LIB.T6G(SCH_1):OCP_V3_2_PRSNTA_R_N
 A11 RST_PERST1_OCP_V3_2_N PERST1# @T6G_MB_LIB.T6G(SCH_1):RST_PERST1_OCP_V3_2_N
 A12 OCP_V3_2_PRSNT2_R_N PRSNTB2# @T6G_MB_LIB.T6G(SCH_1):OCP_V3_2_PRSNT2_R_N
 A13    GND GND_A13 @T6G_MB_LIB.T6G(SCH_1):GND
 A14 CLK_100M_CPU1_CLK03_DN REFCLKN1 @T6G_MB_LIB.T6G(SCH_1):CLK_100M_CPU1_CLK03_DN
 A15 CLK_100M_CPU1_CLK03_DP REFCLKP1 @T6G_MB_LIB.T6G(SCH_1):CLK_100M_CPU1_CLK03_DP
 A16    GND GND_A16 @T6G_MB_LIB.T6G(SCH_1):GND
 A17 P5E_CPU1_G1_RX_DN<0>  PERN0 @T6G_MB_LIB.T6G(SCH_1):P5E_CPU1_G1_RX_DN(0)
 A18 P5E_CPU1_G1_RX_DP<0>  PERP0 @T6G_MB_LIB.T6G(SCH_1):P5E_CPU1_G1_RX_DP(0)
 A19    GND GND_A19 @T6G_MB_LIB.T6G(SCH_1):GND
 A20 P5E_CPU1_G1_RX_DN<1>  PERN1 @T6G_MB_LIB.T6G(SCH_1):P5E_CPU1_G1_RX_DN(1)
 A21 P5E_CPU1_G1_RX_DP<1>  PERP1 @T6G_MB_LIB.T6G(SCH_1):P5E_CPU1_G1_RX_DP(1)
 A22    GND GND_A22 @T6G_MB_LIB.T6G(SCH_1):GND
 A23 P5E_CPU1_G1_RX_DN<2>  PERN2 @T6G_MB_LIB.T6G(SCH_1):P5E_CPU1_G1_RX_DN(2)
 A24 P5E_CPU1_G1_RX_DP<2>  PERP2 @T6G_MB_LIB.T6G(SCH_1):P5E_CPU1_G1_RX_DP(2)
 A25    GND GND_A25 @T6G_MB_LIB.T6G(SCH_1):GND
 A26 P5E_CPU1_G1_RX_DN<3>  PERN3 @T6G_MB_LIB.T6G(SCH_1):P5E_CPU1_G1_RX_DN(3)
 A27 P5E_CPU1_G1_RX_DP<3>  PERP3 @T6G_MB_LIB.T6G(SCH_1):P5E_CPU1_G1_RX_DP(3)
 A28    GND GND_A28 @T6G_MB_LIB.T6G(SCH_1):GND
 A29    GND GND_A29 @T6G_MB_LIB.T6G(SCH_1):GND
 A30 P5E_CPU1_G1_RX_DN<4>  PERN4 @T6G_MB_LIB.T6G(SCH_1):P5E_CPU1_G1_RX_DN(4)
 A31 P5E_CPU1_G1_RX_DP<4>  PERP4 @T6G_MB_LIB.T6G(SCH_1):P5E_CPU1_G1_RX_DP(4)
 A32    GND GND_A32 @T6G_MB_LIB.T6G(SCH_1):GND
 A33 P5E_CPU1_G1_RX_DN<5>  PERN5 @T6G_MB_LIB.T6G(SCH_1):P5E_CPU1_G1_RX_DN(5)
 A34 P5E_CPU1_G1_RX_DP<5>  PERP5 @T6G_MB_LIB.T6G(SCH_1):P5E_CPU1_G1_RX_DP(5)
 A35    GND GND_A35 @T6G_MB_LIB.T6G(SCH_1):GND
 A36 P5E_CPU1_G1_RX_DN<6>  PERN6 @T6G_MB_LIB.T6G(SCH_1):P5E_CPU1_G1_RX_DN(6)
 A37 P5E_CPU1_G1_RX_DP<6>  PERP6 @T6G_MB_LIB.T6G(SCH_1):P5E_CPU1_G1_RX_DP(6)
 A38    GND GND_A38 @T6G_MB_LIB.T6G(SCH_1):GND
 A39 P5E_CPU1_G1_RX_DN<7>  PERN7 @T6G_MB_LIB.T6G(SCH_1):P5E_CPU1_G1_RX_DN(7)
 A40 P5E_CPU1_G1_RX_DP<7>  PERP7 @T6G_MB_LIB.T6G(SCH_1):P5E_CPU1_G1_RX_DP(7)
 A41    GND GND_A41 @T6G_MB_LIB.T6G(SCH_1):GND
 A42 OCP_V3_2_PRSNT1_R_N PRSNTB1# @T6G_MB_LIB.T6G(SCH_1):OCP_V3_2_PRSNT1_R_N
 A43    GND GND_A43 @T6G_MB_LIB.T6G(SCH_1):GND
 A44 P5E_CPU1_G1_RX_DN<8>  PERN8 @T6G_MB_LIB.T6G(SCH_1):P5E_CPU1_G1_RX_DN(8)
 A45 P5E_CPU1_G1_RX_DP<8>  PERP8 @T6G_MB_LIB.T6G(SCH_1):P5E_CPU1_G1_RX_DP(8)
 A46    GND GND_A46 @T6G_MB_LIB.T6G(SCH_1):GND
 A47 P5E_CPU1_G1_RX_DN<9>  PERN9 @T6G_MB_LIB.T6G(SCH_1):P5E_CPU1_G1_RX_DN(9)
 A48 P5E_CPU1_G1_RX_DP<9>  PERP9 @T6G_MB_LIB.T6G(SCH_1):P5E_CPU1_G1_RX_DP(9)
 A49    GND GND_A49 @T6G_MB_LIB.T6G(SCH_1):GND
 A50 P5E_CPU1_G1_RX_DN<10> PERN10 @T6G_MB_LIB.T6G(SCH_1):P5E_CPU1_G1_RX_DN(10)
 A51 P5E_CPU1_G1_RX_DP<10> PERP10 @T6G_MB_LIB.T6G(SCH_1):P5E_CPU1_G1_RX_DP(10)
 A52    GND GND_A52 @T6G_MB_LIB.T6G(SCH_1):GND
 A53 P5E_CPU1_G1_RX_DN<11> PERN11 @T6G_MB_LIB.T6G(SCH_1):P5E_CPU1_G1_RX_DN(11)
 A54 P5E_CPU1_G1_RX_DP<11> PERP11 @T6G_MB_LIB.T6G(SCH_1):P5E_CPU1_G1_RX_DP(11)
 A55    GND GND_A55 @T6G_MB_LIB.T6G(SCH_1):GND
 A56 P5E_CPU1_G1_RX_DN<12> PERN12 @T6G_MB_LIB.T6G(SCH_1):P5E_CPU1_G1_RX_DN(12)
 A57 P5E_CPU1_G1_RX_DP<12> PERP12 @T6G_MB_LIB.T6G(SCH_1):P5E_CPU1_G1_RX_DP(12)
 A58    GND GND_A58 @T6G_MB_LIB.T6G(SCH_1):GND
 A59 P5E_CPU1_G1_RX_DN<13> PERN13 @T6G_MB_LIB.T6G(SCH_1):P5E_CPU1_G1_RX_DN(13)
 A60 P5E_CPU1_G1_RX_DP<13> PERP13 @T6G_MB_LIB.T6G(SCH_1):P5E_CPU1_G1_RX_DP(13)
 A61    GND GND_A61 @T6G_MB_LIB.T6G(SCH_1):GND
 A62 P5E_CPU1_G1_RX_DN<14> PERN14 @T6G_MB_LIB.T6G(SCH_1):P5E_CPU1_G1_RX_DN(14)
 A63 P5E_CPU1_G1_RX_DP<14> PERP14 @T6G_MB_LIB.T6G(SCH_1):P5E_CPU1_G1_RX_DP(14)
 A64    GND GND_A64 @T6G_MB_LIB.T6G(SCH_1):GND
 A65 P5E_CPU1_G1_RX_DN<15> PERN15 @T6G_MB_LIB.T6G(SCH_1):P5E_CPU1_G1_RX_DN(15)
 A66 P5E_CPU1_G1_RX_DP<15> PERP15 @T6G_MB_LIB.T6G(SCH_1):P5E_CPU1_G1_RX_DP(15)
 A67    GND GND_A67 @T6G_MB_LIB.T6G(SCH_1):GND
 A68 USB2_P10_DN USB_DATN @T6G_MB_LIB.T6G(SCH_1):USB2_P10_DN
 A69 USB2_P10_DP USB_DATP @T6G_MB_LIB.T6G(SCH_1):USB2_P10_DP
 A70 OCP_V3_2_PWRBRK_N PWRBRK0# @T6G_MB_LIB.T6G(SCH_1):OCP_V3_2_PWRBRK_N
 B57 P5E_CPU1_G1_TX_C_DN<12> PETP12 @T6G_MB_LIB.T6G(SCH_1):P5E_CPU1_G1_TX_C_DN(12)
 B58    GND GND_B58 @T6G_MB_LIB.T6G(SCH_1):GND
 B59 P5E_CPU1_G1_TX_C_DP<13> PETN13 @T6G_MB_LIB.T6G(SCH_1):P5E_CPU1_G1_TX_C_DP(13)
 B60 P5E_CPU1_G1_TX_C_DN<13> PETP13 @T6G_MB_LIB.T6G(SCH_1):P5E_CPU1_G1_TX_C_DN(13)
 B61    GND GND_B61 @T6G_MB_LIB.T6G(SCH_1):GND
 B62 P5E_CPU1_G1_TX_C_DP<14> PETN14 @T6G_MB_LIB.T6G(SCH_1):P5E_CPU1_G1_TX_C_DP(14)
 B63 P5E_CPU1_G1_TX_C_DN<14> PETP14 @T6G_MB_LIB.T6G(SCH_1):P5E_CPU1_G1_TX_C_DN(14)
 B64    GND GND_B64 @T6G_MB_LIB.T6G(SCH_1):GND
 B65 P5E_CPU1_G1_TX_C_DP<15> PETN15 @T6G_MB_LIB.T6G(SCH_1):P5E_CPU1_G1_TX_C_DP(15)
 B66 P5E_CPU1_G1_TX_C_DN<15> PETP15 @T6G_MB_LIB.T6G(SCH_1):P5E_CPU1_G1_TX_C_DN(15)
 B67    GND GND_B67 @T6G_MB_LIB.T6G(SCH_1):GND
 B68 TP_OCP_V3_2_B68 RFU1_NC_B68 @T6G_MB_LIB.T6G(SCH_1):TP_OCP_V3_2_B68
 B69 TP_OCP_V3_2_B69 RFU1_NC_B69 @T6G_MB_LIB.T6G(SCH_1):TP_OCP_V3_2_B69
 B70 OCP_V3_2_PRSNT3_R_N PRSNTB3# @T6G_MB_LIB.T6G(SCH_1):OCP_V3_2_PRSNT3_R_N
  G1    GND     G1 @T6G_MB_LIB.T6G(SCH_1):GND
  G2    GND     G2 @T6G_MB_LIB.T6G(SCH_1):GND
  G3    GND     G3 @T6G_MB_LIB.T6G(SCH_1):GND
  G4    GND     G4 @T6G_MB_LIB.T6G(SCH_1):GND
  G5    GND     G5 @T6G_MB_LIB.T6G(SCH_1):GND

Q_RES_0402LF-4.7K,1%,1/16W,EMPTY,CS24702FB06  I2  R3163
   1 OCP_V3_2_ID0      A @T6G_MB_LIB.T6G(SCH_1):OCP_V3_2_ID0
   2    GND      B @T6G_MB_LIB.T6G(SCH_1):GND

Q_RES_0402LF-4.7K,1%,1/16W,CHIP,CS24702FB06  I3  R3167
   1 OCP_V3_2_ID1      A @T6G_MB_LIB.T6G(SCH_1):OCP_V3_2_ID1
   2    GND      B @T6G_MB_LIB.T6G(SCH_1):GND

Q_RES_0402LF-10K,1%,1/16W,CHIP,CS31002FB08  I9  R3174
   1 SGPIO_OCP_V3_2_DATAIN      A @T6G_MB_LIB.T6G(SCH_1):SGPIO_OCP_V3_2_DATAIN
   2 P3V3_OCP_V3_2      B @T6G_MB_LIB.T6G(SCH_1):P3V3_OCP_V3_2

Q_RES_0402LF-1K,1%,1/16W,CHIP,CS21002FB06  I10  R3173
   1 SGPIO_OCP_V3_2_LD_N      A @T6G_MB_LIB.T6G(SCH_1):SGPIO_OCP_V3_2_LD_N
   2 P3V3_OCP_V3_2      B @T6G_MB_LIB.T6G(SCH_1):P3V3_OCP_V3_2

Q_RES_0402LF-10K,1%,1/16W,CHIP,CS31002FB08  I11  R3175
   1 SGPIO_OCP_V3_2_DATAOUT      A @T6G_MB_LIB.T6G(SCH_1):SGPIO_OCP_V3_2_DATAOUT
   2    GND      B @T6G_MB_LIB.T6G(SCH_1):GND

Q_RES_0402LF-1K,1%,1/16W,CHIP,CS21002FB06  I12  R3176
   1 SGPIO_OCP_V3_2_CLK      A @T6G_MB_LIB.T6G(SCH_1):SGPIO_OCP_V3_2_CLK
   2 P3V3_OCP_V3_2      B @T6G_MB_LIB.T6G(SCH_1):P3V3_OCP_V3_2

Q_CAP_C0805-22UF,16V,20%,X6S,CH6223MEA00  I13  C1829
   1 P12V_OCP_V3_2_R      A @T6G_MB_LIB.T6G(SCH_1):P12V_OCP_V3_2_R
   2    GND      B @T6G_MB_LIB.T6G(SCH_1):GND

Q_CAP_C0805-22UF,16V,20%,X6S,CH6223MEA00  I14  C1830
   1 P12V_OCP_V3_2_R      A @T6G_MB_LIB.T6G(SCH_1):P12V_OCP_V3_2_R
   2    GND      B @T6G_MB_LIB.T6G(SCH_1):GND

Q_CAP_0402-0.1UF,25V,10%,X7R,CH4104K1B00  I15  C1831
   1 P12V_OCP_V3_2_R      A @T6G_MB_LIB.T6G(SCH_1):P12V_OCP_V3_2_R
   2    GND      B @T6G_MB_LIB.T6G(SCH_1):GND

Q_CAP_0402-0.1UF,25V,10%,X7R,CH4104K1B00  I16  C1832
   1 P12V_OCP_V3_2_R      A @T6G_MB_LIB.T6G(SCH_1):P12V_OCP_V3_2_R
   2    GND      B @T6G_MB_LIB.T6G(SCH_1):GND

Q_CAP_0402-0.1UF,25V,10%,X7R,CH4104K1B00  I17  C1833
   1 P12V_OCP_V3_2_R      A @T6G_MB_LIB.T6G(SCH_1):P12V_OCP_V3_2_R
   2    GND      B @T6G_MB_LIB.T6G(SCH_1):GND

Q_CAP_0402-0.1UF,25V,10%,X7R,CH4104K1B00  I18  C1839
   1 P12V_OCP_V3_2_R      A @T6G_MB_LIB.T6G(SCH_1):P12V_OCP_V3_2_R
   2    GND      B @T6G_MB_LIB.T6G(SCH_1):GND

Q_CAP_0402-0.1UF,25V,10%,X7R,CH4104K1B00  I21  C1835
   1 P3V3_OCP_V3_2      A @T6G_MB_LIB.T6G(SCH_1):P3V3_OCP_V3_2
   2    GND      B @T6G_MB_LIB.T6G(SCH_1):GND

Q_CAP_0402-0.1UF,25V,10%,X7R,CH4104K1B00  I22  C1836
   1 P3V3_OCP_V3_2      A @T6G_MB_LIB.T6G(SCH_1):P3V3_OCP_V3_2
   2    GND      B @T6G_MB_LIB.T6G(SCH_1):GND

Q_CAP_0402-0.1UF,25V,10%,X7R,CH4104K1B00  I24  C1838
   1 P3V3_OCP_V3_2      A @T6G_MB_LIB.T6G(SCH_1):P3V3_OCP_V3_2
   2    GND      B @T6G_MB_LIB.T6G(SCH_1):GND

Q_RES_0402LF-4.7K,1%,1/16W,EMPTY,CS24702FB06  I28  R3166
   1 P3V3_OCP_V3_2      A @T6G_MB_LIB.T6G(SCH_1):P3V3_OCP_V3_2
   2 OCP_V3_2_ID1      B @T6G_MB_LIB.T6G(SCH_1):OCP_V3_2_ID1

Q_RES_0402LF-10K,1%,1/16W,CHIP,CS31002FB08  I34  R3164
   1    GND      A @T6G_MB_LIB.T6G(SCH_1):GND
   2 OCP_V3_2_AUX_PWR_EN      B @T6G_MB_LIB.T6G(SCH_1):OCP_V3_2_AUX_PWR_EN

Q_RES_0402LF-0,5%,1/16W,CHIP,CS00002JB13  I42  R3172
   1 OCP_V3_2_AUX_PWR_EN      A @T6G_MB_LIB.T6G(SCH_1):OCP_V3_2_AUX_PWR_EN
   2 OCP_V3_2_AUX_PWR_EN_R      B @T6G_MB_LIB.T6G(SCH_1):OCP_V3_2_AUX_PWR_EN_R

Q_RES_0402LF-0,5%,1/16W,CHIP,CS00002JB13  I44  R3170
   1 OCP_V3_2_ISO_BIF1_EN      A @T6G_MB_LIB.T6G(SCH_1):OCP_V3_2_ISO_BIF1_EN
   2 OCP_V3_2_BIF1_R_N      B @T6G_MB_LIB.T6G(SCH_1):OCP_V3_2_BIF1_R_N

Q_RES_0402LF-0,5%,1/16W,CHIP,CS00002JB13  I45  R3171
   1 OCP_V3_2_ISO_BIF2_EN      A @T6G_MB_LIB.T6G(SCH_1):OCP_V3_2_ISO_BIF2_EN
   2 OCP_V3_2_BIF2_R_N      B @T6G_MB_LIB.T6G(SCH_1):OCP_V3_2_BIF2_R_N

Q_RES_0402LF-0,5%,1/16W,CHIP,CS00002JB13  I86  R3168
   1 OCP_V3_2_MAIN_PWR_EN      A @T6G_MB_LIB.T6G(SCH_1):OCP_V3_2_MAIN_PWR_EN
   2 OCP_V3_2_MAIN_PWR_EN_R      B @T6G_MB_LIB.T6G(SCH_1):OCP_V3_2_MAIN_PWR_EN_R

Q_RES_0402LF-0,5%,1/16W,CHIP,CS00002JB13  I135  R3178
   1 USB2_P10_DP      A @T6G_MB_LIB.T6G(SCH_1):USB2_P10_DP
   2 USB2_CPU0_P10_DP      B @T6G_MB_LIB.T6G(SCH_1):USB2_CPU0_P10_DP

Q_RES_0402LF-0,5%,1/16W,CHIP,CS00002JB13  I136  R3177
   1 USB2_P10_DN      A @T6G_MB_LIB.T6G(SCH_1):USB2_P10_DN
   2 USB2_CPU0_P10_DN      B @T6G_MB_LIB.T6G(SCH_1):USB2_CPU0_P10_DN

Q_RES_0402LF-0,5%,1/16W,CHIP,CS00002JB13  I150  R3180
   1 OCP_V3_2_PRSNTA_R_N      A @T6G_MB_LIB.T6G(SCH_1):OCP_V3_2_PRSNTA_R_N
   2    GND      B @T6G_MB_LIB.T6G(SCH_1):GND

Q_RES_0402LF-200,1%,1/16W,CHIP,CS12002FB06  I170  R3229
   1 SMB_OCP_V3_2_3V3AUX_BUF_R_SDA      A @T6G_MB_LIB.T6G(SCH_1):SMB_OCP_V3_2_3V3AUX_BUF_R_SDA
   2 SMB_OCP_V3_2_3V3AUX_BUF_SDA      B @T6G_MB_LIB.T6G(SCH_1):SMB_OCP_V3_2_3V3AUX_BUF_SDA

Q_RES_0402LF-200,1%,1/16W,CHIP,CS12002FB06  I171  R3228
   1 SMB_OCP_V3_2_3V3AUX_BUF_R_SCL      A @T6G_MB_LIB.T6G(SCH_1):SMB_OCP_V3_2_3V3AUX_BUF_R_SCL
   2 SMB_OCP_V3_2_3V3AUX_BUF_SCL      B @T6G_MB_LIB.T6G(SCH_1):SMB_OCP_V3_2_3V3AUX_BUF_SCL


DRAWING: @T6G_MB_LIB.T6G(SCH_1):PAGE342 

Q_RES_0402LF-33.2,1%,1/16W,CHIP,CS03322FB03  I6  R3234
   1 OCP_V3_2_AUX_PWR_EN      A @T6G_MB_LIB.T6G(SCH_1):OCP_V3_2_AUX_PWR_EN
   2 OCP_V3_2_AUX_PWR_EN_R3      B @T6G_MB_LIB.T6G(SCH_1):OCP_V3_2_AUX_PWR_EN_R3

Q_CAP_0402-0.1UF,25V,10%,X7R,CH4104K1B00  I12  C1841
   1 P3V3_AUX      A @T6G_MB_LIB.T6G(SCH_1):P3V3_AUX
   2    GND      B @T6G_MB_LIB.T6G(SCH_1):GND

Q_RES_0402LF-100K,1%,1/16W,CHIP,CS41002FB09  I24  R3235
   1 RST_HP_OCP_V3_2_R_N      A @T6G_MB_LIB.T6G(SCH_1):RST_HP_OCP_V3_2_R_N
   2    GND      B @T6G_MB_LIB.T6G(SCH_1):GND

Q_CAP_0402-0.1UF,25V,10%,X7R,CH4104K1B00  I31  C1823
   1 P3V3_AUX      A @T6G_MB_LIB.T6G(SCH_1):P3V3_AUX
   2    GND      B @T6G_MB_LIB.T6G(SCH_1):GND

Q_RES_0402LF-33.2,1%,1/16W,CHIP,CS03322FB03  I33  R3191
   1 OCP_V3_2_PWRBRK_BUFF_N      A @T6G_MB_LIB.T6G(SCH_1):OCP_V3_2_PWRBRK_BUFF_N
   2 OCP_V3_2_PWRBRK_N      B @T6G_MB_LIB.T6G(SCH_1):OCP_V3_2_PWRBRK_N

Q_CAP_0402-0.1UF,25V,10%,X7R,CH4104K1B00  I41  C1824
   1 P3V3_AUX      A @T6G_MB_LIB.T6G(SCH_1):P3V3_AUX
   2    GND      B @T6G_MB_LIB.T6G(SCH_1):GND

Q_RES_0402LF-4.7K,1%,1/16W,EMPTY,CS24702FB06  I44  R3192
   1 P3V3_AUX      A @T6G_MB_LIB.T6G(SCH_1):P3V3_AUX
   2 IRQ_LVC3_V3_2_WAKE_BUF_N      B @T6G_MB_LIB.T6G(SCH_1):IRQ_LVC3_V3_2_WAKE_BUF_N

Q_CAP_0402-0.1UF,25V,10%,X7R,CH4104K1B00  I47  C38
   1 P3V3_AUX      A @T6G_MB_LIB.T6G(SCH_1):P3V3_AUX
   2    GND      B @T6G_MB_LIB.T6G(SCH_1):GND

Q_RES_0402LF-10K,1%,1/16W,CHIP,CS31002FB08  I3  R3182
   1 P3V3_OCP_V3_2      A @T6G_MB_LIB.T6G(SCH_1):P3V3_OCP_V3_2
   2 IRQ_LVC3_OCP_V3_2_WAKE_N      B @T6G_MB_LIB.T6G(SCH_1):IRQ_LVC3_OCP_V3_2_WAKE_N

Q_RES_0402LF-10K,1%,1/16W,CHIP,CS31002FB08  I4  R3183
   1 P3V3_OCP_V3_2      A @T6G_MB_LIB.T6G(SCH_1):P3V3_OCP_V3_2
   2 PU_OCP_V3_2_WAKE_OE      B @T6G_MB_LIB.T6G(SCH_1):PU_OCP_V3_2_WAKE_OE

74LVC1G126SE7-74LVC1G126SE-7,SMLF,IC,AL1G0126009  I9  U225
   2 RST_SMB_SWITCH_N      A @T6G_MB_LIB.T6G(SCH_1):RST_SMB_SWITCH_N
   4 RST_HP_OCP_V3_2_R_N      Y @T6G_MB_LIB.T6G(SCH_1):RST_HP_OCP_V3_2_R_N
   5 P3V3_AUX    VCC @T6G_MB_LIB.T6G(SCH_1):P3V3_AUX
   3    GND    GND @T6G_MB_LIB.T6G(SCH_1):GND
   1 OCP_V3_2_AUX_PWR_EN_R3     OE @T6G_MB_LIB.T6G(SCH_1):OCP_V3_2_AUX_PWR_EN_R3

74LVC1G126SE7-74LVC1G126SE-7,SMLF,IC,AL1G0126009  I14  U217
   2 IRQ_LVC3_OCP_V3_2_WAKE_N      A @T6G_MB_LIB.T6G(SCH_1):IRQ_LVC3_OCP_V3_2_WAKE_N
   4 OCP_V3_2_WAKE_BUFF_N      Y @T6G_MB_LIB.T6G(SCH_1):OCP_V3_2_WAKE_BUFF_N
   5 P3V3_AUX    VCC @T6G_MB_LIB.T6G(SCH_1):P3V3_AUX
   3    GND    GND @T6G_MB_LIB.T6G(SCH_1):GND
   1 PU_OCP_V3_2_WAKE_OE     OE @T6G_MB_LIB.T6G(SCH_1):PU_OCP_V3_2_WAKE_OE

Q_CAP_0402-0.1UF,25V,10%,X7R,CH4104K1B00  I16  C1822
   1 P3V3_AUX      A @T6G_MB_LIB.T6G(SCH_1):P3V3_AUX
   2    GND      B @T6G_MB_LIB.T6G(SCH_1):GND

Q_RES_0402LF-4.7K,1%,1/16W,CHIP,CS24702FB06  I18  R3184
   1 P3V3_AUX      A @T6G_MB_LIB.T6G(SCH_1):P3V3_AUX
   2 OCP_V3_2_WAKE_BUFF_N      B @T6G_MB_LIB.T6G(SCH_1):OCP_V3_2_WAKE_BUFF_N

74LVC1G07GV-74LVC1G07GV,SMLF,IC,AL1G0007001  I22  U218
   5 P3V3_AUX    VCC @T6G_MB_LIB.T6G(SCH_1):P3V3_AUX
   2 FM_SYS_THROTTLE_N      A @T6G_MB_LIB.T6G(SCH_1):FM_SYS_THROTTLE_N
   3    GND    GND @T6G_MB_LIB.T6G(SCH_1):GND
   4 OCP_V3_2_PWRBRK_BUFF_N      Y @T6G_MB_LIB.T6G(SCH_1):OCP_V3_2_PWRBRK_BUFF_N
   1 NC_U218_NC1    NC1 @T6G_MB_LIB.T6G(SCH_1):NC_U218_NC1

Q_RES_0402LF-0,5%,1/16W,CHIP,CS00002JB13  I25  R3236
   1 RST_HP_OCP_V3_2_R_N      A @T6G_MB_LIB.T6G(SCH_1):RST_HP_OCP_V3_2_R_N
   2 RST_SMB_OCP_V3_2_N      B @T6G_MB_LIB.T6G(SCH_1):RST_SMB_OCP_V3_2_N

Q_RES_0402LF-33.2,1%,1/16W,CHIP,CS03322FB03  I29  R3185
   1 OCP_V3_2_WAKE_BUFF_N      A @T6G_MB_LIB.T6G(SCH_1):OCP_V3_2_WAKE_BUFF_N
   2 OCP_V3_2_WAKE_BUFF_R_N      B @T6G_MB_LIB.T6G(SCH_1):OCP_V3_2_WAKE_BUFF_R_N

74LVC1G07GV-74LVC1G07GV,SMLF,IC,AL1G0007001  I32  U219
   5 P3V3_AUX    VCC @T6G_MB_LIB.T6G(SCH_1):P3V3_AUX
   2 OCP_V3_2_WAKE_BUFF_R_N      A @T6G_MB_LIB.T6G(SCH_1):OCP_V3_2_WAKE_BUFF_R_N
   3    GND    GND @T6G_MB_LIB.T6G(SCH_1):GND
   4 IRQ_LVC3_V3_2_WAKE_BUF_N      Y @T6G_MB_LIB.T6G(SCH_1):IRQ_LVC3_V3_2_WAKE_BUF_N
   1 NC_U219_NC1    NC1 @T6G_MB_LIB.T6G(SCH_1):NC_U219_NC1

Q_RES_0402LF-4.7K,1%,1/16W,CHIP,CS24702FB06  I34  R3190
   1 P3V3_AUX      A @T6G_MB_LIB.T6G(SCH_1):P3V3_AUX
   2 OCP_V3_2_PWRBRK_BUFF_N      B @T6G_MB_LIB.T6G(SCH_1):OCP_V3_2_PWRBRK_BUFF_N

Q_RES_0402LF-0,5%,1/16W,CHIP,CS00002JB13  I36  R4602
   1 CLK_50M_NCSI_OCP_V3_2_ISO      A @T6G_MB_LIB.T6G(SCH_1):CLK_50M_NCSI_OCP_V3_2_ISO
   2 CLK_50M_NCSI_OCP_V3_2_ISO_R      B @T6G_MB_LIB.T6G(SCH_1):CLK_50M_NCSI_OCP_V3_2_ISO_R

Q_RES_0402LF-33.2,1%,1/16W,CHIP,CS03322FB03  I43  R3193
   1 IRQ_LVC3_V3_2_WAKE_BUF_N      A @T6G_MB_LIB.T6G(SCH_1):IRQ_LVC3_V3_2_WAKE_BUF_N
   2 IRQ_OCP_V3_2_WAKE_BUF_N      B @T6G_MB_LIB.T6G(SCH_1):IRQ_OCP_V3_2_WAKE_BUF_N

Q_CAP_0402-0.1UF,25V,10%,X7R,CH4104K1B00  I55  C1821
   1 P3V3_AUX      A @T6G_MB_LIB.T6G(SCH_1):P3V3_AUX
   2    GND      B @T6G_MB_LIB.T6G(SCH_1):GND

74LVC1G17GW-74LVC1G17GW,SMLF,IC,AL1G0017K01  I58  U207
   5 P3V3_AUX    VCC @T6G_MB_LIB.T6G(SCH_1):P3V3_AUX
   2 RST_PERST_OCP_V3_2_BUF_N      A @T6G_MB_LIB.T6G(SCH_1):RST_PERST_OCP_V3_2_BUF_N
   3    GND    GND @T6G_MB_LIB.T6G(SCH_1):GND
   4 RST_PERST_OCP_V3_2_BUF2_N      Y @T6G_MB_LIB.T6G(SCH_1):RST_PERST_OCP_V3_2_BUF2_N
   1     NC     NC     NC

Q_RES_0402LF-0,5%,1/16W,CHIP,CS00002JB13  I72  R6056
   1 RST_PERST_OCP_V3_2_BUF2_N      A @T6G_MB_LIB.T6G(SCH_1):RST_PERST_OCP_V3_2_BUF2_N
   2 RST_PERST0_OCP_V3_2_N      B @T6G_MB_LIB.T6G(SCH_1):RST_PERST0_OCP_V3_2_N

Q_RES_0402LF-0,5%,1/16W,CHIP,CS00002JB13  I73  R6057
   1 RST_PERST_OCP_V3_2_BUF2_N      A @T6G_MB_LIB.T6G(SCH_1):RST_PERST_OCP_V3_2_BUF2_N
   2 RST_PERST1_OCP_V3_2_N      B @T6G_MB_LIB.T6G(SCH_1):RST_PERST1_OCP_V3_2_N

Q_RES_0402LF-0,5%,1/16W,CHIP,CS00002JB13  I74  R6058
   1 RST_PERST_OCP_V3_2_BUF2_N      A @T6G_MB_LIB.T6G(SCH_1):RST_PERST_OCP_V3_2_BUF2_N
   2 RST_PERST2_OCP_V3_2_N      B @T6G_MB_LIB.T6G(SCH_1):RST_PERST2_OCP_V3_2_N

Q_RES_0402LF-0,5%,1/16W,CHIP,CS00002JB13  I75  R6059
   1 RST_PERST_OCP_V3_2_BUF2_N      A @T6G_MB_LIB.T6G(SCH_1):RST_PERST_OCP_V3_2_BUF2_N
   2 RST_PERST3_OCP_V3_2_N      B @T6G_MB_LIB.T6G(SCH_1):RST_PERST3_OCP_V3_2_N

74LVC1G66GV-74LVC1G66GV,SMLF,IC,AL001G66000  I76  U321
   1 CLK_50M_NCSI_OCP_V3_2      Y @T6G_MB_LIB.T6G(SCH_1):CLK_50M_NCSI_OCP_V3_2
   2 CLK_50M_NCSI_OCP_V3_2_ISO_R      Z @T6G_MB_LIB.T6G(SCH_1):CLK_50M_NCSI_OCP_V3_2_ISO_R
   3    GND    GND @T6G_MB_LIB.T6G(SCH_1):GND
   4 FB_BMC_ISOLATE1      E @T6G_MB_LIB.T6G(SCH_1):FB_BMC_ISOLATE1
   5 P3V3_AUX    VCC @T6G_MB_LIB.T6G(SCH_1):P3V3_AUX


DRAWING: @T6G_MB_LIB.T6G(SCH_1):PAGE343 

Q_RES_0402LF-1K,1%,1/16W,CHIP,CS21002FB06  I6  R3136
   1 P3V3_AUX      A @T6G_MB_LIB.T6G(SCH_1):P3V3_AUX
   2 OCP_V3_2_PRSNT3_R_N      B @T6G_MB_LIB.T6G(SCH_1):OCP_V3_2_PRSNT3_R_N

MOSFET_NCH_DUAL-PJT138K,SMLF,IC,BAM138K0003  I10  Q118
   1    GND     S1 @T6G_MB_LIB.T6G(SCH_1):GND
   2 P12V_OCP_EN_2_R     G1 @T6G_MB_LIB.T6G(SCH_1):P12V_OCP_EN_2_R
   6 P12V_OCP_2_EN_G     D1 @T6G_MB_LIB.T6G(SCH_1):P12V_OCP_2_EN_G

Q_RES_0402LF-1K,1%,1/16W,CHIP,CS21002FB06  I14  R3133
   1 P3V3_AUX      A @T6G_MB_LIB.T6G(SCH_1):P3V3_AUX
   2 OCP_V3_2_PRSNT0_R_N      B @T6G_MB_LIB.T6G(SCH_1):OCP_V3_2_PRSNT0_R_N

Q_RES_0402LF-1K,1%,1/16W,CHIP,CS21002FB06  I16  R3135
   1 P3V3_AUX      A @T6G_MB_LIB.T6G(SCH_1):P3V3_AUX
   2 OCP_V3_2_PRSNT1_R_N      B @T6G_MB_LIB.T6G(SCH_1):OCP_V3_2_PRSNT1_R_N

MOSFET_NCH_DUAL-PJT138K,SMLF,IC,BAM138K0003  I19  Q118
   3 P12V_OCP_UV_2_R     D2 @T6G_MB_LIB.T6G(SCH_1):P12V_OCP_UV_2_R
   5 P12V_OCP_2_EN_G     G2 @T6G_MB_LIB.T6G(SCH_1):P12V_OCP_2_EN_G
   4    GND     S2 @T6G_MB_LIB.T6G(SCH_1):GND

74LVC2G07DW7-74LVC2G07DW-7,SMLF,IC,AL002G07003  I28  U58
   1 OCP_V3_2_PRSNT0_R_N     1A @T6G_MB_LIB.T6G(SCH_1):OCP_V3_2_PRSNT0_R_N
   3 OCP_V3_2_PRSNT1_R_N     2A @T6G_MB_LIB.T6G(SCH_1):OCP_V3_2_PRSNT1_R_N
   6 HP_LVC3_OCP_V3_2_PRSNT2_N_R     1Y @T6G_MB_LIB.T6G(SCH_1):HP_LVC3_OCP_V3_2_PRSNT2_N_R
   4 HP_LVC3_OCP_V3_2_PRSNT2_N_R     2Y @T6G_MB_LIB.T6G(SCH_1):HP_LVC3_OCP_V3_2_PRSNT2_N_R
   2    GND    GND @T6G_MB_LIB.T6G(SCH_1):GND
   5 P3V3_AUX    VCC @T6G_MB_LIB.T6G(SCH_1):P3V3_AUX

Q_RES_0402LF-0,5%,1/16W,CHIP,CS00002JB13  I33  R3827
   1 P12V_OCP_UV_2_R      A @T6G_MB_LIB.T6G(SCH_1):P12V_OCP_UV_2_R
   2 P12V_OCP_UV_2      B @T6G_MB_LIB.T6G(SCH_1):P12V_OCP_UV_2

Q_RES_0402LF-6.8K,1%,1/16W,CHIP,CS26802FB02  I35  PR3806
   1 P12V_OCP_UV_2      A @T6G_MB_LIB.T6G(SCH_1):P12V_OCP_UV_2
   2 P12V_OCP_OV_2      B @T6G_MB_LIB.T6G(SCH_1):P12V_OCP_OV_2

Q_RES_0402LF-160K,1%,1/16W,CHIP,CS41602FB05  I36  PR3805
   1 P12V_AUX      A @T6G_MB_LIB.T6G(SCH_1):P12V_AUX
   2 P12V_OCP_UV_2      B @T6G_MB_LIB.T6G(SCH_1):P12V_OCP_UV_2

MOSFET_NCH_DUAL-PJT138K,SMLF,IC,BAM138K0003  I42  Q119
   1    GND     S1 @T6G_MB_LIB.T6G(SCH_1):GND
   2 P3V3_OCP_EN_2_R     G1 @T6G_MB_LIB.T6G(SCH_1):P3V3_OCP_EN_2_R
   6 P3V3_OCP_2_EN_G     D1 @T6G_MB_LIB.T6G(SCH_1):P3V3_OCP_2_EN_G

Q_RES_0402LF-10K,1%,1/16W,CHIP,CS31002FB08  I43  R4067
   1 P12V_AUX      A @T6G_MB_LIB.T6G(SCH_1):P12V_AUX
   2 P3V3_OCP_2_EN_G      B @T6G_MB_LIB.T6G(SCH_1):P3V3_OCP_2_EN_G

MOSFET_NCH_DUAL-PJT138K,SMLF,IC,BAM138K0003  I45  Q119
   3 P3V3_OCP_UV_2_R1     D2 @T6G_MB_LIB.T6G(SCH_1):P3V3_OCP_UV_2_R1
   5 P3V3_OCP_2_EN_G     G2 @T6G_MB_LIB.T6G(SCH_1):P3V3_OCP_2_EN_G
   4    GND     S2 @T6G_MB_LIB.T6G(SCH_1):GND

DIODE_TVS-SMF14A,SMLF,IC,BCSMF14AZ01  I47  PD107
   A    GND      A @T6G_MB_LIB.T6G(SCH_1):GND
   C P12V_AUX      C @T6G_MB_LIB.T6G(SCH_1):P12V_AUX

Q_CAP_C0402-1UF,25V,10%,X6S,CH5104KEB02  I49  PC2139
   1 P12V_AUX      A @T6G_MB_LIB.T6G(SCH_1):P12V_AUX
   2    GND      B @T6G_MB_LIB.T6G(SCH_1):GND

Q_RES_0402LF-15K,1%,1/16W,CHIP,CS31502FB05  I51  PR3812
   1 P3V3_OCP_OV_2      A @T6G_MB_LIB.T6G(SCH_1):P3V3_OCP_OV_2
   2    GND      B @T6G_MB_LIB.T6G(SCH_1):GND

Q_RES_0402LF-25.5K,1%,1/16W,CHIP,CS32552FB06  I56  PR3795
   1 P3V3_AUX      A @T6G_MB_LIB.T6G(SCH_1):P3V3_AUX
   2 P3V3_OCP_UV_2      B @T6G_MB_LIB.T6G(SCH_1):P3V3_OCP_UV_2

Q_RES_0402LF-0,5%,1/16W,CHIP,CS00002JB13  I59  R3142
   1 HP_LVC3_OCP_V3_2_PRSNT2_N_R      A @T6G_MB_LIB.T6G(SCH_1):HP_LVC3_OCP_V3_2_PRSNT2_N_R
   2 HP_LVC3_OCP_V3_2_PRSNT2_PLD_N      B @T6G_MB_LIB.T6G(SCH_1):HP_LVC3_OCP_V3_2_PRSNT2_PLD_N

Q_RES_0402LF-30.1K,1%,1/16W,CHIP,CS33012FB03  I63  PR3821
   1 P12V_OCP_CB_2      A @T6G_MB_LIB.T6G(SCH_1):P12V_OCP_CB_2
   2    GND      B @T6G_MB_LIB.T6G(SCH_1):GND

Q_CAP_C0402-1UF,25V,10%,X6S,CH5104KEB02  I65  PC2098
   1 P12V_OCP_VCC_2      A @T6G_MB_LIB.T6G(SCH_1):P12V_OCP_VCC_2
   2    GND      B @T6G_MB_LIB.T6G(SCH_1):GND

Q_CAP_C0402-1UF,25V,10%,X6S,CH5104KEB02  I66  PC2146
   1    GND      A @T6G_MB_LIB.T6G(SCH_1):GND
   2 P12V_OCP_REG_2      B @T6G_MB_LIB.T6G(SCH_1):P12V_OCP_REG_2

MAX15090BEWIT-MAX15090BEWI+T,SMLF,IC,AL015080B00  I67  PU201
  A2 P12V_OCP_VCC_2    VCC @T6G_MB_LIB.T6G(SCH_1):P12V_OCP_VCC_2
  A3 P12V_AUX  IN_A3 @T6G_MB_LIB.T6G(SCH_1):P12V_AUX
  A5 P12V_AUX  IN_A5 @T6G_MB_LIB.T6G(SCH_1):P12V_AUX
  B3 P12V_AUX  IN_B3 @T6G_MB_LIB.T6G(SCH_1):P12V_AUX
  B5 P12V_AUX  IN_B5 @T6G_MB_LIB.T6G(SCH_1):P12V_AUX
  C3 P12V_AUX  IN_C3 @T6G_MB_LIB.T6G(SCH_1):P12V_AUX
  C5 P12V_AUX  IN_C5 @T6G_MB_LIB.T6G(SCH_1):P12V_AUX
  D5 P12V_AUX  IN_D5 @T6G_MB_LIB.T6G(SCH_1):P12V_AUX
  B1 P12V_OCP_CB_2     CB @T6G_MB_LIB.T6G(SCH_1):P12V_OCP_CB_2
  B7    GND    EN# @T6G_MB_LIB.T6G(SCH_1):GND
  D1 P12V_OCP_REG_2    REG @T6G_MB_LIB.T6G(SCH_1):P12V_OCP_REG_2
  D2 P12V_OCP_UV_2     UV @T6G_MB_LIB.T6G(SCH_1):P12V_OCP_UV_2
  D3 P12V_OCP_OV_2     OV @T6G_MB_LIB.T6G(SCH_1):P12V_OCP_OV_2
  A1 P12V_OCP_SENSE_2 ISENSE @T6G_MB_LIB.T6G(SCH_1):P12V_OCP_SENSE_2
  A4 P12V_OCP_V3_2 OUT_A4 @T6G_MB_LIB.T6G(SCH_1):P12V_OCP_V3_2
  B4 P12V_OCP_V3_2 OUT_B4 @T6G_MB_LIB.T6G(SCH_1):P12V_OCP_V3_2
  B6 P12V_OCP_V3_2 OUT_B6 @T6G_MB_LIB.T6G(SCH_1):P12V_OCP_V3_2
  C4 P12V_OCP_V3_2 OUT_C4 @T6G_MB_LIB.T6G(SCH_1):P12V_OCP_V3_2
  C6 P12V_OCP_V3_2 OUT_C6 @T6G_MB_LIB.T6G(SCH_1):P12V_OCP_V3_2
  D4 P12V_OCP_V3_2 OUT_D4 @T6G_MB_LIB.T6G(SCH_1):P12V_OCP_V3_2
  D6 P12V_OCP_V3_2 OUT_D6 @T6G_MB_LIB.T6G(SCH_1):P12V_OCP_V3_2
  A6 P12V_OCP_GATE_2   GATE @T6G_MB_LIB.T6G(SCH_1):P12V_OCP_GATE_2
  A7    GND   CDLY @T6G_MB_LIB.T6G(SCH_1):GND
  B2    GND GND_B2 @T6G_MB_LIB.T6G(SCH_1):GND
  C1    GND GND_C1 @T6G_MB_LIB.T6G(SCH_1):GND
  C2    GND GND_C2 @T6G_MB_LIB.T6G(SCH_1):GND
  C7 P12V_OCP_FAULT_2 FAULT# @T6G_MB_LIB.T6G(SCH_1):P12V_OCP_FAULT_2
  D7 P12V_OCP_PWRGD_2     PG @T6G_MB_LIB.T6G(SCH_1):P12V_OCP_PWRGD_2

Q_RES_0402LF-1K,1%,1/16W,CHIP,CS21002FB06  I69  R3147
   1 P3V3_AUX      A @T6G_MB_LIB.T6G(SCH_1):P3V3_AUX
   2 HP_LVC3_OCP_V3_2_PRSNT2_PLD_N      B @T6G_MB_LIB.T6G(SCH_1):HP_LVC3_OCP_V3_2_PRSNT2_PLD_N

Q_RES_0402LF-845,1%,1/16W,CHIP,CS18452FB01  I71  PR3823
   1 P12V_OCP_SENSE_2      A @T6G_MB_LIB.T6G(SCH_1):P12V_OCP_SENSE_2
   2    GND      B @T6G_MB_LIB.T6G(SCH_1):GND

Q_RES_0402LF-0,5%,1/16W,CHIP,CS00002JB13  I73  R3868
   1 P12V_OCP_SENSE_2      A @T6G_MB_LIB.T6G(SCH_1):P12V_OCP_SENSE_2
   2 P12V_OCP_V3_2_ISENSE_MAM_TIC      B @T6G_MB_LIB.T6G(SCH_1):P12V_OCP_V3_2_ISENSE_MAM_TIC

Q_RES_0402LF-0,5%,1/16W,EMPTY,CS00002JB13  I74  R3867
   1 P12V_OCP_SENSE_2      A @T6G_MB_LIB.T6G(SCH_1):P12V_OCP_SENSE_2
   2 P12V_OCP_V3_2_ISENSE_MAM_MAM      B @T6G_MB_LIB.T6G(SCH_1):P12V_OCP_V3_2_ISENSE_MAM_MAM

Q_RES_0402LF-100K,1%,1/16W,CHIP,CS41002FB09  I80  R3825
   1 P3V3_AUX      A @T6G_MB_LIB.T6G(SCH_1):P3V3_AUX
   2 HP_LVC3_OCP_V3_2_P12V_PWRGD      B @T6G_MB_LIB.T6G(SCH_1):HP_LVC3_OCP_V3_2_P12V_PWRGD

Q_RES_0402LF-10,1%,1/16W,CHIP,CS01002FB07  I84  PR3830
   1 P12V_AUX      A @T6G_MB_LIB.T6G(SCH_1):P12V_AUX
   2 P12V_OCP_VCC_2      B @T6G_MB_LIB.T6G(SCH_1):P12V_OCP_VCC_2

Q_CAP_C0402-1UF,25V,10%,X6S,CH5104KEB02  I86  PC2147
   1    GND      A @T6G_MB_LIB.T6G(SCH_1):GND
   2 P3V3_OCP_REG_2      B @T6G_MB_LIB.T6G(SCH_1):P3V3_OCP_REG_2

Q_RES_0402LF-5.36K,1%,1/16W,CHIP,CS25362FB02  I88  PR3822
   1 P3V3_OCP_CB_2      A @T6G_MB_LIB.T6G(SCH_1):P3V3_OCP_CB_2
   2    GND      B @T6G_MB_LIB.T6G(SCH_1):GND

MAX15090BEWIT-MAX15090BEWI+T,SMLF,IC,AL015080B00  I89  PU200
  A2 P3V3_OCP_VCC_2    VCC @T6G_MB_LIB.T6G(SCH_1):P3V3_OCP_VCC_2
  A3 P3V3_AUX  IN_A3 @T6G_MB_LIB.T6G(SCH_1):P3V3_AUX
  A5 P3V3_AUX  IN_A5 @T6G_MB_LIB.T6G(SCH_1):P3V3_AUX
  B3 P3V3_AUX  IN_B3 @T6G_MB_LIB.T6G(SCH_1):P3V3_AUX
  B5 P3V3_AUX  IN_B5 @T6G_MB_LIB.T6G(SCH_1):P3V3_AUX
  C3 P3V3_AUX  IN_C3 @T6G_MB_LIB.T6G(SCH_1):P3V3_AUX
  C5 P3V3_AUX  IN_C5 @T6G_MB_LIB.T6G(SCH_1):P3V3_AUX
  D5 P3V3_AUX  IN_D5 @T6G_MB_LIB.T6G(SCH_1):P3V3_AUX
  B1 P3V3_OCP_CB_2     CB @T6G_MB_LIB.T6G(SCH_1):P3V3_OCP_CB_2
  B7    GND    EN# @T6G_MB_LIB.T6G(SCH_1):GND
  D1 P3V3_OCP_REG_2    REG @T6G_MB_LIB.T6G(SCH_1):P3V3_OCP_REG_2
  D2 P3V3_OCP_UV_2     UV @T6G_MB_LIB.T6G(SCH_1):P3V3_OCP_UV_2
  D3 P3V3_OCP_OV_2     OV @T6G_MB_LIB.T6G(SCH_1):P3V3_OCP_OV_2
  A1 P3V3_OCP_SENSE_2 ISENSE @T6G_MB_LIB.T6G(SCH_1):P3V3_OCP_SENSE_2
  A4 P3V3_OCP_V3_2_R OUT_A4 @T6G_MB_LIB.T6G(SCH_1):P3V3_OCP_V3_2_R
  B4 P3V3_OCP_V3_2_R OUT_B4 @T6G_MB_LIB.T6G(SCH_1):P3V3_OCP_V3_2_R
  B6 P3V3_OCP_V3_2_R OUT_B6 @T6G_MB_LIB.T6G(SCH_1):P3V3_OCP_V3_2_R
  C4 P3V3_OCP_V3_2_R OUT_C4 @T6G_MB_LIB.T6G(SCH_1):P3V3_OCP_V3_2_R
  C6 P3V3_OCP_V3_2_R OUT_C6 @T6G_MB_LIB.T6G(SCH_1):P3V3_OCP_V3_2_R
  D4 P3V3_OCP_V3_2_R OUT_D4 @T6G_MB_LIB.T6G(SCH_1):P3V3_OCP_V3_2_R
  D6 P3V3_OCP_V3_2_R OUT_D6 @T6G_MB_LIB.T6G(SCH_1):P3V3_OCP_V3_2_R
  A6 P3V3_OCP_GATE_2   GATE @T6G_MB_LIB.T6G(SCH_1):P3V3_OCP_GATE_2
  A7    GND   CDLY @T6G_MB_LIB.T6G(SCH_1):GND
  B2    GND GND_B2 @T6G_MB_LIB.T6G(SCH_1):GND
  C1    GND GND_C1 @T6G_MB_LIB.T6G(SCH_1):GND
  C2    GND GND_C2 @T6G_MB_LIB.T6G(SCH_1):GND
  C7 P3V3_OCP_FAULT_2 FAULT# @T6G_MB_LIB.T6G(SCH_1):P3V3_OCP_FAULT_2
  D7 P3V3_OCP_PWRGD_2     PG @T6G_MB_LIB.T6G(SCH_1):P3V3_OCP_PWRGD_2

Q_CAP_C0402-1UF,25V,10%,X6S,CH5104KEB02  I90  C39
   1 P3V3_OCP_VCC_2      A @T6G_MB_LIB.T6G(SCH_1):P3V3_OCP_VCC_2
   2    GND      B @T6G_MB_LIB.T6G(SCH_1):GND

SCHOTTKY_AC-B340A-13-F,SMLF,IC,BC000340Z30  I92  PD108
   A    GND      A @T6G_MB_LIB.T6G(SCH_1):GND
   C P12V_OCP_V3_2      C @T6G_MB_LIB.T6G(SCH_1):P12V_OCP_V3_2

Q_RES_0402LF-4.53K,1%,1/16W,CHIP,CS24532FB03  I94  PR3824
   1 P3V3_OCP_SENSE_2      A @T6G_MB_LIB.T6G(SCH_1):P3V3_OCP_SENSE_2
   2    GND      B @T6G_MB_LIB.T6G(SCH_1):GND

Q_CAP_0402-0.1UF,25V,10%,X7R,CH4104K1B00  I97  PC2152
   1 P12V_OCP_V3_2      A @T6G_MB_LIB.T6G(SCH_1):P12V_OCP_V3_2
   2    GND      B @T6G_MB_LIB.T6G(SCH_1):GND

Q_CAP_C0805-22UF,16V,20%,X6S,CH6223MEA01  I99  PC2141
   1 P12V_OCP_V3_2      A @T6G_MB_LIB.T6G(SCH_1):P12V_OCP_V3_2
   2    GND      B @T6G_MB_LIB.T6G(SCH_1):GND

Q_CAP_C0805-10UF,16V,10%,X6S,CH6103KEA01  I101  PC2143
   1 P12V_OCP_V3_2      A @T6G_MB_LIB.T6G(SCH_1):P12V_OCP_V3_2
   2    GND      B @T6G_MB_LIB.T6G(SCH_1):GND

Q_RES_0402LF-10M,1%,1/16W,CHIP,CS61002FB02  I105  PR4523
   1 P3V3_OCP_V3_2_R      A @T6G_MB_LIB.T6G(SCH_1):P3V3_OCP_V3_2_R
   2 P3V3_OCP_GATE_2      B @T6G_MB_LIB.T6G(SCH_1):P3V3_OCP_GATE_2

Q_RES_0402LF-100K,1%,1/16W,CHIP,CS41002FB09  I107  R3833
   1 P3V3_AUX      A @T6G_MB_LIB.T6G(SCH_1):P3V3_AUX
   2 P3V3_OCP_FAULT_2      B @T6G_MB_LIB.T6G(SCH_1):P3V3_OCP_FAULT_2

Q_RES_0402LF-1K,1%,1/16W,CHIP,CS21002FB06  I4  R3134
   1 P3V3_AUX      A @T6G_MB_LIB.T6G(SCH_1):P3V3_AUX
   2 OCP_V3_2_PRSNT2_R_N      B @T6G_MB_LIB.T6G(SCH_1):OCP_V3_2_PRSNT2_R_N

Q_RES_0402LF-10K,1%,1/16W,CHIP,CS31002FB08  I17  R4065
   1 P12V_AUX      A @T6G_MB_LIB.T6G(SCH_1):P12V_AUX
   2 P12V_OCP_2_EN_G      B @T6G_MB_LIB.T6G(SCH_1):P12V_OCP_2_EN_G

74LVC2G07DW7-74LVC2G07DW-7,SMLF,IC,AL002G07003  I22  U59
   1 OCP_V3_2_PRSNT2_R_N     1A @T6G_MB_LIB.T6G(SCH_1):OCP_V3_2_PRSNT2_R_N
   3 OCP_V3_2_PRSNT3_R_N     2A @T6G_MB_LIB.T6G(SCH_1):OCP_V3_2_PRSNT3_R_N
   6 HP_LVC3_OCP_V3_2_PRSNT2_N_R     1Y @T6G_MB_LIB.T6G(SCH_1):HP_LVC3_OCP_V3_2_PRSNT2_N_R
   4 HP_LVC3_OCP_V3_2_PRSNT2_N_R     2Y @T6G_MB_LIB.T6G(SCH_1):HP_LVC3_OCP_V3_2_PRSNT2_N_R
   2    GND    GND @T6G_MB_LIB.T6G(SCH_1):GND
   5 P3V3_AUX    VCC @T6G_MB_LIB.T6G(SCH_1):P3V3_AUX

Q_CAP_0402-0.1UF,25V,10%,X7R,CH4104K1B00  I23  C1810
   1 P3V3_AUX      A @T6G_MB_LIB.T6G(SCH_1):P3V3_AUX
   2    GND      B @T6G_MB_LIB.T6G(SCH_1):GND

Q_CAP_0402-0.1UF,25V,10%,X7R,CH4104K1B00  I29  C1809
   1 P3V3_AUX      A @T6G_MB_LIB.T6G(SCH_1):P3V3_AUX
   2    GND      B @T6G_MB_LIB.T6G(SCH_1):GND

Q_RES_0402LF-15K,1%,1/16W,CHIP,CS31502FB05  I31  PR3828
   1 P12V_OCP_OV_2      A @T6G_MB_LIB.T6G(SCH_1):P12V_OCP_OV_2
   2    GND      B @T6G_MB_LIB.T6G(SCH_1):GND

Q_RES_0402LF-0,5%,1/16W,CHIP,CS00002JB13  I50  R3807
   1 P3V3_OCP_UV_2_R1      A @T6G_MB_LIB.T6G(SCH_1):P3V3_OCP_UV_2_R1
   2 P3V3_OCP_UV_2      B @T6G_MB_LIB.T6G(SCH_1):P3V3_OCP_UV_2

Q_RES_0402LF-7.15K,1%,1/16W,CHIP,CS27152FB03  I53  PR3829
   1 P3V3_OCP_UV_2      A @T6G_MB_LIB.T6G(SCH_1):P3V3_OCP_UV_2
   2 P3V3_OCP_OV_2      B @T6G_MB_LIB.T6G(SCH_1):P3V3_OCP_OV_2

Q_CAP_C0402-1UF,25V,10%,X6S,CH5104KEB02  I55  PC2140
   1 P3V3_AUX      A @T6G_MB_LIB.T6G(SCH_1):P3V3_AUX
   2    GND      B @T6G_MB_LIB.T6G(SCH_1):GND

Q_CAP_C0402-0.01UF,50V,10%,EMPTY,CH31006KB18  I72  C40
   1 P12V_OCP_V3_2      A @T6G_MB_LIB.T6G(SCH_1):P12V_OCP_V3_2
   2 P12V_OCP_GATE_2      B @T6G_MB_LIB.T6G(SCH_1):P12V_OCP_GATE_2

Q_CAP_C0402-3900PF,50V,10%,X7R,CH23906KB14  I75  PC2150
   1 P12V_OCP_GATE_2      A @T6G_MB_LIB.T6G(SCH_1):P12V_OCP_GATE_2
   2    GND      B @T6G_MB_LIB.T6G(SCH_1):GND

Q_RES_0402LF-10M,1%,1/16W,CHIP,CS61002FB02  I76  PR4522
   1 P12V_OCP_V3_2      A @T6G_MB_LIB.T6G(SCH_1):P12V_OCP_V3_2
   2 P12V_OCP_GATE_2      B @T6G_MB_LIB.T6G(SCH_1):P12V_OCP_GATE_2

Q_RES_0402LF-0,5%,1/16W,CHIP,CS00002JB13  I77  R3831
   1 P12V_OCP_PWRGD_2      A @T6G_MB_LIB.T6G(SCH_1):P12V_OCP_PWRGD_2
   2 HP_LVC3_OCP_V3_2_P12V_PWRGD      B @T6G_MB_LIB.T6G(SCH_1):HP_LVC3_OCP_V3_2_P12V_PWRGD

Q_RES_0402LF-100K,1%,1/16W,CHIP,CS41002FB09  I79  R3816
   1 P3V3_AUX      A @T6G_MB_LIB.T6G(SCH_1):P3V3_AUX
   2 P12V_OCP_FAULT_2      B @T6G_MB_LIB.T6G(SCH_1):P12V_OCP_FAULT_2

Q_RES_0402LF-10,1%,1/16W,CHIP,CS01002FB07  I91  PR3782
   1 P3V3_AUX      A @T6G_MB_LIB.T6G(SCH_1):P3V3_AUX
   2 P3V3_OCP_VCC_2      B @T6G_MB_LIB.T6G(SCH_1):P3V3_OCP_VCC_2

Q_CAP_C0402-6800PF,50V,10%,X7R,CH2686K1B01  I95  PC2151
   1 P3V3_OCP_GATE_2      A @T6G_MB_LIB.T6G(SCH_1):P3V3_OCP_GATE_2
   2    GND      B @T6G_MB_LIB.T6G(SCH_1):GND

Q_CAP_C0402-0.01UF,50V,10%,EMPTY,CH31006KB18  I104  PC2149
   1 P3V3_OCP_V3_2_R      A @T6G_MB_LIB.T6G(SCH_1):P3V3_OCP_V3_2_R
   2 P3V3_OCP_GATE_2      B @T6G_MB_LIB.T6G(SCH_1):P3V3_OCP_GATE_2

SCHOTTKY_AC-B340A-13-F,SMLF,IC,BC000340Z30  I106  PD109
   A    GND      A @T6G_MB_LIB.T6G(SCH_1):GND
   C P3V3_OCP_V3_2_R      C @T6G_MB_LIB.T6G(SCH_1):P3V3_OCP_V3_2_R

Q_CAP_0402-0.1UF,25V,10%,X7R,CH4104K1B00  I108  PC2137
   1 P3V3_OCP_V3_2_R      A @T6G_MB_LIB.T6G(SCH_1):P3V3_OCP_V3_2_R
   2    GND      B @T6G_MB_LIB.T6G(SCH_1):GND

Q_CAP_C0805-10UF,16V,10%,X6S,CH6103KEA01  I112  PC2142
   1 P3V3_OCP_V3_2_R      A @T6G_MB_LIB.T6G(SCH_1):P3V3_OCP_V3_2_R
   2    GND      B @T6G_MB_LIB.T6G(SCH_1):GND

Q_RES_0402LF-0,5%,1/16W,CHIP,CS00002JB13  I116  R1191
   1 HP_LVC3_OCP_V3_2_PRSNT2_N_R      A @T6G_MB_LIB.T6G(SCH_1):HP_LVC3_OCP_V3_2_PRSNT2_N_R
   2 HP_LVC3_OCP_V3_2_PRSNT2_N      B @T6G_MB_LIB.T6G(SCH_1):HP_LVC3_OCP_V3_2_PRSNT2_N

Q_RES_0402LF-1K,1%,1/16W,CHIP,CS21002FB06  I118  R1192
   1 P3V3_AUX      A @T6G_MB_LIB.T6G(SCH_1):P3V3_AUX
   2 HP_LVC3_OCP_V3_2_PRSNT2_N      B @T6G_MB_LIB.T6G(SCH_1):HP_LVC3_OCP_V3_2_PRSNT2_N

Q_RES_0402LF-0,5%,1/16W,EMPTY,CS00002JB13  I119  R4059
   1 P12V_OCP_V3_2_EN_R      A @T6G_MB_LIB.T6G(SCH_1):P12V_OCP_V3_2_EN_R
   2 P12V_OCP_EN_2_R      B @T6G_MB_LIB.T6G(SCH_1):P12V_OCP_EN_2_R

Q_RES_0402LF-4.7K,5%,1/16W,EMPTY,CS24702JB10  I120  R6060
   1 P12V_OCP_EN_2_R      A @T6G_MB_LIB.T6G(SCH_1):P12V_OCP_EN_2_R
   2    GND      B @T6G_MB_LIB.T6G(SCH_1):GND

Q_RES_0402LF-4.7K,5%,1/16W,EMPTY,CS24702JB10  I121  R4066
   1 P3V3_OCP_EN_2_R      A @T6G_MB_LIB.T6G(SCH_1):P3V3_OCP_EN_2_R
   2    GND      B @T6G_MB_LIB.T6G(SCH_1):GND

Q_RES_0402LF-0,5%,1/16W,EMPTY,CS00002JB13  I122  R4060
   1 P3V3_OCP_V3_2_EN_R      A @T6G_MB_LIB.T6G(SCH_1):P3V3_OCP_V3_2_EN_R
   2 P3V3_OCP_EN_2_R      B @T6G_MB_LIB.T6G(SCH_1):P3V3_OCP_EN_2_R

Q_RES_0402LF-0,5%,1/16W,CHIP,CS00002JB13  I123  R1181
   1 P12V_OCP_V3_2_BUF_EN_R      A @T6G_MB_LIB.T6G(SCH_1):P12V_OCP_V3_2_BUF_EN_R
   2 P12V_OCP_EN_2_R      B @T6G_MB_LIB.T6G(SCH_1):P12V_OCP_EN_2_R

Q_RES_0402LF-0,5%,1/16W,EMPTY,CS00002JB13  I127  R3832
   1 P3V3_OCP_PWRGD_2      A @T6G_MB_LIB.T6G(SCH_1):P3V3_OCP_PWRGD_2
   2 OCP_V3_2_P3V3_PWRGD      B @T6G_MB_LIB.T6G(SCH_1):OCP_V3_2_P3V3_PWRGD

Q_RES_0402LF-100K,1%,1/16W,EMPTY,CS41002FB09  I128  R3826
   1 P3V3_AUX      A @T6G_MB_LIB.T6G(SCH_1):P3V3_AUX
   2 OCP_V3_2_P3V3_PWRGD      B @T6G_MB_LIB.T6G(SCH_1):OCP_V3_2_P3V3_PWRGD

Q_RES_0402LF-0,5%,1/16W,EMPTY,CS00002JB13  I129  R1182
   1 HP_LVC3_OCP_V3_2_P12V_PWRGD      A @T6G_MB_LIB.T6G(SCH_1):HP_LVC3_OCP_V3_2_P12V_PWRGD
   2 P3V3_OCP_EN_2_R      B @T6G_MB_LIB.T6G(SCH_1):P3V3_OCP_EN_2_R

Q_RES_0402LF-0,5%,1/16W,CHIP,CS00002JB13  I130  R1520
   1 P12V_OCP_V3_2_BUF_EN_R      A @T6G_MB_LIB.T6G(SCH_1):P12V_OCP_V3_2_BUF_EN_R
   2 P3V3_OCP_EN_2_R      B @T6G_MB_LIB.T6G(SCH_1):P3V3_OCP_EN_2_R


DRAWING: @T6G_MB_LIB.T6G(SCH_1):PAGE344 

Q_CAP_0402-0.22UF,16V,10%,X7R,CH4223K1B00  I2  PC2164
   1 P12V_OCP_TIMER_2      A @T6G_MB_LIB.T6G(SCH_1):P12V_OCP_TIMER_2
   2    GND      B @T6G_MB_LIB.T6G(SCH_1):GND

Q_RES_0402LF-14.3K,1%,1/16W,CHIP,CS31432FB02  I4  PR3847
   1 P12V_OCP_ISET_2      A @T6G_MB_LIB.T6G(SCH_1):P12V_OCP_ISET_2
   2    GND      B @T6G_MB_LIB.T6G(SCH_1):GND

Q_CAP_C0402-0.047UF,25V,10%,X7R,CH3474K1B04  I6  PC2166
   1 P12V_OCP_SS_2      A @T6G_MB_LIB.T6G(SCH_1):P12V_OCP_SS_2
   2    GND      B @T6G_MB_LIB.T6G(SCH_1):GND

Q_CAP_C0402-1UF,25V,10%,X6S,CH5104KEB02  I13  PC2165
   1 P12V_AUX      A @T6G_MB_LIB.T6G(SCH_1):P12V_AUX
   2    GND      B @T6G_MB_LIB.T6G(SCH_1):GND

Q_RES_0402LF-17.4K,1%,1/16W,CHIP,CS31742FB04  I15  PR3849
   1 P12V_OCP_IMON_2      A @T6G_MB_LIB.T6G(SCH_1):P12V_OCP_IMON_2
   2    GND      B @T6G_MB_LIB.T6G(SCH_1):GND

Q_RES_0402LF-10K,1%,1/16W,CHIP,CS31002FB08  I18  PR3851
   1 P12V_OCP_FLTB_2      A @T6G_MB_LIB.T6G(SCH_1):P12V_OCP_FLTB_2
   2 P3V3_AUX      B @T6G_MB_LIB.T6G(SCH_1):P3V3_AUX

Q_RES_0402LF-10K,1%,1/16W,CHIP,CS31002FB08  I20  PR3854
   1 P12V_OCP_OV_FB_2      A @T6G_MB_LIB.T6G(SCH_1):P12V_OCP_OV_FB_2
   2    GND      B @T6G_MB_LIB.T6G(SCH_1):GND

Q_RES_0402LF-0,5%,1/16W,EMPTY,CS00002JB13  I22  R3874
   1 P12V_OCP_IMON_2      A @T6G_MB_LIB.T6G(SCH_1):P12V_OCP_IMON_2
   2 P12V_OCP_V3_2_ISENSE_MPS_TIC      B @T6G_MB_LIB.T6G(SCH_1):P12V_OCP_V3_2_ISENSE_MPS_TIC

Q_RES_0402LF-0,5%,1/16W,CHIP,CS00002JB13  I23  R3873
   1 P12V_OCP_IMON_2      A @T6G_MB_LIB.T6G(SCH_1):P12V_OCP_IMON_2
   2 P12V_OCP_V3_2_ISENSE_MPS_MAM      B @T6G_MB_LIB.T6G(SCH_1):P12V_OCP_V3_2_ISENSE_MPS_MAM

Q_CAP_C0603-2.2UF,16V,20%,X7R,CH5223M1900  I24  PC1320
   1 P12V_OCP_AVIN_PD_2      A @T6G_MB_LIB.T6G(SCH_1):P12V_OCP_AVIN_PD_2
   2    GND      B @T6G_MB_LIB.T6G(SCH_1):GND

Q_RES_0402LF-10K,1%,1/16W,CHIP,CS31002FB08  I27  R3848
   1 P3V3_AUX      A @T6G_MB_LIB.T6G(SCH_1):P3V3_AUX
   2 HP_LVC3_OCP_V3_2_P12V_PWRGD      B @T6G_MB_LIB.T6G(SCH_1):HP_LVC3_OCP_V3_2_P12V_PWRGD

Q_RES_0402LF-100,1%,1/16W,EMPTY,CS11002FB07  I30  PR3850
   1 P12V_OCP_V3_2      A @T6G_MB_LIB.T6G(SCH_1):P12V_OCP_V3_2
   2 P12V_OCP_AVIN_PD_2      B @T6G_MB_LIB.T6G(SCH_1):P12V_OCP_AVIN_PD_2

Q_RES_0402LF-71.5K,1%,1/16W,EMPTY,CS37152FB05  I31  PR3852
   1 P12V_OCP_V3_2      A @T6G_MB_LIB.T6G(SCH_1):P12V_OCP_V3_2
   2 P12V_OCP_OV_FB_2      B @T6G_MB_LIB.T6G(SCH_1):P12V_OCP_OV_FB_2

Q_CAP_0402-39PF,50V,5%,NPO,CH03906JB06  I35  PC2168
   1 P3V3_OCP_MODE_2      A @T6G_MB_LIB.T6G(SCH_1):P3V3_OCP_MODE_2
   2    GND      B @T6G_MB_LIB.T6G(SCH_1):GND

Q_RES_0402LF-120K,1%,1/16W,CHIP,CS41202FB05  I36  PR3853
   1 P12V_AUX      A @T6G_MB_LIB.T6G(SCH_1):P12V_AUX
   2 P12V_OCP_OV_FB_2      B @T6G_MB_LIB.T6G(SCH_1):P12V_OCP_OV_FB_2

Q_RES_0603LF-49.9,1%,1/10W,CHIP,CS04993F909  I37  PR3857
   1 P12V_AUX      A @T6G_MB_LIB.T6G(SCH_1):P12V_AUX
   2 P12V_OCP_AVIN_PD_2      B @T6G_MB_LIB.T6G(SCH_1):P12V_OCP_AVIN_PD_2

Q_CAP_0402-0.1UF,25V,10%,X7R,CH4104K1B00  I40  PC2174
   1 P12V_OCP_V3_2      A @T6G_MB_LIB.T6G(SCH_1):P12V_OCP_V3_2
   2    GND      B @T6G_MB_LIB.T6G(SCH_1):GND

Q_RES_0402LF-71.5K,1%,1/16W,CHIP,CS37152FB05  I43  PR3855
   1 P3V3_OCP_MODE_2      A @T6G_MB_LIB.T6G(SCH_1):P3V3_OCP_MODE_2
   2    GND      B @T6G_MB_LIB.T6G(SCH_1):GND

Q_RES_0402LF-1.33K,1%,1/16W,CHIP,CS21332FB05  I46  PR3856
   1    GND      A @T6G_MB_LIB.T6G(SCH_1):GND
   2 P3V3_OCP_ILIMIT_2      B @T6G_MB_LIB.T6G(SCH_1):P3V3_OCP_ILIMIT_2

Q_CAP_C0402-1UF,25V,10%,X6S,CH5104KEB02  I48  PC2169
   1 P3V3_AUX      A @T6G_MB_LIB.T6G(SCH_1):P3V3_AUX
   2    GND      B @T6G_MB_LIB.T6G(SCH_1):GND

Q_CAP_0402-0.068UF,16V,10%,X7R,CH3683K1B09  I50  PC1321
   1 P3V3_OCP_DVDT_2      A @T6G_MB_LIB.T6G(SCH_1):P3V3_OCP_DVDT_2
   2    GND      B @T6G_MB_LIB.T6G(SCH_1):GND

MP5016GQHLZ-MP5016GQH-L-Z,SMLF,IC,AL005016007  I51  PU207
   9 P3V3_OCP_EN_2     EN @T6G_MB_LIB.T6G(SCH_1):P3V3_OCP_EN_2
   5 P3V3_OCP_MODE_2   MODE @T6G_MB_LIB.T6G(SCH_1):P3V3_OCP_MODE_2
   4 P3V3_OCP_ILIMIT_2 ILIMIT @T6G_MB_LIB.T6G(SCH_1):P3V3_OCP_ILIMIT_2
   3    GND    GND @T6G_MB_LIB.T6G(SCH_1):GND
 1_2 P3V3_AUX    VCC @T6G_MB_LIB.T6G(SCH_1):P3V3_AUX
  10 P3V3_OCP_DVDT_2  DV_DT @T6G_MB_LIB.T6G(SCH_1):P3V3_OCP_DVDT_2
   8 P3V3_OCP_GATE_PU207_2   GATE @T6G_MB_LIB.T6G(SCH_1):P3V3_OCP_GATE_PU207_2
 6_7 P3V3_OCP_V3_2_R SOURCE @T6G_MB_LIB.T6G(SCH_1):P3V3_OCP_V3_2_R

Q_CAP_0402-100PF,50V,5%,X7R,CH11006JB18  I54  PC1322
   1 P3V3_OCP_GATE_PU207_2      A @T6G_MB_LIB.T6G(SCH_1):P3V3_OCP_GATE_PU207_2
   2    GND      B @T6G_MB_LIB.T6G(SCH_1):GND

Q_CAP_C0805-10UF,16V,10%,X6S,CH6103KEA01  I56  PC2173
   1 P3V3_OCP_V3_2_R      A @T6G_MB_LIB.T6G(SCH_1):P3V3_OCP_V3_2_R
   2    GND      B @T6G_MB_LIB.T6G(SCH_1):GND

Q_CAP_0402-100PF,50V,5%,NPO,CH11006JB00  I58  PC2167
   1 P12V_OCP_IMON_2      A @T6G_MB_LIB.T6G(SCH_1):P12V_OCP_IMON_2
   2    GND      B @T6G_MB_LIB.T6G(SCH_1):GND

Q_RES_0402LF-0,5%,1/16W,EMPTY,CS00002JB13  I73  R3630
   1 P12V_OCP_V3_2_EN_R      A @T6G_MB_LIB.T6G(SCH_1):P12V_OCP_V3_2_EN_R
   2 P12V_OCP_V3_2_EN_2_R3      B @T6G_MB_LIB.T6G(SCH_1):P12V_OCP_V3_2_EN_2_R3

Q_RES_0402LF-0,5%,1/16W,EMPTY,CS00002JB13  I74  R3631
   1 P3V3_OCP_V3_2_EN_R      A @T6G_MB_LIB.T6G(SCH_1):P3V3_OCP_V3_2_EN_R
   2 P3V3_OCP_EN_2      B @T6G_MB_LIB.T6G(SCH_1):P3V3_OCP_EN_2

Q_RES_0402LF-0,5%,1/16W,CHIP,CS00002JB13  I76  R1193
   1 P12V_OCP_V3_2_BUF_EN_R      A @T6G_MB_LIB.T6G(SCH_1):P12V_OCP_V3_2_BUF_EN_R
   2 P12V_OCP_V3_2_EN_2_R3      B @T6G_MB_LIB.T6G(SCH_1):P12V_OCP_V3_2_EN_2_R3

Q_RES_0402LF-0,5%,1/16W,EMPTY,CS00002JB13  I79  R1196
   1 HP_LVC3_OCP_V3_2_P12V_PWRGD      A @T6G_MB_LIB.T6G(SCH_1):HP_LVC3_OCP_V3_2_P12V_PWRGD
   2 P3V3_OCP_EN_2      B @T6G_MB_LIB.T6G(SCH_1):P3V3_OCP_EN_2

Q_RES_0402LF-0,5%,1/16W,CHIP,CS00002JB13  I80  R1521
   1 P12V_OCP_V3_2_BUF_EN_R      A @T6G_MB_LIB.T6G(SCH_1):P12V_OCP_V3_2_BUF_EN_R
   2 P3V3_OCP_EN_2      B @T6G_MB_LIB.T6G(SCH_1):P3V3_OCP_EN_2

RS31312R-RS31312R,SMLF,IC,AL031312000  I82  PU206
  20 P12V_OCP_V3_2 VOUT_20 @T6G_MB_LIB.T6G(SCH_1):P12V_OCP_V3_2
21_22 P12V_AUX VIN_21_22 @T6G_MB_LIB.T6G(SCH_1):P12V_AUX
  19 P12V_OCP_V3_2 VOUT_19 @T6G_MB_LIB.T6G(SCH_1):P12V_OCP_V3_2
  18 P12V_OCP_V3_2 VOUT_18 @T6G_MB_LIB.T6G(SCH_1):P12V_OCP_V3_2
  17 P12V_OCP_V3_2 VOUT_17 @T6G_MB_LIB.T6G(SCH_1):P12V_OCP_V3_2
  16 P12V_OCP_V3_2 VOUT_16 @T6G_MB_LIB.T6G(SCH_1):P12V_OCP_V3_2
  15 P12V_OCP_V3_2 VOUT_15 @T6G_MB_LIB.T6G(SCH_1):P12V_OCP_V3_2
  14 P12V_OCP_V3_2 VOUT_14 @T6G_MB_LIB.T6G(SCH_1):P12V_OCP_V3_2
  12 P12V_OCP_AVIN_PD_2   AVIN @T6G_MB_LIB.T6G(SCH_1):P12V_OCP_AVIN_PD_2
  13 P12V_OCP_V3_2 VOUT_13 @T6G_MB_LIB.T6G(SCH_1):P12V_OCP_V3_2
  11 P12V_OCP_OV_FB_2     OV @T6G_MB_LIB.T6G(SCH_1):P12V_OCP_OV_FB_2
  10 HP_LVC3_OCP_V3_2_P12V_PWRGD     PG @T6G_MB_LIB.T6G(SCH_1):HP_LVC3_OCP_V3_2_P12V_PWRGD
   9 P12V_OCP_FLTB_2   FLTB @T6G_MB_LIB.T6G(SCH_1):P12V_OCP_FLTB_2
   8 P12V_OCP_IMON_2   IMON @T6G_MB_LIB.T6G(SCH_1):P12V_OCP_IMON_2
  23 P12V_AUX VIN_23 @T6G_MB_LIB.T6G(SCH_1):P12V_AUX
  24 P12V_AUX VIN_24 @T6G_MB_LIB.T6G(SCH_1):P12V_AUX
  25 P12V_AUX VIN_25 @T6G_MB_LIB.T6G(SCH_1):P12V_AUX
  26 P12V_AUX VIN_26 @T6G_MB_LIB.T6G(SCH_1):P12V_AUX
   1 P12V_OCP_V3_2_EN_2_R3     EN @T6G_MB_LIB.T6G(SCH_1):P12V_OCP_V3_2_EN_2_R3
   2    GND LOADEN @T6G_MB_LIB.T6G(SCH_1):GND
   3    GND   ENTM @T6G_MB_LIB.T6G(SCH_1):GND
   4 P12V_OCP_TIMER_2  TIMER @T6G_MB_LIB.T6G(SCH_1):P12V_OCP_TIMER_2
   5 P12V_OCP_ISET_2   ISET @T6G_MB_LIB.T6G(SCH_1):P12V_OCP_ISET_2
   6 P12V_OCP_SS_2     SS @T6G_MB_LIB.T6G(SCH_1):P12V_OCP_SS_2
   7    GND    GND @T6G_MB_LIB.T6G(SCH_1):GND


DRAWING: @T6G_MB_LIB.T6G(SCH_1):PAGE258 

74LVC2G08DP-74LVC2G08DP,SMLF,EMPTY,ALVC2G08K01  I1  U241
   8 P3V3_AUX    VCC @T6G_MB_LIB.T6G(SCH_1):P3V3_AUX
   4    GND    GND @T6G_MB_LIB.T6G(SCH_1):GND
   1 OCP_V3_2_PRSNT0_R_N     1A @T6G_MB_LIB.T6G(SCH_1):OCP_V3_2_PRSNT0_R_N
   2 OCP_V3_2_PRSNT1_R_N     1B @T6G_MB_LIB.T6G(SCH_1):OCP_V3_2_PRSNT1_R_N
   7 OCP_V3_2_PRSNT01_R_N     1Y @T6G_MB_LIB.T6G(SCH_1):OCP_V3_2_PRSNT01_R_N

74LVC2G08DP-74LVC2G08DP,SMLF,EMPTY,ALVC2G08K01  I2  U241
   5 OCP_V3_2_PRSNT2_R_N     2A @T6G_MB_LIB.T6G(SCH_1):OCP_V3_2_PRSNT2_R_N
   6 OCP_V3_2_PRSNT3_R_N     2B @T6G_MB_LIB.T6G(SCH_1):OCP_V3_2_PRSNT3_R_N
   3 OCP_V3_2_PRSNT23_R_N     2Y @T6G_MB_LIB.T6G(SCH_1):OCP_V3_2_PRSNT23_R_N

74LVC2G08DP-74LVC2G08DP,SMLF,EMPTY,ALVC2G08K01  I11  U240
   8 P3V3_AUX    VCC @T6G_MB_LIB.T6G(SCH_1):P3V3_AUX
   4    GND    GND @T6G_MB_LIB.T6G(SCH_1):GND
   1 OCP_SFF_PRSNT0_R_N     1A @T6G_MB_LIB.T6G(SCH_1):OCP_SFF_PRSNT0_R_N
   2 OCP_SFF_PRSNT1_R_N     1B @T6G_MB_LIB.T6G(SCH_1):OCP_SFF_PRSNT1_R_N
   7 OCP_SFF_PRSNT01_R_N     1Y @T6G_MB_LIB.T6G(SCH_1):OCP_SFF_PRSNT01_R_N

74LVC2G08DP-74LVC2G08DP,SMLF,EMPTY,ALVC2G08K01  I12  U240
   5 OCP_SFF_PRSNT2_R_N     2A @T6G_MB_LIB.T6G(SCH_1):OCP_SFF_PRSNT2_R_N
   6 OCP_SFF_PRSNT3_R_N     2B @T6G_MB_LIB.T6G(SCH_1):OCP_SFF_PRSNT3_R_N
   3 OCP_SFF_PRSNT23_R_N     2Y @T6G_MB_LIB.T6G(SCH_1):OCP_SFF_PRSNT23_R_N

74LVC2G08DP-74LVC2G08DP,SMLF,EMPTY,ALVC2G08K01  I13  U242
   8 P3V3_AUX    VCC @T6G_MB_LIB.T6G(SCH_1):P3V3_AUX
   4    GND    GND @T6G_MB_LIB.T6G(SCH_1):GND
   1 OCP_SFF_PRSNT01_R1_N     1A @T6G_MB_LIB.T6G(SCH_1):OCP_SFF_PRSNT01_R1_N
   2 OCP_SFF_PRSNT23_R1_N     1B @T6G_MB_LIB.T6G(SCH_1):OCP_SFF_PRSNT23_R1_N
   7 OCP_SFF_PRSNT_ALL_R_N     1Y @T6G_MB_LIB.T6G(SCH_1):OCP_SFF_PRSNT_ALL_R_N

74LVC2G08DP-74LVC2G08DP,SMLF,EMPTY,ALVC2G08K01  I14  U242
   5 OCP_V3_2_PRSNT01_R1_N     2A @T6G_MB_LIB.T6G(SCH_1):OCP_V3_2_PRSNT01_R1_N
   6 OCP_V3_2_PRSNT23_R1_N     2B @T6G_MB_LIB.T6G(SCH_1):OCP_V3_2_PRSNT23_R1_N
   3 OCP_V3_2_PRSNT_ALL_R_N     2Y @T6G_MB_LIB.T6G(SCH_1):OCP_V3_2_PRSNT_ALL_R_N

NC7SB3157_SMLF-NC7SB3157P6X,NC7SB3157P6X,EMPTY,ALSA  I15  U243
   1 OCP_SFF_NOT_PRSNT_RBT_ARB_IN     B1 @T6G_MB_LIB.T6G(SCH_1):OCP_SFF_NOT_PRSNT_RBT_ARB_IN
   2    GND    GND @T6G_MB_LIB.T6G(SCH_1):GND
   3 OCP_SFF_RBT_ARB_OUT     B0 @T6G_MB_LIB.T6G(SCH_1):OCP_SFF_RBT_ARB_OUT
   6 OCP_SFF_PRSNT_ALL_R1_N      S @T6G_MB_LIB.T6G(SCH_1):OCP_SFF_PRSNT_ALL_R1_N
   5 P3V3_AUX    VCC @T6G_MB_LIB.T6G(SCH_1):P3V3_AUX
   4 OCP_SFF_RBT_ARB_IN_MUX2      A @T6G_MB_LIB.T6G(SCH_1):OCP_SFF_RBT_ARB_IN_MUX2

NC7SB3157_SMLF-NC7SB3157P6X,NC7SB3157P6X,EMPTY,ALSA  I16  U244
   1 OCP_SFF_NOT_PRSNT_RBT_ARB_IN     B1 @T6G_MB_LIB.T6G(SCH_1):OCP_SFF_NOT_PRSNT_RBT_ARB_IN
   2    GND    GND @T6G_MB_LIB.T6G(SCH_1):GND
   3 OCP_SFF_RBT_ARB_IN     B0 @T6G_MB_LIB.T6G(SCH_1):OCP_SFF_RBT_ARB_IN
   6 OCP_SFF_PRSNT_ALL_R3_N      S @T6G_MB_LIB.T6G(SCH_1):OCP_SFF_PRSNT_ALL_R3_N
   5 P3V3_AUX    VCC @T6G_MB_LIB.T6G(SCH_1):P3V3_AUX
   4 OCP_SFF_RBT_ARB_IN_MUX1_R      A @T6G_MB_LIB.T6G(SCH_1):OCP_SFF_RBT_ARB_IN_MUX1_R

NC7SB3157_SMLF-NC7SB3157P6X,NC7SB3157P6X,EMPTY,ALSA  I17  U246
   1 OCP_V3_2_NOT_PRSNT_RBT_ARB_IN     B1 @T6G_MB_LIB.T6G(SCH_1):OCP_V3_2_NOT_PRSNT_RBT_ARB_IN
   2    GND    GND @T6G_MB_LIB.T6G(SCH_1):GND
   3 OCP_V3_2_RBT_ARB_OUT     B0 @T6G_MB_LIB.T6G(SCH_1):OCP_V3_2_RBT_ARB_OUT
   6 OCP_V3_2_PRSNT_ALL_R1_N      S @T6G_MB_LIB.T6G(SCH_1):OCP_V3_2_PRSNT_ALL_R1_N
   5 P3V3_AUX    VCC @T6G_MB_LIB.T6G(SCH_1):P3V3_AUX
   4 OCP_SFF_RBT_ARB_IN_MUX1      A @T6G_MB_LIB.T6G(SCH_1):OCP_SFF_RBT_ARB_IN_MUX1

NC7SB3157_SMLF-NC7SB3157P6X,NC7SB3157P6X,EMPTY,ALSA  I18  U245
   1 OCP_V3_2_NOT_PRSNT_RBT_ARB_IN     B1 @T6G_MB_LIB.T6G(SCH_1):OCP_V3_2_NOT_PRSNT_RBT_ARB_IN
   2    GND    GND @T6G_MB_LIB.T6G(SCH_1):GND
   3 OCP_V3_2_RBT_ARB_IN     B0 @T6G_MB_LIB.T6G(SCH_1):OCP_V3_2_RBT_ARB_IN
   6 OCP_V3_2_PRSNT_ALL_R3_N      S @T6G_MB_LIB.T6G(SCH_1):OCP_V3_2_PRSNT_ALL_R3_N
   5 P3V3_AUX    VCC @T6G_MB_LIB.T6G(SCH_1):P3V3_AUX
   4 OCP_SFF_RBT_ARB_IN_MUX2_R      A @T6G_MB_LIB.T6G(SCH_1):OCP_SFF_RBT_ARB_IN_MUX2_R

Q_CAP_0402-0.1UF,25V,10%,X7R,CH4104K1B00  I21  C1875
   1 P3V3_AUX      A @T6G_MB_LIB.T6G(SCH_1):P3V3_AUX
   2    GND      B @T6G_MB_LIB.T6G(SCH_1):GND

Q_CAP_0402-0.1UF,25V,10%,X7R,CH4104K1B00  I22  C1874
   1 P3V3_AUX      A @T6G_MB_LIB.T6G(SCH_1):P3V3_AUX
   2    GND      B @T6G_MB_LIB.T6G(SCH_1):GND

Q_CAP_0402-0.1UF,25V,10%,X7R,CH4104K1B00  I27  C1880
   1 P3V3_AUX      A @T6G_MB_LIB.T6G(SCH_1):P3V3_AUX
   2    GND      B @T6G_MB_LIB.T6G(SCH_1):GND

Q_CAP_0402-0.1UF,25V,10%,X7R,CH4104K1B00  I31  C1879
   1 P3V3_AUX      A @T6G_MB_LIB.T6G(SCH_1):P3V3_AUX
   2    GND      B @T6G_MB_LIB.T6G(SCH_1):GND

Q_CAP_0402-0.1UF,25V,10%,X7R,CH4104K1B00  I34  C1877
   1 P3V3_AUX      A @T6G_MB_LIB.T6G(SCH_1):P3V3_AUX
   2    GND      B @T6G_MB_LIB.T6G(SCH_1):GND

Q_CAP_0402-0.1UF,25V,10%,X7R,CH4104K1B00  I37  C1878
   1 P3V3_AUX      A @T6G_MB_LIB.T6G(SCH_1):P3V3_AUX
   2    GND      B @T6G_MB_LIB.T6G(SCH_1):GND

Q_CAP_0402-0.1UF,25V,10%,X7R,CH4104K1B00  I41  C1876
   1 P3V3_AUX      A @T6G_MB_LIB.T6G(SCH_1):P3V3_AUX
   2    GND      B @T6G_MB_LIB.T6G(SCH_1):GND

Q_RES_0402LF-0,5%,1/16W,CHIP,CS00002JB13  I44  R3303
   1 OCP_SFF_PRSNT_ALL_R_N      A @T6G_MB_LIB.T6G(SCH_1):OCP_SFF_PRSNT_ALL_R_N
   2 OCP_SFF_PRSNT_ALL_R1_N      B @T6G_MB_LIB.T6G(SCH_1):OCP_SFF_PRSNT_ALL_R1_N

Q_RES_0402LF-0,5%,1/16W,CHIP,CS00002JB13  I45  R3304
   1 OCP_SFF_PRSNT_ALL_R_N      A @T6G_MB_LIB.T6G(SCH_1):OCP_SFF_PRSNT_ALL_R_N
   2 OCP_SFF_PRSNT_ALL_R3_N      B @T6G_MB_LIB.T6G(SCH_1):OCP_SFF_PRSNT_ALL_R3_N

Q_RES_0402LF-0,5%,1/16W,CHIP,CS00002JB13  I46  R3308
   1 OCP_V3_2_PRSNT_ALL_R_N      A @T6G_MB_LIB.T6G(SCH_1):OCP_V3_2_PRSNT_ALL_R_N
   2 OCP_V3_2_PRSNT_ALL_R1_N      B @T6G_MB_LIB.T6G(SCH_1):OCP_V3_2_PRSNT_ALL_R1_N

Q_RES_0402LF-0,5%,1/16W,CHIP,CS00002JB13  I47  R3306
   1 OCP_V3_2_PRSNT_ALL_R_N      A @T6G_MB_LIB.T6G(SCH_1):OCP_V3_2_PRSNT_ALL_R_N
   2 OCP_V3_2_PRSNT_ALL_R3_N      B @T6G_MB_LIB.T6G(SCH_1):OCP_V3_2_PRSNT_ALL_R3_N

Q_RES_0402LF-0,5%,1/16W,CHIP,CS00002JB13  I50  R3305
   1 OCP_SFF_RBT_ARB_IN_MUX1      A @T6G_MB_LIB.T6G(SCH_1):OCP_SFF_RBT_ARB_IN_MUX1
   2 OCP_SFF_RBT_ARB_IN_MUX1_R      B @T6G_MB_LIB.T6G(SCH_1):OCP_SFF_RBT_ARB_IN_MUX1_R

Q_RES_0402LF-0,5%,1/16W,CHIP,CS00002JB13  I52  R3307
   1 OCP_SFF_RBT_ARB_IN_MUX2      A @T6G_MB_LIB.T6G(SCH_1):OCP_SFF_RBT_ARB_IN_MUX2
   2 OCP_SFF_RBT_ARB_IN_MUX2_R      B @T6G_MB_LIB.T6G(SCH_1):OCP_SFF_RBT_ARB_IN_MUX2_R

Q_RES_0402LF-0,5%,1/16W,EMPTY,CS00002JB13  I64  R8013
   1 OCP_SFF_PRSNT01_R_N      A @T6G_MB_LIB.T6G(SCH_1):OCP_SFF_PRSNT01_R_N
   2 OCP_SFF_PRSNT01_R1_N      B @T6G_MB_LIB.T6G(SCH_1):OCP_SFF_PRSNT01_R1_N

Q_RES_0402LF-0,5%,1/16W,EMPTY,CS00002JB13  I65  R8014
   1 OCP_SFF_PRSNT23_R_N      A @T6G_MB_LIB.T6G(SCH_1):OCP_SFF_PRSNT23_R_N
   2 OCP_SFF_PRSNT23_R1_N      B @T6G_MB_LIB.T6G(SCH_1):OCP_SFF_PRSNT23_R1_N

Q_RES_0402LF-0,5%,1/16W,EMPTY,CS00002JB13  I66  R8015
   1 OCP_V3_2_PRSNT01_R_N      A @T6G_MB_LIB.T6G(SCH_1):OCP_V3_2_PRSNT01_R_N
   2 OCP_V3_2_PRSNT01_R1_N      B @T6G_MB_LIB.T6G(SCH_1):OCP_V3_2_PRSNT01_R1_N

Q_RES_0402LF-0,5%,1/16W,EMPTY,CS00002JB13  I67  R8016
   1 OCP_V3_2_PRSNT23_R_N      A @T6G_MB_LIB.T6G(SCH_1):OCP_V3_2_PRSNT23_R_N
   2 OCP_V3_2_PRSNT23_R1_N      B @T6G_MB_LIB.T6G(SCH_1):OCP_V3_2_PRSNT23_R1_N

Q_CAP_0402-0.1UF,25V,10%,EMPTY,CH4104K1B00  I68  C8001
   1 OCP_SFF_PRSNT01_R1_N      A @T6G_MB_LIB.T6G(SCH_1):OCP_SFF_PRSNT01_R1_N
   2    GND      B @T6G_MB_LIB.T6G(SCH_1):GND

Q_CAP_0402-0.1UF,25V,10%,EMPTY,CH4104K1B00  I70  C8002
   1 OCP_SFF_PRSNT23_R1_N      A @T6G_MB_LIB.T6G(SCH_1):OCP_SFF_PRSNT23_R1_N
   2    GND      B @T6G_MB_LIB.T6G(SCH_1):GND

Q_CAP_0402-0.1UF,25V,10%,EMPTY,CH4104K1B00  I72  C8003
   1 OCP_V3_2_PRSNT01_R1_N      A @T6G_MB_LIB.T6G(SCH_1):OCP_V3_2_PRSNT01_R1_N
   2    GND      B @T6G_MB_LIB.T6G(SCH_1):GND

Q_CAP_0402-0.1UF,25V,10%,EMPTY,CH4104K1B00  I74  C8004
   1 OCP_V3_2_PRSNT23_R1_N      A @T6G_MB_LIB.T6G(SCH_1):OCP_V3_2_PRSNT23_R1_N
   2    GND      B @T6G_MB_LIB.T6G(SCH_1):GND


DRAWING: @T6G_MB_LIB.T6G(SCH_1):PAGE323 

Q_CAP_0402-39PF,50V,5%,NPO,CH03906JB06  I3  PC2197
   1 P3V3_E1S_MODE_0      A @T6G_MB_LIB.T6G(SCH_1):P3V3_E1S_MODE_0
   2    GND      B @T6G_MB_LIB.T6G(SCH_1):GND

Q_RES_0402LF-71.5K,1%,1/16W,CHIP,CS37152FB05  I4  PR3945
   1 P3V3_E1S_MODE_0      A @T6G_MB_LIB.T6G(SCH_1):P3V3_E1S_MODE_0
   2    GND      B @T6G_MB_LIB.T6G(SCH_1):GND

Q_RES_0402LF-0,5%,1/16W,CHIP,CS00002JB13  I5  R3946
   1 E1S_0_P3V3_EN      A @T6G_MB_LIB.T6G(SCH_1):E1S_0_P3V3_EN
   2 P3V3_E1S_EN_0_R2      B @T6G_MB_LIB.T6G(SCH_1):P3V3_E1S_EN_0_R2

Q_RES_0402LF-2.8K,1%,1/16W,CHIP,CS22802FB04  I6  PR3947
   1    GND      A @T6G_MB_LIB.T6G(SCH_1):GND
   2 P3V3_E1S_ILIMIT_0      B @T6G_MB_LIB.T6G(SCH_1):P3V3_E1S_ILIMIT_0

Q_CAP_C0402-1UF,25V,10%,X6S,CH5104KEB02  I9  PC2200
   1 P3V3_AUX      A @T6G_MB_LIB.T6G(SCH_1):P3V3_AUX
   2    GND      B @T6G_MB_LIB.T6G(SCH_1):GND

Q_CAP_0402-0.22UF,16V,10%,X7R,CH4223K1B00  I13  PC2196
   1 P12V_E1S_TIMER_0      A @T6G_MB_LIB.T6G(SCH_1):P12V_E1S_TIMER_0
   2    GND      B @T6G_MB_LIB.T6G(SCH_1):GND

Q_RES_0402LF-46.4K,1%,1/16W,CHIP,CS34642FB02  I15  PR3944
   1 P12V_E1S_ISET_0      A @T6G_MB_LIB.T6G(SCH_1):P12V_E1S_ISET_0
   2    GND      B @T6G_MB_LIB.T6G(SCH_1):GND

Q_CAP_C0402-560PF,50V,10%,X7R,CH1566K1B09  I17  PC2341
   1 P12V_E1S_ISET_0_R      A @T6G_MB_LIB.T6G(SCH_1):P12V_E1S_ISET_0_R
   2    GND      B @T6G_MB_LIB.T6G(SCH_1):GND

Q_RES_0402LF-20K,1%,1/16W,CHIP,CS32002FB06  I18  PR4541
   1 P12V_E1S_ISET_0      A @T6G_MB_LIB.T6G(SCH_1):P12V_E1S_ISET_0
   2 P12V_E1S_ISET_0_R      B @T6G_MB_LIB.T6G(SCH_1):P12V_E1S_ISET_0_R

Q_RES_0402LF-0,5%,1/16W,CHIP,CS00002JB13  I19  R3943
   1 E1S_0_P12V_EN      A @T6G_MB_LIB.T6G(SCH_1):E1S_0_P12V_EN
   2 P12V_E1S_EN_0_R2      B @T6G_MB_LIB.T6G(SCH_1):P12V_E1S_EN_0_R2

Q_CAP_C0402-0.047UF,25V,10%,X7R,CH3474K1B04  I22  PC2281
   1 P12V_E1S_SS_0      A @T6G_MB_LIB.T6G(SCH_1):P12V_E1S_SS_0
   2    GND      B @T6G_MB_LIB.T6G(SCH_1):GND

Q_CAP_C0402-1UF,25V,10%,X6S,CH5104KEB02  I25  PC2198
   1 P12V_AUX      A @T6G_MB_LIB.T6G(SCH_1):P12V_AUX
   2    GND      B @T6G_MB_LIB.T6G(SCH_1):GND

Q_CAP_0402-0.068UF,16V,10%,X7R,CH3683K1B09  I30  PC2201
   1 P3V3_E1S_DVDT_0      A @T6G_MB_LIB.T6G(SCH_1):P3V3_E1S_DVDT_0
   2    GND      B @T6G_MB_LIB.T6G(SCH_1):GND

MP5016GQHLZ-MP5016GQH-L-Z,SMLF,IC,AL005016007  I31  PU293
   9 P3V3_E1S_EN_0_R2     EN @T6G_MB_LIB.T6G(SCH_1):P3V3_E1S_EN_0_R2
   5 P3V3_E1S_MODE_0   MODE @T6G_MB_LIB.T6G(SCH_1):P3V3_E1S_MODE_0
   4 P3V3_E1S_ILIMIT_0 ILIMIT @T6G_MB_LIB.T6G(SCH_1):P3V3_E1S_ILIMIT_0
   3    GND    GND @T6G_MB_LIB.T6G(SCH_1):GND
 1_2 P3V3_AUX    VCC @T6G_MB_LIB.T6G(SCH_1):P3V3_AUX
  10 P3V3_E1S_DVDT_0  DV_DT @T6G_MB_LIB.T6G(SCH_1):P3V3_E1S_DVDT_0
   8 P3V3_E1S_GATE_0_PU293   GATE @T6G_MB_LIB.T6G(SCH_1):P3V3_E1S_GATE_0_PU293
 6_7 P3V3_E1S_0_R SOURCE @T6G_MB_LIB.T6G(SCH_1):P3V3_E1S_0_R

Q_CAP_0402-100PF,50V,5%,X7R,CH11006JB18  I32  PC2203
   1 P3V3_E1S_GATE_0_PU293      A @T6G_MB_LIB.T6G(SCH_1):P3V3_E1S_GATE_0_PU293
   2    GND      B @T6G_MB_LIB.T6G(SCH_1):GND

Q_CAP_C0805-10UF,16V,10%,X6S,CH6103KEA01  I34  PC2204
   1 P3V3_E1S_0_R      A @T6G_MB_LIB.T6G(SCH_1):P3V3_E1S_0_R
   2    GND      B @T6G_MB_LIB.T6G(SCH_1):GND

Q_RES_0402LF-56K,1%,1/16W,CHIP,CS35602FB00  I36  PR3949
   1 P12V_E1S_IMON_0      A @T6G_MB_LIB.T6G(SCH_1):P12V_E1S_IMON_0
   2    GND      B @T6G_MB_LIB.T6G(SCH_1):GND

Q_RES_0402LF-10K,1%,1/16W,CHIP,CS31002FB08  I37  R3948
   1 P3V3_AUX      A @T6G_MB_LIB.T6G(SCH_1):P3V3_AUX
   2 HP_LVC3_E1S_0_HSC_PWRGD      B @T6G_MB_LIB.T6G(SCH_1):HP_LVC3_E1S_0_HSC_PWRGD

Q_CAP_C0402-100NF,50V,10%,X7R,CH4106K1B01  I39  PC2202
   1 P12V_E1S_IMON_0      A @T6G_MB_LIB.T6G(SCH_1):P12V_E1S_IMON_0
   2    GND      B @T6G_MB_LIB.T6G(SCH_1):GND

Q_RES_0402LF-10K,1%,1/16W,CHIP,CS31002FB08  I40  PR3951
   1 P12V_E1S_FLTB_0      A @T6G_MB_LIB.T6G(SCH_1):P12V_E1S_FLTB_0
   2 P3V3_AUX      B @T6G_MB_LIB.T6G(SCH_1):P3V3_AUX

Q_RES_0402LF-100,1%,1/16W,EMPTY,CS11002FB07  I42  PR3950
   1 P12V_E1S_0      A @T6G_MB_LIB.T6G(SCH_1):P12V_E1S_0
   2 P12V_E1S_AVIN_PD_0      B @T6G_MB_LIB.T6G(SCH_1):P12V_E1S_AVIN_PD_0

Q_RES_0402LF-71.5K,1%,1/16W,EMPTY,CS37152FB05  I45  PR3952
   1 P12V_E1S_0      A @T6G_MB_LIB.T6G(SCH_1):P12V_E1S_0
   2 P12V_E1S_OV_FB_0      B @T6G_MB_LIB.T6G(SCH_1):P12V_E1S_OV_FB_0

Q_RES_0402LF-0,5%,1/16W,EMPTY,CS00002JB13  I47  R3956
   1 P12V_E1S_IMON_0      A @T6G_MB_LIB.T6G(SCH_1):P12V_E1S_IMON_0
   2 P12V_E1S_0_ISENSE_MPS_TIC      B @T6G_MB_LIB.T6G(SCH_1):P12V_E1S_0_ISENSE_MPS_TIC

Q_RES_0402LF-0,5%,1/16W,CHIP,CS00002JB13  I48  R3955
   1 P12V_E1S_IMON_0      A @T6G_MB_LIB.T6G(SCH_1):P12V_E1S_IMON_0
   2 P12V_E1S_0_ISENSE_MPS_MAM      B @T6G_MB_LIB.T6G(SCH_1):P12V_E1S_0_ISENSE_MPS_MAM

Q_RES_0402LF-10K,1%,1/16W,CHIP,CS31002FB08  I49  PR3954
   1 P12V_E1S_OV_FB_0      A @T6G_MB_LIB.T6G(SCH_1):P12V_E1S_OV_FB_0
   2    GND      B @T6G_MB_LIB.T6G(SCH_1):GND

Q_CAP_C0603-2.2UF,16V,20%,X7R,CH5223M1900  I51  PC2205
   1 P12V_E1S_AVIN_PD_0      A @T6G_MB_LIB.T6G(SCH_1):P12V_E1S_AVIN_PD_0
   2    GND      B @T6G_MB_LIB.T6G(SCH_1):GND

Q_RES_0402LF-120K,1%,1/16W,CHIP,CS41202FB05  I52  PR3953
   1 P12V_AUX      A @T6G_MB_LIB.T6G(SCH_1):P12V_AUX
   2 P12V_E1S_OV_FB_0      B @T6G_MB_LIB.T6G(SCH_1):P12V_E1S_OV_FB_0

Q_RES_0603LF-49.9,1%,1/10W,CHIP,CS04993F909  I54  PR3957
   1 P12V_AUX      A @T6G_MB_LIB.T6G(SCH_1):P12V_AUX
   2 P12V_E1S_AVIN_PD_0      B @T6G_MB_LIB.T6G(SCH_1):P12V_E1S_AVIN_PD_0

Q_CAP_0402-0.1UF,25V,10%,X7R,CH4104K1B00  I56  PC2206
   1 P12V_E1S_0      A @T6G_MB_LIB.T6G(SCH_1):P12V_E1S_0
   2    GND      B @T6G_MB_LIB.T6G(SCH_1):GND

Q_CAP_0402-0.1UF,25V,10%,X7R,CH4104K1B00  I64  C8010
   1 P3V3_E1S_0_R      A @T6G_MB_LIB.T6G(SCH_1):P3V3_E1S_0_R
   2    GND      B @T6G_MB_LIB.T6G(SCH_1):GND

APX80929SAG7-APX809-29SAG-7,SMLF,IC,AL080929000  I65  U8003
   3 P3V3_E1S_0_R    VCC @T6G_MB_LIB.T6G(SCH_1):P3V3_E1S_0_R
   2 P3V3_E1S_PWRGD_0_R1 RESET_L @T6G_MB_LIB.T6G(SCH_1):P3V3_E1S_PWRGD_0_R1
   1    GND    GND @T6G_MB_LIB.T6G(SCH_1):GND

Q_RES_0402LF-100K,1%,1/16W,CHIP,CS41002FB09  I68  R8099
   1 P3V3_E1S_PWRGD_0_R1      A @T6G_MB_LIB.T6G(SCH_1):P3V3_E1S_PWRGD_0_R1
   2    GND      B @T6G_MB_LIB.T6G(SCH_1):GND

Q_RES_0402LF-10K,5%,1/16W,EMPTY,CS31002JB08  I70  R8098
   1 P3V3_E1S_0_R      A @T6G_MB_LIB.T6G(SCH_1):P3V3_E1S_0_R
   2 P3V3_E1S_PWRGD_0_R1      B @T6G_MB_LIB.T6G(SCH_1):P3V3_E1S_PWRGD_0_R1

Q_RES_0402LF-0,5%,1/16W,CHIP,CS00002JB13  I71  R8100
   1 P3V3_E1S_PWRGD_0_R1      A @T6G_MB_LIB.T6G(SCH_1):P3V3_E1S_PWRGD_0_R1
   2 P3V3_E1S_PWRGD_0_R      B @T6G_MB_LIB.T6G(SCH_1):P3V3_E1S_PWRGD_0_R

RS31312R-RS31312R,SMLF,IC,AL031312000  I76  PU292
  20 P12V_E1S_0 VOUT_20 @T6G_MB_LIB.T6G(SCH_1):P12V_E1S_0
21_22 P12V_AUX VIN_21_22 @T6G_MB_LIB.T6G(SCH_1):P12V_AUX
  19 P12V_E1S_0 VOUT_19 @T6G_MB_LIB.T6G(SCH_1):P12V_E1S_0
  18 P12V_E1S_0 VOUT_18 @T6G_MB_LIB.T6G(SCH_1):P12V_E1S_0
  17 P12V_E1S_0 VOUT_17 @T6G_MB_LIB.T6G(SCH_1):P12V_E1S_0
  16 P12V_E1S_0 VOUT_16 @T6G_MB_LIB.T6G(SCH_1):P12V_E1S_0
  15 P12V_E1S_0 VOUT_15 @T6G_MB_LIB.T6G(SCH_1):P12V_E1S_0
  14 P12V_E1S_0 VOUT_14 @T6G_MB_LIB.T6G(SCH_1):P12V_E1S_0
  12 P12V_E1S_AVIN_PD_0   AVIN @T6G_MB_LIB.T6G(SCH_1):P12V_E1S_AVIN_PD_0
  13 P12V_E1S_0 VOUT_13 @T6G_MB_LIB.T6G(SCH_1):P12V_E1S_0
  11 P12V_E1S_OV_FB_0     OV @T6G_MB_LIB.T6G(SCH_1):P12V_E1S_OV_FB_0
  10 HP_LVC3_E1S_0_HSC_PWRGD     PG @T6G_MB_LIB.T6G(SCH_1):HP_LVC3_E1S_0_HSC_PWRGD
   9 P12V_E1S_FLTB_0   FLTB @T6G_MB_LIB.T6G(SCH_1):P12V_E1S_FLTB_0
   8 P12V_E1S_IMON_0   IMON @T6G_MB_LIB.T6G(SCH_1):P12V_E1S_IMON_0
  23 P12V_AUX VIN_23 @T6G_MB_LIB.T6G(SCH_1):P12V_AUX
  24 P12V_AUX VIN_24 @T6G_MB_LIB.T6G(SCH_1):P12V_AUX
  25 P12V_AUX VIN_25 @T6G_MB_LIB.T6G(SCH_1):P12V_AUX
  26 P12V_AUX VIN_26 @T6G_MB_LIB.T6G(SCH_1):P12V_AUX
   1 P12V_E1S_EN_0_R2     EN @T6G_MB_LIB.T6G(SCH_1):P12V_E1S_EN_0_R2
   2    GND LOADEN @T6G_MB_LIB.T6G(SCH_1):GND
   3    GND   ENTM @T6G_MB_LIB.T6G(SCH_1):GND
   4 P12V_E1S_TIMER_0  TIMER @T6G_MB_LIB.T6G(SCH_1):P12V_E1S_TIMER_0
   5 P12V_E1S_ISET_0   ISET @T6G_MB_LIB.T6G(SCH_1):P12V_E1S_ISET_0
   6 P12V_E1S_SS_0     SS @T6G_MB_LIB.T6G(SCH_1):P12V_E1S_SS_0
   7    GND    GND @T6G_MB_LIB.T6G(SCH_1):GND


DRAWING: @T6G_MB_LIB.T6G(SCH_1):PAGE324 

Q_RES_0402LF-0,5%,1/16W,CHIP,CS00002JB13  I2  R4063
   1 E1S_0_P3V3_EN      A @T6G_MB_LIB.T6G(SCH_1):E1S_0_P3V3_EN
   2 P3V3_E1S_EN_0_R      B @T6G_MB_LIB.T6G(SCH_1):P3V3_E1S_EN_0_R

Q_RES_0402LF-4.7K,5%,1/16W,CHIP,CS24702JB10  I4  R6049
   1 P3V3_E1S_EN_0_R      A @T6G_MB_LIB.T6G(SCH_1):P3V3_E1S_EN_0_R
   2    GND      B @T6G_MB_LIB.T6G(SCH_1):GND

MOSFET_NCH_DUAL-PJT138K,SMLF,IC,BAM138K0003  I6  Q126
   1    GND     S1 @T6G_MB_LIB.T6G(SCH_1):GND
   2 P3V3_E1S_EN_0_R     G1 @T6G_MB_LIB.T6G(SCH_1):P3V3_E1S_EN_0_R
   6 P3V3_E1S_0_EN_G     D1 @T6G_MB_LIB.T6G(SCH_1):P3V3_E1S_0_EN_G

Q_RES_0402LF-4.7K,5%,1/16W,CHIP,CS24702JB10  I11  R4073
   1 P12V_E1S_EN_0_R      A @T6G_MB_LIB.T6G(SCH_1):P12V_E1S_EN_0_R
   2    GND      B @T6G_MB_LIB.T6G(SCH_1):GND

Q_RES_0402LF-15K,1%,1/16W,CHIP,CS31502FB05  I16  PR3965
   1 P3V3_E1S_OV_0      A @T6G_MB_LIB.T6G(SCH_1):P3V3_E1S_OV_0
   2    GND      B @T6G_MB_LIB.T6G(SCH_1):GND

Q_RES_0402LF-7.15K,1%,1/16W,CHIP,CS27152FB03  I17  PR3964
   1 P3V3_E1S_UV_0      A @T6G_MB_LIB.T6G(SCH_1):P3V3_E1S_UV_0
   2 P3V3_E1S_OV_0      B @T6G_MB_LIB.T6G(SCH_1):P3V3_E1S_OV_0

Q_CAP_C0402-1UF,25V,10%,X6S,CH5104KEB02  I20  PC2208
   1 P3V3_AUX      A @T6G_MB_LIB.T6G(SCH_1):P3V3_AUX
   2    GND      B @T6G_MB_LIB.T6G(SCH_1):GND

Q_RES_0402LF-25.5K,1%,1/16W,CHIP,CS32552FB06  I21  PR3963
   1 P3V3_AUX      A @T6G_MB_LIB.T6G(SCH_1):P3V3_AUX
   2 P3V3_E1S_UV_0      B @T6G_MB_LIB.T6G(SCH_1):P3V3_E1S_UV_0

Q_RES_0402LF-10K,1%,1/16W,CHIP,CS31002FB08  I25  R4074
   1 P12V_AUX      A @T6G_MB_LIB.T6G(SCH_1):P12V_AUX
   2 P12V_E1S_0_EN_G      B @T6G_MB_LIB.T6G(SCH_1):P12V_E1S_0_EN_G

MOSFET_NCH_DUAL-PJT138K,SMLF,IC,BAM138K0003  I27  Q127
   3 P12V_E1S_UV_0_R     D2 @T6G_MB_LIB.T6G(SCH_1):P12V_E1S_UV_0_R
   5 P12V_E1S_0_EN_G     G2 @T6G_MB_LIB.T6G(SCH_1):P12V_E1S_0_EN_G
   4    GND     S2 @T6G_MB_LIB.T6G(SCH_1):GND

Q_RES_0402LF-0,5%,1/16W,CHIP,CS00002JB13  I29  R3958
   1 P12V_E1S_UV_0_R      A @T6G_MB_LIB.T6G(SCH_1):P12V_E1S_UV_0_R
   2 P12V_E1S_UV_0      B @T6G_MB_LIB.T6G(SCH_1):P12V_E1S_UV_0

Q_RES_0402LF-15K,1%,1/16W,CHIP,CS31502FB05  I31  PR3962
   1 P12V_E1S_OV_0      A @T6G_MB_LIB.T6G(SCH_1):P12V_E1S_OV_0
   2    GND      B @T6G_MB_LIB.T6G(SCH_1):GND

DIODE_TVS-SMF14A,SMLF,IC,BCSMF14AZ01  I33  PD114
   A    GND      A @T6G_MB_LIB.T6G(SCH_1):GND
   C P12V_AUX      C @T6G_MB_LIB.T6G(SCH_1):P12V_AUX

Q_CAP_C0402-1UF,25V,10%,X6S,CH5104KEB02  I36  PC2207
   1 P12V_AUX      A @T6G_MB_LIB.T6G(SCH_1):P12V_AUX
   2    GND      B @T6G_MB_LIB.T6G(SCH_1):GND

Q_RES_0402LF-160K,1%,1/16W,CHIP,CS41602FB05  I37  PR3960
   1 P12V_AUX      A @T6G_MB_LIB.T6G(SCH_1):P12V_AUX
   2 P12V_E1S_UV_0      B @T6G_MB_LIB.T6G(SCH_1):P12V_E1S_UV_0

Q_RES_0402LF-2.49K,1%,1/16W,CHIP,CS22492FB05  I39  PR3969
   1 P3V3_E1S_CB_0      A @T6G_MB_LIB.T6G(SCH_1):P3V3_E1S_CB_0
   2    GND      B @T6G_MB_LIB.T6G(SCH_1):GND

Q_CAP_C0402-1UF,25V,10%,X6S,CH5104KEB02  I41  PC2210
   1 P3V3_E1S_VCC_0      A @T6G_MB_LIB.T6G(SCH_1):P3V3_E1S_VCC_0
   2    GND      B @T6G_MB_LIB.T6G(SCH_1):GND

Q_RES_0402LF-10,1%,1/16W,CHIP,CS01002FB07  I43  PR3967
   1 P3V3_AUX      A @T6G_MB_LIB.T6G(SCH_1):P3V3_AUX
   2 P3V3_E1S_VCC_0      B @T6G_MB_LIB.T6G(SCH_1):P3V3_E1S_VCC_0

Q_RES_0402LF-9.76K,1%,1/16W,CHIP,CS29762FB05  I45  PR3971
   1 P3V3_E1S_SENSE_0      A @T6G_MB_LIB.T6G(SCH_1):P3V3_E1S_SENSE_0
   2    GND      B @T6G_MB_LIB.T6G(SCH_1):GND

Q_CAP_C0402-0.01UF,50V,10%,EMPTY,CH31006KB18  I46  PC2213
   1 P3V3_E1S_0_R      A @T6G_MB_LIB.T6G(SCH_1):P3V3_E1S_0_R
   2 P3V3_E1S_GATE_0      B @T6G_MB_LIB.T6G(SCH_1):P3V3_E1S_GATE_0

Q_RES_0402LF-10M,1%,1/16W,CHIP,CS61002FB02  I47  PR4527
   1 P3V3_E1S_0_R      A @T6G_MB_LIB.T6G(SCH_1):P3V3_E1S_0_R
   2 P3V3_E1S_GATE_0      B @T6G_MB_LIB.T6G(SCH_1):P3V3_E1S_GATE_0

Q_RES_0402LF-0,5%,1/16W,CHIP,CS00002JB13  I48  R3973
   1 P3V3_E1S_PWRGD_0      A @T6G_MB_LIB.T6G(SCH_1):P3V3_E1S_PWRGD_0
   2 P3V3_E1S_PWRGD_0_R      B @T6G_MB_LIB.T6G(SCH_1):P3V3_E1S_PWRGD_0_R

SCHOTTKY_AC-B340A-13-F,SMLF,IC,BC000340Z30  I50  PD113
   A    GND      A @T6G_MB_LIB.T6G(SCH_1):GND
   C P3V3_E1S_0_R      C @T6G_MB_LIB.T6G(SCH_1):P3V3_E1S_0_R

Q_RES_0402LF-100K,1%,1/16W,CHIP,CS41002FB09  I54  R3979
   1 P3V3_AUX      A @T6G_MB_LIB.T6G(SCH_1):P3V3_AUX
   2 P3V3_E1S_PWRGD_0_R      B @T6G_MB_LIB.T6G(SCH_1):P3V3_E1S_PWRGD_0_R

Q_CAP_C0805-10UF,16V,10%,X6S,CH6103KEA01  I58  PC2220
   1 P3V3_E1S_0_R      A @T6G_MB_LIB.T6G(SCH_1):P3V3_E1S_0_R
   2    GND      B @T6G_MB_LIB.T6G(SCH_1):GND

Q_CAP_C0402-1UF,25V,10%,X6S,CH5104KEB02  I61  PC2211
   1    GND      A @T6G_MB_LIB.T6G(SCH_1):GND
   2 P12V_E1S_REG_0      B @T6G_MB_LIB.T6G(SCH_1):P12V_E1S_REG_0

Q_RES_0402LF-9.31K,1%,1/16W,CHIP,CS29312FB02  I63  PR3968
   1 P12V_E1S_CB_0      A @T6G_MB_LIB.T6G(SCH_1):P12V_E1S_CB_0
   2    GND      B @T6G_MB_LIB.T6G(SCH_1):GND

Q_RES_0402LF-10,1%,1/16W,CHIP,CS01002FB07  I65  PR3966
   1 P12V_AUX      A @T6G_MB_LIB.T6G(SCH_1):P12V_AUX
   2 P12V_E1S_VCC_0      B @T6G_MB_LIB.T6G(SCH_1):P12V_E1S_VCC_0

MAX15090BEWIT-MAX15090BEWI+T,SMLF,IC,AL015080B00  I66  PU294
  A2 P12V_E1S_VCC_0    VCC @T6G_MB_LIB.T6G(SCH_1):P12V_E1S_VCC_0
  A3 P12V_AUX  IN_A3 @T6G_MB_LIB.T6G(SCH_1):P12V_AUX
  A5 P12V_AUX  IN_A5 @T6G_MB_LIB.T6G(SCH_1):P12V_AUX
  B3 P12V_AUX  IN_B3 @T6G_MB_LIB.T6G(SCH_1):P12V_AUX
  B5 P12V_AUX  IN_B5 @T6G_MB_LIB.T6G(SCH_1):P12V_AUX
  C3 P12V_AUX  IN_C3 @T6G_MB_LIB.T6G(SCH_1):P12V_AUX
  C5 P12V_AUX  IN_C5 @T6G_MB_LIB.T6G(SCH_1):P12V_AUX
  D5 P12V_AUX  IN_D5 @T6G_MB_LIB.T6G(SCH_1):P12V_AUX
  B1 P12V_E1S_CB_0     CB @T6G_MB_LIB.T6G(SCH_1):P12V_E1S_CB_0
  B7    GND    EN# @T6G_MB_LIB.T6G(SCH_1):GND
  D1 P12V_E1S_REG_0    REG @T6G_MB_LIB.T6G(SCH_1):P12V_E1S_REG_0
  D2 P12V_E1S_UV_0     UV @T6G_MB_LIB.T6G(SCH_1):P12V_E1S_UV_0
  D3 P12V_E1S_OV_0     OV @T6G_MB_LIB.T6G(SCH_1):P12V_E1S_OV_0
  A1 P12V_E1S_SENSE_0 ISENSE @T6G_MB_LIB.T6G(SCH_1):P12V_E1S_SENSE_0
  A4 P12V_E1S_0 OUT_A4 @T6G_MB_LIB.T6G(SCH_1):P12V_E1S_0
  B4 P12V_E1S_0 OUT_B4 @T6G_MB_LIB.T6G(SCH_1):P12V_E1S_0
  B6 P12V_E1S_0 OUT_B6 @T6G_MB_LIB.T6G(SCH_1):P12V_E1S_0
  C4 P12V_E1S_0 OUT_C4 @T6G_MB_LIB.T6G(SCH_1):P12V_E1S_0
  C6 P12V_E1S_0 OUT_C6 @T6G_MB_LIB.T6G(SCH_1):P12V_E1S_0
  D4 P12V_E1S_0 OUT_D4 @T6G_MB_LIB.T6G(SCH_1):P12V_E1S_0
  D6 P12V_E1S_0 OUT_D6 @T6G_MB_LIB.T6G(SCH_1):P12V_E1S_0
  A6 P12V_E1S_GATE_0   GATE @T6G_MB_LIB.T6G(SCH_1):P12V_E1S_GATE_0
  A7    GND   CDLY @T6G_MB_LIB.T6G(SCH_1):GND
  B2    GND GND_B2 @T6G_MB_LIB.T6G(SCH_1):GND
  C1    GND GND_C1 @T6G_MB_LIB.T6G(SCH_1):GND
  C2    GND GND_C2 @T6G_MB_LIB.T6G(SCH_1):GND
  C7 P12V_E1S_FAULT_0 FAULT# @T6G_MB_LIB.T6G(SCH_1):P12V_E1S_FAULT_0
  D7 P12V_E1S_PWRGD_0     PG @T6G_MB_LIB.T6G(SCH_1):P12V_E1S_PWRGD_0

Q_RES_0402LF-2.67K,1%,1/16W,CHIP,CS22672FB03  I68  PR3970
   1 P12V_E1S_SENSE_0      A @T6G_MB_LIB.T6G(SCH_1):P12V_E1S_SENSE_0
   2    GND      B @T6G_MB_LIB.T6G(SCH_1):GND

Q_CAP_C0402-3900PF,50V,10%,X7R,CH23906KB14  I69  PC2215
   1 P12V_E1S_GATE_0      A @T6G_MB_LIB.T6G(SCH_1):P12V_E1S_GATE_0
   2    GND      B @T6G_MB_LIB.T6G(SCH_1):GND

Q_RES_0402LF-0,5%,1/16W,EMPTY,CS00002JB13  I70  R3974
   1 P12V_E1S_SENSE_0      A @T6G_MB_LIB.T6G(SCH_1):P12V_E1S_SENSE_0
   2 P12V_E1S_0_ISENSE_MAM_MAM      B @T6G_MB_LIB.T6G(SCH_1):P12V_E1S_0_ISENSE_MAM_MAM

Q_RES_0402LF-0,5%,1/16W,CHIP,CS00002JB13  I71  R3972
   1 P12V_E1S_PWRGD_0      A @T6G_MB_LIB.T6G(SCH_1):P12V_E1S_PWRGD_0
   2 HP_LVC3_E1S_0_HSC_PWRGD      B @T6G_MB_LIB.T6G(SCH_1):HP_LVC3_E1S_0_HSC_PWRGD

Q_CAP_C0402-0.01UF,50V,10%,EMPTY,CH31006KB18  I72  PC2214
   1 P12V_E1S_0      A @T6G_MB_LIB.T6G(SCH_1):P12V_E1S_0
   2 P12V_E1S_GATE_0      B @T6G_MB_LIB.T6G(SCH_1):P12V_E1S_GATE_0

SCHOTTKY_AC-B340A-13-F,SMLF,IC,BC000340Z30  I74  PD112
   A    GND      A @T6G_MB_LIB.T6G(SCH_1):GND
   C P12V_E1S_0      C @T6G_MB_LIB.T6G(SCH_1):P12V_E1S_0

Q_RES_0402LF-100K,1%,1/16W,CHIP,CS41002FB09  I76  R3976
   1 P3V3_AUX      A @T6G_MB_LIB.T6G(SCH_1):P3V3_AUX
   2 P12V_E1S_FAULT_0      B @T6G_MB_LIB.T6G(SCH_1):P12V_E1S_FAULT_0

Q_CAP_0402-0.1UF,25V,10%,X7R,CH4104K1B00  I78  PC2217
   1 P12V_E1S_0      A @T6G_MB_LIB.T6G(SCH_1):P12V_E1S_0
   2    GND      B @T6G_MB_LIB.T6G(SCH_1):GND

Q_CAP_C0805-10UF,16V,10%,X6S,CH6103KEA01  I80  PC2280
   1 P12V_E1S_0      A @T6G_MB_LIB.T6G(SCH_1):P12V_E1S_0
   2    GND      B @T6G_MB_LIB.T6G(SCH_1):GND

MOSFET_NCH_DUAL-PJT138K,SMLF,IC,BAM138K0003  I7  Q126
   3 P3V3_E1S_UV_0_R     D2 @T6G_MB_LIB.T6G(SCH_1):P3V3_E1S_UV_0_R
   5 P3V3_E1S_0_EN_G     G2 @T6G_MB_LIB.T6G(SCH_1):P3V3_E1S_0_EN_G
   4    GND     S2 @T6G_MB_LIB.T6G(SCH_1):GND

Q_RES_0402LF-10K,1%,1/16W,CHIP,CS31002FB08  I8  R4072
   1 P12V_AUX      A @T6G_MB_LIB.T6G(SCH_1):P12V_AUX
   2 P3V3_E1S_0_EN_G      B @T6G_MB_LIB.T6G(SCH_1):P3V3_E1S_0_EN_G

MOSFET_NCH_DUAL-PJT138K,SMLF,IC,BAM138K0003  I12  Q127
   1    GND     S1 @T6G_MB_LIB.T6G(SCH_1):GND
   2 P12V_E1S_EN_0_R     G1 @T6G_MB_LIB.T6G(SCH_1):P12V_E1S_EN_0_R
   6 P12V_E1S_0_EN_G     D1 @T6G_MB_LIB.T6G(SCH_1):P12V_E1S_0_EN_G

Q_RES_0402LF-0,5%,1/16W,CHIP,CS00002JB13  I18  R3959
   1 P3V3_E1S_UV_0_R      A @T6G_MB_LIB.T6G(SCH_1):P3V3_E1S_UV_0_R
   2 P3V3_E1S_UV_0      B @T6G_MB_LIB.T6G(SCH_1):P3V3_E1S_UV_0

Q_RES_0402LF-0,5%,1/16W,CHIP,CS00002JB13  I24  R4064
   1 E1S_0_P12V_EN      A @T6G_MB_LIB.T6G(SCH_1):E1S_0_P12V_EN
   2 P12V_E1S_EN_0_R      B @T6G_MB_LIB.T6G(SCH_1):P12V_E1S_EN_0_R

Q_RES_0402LF-6.8K,1%,1/16W,CHIP,CS26802FB02  I32  PR3961
   1 P12V_E1S_UV_0      A @T6G_MB_LIB.T6G(SCH_1):P12V_E1S_UV_0
   2 P12V_E1S_OV_0      B @T6G_MB_LIB.T6G(SCH_1):P12V_E1S_OV_0

Q_CAP_C0402-1UF,25V,10%,X6S,CH5104KEB02  I42  PC2212
   1    GND      A @T6G_MB_LIB.T6G(SCH_1):GND
   2 P3V3_E1S_REG_0      B @T6G_MB_LIB.T6G(SCH_1):P3V3_E1S_REG_0

Q_CAP_C0402-6800PF,50V,10%,X7R,CH2686K1B01  I49  PC2216
   1 P3V3_E1S_GATE_0      A @T6G_MB_LIB.T6G(SCH_1):P3V3_E1S_GATE_0
   2    GND      B @T6G_MB_LIB.T6G(SCH_1):GND

Q_RES_0402LF-100K,1%,1/16W,CHIP,CS41002FB09  I52  R3977
   1 P3V3_AUX      A @T6G_MB_LIB.T6G(SCH_1):P3V3_AUX
   2 P3V3_E1S_FAULT_0      B @T6G_MB_LIB.T6G(SCH_1):P3V3_E1S_FAULT_0

Q_CAP_0402-0.1UF,25V,10%,X7R,CH4104K1B00  I57  PC2218
   1 P3V3_E1S_0_R      A @T6G_MB_LIB.T6G(SCH_1):P3V3_E1S_0_R
   2    GND      B @T6G_MB_LIB.T6G(SCH_1):GND

Q_CAP_C0402-1UF,25V,10%,X6S,CH5104KEB02  I64  PC2209
   1 P12V_E1S_VCC_0      A @T6G_MB_LIB.T6G(SCH_1):P12V_E1S_VCC_0
   2    GND      B @T6G_MB_LIB.T6G(SCH_1):GND

Q_RES_0402LF-10M,1%,1/16W,CHIP,CS61002FB02  I73  PR4528
   1 P12V_E1S_0      A @T6G_MB_LIB.T6G(SCH_1):P12V_E1S_0
   2 P12V_E1S_GATE_0      B @T6G_MB_LIB.T6G(SCH_1):P12V_E1S_GATE_0

Q_CAP_C0805-10UF,16V,10%,X6S,CH6103KEA01  I79  PC2219
   1 P12V_E1S_0      A @T6G_MB_LIB.T6G(SCH_1):P12V_E1S_0
   2    GND      B @T6G_MB_LIB.T6G(SCH_1):GND

Q_RES_0402LF-100K,1%,1/16W,CHIP,CS41002FB09  I86  R3978
   1 P3V3_AUX      A @T6G_MB_LIB.T6G(SCH_1):P3V3_AUX
   2 HP_LVC3_E1S_0_HSC_PWRGD      B @T6G_MB_LIB.T6G(SCH_1):HP_LVC3_E1S_0_HSC_PWRGD

Q_RES_0402LF-0,5%,1/16W,CHIP,CS00002JB13  I87  R3975
   1 P12V_E1S_SENSE_0      A @T6G_MB_LIB.T6G(SCH_1):P12V_E1S_SENSE_0
   2 P12V_E1S_0_ISENSE_MAM_TIC      B @T6G_MB_LIB.T6G(SCH_1):P12V_E1S_0_ISENSE_MAM_TIC

MAX15090BEWIT-MAX15090BEWI+T,SMLF,IC,AL015080B00  I88  PU295
  A2 P3V3_E1S_VCC_0    VCC @T6G_MB_LIB.T6G(SCH_1):P3V3_E1S_VCC_0
  A3 P3V3_AUX  IN_A3 @T6G_MB_LIB.T6G(SCH_1):P3V3_AUX
  A5 P3V3_AUX  IN_A5 @T6G_MB_LIB.T6G(SCH_1):P3V3_AUX
  B3 P3V3_AUX  IN_B3 @T6G_MB_LIB.T6G(SCH_1):P3V3_AUX
  B5 P3V3_AUX  IN_B5 @T6G_MB_LIB.T6G(SCH_1):P3V3_AUX
  C3 P3V3_AUX  IN_C3 @T6G_MB_LIB.T6G(SCH_1):P3V3_AUX
  C5 P3V3_AUX  IN_C5 @T6G_MB_LIB.T6G(SCH_1):P3V3_AUX
  D5 P3V3_AUX  IN_D5 @T6G_MB_LIB.T6G(SCH_1):P3V3_AUX
  B1 P3V3_E1S_CB_0     CB @T6G_MB_LIB.T6G(SCH_1):P3V3_E1S_CB_0
  B7    GND    EN# @T6G_MB_LIB.T6G(SCH_1):GND
  D1 P3V3_E1S_REG_0    REG @T6G_MB_LIB.T6G(SCH_1):P3V3_E1S_REG_0
  D2 P3V3_E1S_UV_0     UV @T6G_MB_LIB.T6G(SCH_1):P3V3_E1S_UV_0
  D3 P3V3_E1S_OV_0     OV @T6G_MB_LIB.T6G(SCH_1):P3V3_E1S_OV_0
  A1 P3V3_E1S_SENSE_0 ISENSE @T6G_MB_LIB.T6G(SCH_1):P3V3_E1S_SENSE_0
  A4 P3V3_E1S_0_R OUT_A4 @T6G_MB_LIB.T6G(SCH_1):P3V3_E1S_0_R
  B4 P3V3_E1S_0_R OUT_B4 @T6G_MB_LIB.T6G(SCH_1):P3V3_E1S_0_R
  B6 P3V3_E1S_0_R OUT_B6 @T6G_MB_LIB.T6G(SCH_1):P3V3_E1S_0_R
  C4 P3V3_E1S_0_R OUT_C4 @T6G_MB_LIB.T6G(SCH_1):P3V3_E1S_0_R
  C6 P3V3_E1S_0_R OUT_C6 @T6G_MB_LIB.T6G(SCH_1):P3V3_E1S_0_R
  D4 P3V3_E1S_0_R OUT_D4 @T6G_MB_LIB.T6G(SCH_1):P3V3_E1S_0_R
  D6 P3V3_E1S_0_R OUT_D6 @T6G_MB_LIB.T6G(SCH_1):P3V3_E1S_0_R
  A6 P3V3_E1S_GATE_0   GATE @T6G_MB_LIB.T6G(SCH_1):P3V3_E1S_GATE_0
  A7    GND   CDLY @T6G_MB_LIB.T6G(SCH_1):GND
  B2    GND GND_B2 @T6G_MB_LIB.T6G(SCH_1):GND
  C1    GND GND_C1 @T6G_MB_LIB.T6G(SCH_1):GND
  C2    GND GND_C2 @T6G_MB_LIB.T6G(SCH_1):GND
  C7 P3V3_E1S_FAULT_0 FAULT# @T6G_MB_LIB.T6G(SCH_1):P3V3_E1S_FAULT_0
  D7 P3V3_E1S_PWRGD_0     PG @T6G_MB_LIB.T6G(SCH_1):P3V3_E1S_PWRGD_0


DRAWING: @T6G_MB_LIB.T6G(SCH_1):PAGE345 

SCONN75K_APCI0155P004A-SCONN75K_APCI0155-P004A,SMLA  I88  J59
   2 P3V3_M2_0 3.3V_1 @T6G_MB_LIB.T6G(SCH_1):P3V3_M2_0
   4 P3V3_M2_0 3.3V_2 @T6G_MB_LIB.T6G(SCH_1):P3V3_M2_0
  10 LED_M2_SSD_0_ACT_N DAS_DSS#||LED1# @T6G_MB_LIB.T6G(SCH_1):LED_M2_SSD_0_ACT_N
  12 P3V3_M2_0 3.3V_3 @T6G_MB_LIB.T6G(SCH_1):P3V3_M2_0
  14 P3V3_M2_0 3.3V_4 @T6G_MB_LIB.T6G(SCH_1):P3V3_M2_0
  16 P3V3_M2_0 3.3V_5 @T6G_MB_LIB.T6G(SCH_1):P3V3_M2_0
  18 P3V3_M2_0 3.3V_6 @T6G_MB_LIB.T6G(SCH_1):P3V3_M2_0
  38 PD_M2_0_DEVSLP DEVSLP @T6G_MB_LIB.T6G(SCH_1):PD_M2_0_DEVSLP
  50 RST_PERST_BUF_M2_0_R_N PERST# @T6G_MB_LIB.T6G(SCH_1):RST_PERST_BUF_M2_0_R_N
  52 M2_SSD0_CLKREQ_EN_N_BUF CLKREQ# @T6G_MB_LIB.T6G(SCH_1):M2_SSD0_CLKREQ_EN_N_BUF
  54 M2_0_PEWAKE_N PEWAKE# @T6G_MB_LIB.T6G(SCH_1):M2_0_PEWAKE_N
  58 NC_M2_0_NC18   NC18 @T6G_MB_LIB.T6G(SCH_1):NC_M2_0_NC18
  68 NC_M2_0_SUSCLK SUSCLK @T6G_MB_LIB.T6G(SCH_1):NC_M2_0_SUSCLK
  70 P3V3_M2_0 3.3V_7 @T6G_MB_LIB.T6G(SCH_1):P3V3_M2_0
  72 P3V3_M2_0 3.3V_8 @T6G_MB_LIB.T6G(SCH_1):P3V3_M2_0
  74 P3V3_M2_0 3.3V_9 @T6G_MB_LIB.T6G(SCH_1):P3V3_M2_0
  41 P3E_CPU1_P4_RX_DN<0> PERN0||SATA-B+ @T6G_MB_LIB.T6G(SCH_1):P3E_CPU1_P4_RX_DN(0)
  43 P3E_CPU1_P4_RX_DP<0> PERP0||SATA-B- @T6G_MB_LIB.T6G(SCH_1):P3E_CPU1_P4_RX_DP(0)
  47 P3E_CPU1_P4_TX_C_DN<0> PETN0||SATA-A- @T6G_MB_LIB.T6G(SCH_1):P3E_CPU1_P4_TX_C_DN(0)
  49 P3E_CPU1_P4_TX_C_DP<0> PETP0||SATA-A+ @T6G_MB_LIB.T6G(SCH_1):P3E_CPU1_P4_TX_C_DP(0)
  57    GND  GND11 @T6G_MB_LIB.T6G(SCH_1):GND
  67 NC_M2_0_NC19   NC19 @T6G_MB_LIB.T6G(SCH_1):NC_M2_0_NC19
  69 FM_M2_SSD_0_PEDET  PEDET @T6G_MB_LIB.T6G(SCH_1):FM_M2_SSD_0_PEDET
  71    GND  GND12 @T6G_MB_LIB.T6G(SCH_1):GND
  73    GND  GND13 @T6G_MB_LIB.T6G(SCH_1):GND
  75    GND  GND14 @T6G_MB_LIB.T6G(SCH_1):GND
  G1    GND     G1 @T6G_MB_LIB.T6G(SCH_1):GND
  G2    GND     G2 @T6G_MB_LIB.T6G(SCH_1):GND
   6 NC_M2_0_NC1    NC1 @T6G_MB_LIB.T6G(SCH_1):NC_M2_0_NC1
   8 NC_M2_0_NC2    NC2 @T6G_MB_LIB.T6G(SCH_1):NC_M2_0_NC2
  20 NC_M2_0_NC3    NC3 @T6G_MB_LIB.T6G(SCH_1):NC_M2_0_NC3
  34 NC_M2_0_NC10   NC10 @T6G_MB_LIB.T6G(SCH_1):NC_M2_0_NC10
  56 NC_M2_0_NC17   NC17 @T6G_MB_LIB.T6G(SCH_1):NC_M2_0_NC17
  48 NC_M2_0_NC16   NC16 @T6G_MB_LIB.T6G(SCH_1):NC_M2_0_NC16
  46 NC_M2_0_NC15   NC15 @T6G_MB_LIB.T6G(SCH_1):NC_M2_0_NC15
  44 NC_M2_0_NC14   NC14 @T6G_MB_LIB.T6G(SCH_1):NC_M2_0_NC14
  42 SMB_M2_P1_1V8AUX_SDA   NC13 @T6G_MB_LIB.T6G(SCH_1):SMB_M2_P1_1V8AUX_SDA
  40 SMB_M2_P1_1V8AUX_SCL   NC12 @T6G_MB_LIB.T6G(SCH_1):SMB_M2_P1_1V8AUX_SCL
  36 NC_M2_0_NC11   NC11 @T6G_MB_LIB.T6G(SCH_1):NC_M2_0_NC11
  32 NC_M2_0_NC9    NC9 @T6G_MB_LIB.T6G(SCH_1):NC_M2_0_NC9
  30 NC_M2_0_NC8    NC8 @T6G_MB_LIB.T6G(SCH_1):NC_M2_0_NC8
  28 NC_M2_0_NC7    NC7 @T6G_MB_LIB.T6G(SCH_1):NC_M2_0_NC7
  26 NC_M2_0_NC6    NC6 @T6G_MB_LIB.T6G(SCH_1):NC_M2_0_NC6
  24 NC_M2_0_NC5    NC5 @T6G_MB_LIB.T6G(SCH_1):NC_M2_0_NC5
  22 NC_M2_0_NC4    NC4 @T6G_MB_LIB.T6G(SCH_1):NC_M2_0_NC4
   1 PCIE_M2_SSD0_PRSNT_N   GND1 @T6G_MB_LIB.T6G(SCH_1):PCIE_M2_SSD0_PRSNT_N
   3    GND   GND2 @T6G_MB_LIB.T6G(SCH_1):GND
   9    GND   GND3 @T6G_MB_LIB.T6G(SCH_1):GND
  15    GND   GND4 @T6G_MB_LIB.T6G(SCH_1):GND
  21    GND   GND5 @T6G_MB_LIB.T6G(SCH_1):GND
  27    GND   GND6 @T6G_MB_LIB.T6G(SCH_1):GND
  33    GND   GND7 @T6G_MB_LIB.T6G(SCH_1):GND
  39    GND   GND8 @T6G_MB_LIB.T6G(SCH_1):GND
  45    GND   GND9 @T6G_MB_LIB.T6G(SCH_1):GND
  51    GND  GND10 @T6G_MB_LIB.T6G(SCH_1):GND
   5 P3E_CPU1_P4_RX_DN<3>  PERN3 @T6G_MB_LIB.T6G(SCH_1):P3E_CPU1_P4_RX_DN(3)
   7 P3E_CPU1_P4_RX_DP<3>  PERP3 @T6G_MB_LIB.T6G(SCH_1):P3E_CPU1_P4_RX_DP(3)
  11 P3E_CPU1_P4_TX_C_DN<3>  PETN3 @T6G_MB_LIB.T6G(SCH_1):P3E_CPU1_P4_TX_C_DN(3)
  13 P3E_CPU1_P4_TX_C_DP<3>  PETP3 @T6G_MB_LIB.T6G(SCH_1):P3E_CPU1_P4_TX_C_DP(3)
  17 P3E_CPU1_P4_RX_DN<2>  PERN2 @T6G_MB_LIB.T6G(SCH_1):P3E_CPU1_P4_RX_DN(2)
  19 P3E_CPU1_P4_RX_DP<2>  PERP2 @T6G_MB_LIB.T6G(SCH_1):P3E_CPU1_P4_RX_DP(2)
  23 P3E_CPU1_P4_TX_C_DN<2>  PETN2 @T6G_MB_LIB.T6G(SCH_1):P3E_CPU1_P4_TX_C_DN(2)
  25 P3E_CPU1_P4_TX_C_DP<2>  PETP2 @T6G_MB_LIB.T6G(SCH_1):P3E_CPU1_P4_TX_C_DP(2)
  29 P3E_CPU1_P4_RX_DN<1>  PERN1 @T6G_MB_LIB.T6G(SCH_1):P3E_CPU1_P4_RX_DN(1)
  31 P3E_CPU1_P4_RX_DP<1>  PERP1 @T6G_MB_LIB.T6G(SCH_1):P3E_CPU1_P4_RX_DP(1)
  35 P3E_CPU1_P4_TX_C_DN<1>  PETN1 @T6G_MB_LIB.T6G(SCH_1):P3E_CPU1_P4_TX_C_DN(1)
  37 P3E_CPU1_P4_TX_C_DP<1>  PETP1 @T6G_MB_LIB.T6G(SCH_1):P3E_CPU1_P4_TX_C_DP(1)
  53 CLK_100M_CPU1_CLK12_DN REFCLKN @T6G_MB_LIB.T6G(SCH_1):CLK_100M_CPU1_CLK12_DN
  55 CLK_100M_CPU1_CLK12_DP REFCLKP @T6G_MB_LIB.T6G(SCH_1):CLK_100M_CPU1_CLK12_DP

SN74LVC2G07DCKR_SMLF-SN74LVC2G07DCKR,IC,AL002G07006  I5  U259
   1 M2_SSD0_CLKREQ_EN_N     1A @T6G_MB_LIB.T6G(SCH_1):M2_SSD0_CLKREQ_EN_N
   3 RST_PERST_M2_0_N     2A @T6G_MB_LIB.T6G(SCH_1):RST_PERST_M2_0_N
   6 HDD_ACTIVITY_BUF     1Y @T6G_MB_LIB.T6G(SCH_1):HDD_ACTIVITY_BUF
   4 RST_PERST_BUF_M2_0_N     2Y @T6G_MB_LIB.T6G(SCH_1):RST_PERST_BUF_M2_0_N
   2    GND    GND @T6G_MB_LIB.T6G(SCH_1):GND
   5 P3V3_AUX    VCC @T6G_MB_LIB.T6G(SCH_1):P3V3_AUX

Q_CAP_C0402-1UF,25V,10%,X6S,CH5104KEB02  I6  C2007
   1 P3V3_AUX      A @T6G_MB_LIB.T6G(SCH_1):P3V3_AUX
   2    GND      B @T6G_MB_LIB.T6G(SCH_1):GND

MOSFET_NCH_DUAL-PJT138K,SMLF,IC,BAM138K0003  I8  Q95
   1    GND     S1 @T6G_MB_LIB.T6G(SCH_1):GND
   2 HDD_ACTIVITY_BUF     G1 @T6G_MB_LIB.T6G(SCH_1):HDD_ACTIVITY_BUF
   6 HDD_ACTIVITY_BUF_N     D1 @T6G_MB_LIB.T6G(SCH_1):HDD_ACTIVITY_BUF_N

Q_RES_0402LF-4.7K,5%,1/16W,CHIP,CS24702JB10  I10  R2121
   1 P3V3_AUX      A @T6G_MB_LIB.T6G(SCH_1):P3V3_AUX
   2 RST_PERST_BUF_M2_0_N      B @T6G_MB_LIB.T6G(SCH_1):RST_PERST_BUF_M2_0_N

Q_RES_0402LF-0,5%,1/16W,CHIP,CS00002JB13  I12  R2113
   1 RST_PERST_BUF_M2_0_N      A @T6G_MB_LIB.T6G(SCH_1):RST_PERST_BUF_M2_0_N
   2 RST_PERST_BUF_M2_0_R_N      B @T6G_MB_LIB.T6G(SCH_1):RST_PERST_BUF_M2_0_R_N

Q_RES_0402LF-4.7K,1%,1/16W,EMPTY,CS24702FB06  I15  R138
   1 M2_SSD0_CLKREQ_EN_N      A @T6G_MB_LIB.T6G(SCH_1):M2_SSD0_CLKREQ_EN_N
   2    GND      B @T6G_MB_LIB.T6G(SCH_1):GND

Q_RES_0402LF-0,5%,1/16W,CHIP,CS00002JB13  I19  R3294
   1 LED_M2_SSD_0_ACT_N      A @T6G_MB_LIB.T6G(SCH_1):LED_M2_SSD_0_ACT_N
   2 LED_HDD_ACTIVITY_N      B @T6G_MB_LIB.T6G(SCH_1):LED_HDD_ACTIVITY_N

Q_RES_0402LF-4.7K,1%,1/16W,CHIP,CS24702FB06  I21  R3295
   1 P3V3_M2_0      A @T6G_MB_LIB.T6G(SCH_1):P3V3_M2_0
   2 LED_HDD_ACTIVITY_N      B @T6G_MB_LIB.T6G(SCH_1):LED_HDD_ACTIVITY_N

Q_RES_0402LF-1K,1%,1/16W,CHIP,CS21002FB06  I24  R178
   1 P3V3_AUX      A @T6G_MB_LIB.T6G(SCH_1):P3V3_AUX
   2 PCIE_M2_SSD0_PRSNT_N      B @T6G_MB_LIB.T6G(SCH_1):PCIE_M2_SSD0_PRSNT_N

Q_RES_0402LF-0,5%,1/16W,CHIP,CS00002JB13  I27  R153
   1 M2_SSD0_CLKREQ_EN_N      A @T6G_MB_LIB.T6G(SCH_1):M2_SSD0_CLKREQ_EN_N
   2 M2_SSD0_CLKREQ_EN_N_BUF      B @T6G_MB_LIB.T6G(SCH_1):M2_SSD0_CLKREQ_EN_N_BUF

Q_RES_0402LF-33.2,1%,1/16W,CHIP,CS03322FB03  I30  R3301
   1 M2_0_PEWAKE_R_N      A @T6G_MB_LIB.T6G(SCH_1):M2_0_PEWAKE_R_N
   2 M2_0_PEWAKE_N      B @T6G_MB_LIB.T6G(SCH_1):M2_0_PEWAKE_N

Q_RES_0402LF-1K,1%,1/16W,EMPTY,CS21002FB06  I32  R155
   1 P3V3_AUX      A @T6G_MB_LIB.T6G(SCH_1):P3V3_AUX
   2 M2_SSD0_CLKREQ_EN_N_BUF      B @T6G_MB_LIB.T6G(SCH_1):M2_SSD0_CLKREQ_EN_N_BUF

Q_RES_0402LF-4.7K,1%,1/16W,CHIP,CS24702FB06  I51  R3296
   1 P3V3_AUX      A @T6G_MB_LIB.T6G(SCH_1):P3V3_AUX
   2 HDD_ACTIVITY_BUF      B @T6G_MB_LIB.T6G(SCH_1):HDD_ACTIVITY_BUF

74LVC1G126SE7-74LVC1G126SE-7,SMLF,IC,AL1G0126009  I53  U239
   2 LED_HDD_ACTIVITY_N      A @T6G_MB_LIB.T6G(SCH_1):LED_HDD_ACTIVITY_N
   4 LED_HDD_ACTIVITY_B_N      Y @T6G_MB_LIB.T6G(SCH_1):LED_HDD_ACTIVITY_B_N
   5 P3V3_AUX    VCC @T6G_MB_LIB.T6G(SCH_1):P3V3_AUX
   3    GND    GND @T6G_MB_LIB.T6G(SCH_1):GND
   1 PU_BUFFER_HDD_ACTIVITY     OE @T6G_MB_LIB.T6G(SCH_1):PU_BUFFER_HDD_ACTIVITY

Q_CAP_0402-0.1UF,25V,10%,X7R,CH4104K1B00  I56  C1873
   1 P3V3_AUX      A @T6G_MB_LIB.T6G(SCH_1):P3V3_AUX
   2    GND      B @T6G_MB_LIB.T6G(SCH_1):GND

Q_RES_0402LF-10K,1%,1/16W,CHIP,CS31002FB08  I58  R3298
   1 P3V3_AUX      A @T6G_MB_LIB.T6G(SCH_1):P3V3_AUX
   2 HDD_ACTIVITY_BUF_N      B @T6G_MB_LIB.T6G(SCH_1):HDD_ACTIVITY_BUF_N

Q_RES_0402LF-10K,1%,1/16W,CHIP,CS31002FB08  I60  R3297
   1 LED_HDD_ACTIVITY_B_N      A @T6G_MB_LIB.T6G(SCH_1):LED_HDD_ACTIVITY_B_N
   2    GND      B @T6G_MB_LIB.T6G(SCH_1):GND

Q_RES_0402LF-0,5%,1/16W,CHIP,CS00002JB13  I62  R5377
   1 HDD_ACTIVITY_BUF_N      A @T6G_MB_LIB.T6G(SCH_1):HDD_ACTIVITY_BUF_N
   2 PU_BUFFER_HDD_ACTIVITY      B @T6G_MB_LIB.T6G(SCH_1):PU_BUFFER_HDD_ACTIVITY

Q_RES_0402LF-10K,1%,1/16W,CHIP,CS31002FB08  I66  R1396
   1 FM_M2_SSD_0_PEDET      A @T6G_MB_LIB.T6G(SCH_1):FM_M2_SSD_0_PEDET
   2 P3V3_AUX      B @T6G_MB_LIB.T6G(SCH_1):P3V3_AUX

Q_CAP_C0603-22UF,6.3V,20%,X6S,CH6221ME900  I77  C1920
   1 P3V3_M2_0      A @T6G_MB_LIB.T6G(SCH_1):P3V3_M2_0
   2    GND      B @T6G_MB_LIB.T6G(SCH_1):GND

Q_CAP_C0603-22UF,6.3V,20%,X6S,CH6221ME900  I78  C1921
   1 P3V3_M2_0      A @T6G_MB_LIB.T6G(SCH_1):P3V3_M2_0
   2    GND      B @T6G_MB_LIB.T6G(SCH_1):GND

Q_CAP_C0603-22UF,6.3V,20%,X6S,CH6221ME900  I79  C9922
   1 P3V3_M2_0      A @T6G_MB_LIB.T6G(SCH_1):P3V3_M2_0
   2    GND      B @T6G_MB_LIB.T6G(SCH_1):GND

Q_RES_0402LF-1K,1%,1/16W,CHIP,CS21002FB06  I83  R1605
   1 PD_M2_0_DEVSLP      A @T6G_MB_LIB.T6G(SCH_1):PD_M2_0_DEVSLP
   2    GND      B @T6G_MB_LIB.T6G(SCH_1):GND

Q_CAP_0402-0.1UF,25V,10%,X7R,CH4104K1B00  I84  C1923
   1 P3V3_M2_0      A @T6G_MB_LIB.T6G(SCH_1):P3V3_M2_0
   2    GND      B @T6G_MB_LIB.T6G(SCH_1):GND

Q_CAP_0402-0.1UF,25V,10%,X7R,CH4104K1B00  I85  C1924
   1 P3V3_M2_0      A @T6G_MB_LIB.T6G(SCH_1):P3V3_M2_0
   2    GND      B @T6G_MB_LIB.T6G(SCH_1):GND

Q_CAP_0402-0.1UF,25V,10%,X7R,CH4104K1B00  I86  C1925
   1 P3V3_M2_0      A @T6G_MB_LIB.T6G(SCH_1):P3V3_M2_0
   2    GND      B @T6G_MB_LIB.T6G(SCH_1):GND

MOSFET_NCH_DUAL-PJT138K,SMLF,IC,BAM138K0003  I89  Q95
   3 NC_Q95_D2     D2 @T6G_MB_LIB.T6G(SCH_1):NC_Q95_D2
   5 NC_Q95_G2     G2 @T6G_MB_LIB.T6G(SCH_1):NC_Q95_G2
   4 NC_Q95_S2     S2 @T6G_MB_LIB.T6G(SCH_1):NC_Q95_S2


DRAWING: @T6G_MB_LIB.T6G(SCH_1):PAGE346 

PCA9306DP1-PCA9306DP1,SMLF,IC,AL009306K04  I27  U98
   2 P1V8_AUX  VREF1 @T6G_MB_LIB.T6G(SCH_1):P1V8_AUX
   3 SMB_M2_P1_1V8AUX_SCL_R   SCL1 @T6G_MB_LIB.T6G(SCH_1):SMB_M2_P1_1V8AUX_SCL_R
   4 SMB_M2_P1_1V8AUX_SDA_R   SDA1 @T6G_MB_LIB.T6G(SCH_1):SMB_M2_P1_1V8AUX_SDA_R
   5 SMB_SENSOR_M2_P1_3V3AUX_SDA   SDA2 @T6G_MB_LIB.T6G(SCH_1):SMB_SENSOR_M2_P1_3V3AUX_SDA
   6 SMB_SENSOR_M2_P1_3V3AUX_SCL   SCL2 @T6G_MB_LIB.T6G(SCH_1):SMB_SENSOR_M2_P1_3V3AUX_SCL
   7 SMB_PCIE_M2_0_EN  VREF2 @T6G_MB_LIB.T6G(SCH_1):SMB_PCIE_M2_0_EN
   8 SMB_PCIE_M2_0_EN     EN @T6G_MB_LIB.T6G(SCH_1):SMB_PCIE_M2_0_EN
   1    GND    GND @T6G_MB_LIB.T6G(SCH_1):GND

Q_CAP_0402-0.1UF,25V,10%,X7R,CH4104K1B00  I28  C1323
   1 P1V8_AUX      A @T6G_MB_LIB.T6G(SCH_1):P1V8_AUX
   2    GND      B @T6G_MB_LIB.T6G(SCH_1):GND

Q_RES_0402LF-4.7K,5%,1/16W,CHIP,CS24702JB10  I43  R1702
   1 P1V8_AUX      A @T6G_MB_LIB.T6G(SCH_1):P1V8_AUX
   2 SMB_M2_P1_1V8AUX_SDA_R      B @T6G_MB_LIB.T6G(SCH_1):SMB_M2_P1_1V8AUX_SDA_R

Q_RES_0402LF-4.7K,5%,1/16W,CHIP,CS24702JB10  I45  R1703
   1 P1V8_AUX      A @T6G_MB_LIB.T6G(SCH_1):P1V8_AUX
   2 SMB_M2_P1_1V8AUX_SCL_R      B @T6G_MB_LIB.T6G(SCH_1):SMB_M2_P1_1V8AUX_SCL_R

Q_CAP_0402-0.1UF,25V,10%,X7R,CH4104K1B00  I52  C1305
   1 P3V3_AUX      A @T6G_MB_LIB.T6G(SCH_1):P3V3_AUX
   2    GND      B @T6G_MB_LIB.T6G(SCH_1):GND

Q_RES_0402LF-33.2,1%,1/16W,CHIP,CS03322FB03  I65  R2410
   1 SMB_M2_P1_1V8AUX_SDA_R      A @T6G_MB_LIB.T6G(SCH_1):SMB_M2_P1_1V8AUX_SDA_R
   2 SMB_M2_P1_1V8AUX_SDA      B @T6G_MB_LIB.T6G(SCH_1):SMB_M2_P1_1V8AUX_SDA

Q_RES_0402LF-33.2,1%,1/16W,CHIP,CS03322FB03  I66  R2411
   1 SMB_M2_P1_1V8AUX_SCL_R      A @T6G_MB_LIB.T6G(SCH_1):SMB_M2_P1_1V8AUX_SCL_R
   2 SMB_M2_P1_1V8AUX_SCL      B @T6G_MB_LIB.T6G(SCH_1):SMB_M2_P1_1V8AUX_SCL

Q_RES_0402LF-200K,1%,1/16W,EMPTY,CS42002FB05  I70  R2476
   1 SMB_PCIE_M2_0_EN      A @T6G_MB_LIB.T6G(SCH_1):SMB_PCIE_M2_0_EN
   2 PWRGD_P1V8_AUX_R      B @T6G_MB_LIB.T6G(SCH_1):PWRGD_P1V8_AUX_R

Q_RES_0402LF-200K,1%,1/16W,CHIP,CS42002FB05  I72  R1700
   1 P3V3_AUX      A @T6G_MB_LIB.T6G(SCH_1):P3V3_AUX
   2 SMB_PCIE_M2_0_EN      B @T6G_MB_LIB.T6G(SCH_1):SMB_PCIE_M2_0_EN

Q_RES_0402LF-33.2,1%,1/16W,CHIP,CS03322FB03  I76  R3533
   1 SMB_E1S_3V3AUX_ISO_SCL_R      A @T6G_MB_LIB.T6G(SCH_1):SMB_E1S_3V3AUX_ISO_SCL_R
   2 SMB_E1S_3V3AUX_ISO_SCL      B @T6G_MB_LIB.T6G(SCH_1):SMB_E1S_3V3AUX_ISO_SCL

Q_RES_0402LF-33.2,1%,1/16W,CHIP,CS03322FB03  I77  R3534
   1 SMB_E1S_3V3AUX_ISO_SDA_R      A @T6G_MB_LIB.T6G(SCH_1):SMB_E1S_3V3AUX_ISO_SDA_R
   2 SMB_E1S_3V3AUX_ISO_SDA      B @T6G_MB_LIB.T6G(SCH_1):SMB_E1S_3V3AUX_ISO_SDA

Q_RES_0402LF-4.7K,5%,1/16W,CHIP,CS24702JB10  I78  R3532
   1 P3V3_E1S_0      A @T6G_MB_LIB.T6G(SCH_1):P3V3_E1S_0
   2 SMB_E1S_3V3AUX_ISO_SDA_R      B @T6G_MB_LIB.T6G(SCH_1):SMB_E1S_3V3AUX_ISO_SDA_R

Q_RES_0402LF-4.7K,5%,1/16W,CHIP,CS24702JB10  I80  R3530
   1 P3V3_E1S_0      A @T6G_MB_LIB.T6G(SCH_1):P3V3_E1S_0
   2 SMB_E1S_3V3AUX_ISO_SCL_R      B @T6G_MB_LIB.T6G(SCH_1):SMB_E1S_3V3AUX_ISO_SCL_R

Q_CAP_0402-0.1UF,25V,10%,X7R,CH4104K1B00  I82  C1998
   1 P3V3_E1S_0      A @T6G_MB_LIB.T6G(SCH_1):P3V3_E1S_0
   2    GND      B @T6G_MB_LIB.T6G(SCH_1):GND

Q_CAP_0402-0.1UF,25V,10%,X7R,CH4104K1B00  I89  C1997
   1 P3V3_AUX      A @T6G_MB_LIB.T6G(SCH_1):P3V3_AUX
   2    GND      B @T6G_MB_LIB.T6G(SCH_1):GND

PCA9617ADP-PCA9617ADP,SMLF,IC,AL009617K02  I93  U279
   5 SMB_PCIE_E1S_ISO_EN_R     EN @T6G_MB_LIB.T6G(SCH_1):SMB_PCIE_E1S_ISO_EN_R
   1 P3V3_E1S_0   VCCA @T6G_MB_LIB.T6G(SCH_1):P3V3_E1S_0
   8 P3V3_AUX   VCCB @T6G_MB_LIB.T6G(SCH_1):P3V3_AUX
   2 SMB_E1S_3V3AUX_ISO_SCL_R   SCLA @T6G_MB_LIB.T6G(SCH_1):SMB_E1S_3V3AUX_ISO_SCL_R
   3 SMB_E1S_3V3AUX_ISO_SDA_R   SDAA @T6G_MB_LIB.T6G(SCH_1):SMB_E1S_3V3AUX_ISO_SDA_R
   6 SMB_SENSOR_E1S_3V3AUX_SDA   SDAB @T6G_MB_LIB.T6G(SCH_1):SMB_SENSOR_E1S_3V3AUX_SDA
   7 SMB_SENSOR_E1S_3V3AUX_SCL   SCLB @T6G_MB_LIB.T6G(SCH_1):SMB_SENSOR_E1S_3V3AUX_SCL
   4    GND    GND @T6G_MB_LIB.T6G(SCH_1):GND

Q_RES_0402LF-200K,1%,1/16W,EMPTY,CS42002FB05  I96  R3531
   1 SMB_PCIE_E1S_ISO_EN      A @T6G_MB_LIB.T6G(SCH_1):SMB_PCIE_E1S_ISO_EN
   2 SMB_PCIE_E1S_ISO_EN_R      B @T6G_MB_LIB.T6G(SCH_1):SMB_PCIE_E1S_ISO_EN_R

Q_RES_0402LF-10K,1%,1/16W,CHIP,CS31002FB08  I99  R3529
   1 P3V3_AUX      A @T6G_MB_LIB.T6G(SCH_1):P3V3_AUX
   2 SMB_PCIE_E1S_ISO_EN_R      B @T6G_MB_LIB.T6G(SCH_1):SMB_PCIE_E1S_ISO_EN_R


DRAWING: @T6G_MB_LIB.T6G(SCH_1):PAGE350 

Q_RES_0402LF-1K,1%,1/16W,CHIP,CS21002FB06  I2  R1854
   1 P3V3_AUX      A @T6G_MB_LIB.T6G(SCH_1):P3V3_AUX
   2 FM_SCM_PRSNT1_N      B @T6G_MB_LIB.T6G(SCH_1):FM_SCM_PRSNT1_N

Q_RES_0402LF-100,1%,1/16W,CHIP,CS11002FB07  I3  R1856
   1 FM_SCM_PRSNT1_N      A @T6G_MB_LIB.T6G(SCH_1):FM_SCM_PRSNT1_N
   2 FM_SCM_PRSNT1_R_N      B @T6G_MB_LIB.T6G(SCH_1):FM_SCM_PRSNT1_R_N

Q_CAP_0402-0.22UF,16V,10%,X7R,CH4223K1B00  I8  PC2229
   1 P12V_SCM_TIMER      A @T6G_MB_LIB.T6G(SCH_1):P12V_SCM_TIMER
   2    GND      B @T6G_MB_LIB.T6G(SCH_1):GND

Q_RES_0402LF-24.3K,1%,1/16W,CHIP,CS32432FB03  I11  PR3999
   1 P12V_SCM_ISET      A @T6G_MB_LIB.T6G(SCH_1):P12V_SCM_ISET
   2    GND      B @T6G_MB_LIB.T6G(SCH_1):GND

Q_RES_0402LF-20K,1%,1/16W,CHIP,CS32002FB06  I12  PR4540
   1 P12V_SCM_ISET      A @T6G_MB_LIB.T6G(SCH_1):P12V_SCM_ISET
   2 P12V_SCM_ISET_R      B @T6G_MB_LIB.T6G(SCH_1):P12V_SCM_ISET_R

Q_RES_0402LF-0,5%,1/16W,CHIP,CS00002JB13  I14  R3998
   1 P12V_SCM_EN      A @T6G_MB_LIB.T6G(SCH_1):P12V_SCM_EN
   2 P12V_SCM_EN_R2      B @T6G_MB_LIB.T6G(SCH_1):P12V_SCM_EN_R2

Q_RES_0402LF-0,5%,1/16W,CHIP,CS00002JB13  I17  R3996
   1 VIRTUAL_RESEAT_FPGA_N      A @T6G_MB_LIB.T6G(SCH_1):VIRTUAL_RESEAT_FPGA_N
   2 P12V_SCM_EN      B @T6G_MB_LIB.T6G(SCH_1):P12V_SCM_EN

Q_RES_0402LF-10K,1%,1/16W,CHIP,CS31002FB08  I18  R1857
   1 P3V3_AUX      A @T6G_MB_LIB.T6G(SCH_1):P3V3_AUX
   2 P12V_SCM_EN      B @T6G_MB_LIB.T6G(SCH_1):P12V_SCM_EN

Q_RES_0402LF-0,5%,1/16W,CHIP,CS00002JB13  I20  R4062
   1 P12V_SCM_EN      A @T6G_MB_LIB.T6G(SCH_1):P12V_SCM_EN
   2 P12V_SCM_EN_R      B @T6G_MB_LIB.T6G(SCH_1):P12V_SCM_EN_R

Q_RES_0402LF-10K,1%,1/16W,CHIP,CS31002FB08  I25  R4071
   1 P12V_AUX      A @T6G_MB_LIB.T6G(SCH_1):P12V_AUX
   2 P12V_SCM_EN_G      B @T6G_MB_LIB.T6G(SCH_1):P12V_SCM_EN_G

Q_RES_0402LF-0,5%,1/16W,CHIP,CS00002JB13  I27  R3997
   1 P12V_SCM_UV_R      A @T6G_MB_LIB.T6G(SCH_1):P12V_SCM_UV_R
   2 P12V_SCM_UV      B @T6G_MB_LIB.T6G(SCH_1):P12V_SCM_UV

Q_CAP_C0402-1UF,25V,10%,X6S,CH5104KEB02  I31  PC2230
   1 P12V_AUX      A @T6G_MB_LIB.T6G(SCH_1):P12V_AUX
   2    GND      B @T6G_MB_LIB.T6G(SCH_1):GND

Q_CAP_C0402-0.047UF,25V,10%,X7R,CH3474K1B04  I33  PC2232
   1 P12V_SCM_SS      A @T6G_MB_LIB.T6G(SCH_1):P12V_SCM_SS
   2    GND      B @T6G_MB_LIB.T6G(SCH_1):GND

Q_CAP_C0402-1UF,25V,10%,X6S,CH5104KEB02  I37  PC2231
   1 P12V_AUX      A @T6G_MB_LIB.T6G(SCH_1):P12V_AUX
   2    GND      B @T6G_MB_LIB.T6G(SCH_1):GND

Q_RES_0402LF-10K,1%,1/16W,CHIP,CS31002FB08  I40  PR4007
   1 P12V_SCM_FLTB_N      A @T6G_MB_LIB.T6G(SCH_1):P12V_SCM_FLTB_N
   2 P3V3_AUX      B @T6G_MB_LIB.T6G(SCH_1):P3V3_AUX

Q_CAP_C0402-100NF,50V,10%,X7R,CH4106K1B01  I45  PC2235
   1 P12V_SCM_IMON      A @T6G_MB_LIB.T6G(SCH_1):P12V_SCM_IMON
   2    GND      B @T6G_MB_LIB.T6G(SCH_1):GND

Q_RES_0402LF-71.5K,1%,1/16W,EMPTY,CS37152FB05  I50  PR4009
   1 P12V_SCM_R      A @T6G_MB_LIB.T6G(SCH_1):P12V_SCM_R
   2 P12V_SCM_OV_FB      B @T6G_MB_LIB.T6G(SCH_1):P12V_SCM_OV_FB

Q_RES_0402LF-120K,1%,1/16W,CHIP,CS41202FB05  I51  PR4010
   1 P12V_AUX      A @T6G_MB_LIB.T6G(SCH_1):P12V_AUX
   2 P12V_SCM_OV_FB      B @T6G_MB_LIB.T6G(SCH_1):P12V_SCM_OV_FB

Q_CAP_C0603-2.2UF,16V,20%,X7R,CH5223M1900  I52  PC2239
   1 P12V_SCM_AVIN_PD      A @T6G_MB_LIB.T6G(SCH_1):P12V_SCM_AVIN_PD
   2    GND      B @T6G_MB_LIB.T6G(SCH_1):GND

Q_RES_0402LF-17.8K,1%,1/16W,CHIP,CS31782FB04  I62  PR4004
   1 P12V_SCM_CB      A @T6G_MB_LIB.T6G(SCH_1):P12V_SCM_CB
   2    GND      B @T6G_MB_LIB.T6G(SCH_1):GND

Q_RES_0402LF-160K,1%,1/16W,CHIP,CS41602FB05  I65  PR4000
   1 P12V_AUX      A @T6G_MB_LIB.T6G(SCH_1):P12V_AUX
   2 P12V_SCM_UV      B @T6G_MB_LIB.T6G(SCH_1):P12V_SCM_UV

Q_CAP_C0402-1UF,25V,10%,X6S,CH5104KEB02  I66  PC2233
   1 P12V_SCM_VCC      A @T6G_MB_LIB.T6G(SCH_1):P12V_SCM_VCC
   2    GND      B @T6G_MB_LIB.T6G(SCH_1):GND

Q_CAP_C0402-1UF,25V,10%,X6S,CH5104KEB02  I67  PC2234
   1    GND      A @T6G_MB_LIB.T6G(SCH_1):GND
   2 P12V_SCM_REG      B @T6G_MB_LIB.T6G(SCH_1):P12V_SCM_REG

Q_RES_0402LF-1.33K,1%,1/16W,CHIP,CS21332FB05  I70  PR4008
   1 P12V_SCM_SENSE      A @T6G_MB_LIB.T6G(SCH_1):P12V_SCM_SENSE
   2    GND      B @T6G_MB_LIB.T6G(SCH_1):GND

Q_CAP_C0402-0.01UF,50V,10%,EMPTY,CH31006KB18  I71  PC2236
   1 P12V_SCM_R      A @T6G_MB_LIB.T6G(SCH_1):P12V_SCM_R
   2 P12V_SCM_GATE      B @T6G_MB_LIB.T6G(SCH_1):P12V_SCM_GATE

Q_CAP_C0402-3900PF,50V,10%,X7R,CH23906KB14  I72  PC2237
   1 P12V_SCM_GATE      A @T6G_MB_LIB.T6G(SCH_1):P12V_SCM_GATE
   2    GND      B @T6G_MB_LIB.T6G(SCH_1):GND

Q_RES_0402LF-0,5%,1/16W,CHIP,CS00002JB13  I73  PR4012
   1 P12V_SCM_PWRGD      A @T6G_MB_LIB.T6G(SCH_1):P12V_SCM_PWRGD
   2 HP_LVC3_SCM_HSC_PWRGD      B @T6G_MB_LIB.T6G(SCH_1):HP_LVC3_SCM_HSC_PWRGD

Q_RES_0402LF-100K,1%,1/16W,CHIP,CS41002FB09  I78  R4015
   1 P3V3_AUX      A @T6G_MB_LIB.T6G(SCH_1):P3V3_AUX
   2 HP_LVC3_SCM_HSC_PWRGD      B @T6G_MB_LIB.T6G(SCH_1):HP_LVC3_SCM_HSC_PWRGD

SCHOTTKY_AC-B340A-13-F,SMLF,IC,BC000340Z30  I79  PD116
   A    GND      A @T6G_MB_LIB.T6G(SCH_1):GND
   C P12V_SCM_R      C @T6G_MB_LIB.T6G(SCH_1):P12V_SCM_R

Q_CAP_0402-0.1UF,25V,10%,X7R,CH4104K1B00  I80  PC2238
   1 P12V_SCM_R      A @T6G_MB_LIB.T6G(SCH_1):P12V_SCM_R
   2    GND      B @T6G_MB_LIB.T6G(SCH_1):GND

Q_CAP_C0402-560PF,50V,10%,X7R,CH1566K1B09  I6  PC2340
   1 P12V_SCM_ISET_R      A @T6G_MB_LIB.T6G(SCH_1):P12V_SCM_ISET_R
   2    GND      B @T6G_MB_LIB.T6G(SCH_1):GND

MOSFET_NCH_GDS_ESD_PROTECTED-2N7002K,SMLF,IC,BAM70A  I9  Q39
   D P12V_SCM_EN      D @T6G_MB_LIB.T6G(SCH_1):P12V_SCM_EN
   G FM_SCM_PRSNT1_R_N      G @T6G_MB_LIB.T6G(SCH_1):FM_SCM_PRSNT1_R_N
   S    GND      S @T6G_MB_LIB.T6G(SCH_1):GND

MOSFET_NCH_DUAL-PJT138K,SMLF,IC,BAM138K0003  I22  Q125
   1    GND     S1 @T6G_MB_LIB.T6G(SCH_1):GND
   2 P12V_SCM_EN_R     G1 @T6G_MB_LIB.T6G(SCH_1):P12V_SCM_EN_R
   6 P12V_SCM_EN_G     D1 @T6G_MB_LIB.T6G(SCH_1):P12V_SCM_EN_G

MOSFET_NCH_DUAL-PJT138K,SMLF,IC,BAM138K0003  I24  Q125
   3 P12V_SCM_UV_R     D2 @T6G_MB_LIB.T6G(SCH_1):P12V_SCM_UV_R
   5 P12V_SCM_EN_G     G2 @T6G_MB_LIB.T6G(SCH_1):P12V_SCM_EN_G
   4    GND     S2 @T6G_MB_LIB.T6G(SCH_1):GND

DIODE_TVS-SMF14A,SMLF,IC,BCSMF14AZ01  I28  PD115
   A    GND      A @T6G_MB_LIB.T6G(SCH_1):GND
   C P12V_AUX      C @T6G_MB_LIB.T6G(SCH_1):P12V_AUX

Q_RES_0402LF-30.1K,1%,1/16W,CHIP,CS33012FB03  I35  PR4005
   1 P12V_SCM_IMON      A @T6G_MB_LIB.T6G(SCH_1):P12V_SCM_IMON
   2    GND      B @T6G_MB_LIB.T6G(SCH_1):GND

Q_RES_0402LF-100,1%,1/16W,EMPTY,CS11002FB07  I41  PR4006
   1 P12V_SCM_R      A @T6G_MB_LIB.T6G(SCH_1):P12V_SCM_R
   2 P12V_SCM_AVIN_PD      B @T6G_MB_LIB.T6G(SCH_1):P12V_SCM_AVIN_PD

Q_RES_0402LF-10K,1%,1/16W,CHIP,CS31002FB08  I43  R3836
   1 P3V3_AUX      A @T6G_MB_LIB.T6G(SCH_1):P3V3_AUX
   2 HP_LVC3_SCM_HSC_PWRGD_R      B @T6G_MB_LIB.T6G(SCH_1):HP_LVC3_SCM_HSC_PWRGD_R

Q_RES_0402LF-10K,1%,1/16W,CHIP,CS31002FB08  I49  PR4011
   1 P12V_SCM_OV_FB      A @T6G_MB_LIB.T6G(SCH_1):P12V_SCM_OV_FB
   2    GND      B @T6G_MB_LIB.T6G(SCH_1):GND

MAX15090BEWIT-MAX15090BEWI+T,SMLF,IC,AL015080B00  I86  PU300
  A2 P12V_SCM_VCC    VCC @T6G_MB_LIB.T6G(SCH_1):P12V_SCM_VCC
  A3 P12V_AUX  IN_A3 @T6G_MB_LIB.T6G(SCH_1):P12V_AUX
  A5 P12V_AUX  IN_A5 @T6G_MB_LIB.T6G(SCH_1):P12V_AUX
  B3 P12V_AUX  IN_B3 @T6G_MB_LIB.T6G(SCH_1):P12V_AUX
  B5 P12V_AUX  IN_B5 @T6G_MB_LIB.T6G(SCH_1):P12V_AUX
  C3 P12V_AUX  IN_C3 @T6G_MB_LIB.T6G(SCH_1):P12V_AUX
  C5 P12V_AUX  IN_C5 @T6G_MB_LIB.T6G(SCH_1):P12V_AUX
  D5 P12V_AUX  IN_D5 @T6G_MB_LIB.T6G(SCH_1):P12V_AUX
  B1 P12V_SCM_CB     CB @T6G_MB_LIB.T6G(SCH_1):P12V_SCM_CB
  B7    GND    EN# @T6G_MB_LIB.T6G(SCH_1):GND
  D1 P12V_SCM_REG    REG @T6G_MB_LIB.T6G(SCH_1):P12V_SCM_REG
  D2 P12V_SCM_UV     UV @T6G_MB_LIB.T6G(SCH_1):P12V_SCM_UV
  D3 P12V_SCM_OV     OV @T6G_MB_LIB.T6G(SCH_1):P12V_SCM_OV
  A1 P12V_SCM_SENSE ISENSE @T6G_MB_LIB.T6G(SCH_1):P12V_SCM_SENSE
  A4 P12V_SCM_R OUT_A4 @T6G_MB_LIB.T6G(SCH_1):P12V_SCM_R
  B4 P12V_SCM_R OUT_B4 @T6G_MB_LIB.T6G(SCH_1):P12V_SCM_R
  B6 P12V_SCM_R OUT_B6 @T6G_MB_LIB.T6G(SCH_1):P12V_SCM_R
  C4 P12V_SCM_R OUT_C4 @T6G_MB_LIB.T6G(SCH_1):P12V_SCM_R
  C6 P12V_SCM_R OUT_C6 @T6G_MB_LIB.T6G(SCH_1):P12V_SCM_R
  D4 P12V_SCM_R OUT_D4 @T6G_MB_LIB.T6G(SCH_1):P12V_SCM_R
  D6 P12V_SCM_R OUT_D6 @T6G_MB_LIB.T6G(SCH_1):P12V_SCM_R
  A6 P12V_SCM_GATE   GATE @T6G_MB_LIB.T6G(SCH_1):P12V_SCM_GATE
  A7    GND   CDLY @T6G_MB_LIB.T6G(SCH_1):GND
  B2    GND GND_B2 @T6G_MB_LIB.T6G(SCH_1):GND
  C1    GND GND_C1 @T6G_MB_LIB.T6G(SCH_1):GND
  C2    GND GND_C2 @T6G_MB_LIB.T6G(SCH_1):GND
  C7 P12V_SCM_FAULT_N FAULT# @T6G_MB_LIB.T6G(SCH_1):P12V_SCM_FAULT_N
  D7 P12V_SCM_PWRGD     PG @T6G_MB_LIB.T6G(SCH_1):P12V_SCM_PWRGD

Q_RES_0603LF-49.9,1%,1/10W,CHIP,CS04993F909  I53  PR4014
   1 P12V_AUX      A @T6G_MB_LIB.T6G(SCH_1):P12V_AUX
   2 P12V_SCM_AVIN_PD      B @T6G_MB_LIB.T6G(SCH_1):P12V_SCM_AVIN_PD

Q_CAP_0402-0.1UF,25V,10%,X7R,CH4104K1B00  I56  PC2241
   1 P12V_SCM_R      A @T6G_MB_LIB.T6G(SCH_1):P12V_SCM_R
   2    GND      B @T6G_MB_LIB.T6G(SCH_1):GND

Q_RES_0402LF-15K,1%,1/16W,CHIP,CS31502FB05  I60  PR4002
   1 P12V_SCM_OV      A @T6G_MB_LIB.T6G(SCH_1):P12V_SCM_OV
   2    GND      B @T6G_MB_LIB.T6G(SCH_1):GND

Q_RES_0402LF-6.8K,1%,1/16W,CHIP,CS26802FB02  I63  PR4001
   1 P12V_SCM_UV      A @T6G_MB_LIB.T6G(SCH_1):P12V_SCM_UV
   2 P12V_SCM_OV      B @T6G_MB_LIB.T6G(SCH_1):P12V_SCM_OV

Q_RES_0402LF-10,1%,1/16W,CHIP,CS01002FB07  I68  PR4003
   1 P12V_AUX      A @T6G_MB_LIB.T6G(SCH_1):P12V_AUX
   2 P12V_SCM_VCC      B @T6G_MB_LIB.T6G(SCH_1):P12V_SCM_VCC

Q_RES_0402LF-10M,1%,1/16W,CHIP,CS61002FB02  I74  PR4526
   1 P12V_SCM_R      A @T6G_MB_LIB.T6G(SCH_1):P12V_SCM_R
   2 P12V_SCM_GATE      B @T6G_MB_LIB.T6G(SCH_1):P12V_SCM_GATE

Q_RES_0402LF-100K,1%,1/16W,CHIP,CS41002FB09  I76  R4013
   1 P3V3_AUX      A @T6G_MB_LIB.T6G(SCH_1):P3V3_AUX
   2 P12V_SCM_FAULT_R_N      B @T6G_MB_LIB.T6G(SCH_1):P12V_SCM_FAULT_R_N

Q_CAP_C0805-10UF,16V,10%,X6S,CH6103KEA01  I81  PC2240
   1 P12V_SCM_R      A @T6G_MB_LIB.T6G(SCH_1):P12V_SCM_R
   2    GND      B @T6G_MB_LIB.T6G(SCH_1):GND

Q_CAP_C0805-22UF,16V,20%,X6S,CH6223MEA01  I84  PC2242
   1 P12V_SCM_R      A @T6G_MB_LIB.T6G(SCH_1):P12V_SCM_R
   2    GND      B @T6G_MB_LIB.T6G(SCH_1):GND

Q_RES_0402LF-0,5%,1/16W,CHIP,CS00002JB13  I89  R8012
   1 HP_LVC3_SCM_HSC_PWRGD_R      A @T6G_MB_LIB.T6G(SCH_1):HP_LVC3_SCM_HSC_PWRGD_R
   2 HP_LVC3_SCM_HSC_PWRGD      B @T6G_MB_LIB.T6G(SCH_1):HP_LVC3_SCM_HSC_PWRGD

Q_RES_0402LF-0,5%,1/16W,CHIP,CS00002JB13  I91  R8030
   1 P12V_SCM_FAULT_N      A @T6G_MB_LIB.T6G(SCH_1):P12V_SCM_FAULT_N
   2 P12V_SCM_FAULT_R_N      B @T6G_MB_LIB.T6G(SCH_1):P12V_SCM_FAULT_R_N

Q_RES_0402LF-0,5%,1/16W,CHIP,CS00002JB13  I93  R8031
   1 P12V_SCM_FLTB_N      A @T6G_MB_LIB.T6G(SCH_1):P12V_SCM_FLTB_N
   2 P12V_SCM_FAULT_R_N      B @T6G_MB_LIB.T6G(SCH_1):P12V_SCM_FAULT_R_N

RS31312R-RS31312R,SMLF,IC,AL031312000  I95  PU299
  20 P12V_SCM_R VOUT_20 @T6G_MB_LIB.T6G(SCH_1):P12V_SCM_R
21_22 P12V_AUX VIN_21_22 @T6G_MB_LIB.T6G(SCH_1):P12V_AUX
  19 P12V_SCM_R VOUT_19 @T6G_MB_LIB.T6G(SCH_1):P12V_SCM_R
  18 P12V_SCM_R VOUT_18 @T6G_MB_LIB.T6G(SCH_1):P12V_SCM_R
  17 P12V_SCM_R VOUT_17 @T6G_MB_LIB.T6G(SCH_1):P12V_SCM_R
  16 P12V_SCM_R VOUT_16 @T6G_MB_LIB.T6G(SCH_1):P12V_SCM_R
  15 P12V_SCM_R VOUT_15 @T6G_MB_LIB.T6G(SCH_1):P12V_SCM_R
  14 P12V_SCM_R VOUT_14 @T6G_MB_LIB.T6G(SCH_1):P12V_SCM_R
  12 P12V_SCM_AVIN_PD   AVIN @T6G_MB_LIB.T6G(SCH_1):P12V_SCM_AVIN_PD
  13 P12V_SCM_R VOUT_13 @T6G_MB_LIB.T6G(SCH_1):P12V_SCM_R
  11 P12V_SCM_OV_FB     OV @T6G_MB_LIB.T6G(SCH_1):P12V_SCM_OV_FB
  10 HP_LVC3_SCM_HSC_PWRGD_R     PG @T6G_MB_LIB.T6G(SCH_1):HP_LVC3_SCM_HSC_PWRGD_R
   9 P12V_SCM_FLTB_N   FLTB @T6G_MB_LIB.T6G(SCH_1):P12V_SCM_FLTB_N
   8 P12V_SCM_IMON   IMON @T6G_MB_LIB.T6G(SCH_1):P12V_SCM_IMON
  23 P12V_AUX VIN_23 @T6G_MB_LIB.T6G(SCH_1):P12V_AUX
  24 P12V_AUX VIN_24 @T6G_MB_LIB.T6G(SCH_1):P12V_AUX
  25 P12V_AUX VIN_25 @T6G_MB_LIB.T6G(SCH_1):P12V_AUX
  26 P12V_AUX VIN_26 @T6G_MB_LIB.T6G(SCH_1):P12V_AUX
   1 P12V_SCM_EN_R2     EN @T6G_MB_LIB.T6G(SCH_1):P12V_SCM_EN_R2
   2    GND LOADEN @T6G_MB_LIB.T6G(SCH_1):GND
   3    GND   ENTM @T6G_MB_LIB.T6G(SCH_1):GND
   4 P12V_SCM_TIMER  TIMER @T6G_MB_LIB.T6G(SCH_1):P12V_SCM_TIMER
   5 P12V_SCM_ISET   ISET @T6G_MB_LIB.T6G(SCH_1):P12V_SCM_ISET
   6 P12V_SCM_SS     SS @T6G_MB_LIB.T6G(SCH_1):P12V_SCM_SS
   7    GND    GND @T6G_MB_LIB.T6G(SCH_1):GND


DRAWING: @T6G_MB_LIB.T6G(SCH_1):PAGE351 

Q_CAP_DIFFBUS_C0201-DIFF BUS_0.22UF,6.3V,20%,X6S,SA  I21  C932
   1 P5E_CPU0_P0_TX_C_DN<0>      1 @T6G_MB_LIB.T6G(SCH_1):P5E_CPU0_P0_TX_C_DN(0)
   2 P5E_CPU0_P0_TX_DN<0>      2 @T6G_MB_LIB.T6G(SCH_1):P5E_CPU0_P0_TX_DN(0)

Q_CAP_DIFFBUS_C0201-DIFF BUS_0.22UF,6.3V,20%,X6S,SA  I22  C933
   1 P5E_CPU0_P0_TX_C_DP<0>      1 @T6G_MB_LIB.T6G(SCH_1):P5E_CPU0_P0_TX_C_DP(0)
   2 P5E_CPU0_P0_TX_DP<0>      2 @T6G_MB_LIB.T6G(SCH_1):P5E_CPU0_P0_TX_DP(0)

Q_CAP_DIFFBUS_C0201-DIFF BUS_0.22UF,6.3V,20%,X6S,SA  I23  C931
   1 P5E_CPU0_P0_TX_C_DP<1>      1 @T6G_MB_LIB.T6G(SCH_1):P5E_CPU0_P0_TX_C_DP(1)
   2 P5E_CPU0_P0_TX_DP<1>      2 @T6G_MB_LIB.T6G(SCH_1):P5E_CPU0_P0_TX_DP(1)

Q_CAP_DIFFBUS_C0201-DIFF BUS_0.22UF,6.3V,20%,X6S,SA  I24  C930
   1 P5E_CPU0_P0_TX_C_DN<1>      1 @T6G_MB_LIB.T6G(SCH_1):P5E_CPU0_P0_TX_C_DN(1)
   2 P5E_CPU0_P0_TX_DN<1>      2 @T6G_MB_LIB.T6G(SCH_1):P5E_CPU0_P0_TX_DN(1)

Q_CAP_DIFFBUS_C0201-DIFF BUS_0.22UF,6.3V,20%,X6S,SA  I25  C928
   1 P5E_CPU0_P0_TX_C_DN<2>      1 @T6G_MB_LIB.T6G(SCH_1):P5E_CPU0_P0_TX_C_DN(2)
   2 P5E_CPU0_P0_TX_DN<2>      2 @T6G_MB_LIB.T6G(SCH_1):P5E_CPU0_P0_TX_DN(2)

Q_CAP_DIFFBUS_C0201-DIFF BUS_0.22UF,6.3V,20%,X6S,SA  I26  C929
   1 P5E_CPU0_P0_TX_C_DP<2>      1 @T6G_MB_LIB.T6G(SCH_1):P5E_CPU0_P0_TX_C_DP(2)
   2 P5E_CPU0_P0_TX_DP<2>      2 @T6G_MB_LIB.T6G(SCH_1):P5E_CPU0_P0_TX_DP(2)

Q_CAP_DIFFBUS_C0201-DIFF BUS_0.22UF,6.3V,20%,X6S,SA  I27  C927
   1 P5E_CPU0_P0_TX_C_DP<3>      1 @T6G_MB_LIB.T6G(SCH_1):P5E_CPU0_P0_TX_C_DP(3)
   2 P5E_CPU0_P0_TX_DP<3>      2 @T6G_MB_LIB.T6G(SCH_1):P5E_CPU0_P0_TX_DP(3)

Q_CAP_DIFFBUS_C0201-DIFF BUS_0.22UF,6.3V,20%,X6S,SA  I28  C926
   1 P5E_CPU0_P0_TX_C_DN<3>      1 @T6G_MB_LIB.T6G(SCH_1):P5E_CPU0_P0_TX_C_DN(3)
   2 P5E_CPU0_P0_TX_DN<3>      2 @T6G_MB_LIB.T6G(SCH_1):P5E_CPU0_P0_TX_DN(3)

Q_CAP_DIFFBUS_C0201-DIFF BUS_0.22UF,6.3V,20%,X6S,SA  I29  C925
   1 P5E_CPU0_P0_TX_C_DP<4>      1 @T6G_MB_LIB.T6G(SCH_1):P5E_CPU0_P0_TX_C_DP(4)
   2 P5E_CPU0_P0_TX_DP<4>      2 @T6G_MB_LIB.T6G(SCH_1):P5E_CPU0_P0_TX_DP(4)

Q_CAP_DIFFBUS_C0201-DIFF BUS_0.22UF,6.3V,20%,X6S,SA  I30  C924
   1 P5E_CPU0_P0_TX_C_DN<4>      1 @T6G_MB_LIB.T6G(SCH_1):P5E_CPU0_P0_TX_C_DN(4)
   2 P5E_CPU0_P0_TX_DN<4>      2 @T6G_MB_LIB.T6G(SCH_1):P5E_CPU0_P0_TX_DN(4)

Q_CAP_DIFFBUS_C0201-DIFF BUS_0.22UF,6.3V,20%,X6S,SA  I31  C923
   1 P5E_CPU0_P0_TX_C_DP<5>      1 @T6G_MB_LIB.T6G(SCH_1):P5E_CPU0_P0_TX_C_DP(5)
   2 P5E_CPU0_P0_TX_DP<5>      2 @T6G_MB_LIB.T6G(SCH_1):P5E_CPU0_P0_TX_DP(5)

Q_CAP_DIFFBUS_C0201-DIFF BUS_0.22UF,6.3V,20%,X6S,SA  I32  C922
   1 P5E_CPU0_P0_TX_C_DN<5>      1 @T6G_MB_LIB.T6G(SCH_1):P5E_CPU0_P0_TX_C_DN(5)
   2 P5E_CPU0_P0_TX_DN<5>      2 @T6G_MB_LIB.T6G(SCH_1):P5E_CPU0_P0_TX_DN(5)

Q_CAP_DIFFBUS_C0201-DIFF BUS_0.22UF,6.3V,20%,X6S,SA  I33  C921
   1 P5E_CPU0_P0_TX_C_DP<6>      1 @T6G_MB_LIB.T6G(SCH_1):P5E_CPU0_P0_TX_C_DP(6)
   2 P5E_CPU0_P0_TX_DP<6>      2 @T6G_MB_LIB.T6G(SCH_1):P5E_CPU0_P0_TX_DP(6)

Q_CAP_DIFFBUS_C0201-DIFF BUS_0.22UF,6.3V,20%,X6S,SA  I34  C920
   1 P5E_CPU0_P0_TX_C_DN<6>      1 @T6G_MB_LIB.T6G(SCH_1):P5E_CPU0_P0_TX_C_DN(6)
   2 P5E_CPU0_P0_TX_DN<6>      2 @T6G_MB_LIB.T6G(SCH_1):P5E_CPU0_P0_TX_DN(6)

Q_CAP_DIFFBUS_C0201-DIFF BUS_0.22UF,6.3V,20%,X6S,SA  I35  C918
   1 P5E_CPU0_P0_TX_C_DN<7>      1 @T6G_MB_LIB.T6G(SCH_1):P5E_CPU0_P0_TX_C_DN(7)
   2 P5E_CPU0_P0_TX_DN<7>      2 @T6G_MB_LIB.T6G(SCH_1):P5E_CPU0_P0_TX_DN(7)

Q_CAP_DIFFBUS_C0201-DIFF BUS_0.22UF,6.3V,20%,X6S,SA  I36  C919
   1 P5E_CPU0_P0_TX_C_DP<7>      1 @T6G_MB_LIB.T6G(SCH_1):P5E_CPU0_P0_TX_C_DP(7)
   2 P5E_CPU0_P0_TX_DP<7>      2 @T6G_MB_LIB.T6G(SCH_1):P5E_CPU0_P0_TX_DP(7)

Q_CAP_DIFFBUS_C0201-DIFF BUS_0.22UF,6.3V,20%,X6S,SA  I53  C916
   1 P5E_CPU0_P0_TX_C_DN<8>      1 @T6G_MB_LIB.T6G(SCH_1):P5E_CPU0_P0_TX_C_DN(8)
   2 P5E_CPU0_P0_TX_DN<8>      2 @T6G_MB_LIB.T6G(SCH_1):P5E_CPU0_P0_TX_DN(8)

Q_CAP_DIFFBUS_C0201-DIFF BUS_0.22UF,6.3V,20%,X6S,SA  I54  C917
   1 P5E_CPU0_P0_TX_C_DP<8>      1 @T6G_MB_LIB.T6G(SCH_1):P5E_CPU0_P0_TX_C_DP(8)
   2 P5E_CPU0_P0_TX_DP<8>      2 @T6G_MB_LIB.T6G(SCH_1):P5E_CPU0_P0_TX_DP(8)

Q_CAP_DIFFBUS_C0201-DIFF BUS_0.22UF,6.3V,20%,X6S,SA  I55  C915
   1 P5E_CPU0_P0_TX_C_DP<9>      1 @T6G_MB_LIB.T6G(SCH_1):P5E_CPU0_P0_TX_C_DP(9)
   2 P5E_CPU0_P0_TX_DP<9>      2 @T6G_MB_LIB.T6G(SCH_1):P5E_CPU0_P0_TX_DP(9)

Q_CAP_DIFFBUS_C0201-DIFF BUS_0.22UF,6.3V,20%,X6S,SA  I56  C914
   1 P5E_CPU0_P0_TX_C_DN<9>      1 @T6G_MB_LIB.T6G(SCH_1):P5E_CPU0_P0_TX_C_DN(9)
   2 P5E_CPU0_P0_TX_DN<9>      2 @T6G_MB_LIB.T6G(SCH_1):P5E_CPU0_P0_TX_DN(9)

Q_CAP_DIFFBUS_C0201-DIFF BUS_0.22UF,6.3V,20%,X6S,SA  I57  C913
   1 P5E_CPU0_P0_TX_C_DP<10>      1 @T6G_MB_LIB.T6G(SCH_1):P5E_CPU0_P0_TX_C_DP(10)
   2 P5E_CPU0_P0_TX_DP<10>      2 @T6G_MB_LIB.T6G(SCH_1):P5E_CPU0_P0_TX_DP(10)

Q_CAP_DIFFBUS_C0201-DIFF BUS_0.22UF,6.3V,20%,X6S,SA  I58  C912
   1 P5E_CPU0_P0_TX_C_DN<10>      1 @T6G_MB_LIB.T6G(SCH_1):P5E_CPU0_P0_TX_C_DN(10)
   2 P5E_CPU0_P0_TX_DN<10>      2 @T6G_MB_LIB.T6G(SCH_1):P5E_CPU0_P0_TX_DN(10)

Q_CAP_DIFFBUS_C0201-DIFF BUS_0.22UF,6.3V,20%,X6S,SA  I59  C911
   1 P5E_CPU0_P0_TX_C_DP<11>      1 @T6G_MB_LIB.T6G(SCH_1):P5E_CPU0_P0_TX_C_DP(11)
   2 P5E_CPU0_P0_TX_DP<11>      2 @T6G_MB_LIB.T6G(SCH_1):P5E_CPU0_P0_TX_DP(11)

Q_CAP_DIFFBUS_C0201-DIFF BUS_0.22UF,6.3V,20%,X6S,SA  I60  C910
   1 P5E_CPU0_P0_TX_C_DN<11>      1 @T6G_MB_LIB.T6G(SCH_1):P5E_CPU0_P0_TX_C_DN(11)
   2 P5E_CPU0_P0_TX_DN<11>      2 @T6G_MB_LIB.T6G(SCH_1):P5E_CPU0_P0_TX_DN(11)

Q_CAP_DIFFBUS_C0201-DIFF BUS_0.22UF,6.3V,20%,X6S,SA  I61  C909
   1 P5E_CPU0_P0_TX_C_DP<12>      1 @T6G_MB_LIB.T6G(SCH_1):P5E_CPU0_P0_TX_C_DP(12)
   2 P5E_CPU0_P0_TX_DP<12>      2 @T6G_MB_LIB.T6G(SCH_1):P5E_CPU0_P0_TX_DP(12)

Q_CAP_DIFFBUS_C0201-DIFF BUS_0.22UF,6.3V,20%,X6S,SA  I62  C908
   1 P5E_CPU0_P0_TX_C_DN<12>      1 @T6G_MB_LIB.T6G(SCH_1):P5E_CPU0_P0_TX_C_DN(12)
   2 P5E_CPU0_P0_TX_DN<12>      2 @T6G_MB_LIB.T6G(SCH_1):P5E_CPU0_P0_TX_DN(12)

Q_CAP_DIFFBUS_C0201-DIFF BUS_0.22UF,6.3V,20%,X6S,SA  I63  C906
   1 P5E_CPU0_P0_TX_C_DN<13>      1 @T6G_MB_LIB.T6G(SCH_1):P5E_CPU0_P0_TX_C_DN(13)
   2 P5E_CPU0_P0_TX_DN<13>      2 @T6G_MB_LIB.T6G(SCH_1):P5E_CPU0_P0_TX_DN(13)

Q_CAP_DIFFBUS_C0201-DIFF BUS_0.22UF,6.3V,20%,X6S,SA  I64  C907
   1 P5E_CPU0_P0_TX_C_DP<13>      1 @T6G_MB_LIB.T6G(SCH_1):P5E_CPU0_P0_TX_C_DP(13)
   2 P5E_CPU0_P0_TX_DP<13>      2 @T6G_MB_LIB.T6G(SCH_1):P5E_CPU0_P0_TX_DP(13)

Q_CAP_DIFFBUS_C0201-DIFF BUS_0.22UF,6.3V,20%,X6S,SA  I65  C905
   1 P5E_CPU0_P0_TX_C_DP<14>      1 @T6G_MB_LIB.T6G(SCH_1):P5E_CPU0_P0_TX_C_DP(14)
   2 P5E_CPU0_P0_TX_DP<14>      2 @T6G_MB_LIB.T6G(SCH_1):P5E_CPU0_P0_TX_DP(14)

Q_CAP_DIFFBUS_C0201-DIFF BUS_0.22UF,6.3V,20%,X6S,SA  I66  C904
   1 P5E_CPU0_P0_TX_C_DN<14>      1 @T6G_MB_LIB.T6G(SCH_1):P5E_CPU0_P0_TX_C_DN(14)
   2 P5E_CPU0_P0_TX_DN<14>      2 @T6G_MB_LIB.T6G(SCH_1):P5E_CPU0_P0_TX_DN(14)

Q_CAP_DIFFBUS_C0201-DIFF BUS_0.22UF,6.3V,20%,X6S,SA  I67  C903
   1 P5E_CPU0_P0_TX_C_DP<15>      1 @T6G_MB_LIB.T6G(SCH_1):P5E_CPU0_P0_TX_C_DP(15)
   2 P5E_CPU0_P0_TX_DP<15>      2 @T6G_MB_LIB.T6G(SCH_1):P5E_CPU0_P0_TX_DP(15)

Q_CAP_DIFFBUS_C0201-DIFF BUS_0.22UF,6.3V,20%,X6S,SA  I68  C902
   1 P5E_CPU0_P0_TX_C_DN<15>      1 @T6G_MB_LIB.T6G(SCH_1):P5E_CPU0_P0_TX_C_DN(15)
   2 P5E_CPU0_P0_TX_DN<15>      2 @T6G_MB_LIB.T6G(SCH_1):P5E_CPU0_P0_TX_DN(15)

Q_CAP_DIFFBUS_C0201-DIFF BUS_0.22UF,6.3V,20%,X6S,SA  I121  C965
   1 P5E_CPU0_P1_TX_C_DP<0>      1 @T6G_MB_LIB.T6G(SCH_1):P5E_CPU0_P1_TX_C_DP(0)
   2 P5E_CPU0_P1_TX_DP<0>      2 @T6G_MB_LIB.T6G(SCH_1):P5E_CPU0_P1_TX_DP(0)

Q_CAP_DIFFBUS_C0201-DIFF BUS_0.22UF,6.3V,20%,X6S,SA  I122  C964
   1 P5E_CPU0_P1_TX_C_DN<0>      1 @T6G_MB_LIB.T6G(SCH_1):P5E_CPU0_P1_TX_C_DN(0)
   2 P5E_CPU0_P1_TX_DN<0>      2 @T6G_MB_LIB.T6G(SCH_1):P5E_CPU0_P1_TX_DN(0)

Q_CAP_DIFFBUS_C0201-DIFF BUS_0.22UF,6.3V,20%,X6S,SA  I123  C963
   1 P5E_CPU0_P1_TX_C_DP<1>      1 @T6G_MB_LIB.T6G(SCH_1):P5E_CPU0_P1_TX_C_DP(1)
   2 P5E_CPU0_P1_TX_DP<1>      2 @T6G_MB_LIB.T6G(SCH_1):P5E_CPU0_P1_TX_DP(1)

Q_CAP_DIFFBUS_C0201-DIFF BUS_0.22UF,6.3V,20%,X6S,SA  I124  C962
   1 P5E_CPU0_P1_TX_C_DN<1>      1 @T6G_MB_LIB.T6G(SCH_1):P5E_CPU0_P1_TX_C_DN(1)
   2 P5E_CPU0_P1_TX_DN<1>      2 @T6G_MB_LIB.T6G(SCH_1):P5E_CPU0_P1_TX_DN(1)

Q_CAP_DIFFBUS_C0201-DIFF BUS_0.22UF,6.3V,20%,X6S,SA  I125  C961
   1 P5E_CPU0_P1_TX_C_DP<2>      1 @T6G_MB_LIB.T6G(SCH_1):P5E_CPU0_P1_TX_C_DP(2)
   2 P5E_CPU0_P1_TX_DP<2>      2 @T6G_MB_LIB.T6G(SCH_1):P5E_CPU0_P1_TX_DP(2)

Q_CAP_DIFFBUS_C0201-DIFF BUS_0.22UF,6.3V,20%,X6S,SA  I126  C960
   1 P5E_CPU0_P1_TX_C_DN<2>      1 @T6G_MB_LIB.T6G(SCH_1):P5E_CPU0_P1_TX_C_DN(2)
   2 P5E_CPU0_P1_TX_DN<2>      2 @T6G_MB_LIB.T6G(SCH_1):P5E_CPU0_P1_TX_DN(2)

Q_CAP_DIFFBUS_C0201-DIFF BUS_0.22UF,6.3V,20%,X6S,SA  I127  C959
   1 P5E_CPU0_P1_TX_C_DP<3>      1 @T6G_MB_LIB.T6G(SCH_1):P5E_CPU0_P1_TX_C_DP(3)
   2 P5E_CPU0_P1_TX_DP<3>      2 @T6G_MB_LIB.T6G(SCH_1):P5E_CPU0_P1_TX_DP(3)

Q_CAP_DIFFBUS_C0201-DIFF BUS_0.22UF,6.3V,20%,X6S,SA  I128  C958
   1 P5E_CPU0_P1_TX_C_DN<3>      1 @T6G_MB_LIB.T6G(SCH_1):P5E_CPU0_P1_TX_C_DN(3)
   2 P5E_CPU0_P1_TX_DN<3>      2 @T6G_MB_LIB.T6G(SCH_1):P5E_CPU0_P1_TX_DN(3)

Q_CAP_DIFFBUS_C0201-DIFF BUS_0.22UF,6.3V,20%,X6S,SA  I133  C954
   1 P5E_CPU0_P1_TX_C_DN<5>      1 @T6G_MB_LIB.T6G(SCH_1):P5E_CPU0_P1_TX_C_DN(5)
   2 P5E_CPU0_P1_TX_DN<5>      2 @T6G_MB_LIB.T6G(SCH_1):P5E_CPU0_P1_TX_DN(5)

Q_CAP_DIFFBUS_C0201-DIFF BUS_0.22UF,6.3V,20%,X6S,SA  I134  C953
   1 P5E_CPU0_P1_TX_C_DP<6>      1 @T6G_MB_LIB.T6G(SCH_1):P5E_CPU0_P1_TX_C_DP(6)
   2 P5E_CPU0_P1_TX_DP<6>      2 @T6G_MB_LIB.T6G(SCH_1):P5E_CPU0_P1_TX_DP(6)

Q_CAP_DIFFBUS_C0201-DIFF BUS_0.22UF,6.3V,20%,X6S,SA  I135  C952
   1 P5E_CPU0_P1_TX_C_DN<6>      1 @T6G_MB_LIB.T6G(SCH_1):P5E_CPU0_P1_TX_C_DN(6)
   2 P5E_CPU0_P1_TX_DN<6>      2 @T6G_MB_LIB.T6G(SCH_1):P5E_CPU0_P1_TX_DN(6)

Q_CAP_DIFFBUS_C0201-DIFF BUS_0.22UF,6.3V,20%,X6S,SA  I136  C951
   1 P5E_CPU0_P1_TX_C_DP<7>      1 @T6G_MB_LIB.T6G(SCH_1):P5E_CPU0_P1_TX_C_DP(7)
   2 P5E_CPU0_P1_TX_DP<7>      2 @T6G_MB_LIB.T6G(SCH_1):P5E_CPU0_P1_TX_DP(7)

Q_CAP_DIFFBUS_C0201-DIFF BUS_0.22UF,6.3V,20%,X6S,SA  I137  C950
   1 P5E_CPU0_P1_TX_C_DN<7>      1 @T6G_MB_LIB.T6G(SCH_1):P5E_CPU0_P1_TX_C_DN(7)
   2 P5E_CPU0_P1_TX_DN<7>      2 @T6G_MB_LIB.T6G(SCH_1):P5E_CPU0_P1_TX_DN(7)

Q_CAP_DIFFBUS_C0201-DIFF BUS_0.22UF,6.3V,20%,X6S,SA  I151  C949
   1 P5E_CPU0_P1_TX_C_DP<8>      1 @T6G_MB_LIB.T6G(SCH_1):P5E_CPU0_P1_TX_C_DP(8)
   2 P5E_CPU0_P1_TX_DP<8>      2 @T6G_MB_LIB.T6G(SCH_1):P5E_CPU0_P1_TX_DP(8)

Q_CAP_DIFFBUS_C0201-DIFF BUS_0.22UF,6.3V,20%,X6S,SA  I152  C948
   1 P5E_CPU0_P1_TX_C_DN<8>      1 @T6G_MB_LIB.T6G(SCH_1):P5E_CPU0_P1_TX_C_DN(8)
   2 P5E_CPU0_P1_TX_DN<8>      2 @T6G_MB_LIB.T6G(SCH_1):P5E_CPU0_P1_TX_DN(8)

Q_CAP_DIFFBUS_C0201-DIFF BUS_0.22UF,6.3V,20%,X6S,SA  I153  C947
   1 P5E_CPU0_P1_TX_C_DP<9>      1 @T6G_MB_LIB.T6G(SCH_1):P5E_CPU0_P1_TX_C_DP(9)
   2 P5E_CPU0_P1_TX_DP<9>      2 @T6G_MB_LIB.T6G(SCH_1):P5E_CPU0_P1_TX_DP(9)

Q_CAP_DIFFBUS_C0201-DIFF BUS_0.22UF,6.3V,20%,X6S,SA  I154  C946
   1 P5E_CPU0_P1_TX_C_DN<9>      1 @T6G_MB_LIB.T6G(SCH_1):P5E_CPU0_P1_TX_C_DN(9)
   2 P5E_CPU0_P1_TX_DN<9>      2 @T6G_MB_LIB.T6G(SCH_1):P5E_CPU0_P1_TX_DN(9)

Q_CAP_DIFFBUS_C0201-DIFF BUS_0.22UF,6.3V,20%,X6S,SA  I155  C945
   1 P5E_CPU0_P1_TX_C_DP<10>      1 @T6G_MB_LIB.T6G(SCH_1):P5E_CPU0_P1_TX_C_DP(10)
   2 P5E_CPU0_P1_TX_DP<10>      2 @T6G_MB_LIB.T6G(SCH_1):P5E_CPU0_P1_TX_DP(10)

Q_CAP_DIFFBUS_C0201-DIFF BUS_0.22UF,6.3V,20%,X6S,SA  I156  C944
   1 P5E_CPU0_P1_TX_C_DN<10>      1 @T6G_MB_LIB.T6G(SCH_1):P5E_CPU0_P1_TX_C_DN(10)
   2 P5E_CPU0_P1_TX_DN<10>      2 @T6G_MB_LIB.T6G(SCH_1):P5E_CPU0_P1_TX_DN(10)

Q_CAP_DIFFBUS_C0201-DIFF BUS_0.22UF,6.3V,20%,X6S,SA  I157  C943
   1 P5E_CPU0_P1_TX_C_DP<11>      1 @T6G_MB_LIB.T6G(SCH_1):P5E_CPU0_P1_TX_C_DP(11)
   2 P5E_CPU0_P1_TX_DP<11>      2 @T6G_MB_LIB.T6G(SCH_1):P5E_CPU0_P1_TX_DP(11)

Q_CAP_DIFFBUS_C0201-DIFF BUS_0.22UF,6.3V,20%,X6S,SA  I158  C942
   1 P5E_CPU0_P1_TX_C_DN<11>      1 @T6G_MB_LIB.T6G(SCH_1):P5E_CPU0_P1_TX_C_DN(11)
   2 P5E_CPU0_P1_TX_DN<11>      2 @T6G_MB_LIB.T6G(SCH_1):P5E_CPU0_P1_TX_DN(11)

Q_CAP_DIFFBUS_C0201-DIFF BUS_0.22UF,6.3V,20%,X6S,SA  I159  C941
   1 P5E_CPU0_P1_TX_C_DP<12>      1 @T6G_MB_LIB.T6G(SCH_1):P5E_CPU0_P1_TX_C_DP(12)
   2 P5E_CPU0_P1_TX_DP<12>      2 @T6G_MB_LIB.T6G(SCH_1):P5E_CPU0_P1_TX_DP(12)

Q_CAP_DIFFBUS_C0201-DIFF BUS_0.22UF,6.3V,20%,X6S,SA  I160  C940
   1 P5E_CPU0_P1_TX_C_DN<12>      1 @T6G_MB_LIB.T6G(SCH_1):P5E_CPU0_P1_TX_C_DN(12)
   2 P5E_CPU0_P1_TX_DN<12>      2 @T6G_MB_LIB.T6G(SCH_1):P5E_CPU0_P1_TX_DN(12)

Q_CAP_DIFFBUS_C0201-DIFF BUS_0.22UF,6.3V,20%,X6S,SA  I164  C939
   1 P5E_CPU0_P1_TX_C_DP<13>      1 @T6G_MB_LIB.T6G(SCH_1):P5E_CPU0_P1_TX_C_DP(13)
   2 P5E_CPU0_P1_TX_DP<13>      2 @T6G_MB_LIB.T6G(SCH_1):P5E_CPU0_P1_TX_DP(13)

Q_CAP_DIFFBUS_C0201-DIFF BUS_0.22UF,6.3V,20%,X6S,SA  I165  C938
   1 P5E_CPU0_P1_TX_C_DN<13>      1 @T6G_MB_LIB.T6G(SCH_1):P5E_CPU0_P1_TX_C_DN(13)
   2 P5E_CPU0_P1_TX_DN<13>      2 @T6G_MB_LIB.T6G(SCH_1):P5E_CPU0_P1_TX_DN(13)

Q_CAP_DIFFBUS_C0201-DIFF BUS_0.22UF,6.3V,20%,X6S,SA  I166  C937
   1 P5E_CPU0_P1_TX_C_DP<14>      1 @T6G_MB_LIB.T6G(SCH_1):P5E_CPU0_P1_TX_C_DP(14)
   2 P5E_CPU0_P1_TX_DP<14>      2 @T6G_MB_LIB.T6G(SCH_1):P5E_CPU0_P1_TX_DP(14)

Q_CAP_DIFFBUS_C0201-DIFF BUS_0.22UF,6.3V,20%,X6S,SA  I167  C936
   1 P5E_CPU0_P1_TX_C_DN<14>      1 @T6G_MB_LIB.T6G(SCH_1):P5E_CPU0_P1_TX_C_DN(14)
   2 P5E_CPU0_P1_TX_DN<14>      2 @T6G_MB_LIB.T6G(SCH_1):P5E_CPU0_P1_TX_DN(14)

Q_CAP_DIFFBUS_C0201-DIFF BUS_0.22UF,6.3V,20%,X6S,SA  I168  C935
   1 P5E_CPU0_P1_TX_C_DP<15>      1 @T6G_MB_LIB.T6G(SCH_1):P5E_CPU0_P1_TX_C_DP(15)
   2 P5E_CPU0_P1_TX_DP<15>      2 @T6G_MB_LIB.T6G(SCH_1):P5E_CPU0_P1_TX_DP(15)

Q_CAP_DIFFBUS_C0201-DIFF BUS_0.22UF,6.3V,20%,X6S,SA  I169  C934
   1 P5E_CPU0_P1_TX_C_DN<15>      1 @T6G_MB_LIB.T6G(SCH_1):P5E_CPU0_P1_TX_C_DN(15)
   2 P5E_CPU0_P1_TX_DN<15>      2 @T6G_MB_LIB.T6G(SCH_1):P5E_CPU0_P1_TX_DN(15)

Q_CAP_DIFFBUS_C0201-DIFF BUS_0.22UF,6.3V,20%,X6S,SA  I206  C957
   1 P5E_CPU0_P1_TX_C_DP<4>      1 @T6G_MB_LIB.T6G(SCH_1):P5E_CPU0_P1_TX_C_DP(4)
   2 P5E_CPU0_P1_TX_DP<4>      2 @T6G_MB_LIB.T6G(SCH_1):P5E_CPU0_P1_TX_DP(4)

Q_CAP_DIFFBUS_C0201-DIFF BUS_0.22UF,6.3V,20%,X6S,SA  I207  C956
   1 P5E_CPU0_P1_TX_C_DN<4>      1 @T6G_MB_LIB.T6G(SCH_1):P5E_CPU0_P1_TX_C_DN(4)
   2 P5E_CPU0_P1_TX_DN<4>      2 @T6G_MB_LIB.T6G(SCH_1):P5E_CPU0_P1_TX_DN(4)

Q_CAP_DIFFBUS_C0201-DIFF BUS_0.22UF,6.3V,20%,X6S,SA  I208  C955
   1 P5E_CPU0_P1_TX_C_DP<5>      1 @T6G_MB_LIB.T6G(SCH_1):P5E_CPU0_P1_TX_C_DP(5)
   2 P5E_CPU0_P1_TX_DP<5>      2 @T6G_MB_LIB.T6G(SCH_1):P5E_CPU0_P1_TX_DP(5)


DRAWING: @T6G_MB_LIB.T6G(SCH_1):PAGE352 

Q_CAP_DIFFBUS_C0201-DIFF BUS_0.22UF,6.3V,20%,X6S,SA  I21  C869
   1 P5E_CPU0_P2_TX_C_DP<0>      1 @T6G_MB_LIB.T6G(SCH_1):P5E_CPU0_P2_TX_C_DP(0)
   2 P5E_CPU0_P2_TX_DP<0>      2 @T6G_MB_LIB.T6G(SCH_1):P5E_CPU0_P2_TX_DP(0)

Q_CAP_DIFFBUS_C0201-DIFF BUS_0.22UF,6.3V,20%,X6S,SA  I22  C868
   1 P5E_CPU0_P2_TX_C_DN<0>      1 @T6G_MB_LIB.T6G(SCH_1):P5E_CPU0_P2_TX_C_DN(0)
   2 P5E_CPU0_P2_TX_DN<0>      2 @T6G_MB_LIB.T6G(SCH_1):P5E_CPU0_P2_TX_DN(0)

Q_CAP_DIFFBUS_C0201-DIFF BUS_0.22UF,6.3V,20%,X6S,SA  I23  C867
   1 P5E_CPU0_P2_TX_C_DP<1>      1 @T6G_MB_LIB.T6G(SCH_1):P5E_CPU0_P2_TX_C_DP(1)
   2 P5E_CPU0_P2_TX_DP<1>      2 @T6G_MB_LIB.T6G(SCH_1):P5E_CPU0_P2_TX_DP(1)

Q_CAP_DIFFBUS_C0201-DIFF BUS_0.22UF,6.3V,20%,X6S,SA  I24  C866
   1 P5E_CPU0_P2_TX_C_DN<1>      1 @T6G_MB_LIB.T6G(SCH_1):P5E_CPU0_P2_TX_C_DN(1)
   2 P5E_CPU0_P2_TX_DN<1>      2 @T6G_MB_LIB.T6G(SCH_1):P5E_CPU0_P2_TX_DN(1)

Q_CAP_DIFFBUS_C0201-DIFF BUS_0.22UF,6.3V,20%,X6S,SA  I25  C864
   1 P5E_CPU0_P2_TX_C_DN<2>      1 @T6G_MB_LIB.T6G(SCH_1):P5E_CPU0_P2_TX_C_DN(2)
   2 P5E_CPU0_P2_TX_DN<2>      2 @T6G_MB_LIB.T6G(SCH_1):P5E_CPU0_P2_TX_DN(2)

Q_CAP_DIFFBUS_C0201-DIFF BUS_0.22UF,6.3V,20%,X6S,SA  I26  C865
   1 P5E_CPU0_P2_TX_C_DP<2>      1 @T6G_MB_LIB.T6G(SCH_1):P5E_CPU0_P2_TX_C_DP(2)
   2 P5E_CPU0_P2_TX_DP<2>      2 @T6G_MB_LIB.T6G(SCH_1):P5E_CPU0_P2_TX_DP(2)

Q_CAP_DIFFBUS_C0201-DIFF BUS_0.22UF,6.3V,20%,X6S,SA  I27  C863
   1 P5E_CPU0_P2_TX_C_DP<3>      1 @T6G_MB_LIB.T6G(SCH_1):P5E_CPU0_P2_TX_C_DP(3)
   2 P5E_CPU0_P2_TX_DP<3>      2 @T6G_MB_LIB.T6G(SCH_1):P5E_CPU0_P2_TX_DP(3)

Q_CAP_DIFFBUS_C0201-DIFF BUS_0.22UF,6.3V,20%,X6S,SA  I28  C862
   1 P5E_CPU0_P2_TX_C_DN<3>      1 @T6G_MB_LIB.T6G(SCH_1):P5E_CPU0_P2_TX_C_DN(3)
   2 P5E_CPU0_P2_TX_DN<3>      2 @T6G_MB_LIB.T6G(SCH_1):P5E_CPU0_P2_TX_DN(3)

Q_CAP_DIFFBUS_C0201-DIFF BUS_0.22UF,6.3V,20%,X6S,SA  I29  C861
   1 P5E_CPU0_P2_TX_C_DP<4>      1 @T6G_MB_LIB.T6G(SCH_1):P5E_CPU0_P2_TX_C_DP(4)
   2 P5E_CPU0_P2_TX_DP<4>      2 @T6G_MB_LIB.T6G(SCH_1):P5E_CPU0_P2_TX_DP(4)

Q_CAP_DIFFBUS_C0201-DIFF BUS_0.22UF,6.3V,20%,X6S,SA  I30  C860
   1 P5E_CPU0_P2_TX_C_DN<4>      1 @T6G_MB_LIB.T6G(SCH_1):P5E_CPU0_P2_TX_C_DN(4)
   2 P5E_CPU0_P2_TX_DN<4>      2 @T6G_MB_LIB.T6G(SCH_1):P5E_CPU0_P2_TX_DN(4)

Q_CAP_DIFFBUS_C0201-DIFF BUS_0.22UF,6.3V,20%,X6S,SA  I36  C859
   1 P5E_CPU0_P2_TX_C_DP<5>      1 @T6G_MB_LIB.T6G(SCH_1):P5E_CPU0_P2_TX_C_DP(5)
   2 P5E_CPU0_P2_TX_DP<5>      2 @T6G_MB_LIB.T6G(SCH_1):P5E_CPU0_P2_TX_DP(5)

Q_CAP_DIFFBUS_C0201-DIFF BUS_0.22UF,6.3V,20%,X6S,SA  I37  C858
   1 P5E_CPU0_P2_TX_C_DN<5>      1 @T6G_MB_LIB.T6G(SCH_1):P5E_CPU0_P2_TX_C_DN(5)
   2 P5E_CPU0_P2_TX_DN<5>      2 @T6G_MB_LIB.T6G(SCH_1):P5E_CPU0_P2_TX_DN(5)

Q_CAP_DIFFBUS_C0201-DIFF BUS_0.22UF,6.3V,20%,X6S,SA  I38  C857
   1 P5E_CPU0_P2_TX_C_DP<6>      1 @T6G_MB_LIB.T6G(SCH_1):P5E_CPU0_P2_TX_C_DP(6)
   2 P5E_CPU0_P2_TX_DP<6>      2 @T6G_MB_LIB.T6G(SCH_1):P5E_CPU0_P2_TX_DP(6)

Q_CAP_DIFFBUS_C0201-DIFF BUS_0.22UF,6.3V,20%,X6S,SA  I39  C856
   1 P5E_CPU0_P2_TX_C_DN<6>      1 @T6G_MB_LIB.T6G(SCH_1):P5E_CPU0_P2_TX_C_DN(6)
   2 P5E_CPU0_P2_TX_DN<6>      2 @T6G_MB_LIB.T6G(SCH_1):P5E_CPU0_P2_TX_DN(6)

Q_CAP_DIFFBUS_C0201-DIFF BUS_0.22UF,6.3V,20%,X6S,SA  I40  C855
   1 P5E_CPU0_P2_TX_C_DP<7>      1 @T6G_MB_LIB.T6G(SCH_1):P5E_CPU0_P2_TX_C_DP(7)
   2 P5E_CPU0_P2_TX_DP<7>      2 @T6G_MB_LIB.T6G(SCH_1):P5E_CPU0_P2_TX_DP(7)

Q_CAP_DIFFBUS_C0201-DIFF BUS_0.22UF,6.3V,20%,X6S,SA  I41  C854
   1 P5E_CPU0_P2_TX_C_DN<7>      1 @T6G_MB_LIB.T6G(SCH_1):P5E_CPU0_P2_TX_C_DN(7)
   2 P5E_CPU0_P2_TX_DN<7>      2 @T6G_MB_LIB.T6G(SCH_1):P5E_CPU0_P2_TX_DN(7)

Q_CAP_DIFFBUS_C0201-DIFF BUS_0.22UF,6.3V,20%,X6S,SA  I61  C852
   1 P5E_CPU0_P2_TX_C_DN<8>      1 @T6G_MB_LIB.T6G(SCH_1):P5E_CPU0_P2_TX_C_DN(8)
   2 P5E_CPU0_P2_TX_DN<8>      2 @T6G_MB_LIB.T6G(SCH_1):P5E_CPU0_P2_TX_DN(8)

Q_CAP_DIFFBUS_C0201-DIFF BUS_0.22UF,6.3V,20%,X6S,SA  I62  C853
   1 P5E_CPU0_P2_TX_C_DP<8>      1 @T6G_MB_LIB.T6G(SCH_1):P5E_CPU0_P2_TX_C_DP(8)
   2 P5E_CPU0_P2_TX_DP<8>      2 @T6G_MB_LIB.T6G(SCH_1):P5E_CPU0_P2_TX_DP(8)

Q_CAP_DIFFBUS_C0201-DIFF BUS_0.22UF,6.3V,20%,X6S,SA  I63  C851
   1 P5E_CPU0_P2_TX_C_DP<9>      1 @T6G_MB_LIB.T6G(SCH_1):P5E_CPU0_P2_TX_C_DP(9)
   2 P5E_CPU0_P2_TX_DP<9>      2 @T6G_MB_LIB.T6G(SCH_1):P5E_CPU0_P2_TX_DP(9)

Q_CAP_DIFFBUS_C0201-DIFF BUS_0.22UF,6.3V,20%,X6S,SA  I64  C850
   1 P5E_CPU0_P2_TX_C_DN<9>      1 @T6G_MB_LIB.T6G(SCH_1):P5E_CPU0_P2_TX_C_DN(9)
   2 P5E_CPU0_P2_TX_DN<9>      2 @T6G_MB_LIB.T6G(SCH_1):P5E_CPU0_P2_TX_DN(9)

Q_CAP_DIFFBUS_C0201-DIFF BUS_0.22UF,6.3V,20%,X6S,SA  I65  C849
   1 P5E_CPU0_P2_TX_C_DP<10>      1 @T6G_MB_LIB.T6G(SCH_1):P5E_CPU0_P2_TX_C_DP(10)
   2 P5E_CPU0_P2_TX_DP<10>      2 @T6G_MB_LIB.T6G(SCH_1):P5E_CPU0_P2_TX_DP(10)

Q_CAP_DIFFBUS_C0201-DIFF BUS_0.22UF,6.3V,20%,X6S,SA  I66  C848
   1 P5E_CPU0_P2_TX_C_DN<10>      1 @T6G_MB_LIB.T6G(SCH_1):P5E_CPU0_P2_TX_C_DN(10)
   2 P5E_CPU0_P2_TX_DN<10>      2 @T6G_MB_LIB.T6G(SCH_1):P5E_CPU0_P2_TX_DN(10)

Q_CAP_DIFFBUS_C0201-DIFF BUS_0.22UF,6.3V,20%,X6S,SA  I67  C847
   1 P5E_CPU0_P2_TX_C_DP<11>      1 @T6G_MB_LIB.T6G(SCH_1):P5E_CPU0_P2_TX_C_DP(11)
   2 P5E_CPU0_P2_TX_DP<11>      2 @T6G_MB_LIB.T6G(SCH_1):P5E_CPU0_P2_TX_DP(11)

Q_CAP_DIFFBUS_C0201-DIFF BUS_0.22UF,6.3V,20%,X6S,SA  I68  C846
   1 P5E_CPU0_P2_TX_C_DN<11>      1 @T6G_MB_LIB.T6G(SCH_1):P5E_CPU0_P2_TX_C_DN(11)
   2 P5E_CPU0_P2_TX_DN<11>      2 @T6G_MB_LIB.T6G(SCH_1):P5E_CPU0_P2_TX_DN(11)

Q_CAP_DIFFBUS_C0201-DIFF BUS_0.22UF,6.3V,20%,X6S,SA  I69  C845
   1 P5E_CPU0_P2_TX_C_DP<12>      1 @T6G_MB_LIB.T6G(SCH_1):P5E_CPU0_P2_TX_C_DP(12)
   2 P5E_CPU0_P2_TX_DP<12>      2 @T6G_MB_LIB.T6G(SCH_1):P5E_CPU0_P2_TX_DP(12)

Q_CAP_DIFFBUS_C0201-DIFF BUS_0.22UF,6.3V,20%,X6S,SA  I70  C844
   1 P5E_CPU0_P2_TX_C_DN<12>      1 @T6G_MB_LIB.T6G(SCH_1):P5E_CPU0_P2_TX_C_DN(12)
   2 P5E_CPU0_P2_TX_DN<12>      2 @T6G_MB_LIB.T6G(SCH_1):P5E_CPU0_P2_TX_DN(12)

Q_CAP_DIFFBUS_C0201-DIFF BUS_0.22UF,6.3V,20%,X6S,SA  I76  C842
   1 P5E_CPU0_P2_TX_C_DN<13>      1 @T6G_MB_LIB.T6G(SCH_1):P5E_CPU0_P2_TX_C_DN(13)
   2 P5E_CPU0_P2_TX_DN<13>      2 @T6G_MB_LIB.T6G(SCH_1):P5E_CPU0_P2_TX_DN(13)

Q_CAP_DIFFBUS_C0201-DIFF BUS_0.22UF,6.3V,20%,X6S,SA  I77  C843
   1 P5E_CPU0_P2_TX_C_DP<13>      1 @T6G_MB_LIB.T6G(SCH_1):P5E_CPU0_P2_TX_C_DP(13)
   2 P5E_CPU0_P2_TX_DP<13>      2 @T6G_MB_LIB.T6G(SCH_1):P5E_CPU0_P2_TX_DP(13)

Q_CAP_DIFFBUS_C0201-DIFF BUS_0.22UF,6.3V,20%,X6S,SA  I78  C841
   1 P5E_CPU0_P2_TX_C_DP<14>      1 @T6G_MB_LIB.T6G(SCH_1):P5E_CPU0_P2_TX_C_DP(14)
   2 P5E_CPU0_P2_TX_DP<14>      2 @T6G_MB_LIB.T6G(SCH_1):P5E_CPU0_P2_TX_DP(14)

Q_CAP_DIFFBUS_C0201-DIFF BUS_0.22UF,6.3V,20%,X6S,SA  I79  C840
   1 P5E_CPU0_P2_TX_C_DN<14>      1 @T6G_MB_LIB.T6G(SCH_1):P5E_CPU0_P2_TX_C_DN(14)
   2 P5E_CPU0_P2_TX_DN<14>      2 @T6G_MB_LIB.T6G(SCH_1):P5E_CPU0_P2_TX_DN(14)

Q_CAP_DIFFBUS_C0201-DIFF BUS_0.22UF,6.3V,20%,X6S,SA  I80  C838
   1 P5E_CPU0_P2_TX_C_DN<15>      1 @T6G_MB_LIB.T6G(SCH_1):P5E_CPU0_P2_TX_C_DN(15)
   2 P5E_CPU0_P2_TX_DN<15>      2 @T6G_MB_LIB.T6G(SCH_1):P5E_CPU0_P2_TX_DN(15)

Q_CAP_DIFFBUS_C0201-DIFF BUS_0.22UF,6.3V,20%,X6S,SA  I81  C839
   1 P5E_CPU0_P2_TX_C_DP<15>      1 @T6G_MB_LIB.T6G(SCH_1):P5E_CPU0_P2_TX_C_DP(15)
   2 P5E_CPU0_P2_TX_DP<15>      2 @T6G_MB_LIB.T6G(SCH_1):P5E_CPU0_P2_TX_DP(15)

Q_CAP_DIFFBUS_C0201-DIFF BUS_0.22UF,6.3V,20%,X6S,SA  I120  C901
   1 P5E_CPU0_P3_TX_C_DP<0>      1 @T6G_MB_LIB.T6G(SCH_1):P5E_CPU0_P3_TX_C_DP(0)
   2 P5E_CPU0_P3_TX_DP<0>      2 @T6G_MB_LIB.T6G(SCH_1):P5E_CPU0_P3_TX_DP(0)

Q_CAP_DIFFBUS_C0201-DIFF BUS_0.22UF,6.3V,20%,X6S,SA  I121  C900
   1 P5E_CPU0_P3_TX_C_DN<0>      1 @T6G_MB_LIB.T6G(SCH_1):P5E_CPU0_P3_TX_C_DN(0)
   2 P5E_CPU0_P3_TX_DN<0>      2 @T6G_MB_LIB.T6G(SCH_1):P5E_CPU0_P3_TX_DN(0)

Q_CAP_DIFFBUS_C0201-DIFF BUS_0.22UF,6.3V,20%,X6S,SA  I122  C899
   1 P5E_CPU0_P3_TX_C_DP<1>      1 @T6G_MB_LIB.T6G(SCH_1):P5E_CPU0_P3_TX_C_DP(1)
   2 P5E_CPU0_P3_TX_DP<1>      2 @T6G_MB_LIB.T6G(SCH_1):P5E_CPU0_P3_TX_DP(1)

Q_CAP_DIFFBUS_C0201-DIFF BUS_0.22UF,6.3V,20%,X6S,SA  I123  C897
   1 P5E_CPU0_P3_TX_C_DP<2>      1 @T6G_MB_LIB.T6G(SCH_1):P5E_CPU0_P3_TX_C_DP(2)
   2 P5E_CPU0_P3_TX_DP<2>      2 @T6G_MB_LIB.T6G(SCH_1):P5E_CPU0_P3_TX_DP(2)

Q_CAP_DIFFBUS_C0201-DIFF BUS_0.22UF,6.3V,20%,X6S,SA  I124  C896
   1 P5E_CPU0_P3_TX_C_DN<2>      1 @T6G_MB_LIB.T6G(SCH_1):P5E_CPU0_P3_TX_C_DN(2)
   2 P5E_CPU0_P3_TX_DN<2>      2 @T6G_MB_LIB.T6G(SCH_1):P5E_CPU0_P3_TX_DN(2)

Q_CAP_DIFFBUS_C0201-DIFF BUS_0.22UF,6.3V,20%,X6S,SA  I125  C895
   1 P5E_CPU0_P3_TX_C_DP<3>      1 @T6G_MB_LIB.T6G(SCH_1):P5E_CPU0_P3_TX_C_DP(3)
   2 P5E_CPU0_P3_TX_DP<3>      2 @T6G_MB_LIB.T6G(SCH_1):P5E_CPU0_P3_TX_DP(3)

Q_CAP_DIFFBUS_C0201-DIFF BUS_0.22UF,6.3V,20%,X6S,SA  I126  C894
   1 P5E_CPU0_P3_TX_C_DN<3>      1 @T6G_MB_LIB.T6G(SCH_1):P5E_CPU0_P3_TX_C_DN(3)
   2 P5E_CPU0_P3_TX_DN<3>      2 @T6G_MB_LIB.T6G(SCH_1):P5E_CPU0_P3_TX_DN(3)

Q_CAP_DIFFBUS_C0201-DIFF BUS_0.22UF,6.3V,20%,X6S,SA  I127  C892
   1 P5E_CPU0_P3_TX_C_DN<4>      1 @T6G_MB_LIB.T6G(SCH_1):P5E_CPU0_P3_TX_C_DN(4)
   2 P5E_CPU0_P3_TX_DN<4>      2 @T6G_MB_LIB.T6G(SCH_1):P5E_CPU0_P3_TX_DN(4)

Q_CAP_DIFFBUS_C0201-DIFF BUS_0.22UF,6.3V,20%,X6S,SA  I128  C893
   1 P5E_CPU0_P3_TX_C_DP<4>      1 @T6G_MB_LIB.T6G(SCH_1):P5E_CPU0_P3_TX_C_DP(4)
   2 P5E_CPU0_P3_TX_DP<4>      2 @T6G_MB_LIB.T6G(SCH_1):P5E_CPU0_P3_TX_DP(4)

Q_CAP_DIFFBUS_C0201-DIFF BUS_0.22UF,6.3V,20%,X6S,SA  I132  C891
   1 P5E_CPU0_P3_TX_C_DP<5>      1 @T6G_MB_LIB.T6G(SCH_1):P5E_CPU0_P3_TX_C_DP(5)
   2 P5E_CPU0_P3_TX_DP<5>      2 @T6G_MB_LIB.T6G(SCH_1):P5E_CPU0_P3_TX_DP(5)

Q_CAP_DIFFBUS_C0201-DIFF BUS_0.22UF,6.3V,20%,X6S,SA  I133  C890
   1 P5E_CPU0_P3_TX_C_DN<5>      1 @T6G_MB_LIB.T6G(SCH_1):P5E_CPU0_P3_TX_C_DN(5)
   2 P5E_CPU0_P3_TX_DN<5>      2 @T6G_MB_LIB.T6G(SCH_1):P5E_CPU0_P3_TX_DN(5)

Q_CAP_DIFFBUS_C0201-DIFF BUS_0.22UF,6.3V,20%,X6S,SA  I134  C889
   1 P5E_CPU0_P3_TX_C_DP<6>      1 @T6G_MB_LIB.T6G(SCH_1):P5E_CPU0_P3_TX_C_DP(6)
   2 P5E_CPU0_P3_TX_DP<6>      2 @T6G_MB_LIB.T6G(SCH_1):P5E_CPU0_P3_TX_DP(6)

Q_CAP_DIFFBUS_C0201-DIFF BUS_0.22UF,6.3V,20%,X6S,SA  I135  C888
   1 P5E_CPU0_P3_TX_C_DN<6>      1 @T6G_MB_LIB.T6G(SCH_1):P5E_CPU0_P3_TX_C_DN(6)
   2 P5E_CPU0_P3_TX_DN<6>      2 @T6G_MB_LIB.T6G(SCH_1):P5E_CPU0_P3_TX_DN(6)

Q_CAP_DIFFBUS_C0201-DIFF BUS_0.22UF,6.3V,20%,X6S,SA  I136  C887
   1 P5E_CPU0_P3_TX_C_DP<7>      1 @T6G_MB_LIB.T6G(SCH_1):P5E_CPU0_P3_TX_C_DP(7)
   2 P5E_CPU0_P3_TX_DP<7>      2 @T6G_MB_LIB.T6G(SCH_1):P5E_CPU0_P3_TX_DP(7)

Q_CAP_DIFFBUS_C0201-DIFF BUS_0.22UF,6.3V,20%,X6S,SA  I137  C886
   1 P5E_CPU0_P3_TX_C_DN<7>      1 @T6G_MB_LIB.T6G(SCH_1):P5E_CPU0_P3_TX_C_DN(7)
   2 P5E_CPU0_P3_TX_DN<7>      2 @T6G_MB_LIB.T6G(SCH_1):P5E_CPU0_P3_TX_DN(7)

Q_CAP_DIFFBUS_C0201-DIFF BUS_0.22UF,6.3V,20%,X6S,SA  I151  C884
   1 P5E_CPU0_P3_TX_C_DN<8>      1 @T6G_MB_LIB.T6G(SCH_1):P5E_CPU0_P3_TX_C_DN(8)
   2 P5E_CPU0_P3_TX_DN<8>      2 @T6G_MB_LIB.T6G(SCH_1):P5E_CPU0_P3_TX_DN(8)

Q_CAP_DIFFBUS_C0201-DIFF BUS_0.22UF,6.3V,20%,X6S,SA  I152  C885
   1 P5E_CPU0_P3_TX_C_DP<8>      1 @T6G_MB_LIB.T6G(SCH_1):P5E_CPU0_P3_TX_C_DP(8)
   2 P5E_CPU0_P3_TX_DP<8>      2 @T6G_MB_LIB.T6G(SCH_1):P5E_CPU0_P3_TX_DP(8)

Q_CAP_DIFFBUS_C0201-DIFF BUS_0.22UF,6.3V,20%,X6S,SA  I153  C883
   1 P5E_CPU0_P3_TX_C_DP<9>      1 @T6G_MB_LIB.T6G(SCH_1):P5E_CPU0_P3_TX_C_DP(9)
   2 P5E_CPU0_P3_TX_DP<9>      2 @T6G_MB_LIB.T6G(SCH_1):P5E_CPU0_P3_TX_DP(9)

Q_CAP_DIFFBUS_C0201-DIFF BUS_0.22UF,6.3V,20%,X6S,SA  I154  C882
   1 P5E_CPU0_P3_TX_C_DN<9>      1 @T6G_MB_LIB.T6G(SCH_1):P5E_CPU0_P3_TX_C_DN(9)
   2 P5E_CPU0_P3_TX_DN<9>      2 @T6G_MB_LIB.T6G(SCH_1):P5E_CPU0_P3_TX_DN(9)

Q_CAP_DIFFBUS_C0201-DIFF BUS_0.22UF,6.3V,20%,X6S,SA  I155  C881
   1 P5E_CPU0_P3_TX_C_DP<10>      1 @T6G_MB_LIB.T6G(SCH_1):P5E_CPU0_P3_TX_C_DP(10)
   2 P5E_CPU0_P3_TX_DP<10>      2 @T6G_MB_LIB.T6G(SCH_1):P5E_CPU0_P3_TX_DP(10)

Q_CAP_DIFFBUS_C0201-DIFF BUS_0.22UF,6.3V,20%,X6S,SA  I156  C880
   1 P5E_CPU0_P3_TX_C_DN<10>      1 @T6G_MB_LIB.T6G(SCH_1):P5E_CPU0_P3_TX_C_DN(10)
   2 P5E_CPU0_P3_TX_DN<10>      2 @T6G_MB_LIB.T6G(SCH_1):P5E_CPU0_P3_TX_DN(10)

Q_CAP_DIFFBUS_C0201-DIFF BUS_0.22UF,6.3V,20%,X6S,SA  I157  C878
   1 P5E_CPU0_P3_TX_C_DN<11>      1 @T6G_MB_LIB.T6G(SCH_1):P5E_CPU0_P3_TX_C_DN(11)
   2 P5E_CPU0_P3_TX_DN<11>      2 @T6G_MB_LIB.T6G(SCH_1):P5E_CPU0_P3_TX_DN(11)

Q_CAP_DIFFBUS_C0201-DIFF BUS_0.22UF,6.3V,20%,X6S,SA  I158  C879
   1 P5E_CPU0_P3_TX_C_DP<11>      1 @T6G_MB_LIB.T6G(SCH_1):P5E_CPU0_P3_TX_C_DP(11)
   2 P5E_CPU0_P3_TX_DP<11>      2 @T6G_MB_LIB.T6G(SCH_1):P5E_CPU0_P3_TX_DP(11)

Q_CAP_DIFFBUS_C0201-DIFF BUS_0.22UF,6.3V,20%,X6S,SA  I159  C877
   1 P5E_CPU0_P3_TX_C_DP<12>      1 @T6G_MB_LIB.T6G(SCH_1):P5E_CPU0_P3_TX_C_DP(12)
   2 P5E_CPU0_P3_TX_DP<12>      2 @T6G_MB_LIB.T6G(SCH_1):P5E_CPU0_P3_TX_DP(12)

Q_CAP_DIFFBUS_C0201-DIFF BUS_0.22UF,6.3V,20%,X6S,SA  I160  C876
   1 P5E_CPU0_P3_TX_C_DN<12>      1 @T6G_MB_LIB.T6G(SCH_1):P5E_CPU0_P3_TX_C_DN(12)
   2 P5E_CPU0_P3_TX_DN<12>      2 @T6G_MB_LIB.T6G(SCH_1):P5E_CPU0_P3_TX_DN(12)

Q_CAP_DIFFBUS_C0201-DIFF BUS_0.22UF,6.3V,20%,X6S,SA  I164  C875
   1 P5E_CPU0_P3_TX_C_DP<13>      1 @T6G_MB_LIB.T6G(SCH_1):P5E_CPU0_P3_TX_C_DP(13)
   2 P5E_CPU0_P3_TX_DP<13>      2 @T6G_MB_LIB.T6G(SCH_1):P5E_CPU0_P3_TX_DP(13)

Q_CAP_DIFFBUS_C0201-DIFF BUS_0.22UF,6.3V,20%,X6S,SA  I165  C874
   1 P5E_CPU0_P3_TX_C_DN<13>      1 @T6G_MB_LIB.T6G(SCH_1):P5E_CPU0_P3_TX_C_DN(13)
   2 P5E_CPU0_P3_TX_DN<13>      2 @T6G_MB_LIB.T6G(SCH_1):P5E_CPU0_P3_TX_DN(13)

Q_CAP_DIFFBUS_C0201-DIFF BUS_0.22UF,6.3V,20%,X6S,SA  I166  C873
   1 P5E_CPU0_P3_TX_C_DP<14>      1 @T6G_MB_LIB.T6G(SCH_1):P5E_CPU0_P3_TX_C_DP(14)
   2 P5E_CPU0_P3_TX_DP<14>      2 @T6G_MB_LIB.T6G(SCH_1):P5E_CPU0_P3_TX_DP(14)

Q_CAP_DIFFBUS_C0201-DIFF BUS_0.22UF,6.3V,20%,X6S,SA  I167  C872
   1 P5E_CPU0_P3_TX_C_DN<14>      1 @T6G_MB_LIB.T6G(SCH_1):P5E_CPU0_P3_TX_C_DN(14)
   2 P5E_CPU0_P3_TX_DN<14>      2 @T6G_MB_LIB.T6G(SCH_1):P5E_CPU0_P3_TX_DN(14)

Q_CAP_DIFFBUS_C0201-DIFF BUS_0.22UF,6.3V,20%,X6S,SA  I168  C871
   1 P5E_CPU0_P3_TX_C_DP<15>      1 @T6G_MB_LIB.T6G(SCH_1):P5E_CPU0_P3_TX_C_DP(15)
   2 P5E_CPU0_P3_TX_DP<15>      2 @T6G_MB_LIB.T6G(SCH_1):P5E_CPU0_P3_TX_DP(15)

Q_CAP_DIFFBUS_C0201-DIFF BUS_0.22UF,6.3V,20%,X6S,SA  I169  C870
   1 P5E_CPU0_P3_TX_C_DN<15>      1 @T6G_MB_LIB.T6G(SCH_1):P5E_CPU0_P3_TX_C_DN(15)
   2 P5E_CPU0_P3_TX_DN<15>      2 @T6G_MB_LIB.T6G(SCH_1):P5E_CPU0_P3_TX_DN(15)

Q_CAP_DIFFBUS_C0201-DIFF BUS_0.22UF,6.3V,20%,X6S,SA  I206  C898
   1 P5E_CPU0_P3_TX_C_DN<1>      1 @T6G_MB_LIB.T6G(SCH_1):P5E_CPU0_P3_TX_C_DN(1)
   2 P5E_CPU0_P3_TX_DN<1>      2 @T6G_MB_LIB.T6G(SCH_1):P5E_CPU0_P3_TX_DN(1)


DRAWING: @T6G_MB_LIB.T6G(SCH_1):PAGE353 

Q_CAP_DIFFBUS_C0201-DIFF BUS_0.22UF,6.3V,20%,X6S,SA  I229  C1579
   1 P5E_CPU0_G3_TX_C_DP<0>      1 @T6G_MB_LIB.T6G(SCH_1):P5E_CPU0_G3_TX_C_DP(0)
   2 P5E_CPU0_G3_TX_DP<0>      2 @T6G_MB_LIB.T6G(SCH_1):P5E_CPU0_G3_TX_DP(0)

Q_CAP_DIFFBUS_C0201-DIFF BUS_0.22UF,6.3V,20%,X6S,SA  I230  C1578
   1 P5E_CPU0_G3_TX_C_DN<0>      1 @T6G_MB_LIB.T6G(SCH_1):P5E_CPU0_G3_TX_C_DN(0)
   2 P5E_CPU0_G3_TX_DN<0>      2 @T6G_MB_LIB.T6G(SCH_1):P5E_CPU0_G3_TX_DN(0)

Q_CAP_DIFFBUS_C0201-DIFF BUS_0.22UF,6.3V,20%,X6S,SA  I231  C1575
   1 P5E_CPU0_G3_TX_C_DP<2>      1 @T6G_MB_LIB.T6G(SCH_1):P5E_CPU0_G3_TX_C_DP(2)
   2 P5E_CPU0_G3_TX_DP<2>      2 @T6G_MB_LIB.T6G(SCH_1):P5E_CPU0_G3_TX_DP(2)

Q_CAP_DIFFBUS_C0201-DIFF BUS_0.22UF,6.3V,20%,X6S,SA  I232  C1574
   1 P5E_CPU0_G3_TX_C_DN<2>      1 @T6G_MB_LIB.T6G(SCH_1):P5E_CPU0_G3_TX_C_DN(2)
   2 P5E_CPU0_G3_TX_DN<2>      2 @T6G_MB_LIB.T6G(SCH_1):P5E_CPU0_G3_TX_DN(2)

Q_CAP_DIFFBUS_C0201-DIFF BUS_0.22UF,6.3V,20%,X6S,SA  I233  C1573
   1 P5E_CPU0_G3_TX_C_DP<3>      1 @T6G_MB_LIB.T6G(SCH_1):P5E_CPU0_G3_TX_C_DP(3)
   2 P5E_CPU0_G3_TX_DP<3>      2 @T6G_MB_LIB.T6G(SCH_1):P5E_CPU0_G3_TX_DP(3)

Q_CAP_DIFFBUS_C0201-DIFF BUS_0.22UF,6.3V,20%,X6S,SA  I234  C1572
   1 P5E_CPU0_G3_TX_C_DN<3>      1 @T6G_MB_LIB.T6G(SCH_1):P5E_CPU0_G3_TX_C_DN(3)
   2 P5E_CPU0_G3_TX_DN<3>      2 @T6G_MB_LIB.T6G(SCH_1):P5E_CPU0_G3_TX_DN(3)

Q_CAP_DIFFBUS_C0201-DIFF BUS_0.22UF,6.3V,20%,X6S,SA  I235  C1570
   1 P5E_CPU0_G3_TX_C_DN<4>      1 @T6G_MB_LIB.T6G(SCH_1):P5E_CPU0_G3_TX_C_DN(4)
   2 P5E_CPU0_G3_TX_DN<4>      2 @T6G_MB_LIB.T6G(SCH_1):P5E_CPU0_G3_TX_DN(4)

Q_CAP_DIFFBUS_C0201-DIFF BUS_0.22UF,6.3V,20%,X6S,SA  I236  C1571
   1 P5E_CPU0_G3_TX_C_DP<4>      1 @T6G_MB_LIB.T6G(SCH_1):P5E_CPU0_G3_TX_C_DP(4)
   2 P5E_CPU0_G3_TX_DP<4>      2 @T6G_MB_LIB.T6G(SCH_1):P5E_CPU0_G3_TX_DP(4)

Q_CAP_DIFFBUS_C0201-DIFF BUS_0.22UF,6.3V,20%,X6S,SA  I237  C1569
   1 P5E_CPU0_G3_TX_C_DP<5>      1 @T6G_MB_LIB.T6G(SCH_1):P5E_CPU0_G3_TX_C_DP(5)
   2 P5E_CPU0_G3_TX_DP<5>      2 @T6G_MB_LIB.T6G(SCH_1):P5E_CPU0_G3_TX_DP(5)

Q_CAP_DIFFBUS_C0201-DIFF BUS_0.22UF,6.3V,20%,X6S,SA  I238  C1568
   1 P5E_CPU0_G3_TX_C_DN<5>      1 @T6G_MB_LIB.T6G(SCH_1):P5E_CPU0_G3_TX_C_DN(5)
   2 P5E_CPU0_G3_TX_DN<5>      2 @T6G_MB_LIB.T6G(SCH_1):P5E_CPU0_G3_TX_DN(5)

Q_CAP_DIFFBUS_C0201-DIFF BUS_0.22UF,6.3V,20%,X6S,SA  I239  C47
   1 P5E_CPU0_G3_TX_C_DP<6>      1 @T6G_MB_LIB.T6G(SCH_1):P5E_CPU0_G3_TX_C_DP(6)
   2 P5E_CPU0_G3_TX_DP<6>      2 @T6G_MB_LIB.T6G(SCH_1):P5E_CPU0_G3_TX_DP(6)

Q_CAP_DIFFBUS_C0201-DIFF BUS_0.22UF,6.3V,20%,X6S,SA  I240  C1566
   1 P5E_CPU0_G3_TX_C_DN<6>      1 @T6G_MB_LIB.T6G(SCH_1):P5E_CPU0_G3_TX_C_DN(6)
   2 P5E_CPU0_G3_TX_DN<6>      2 @T6G_MB_LIB.T6G(SCH_1):P5E_CPU0_G3_TX_DN(6)

Q_CAP_DIFFBUS_C0201-DIFF BUS_0.22UF,6.3V,20%,X6S,SA  I241  C1565
   1 P5E_CPU0_G3_TX_C_DP<7>      1 @T6G_MB_LIB.T6G(SCH_1):P5E_CPU0_G3_TX_C_DP(7)
   2 P5E_CPU0_G3_TX_DP<7>      2 @T6G_MB_LIB.T6G(SCH_1):P5E_CPU0_G3_TX_DP(7)

Q_CAP_DIFFBUS_C0201-DIFF BUS_0.22UF,6.3V,20%,X6S,SA  I242  C46
   1 P5E_CPU0_G3_TX_C_DN<7>      1 @T6G_MB_LIB.T6G(SCH_1):P5E_CPU0_G3_TX_C_DN(7)
   2 P5E_CPU0_G3_TX_DN<7>      2 @T6G_MB_LIB.T6G(SCH_1):P5E_CPU0_G3_TX_DN(7)

Q_CAP_DIFFBUS_C0201-DIFF BUS_0.22UF,6.3V,20%,X6S,SA  I259  C44
   1 P5E_CPU0_G3_TX_C_DP<8>      1 @T6G_MB_LIB.T6G(SCH_1):P5E_CPU0_G3_TX_C_DP(8)
   2 P5E_CPU0_G3_TX_DP<8>      2 @T6G_MB_LIB.T6G(SCH_1):P5E_CPU0_G3_TX_DP(8)

Q_CAP_DIFFBUS_C0201-DIFF BUS_0.22UF,6.3V,20%,X6S,SA  I260  C1794
   1 P5E_CPU0_G3_TX_C_DN<8>      1 @T6G_MB_LIB.T6G(SCH_1):P5E_CPU0_G3_TX_C_DN(8)
   2 P5E_CPU0_G3_TX_DN<8>      2 @T6G_MB_LIB.T6G(SCH_1):P5E_CPU0_G3_TX_DN(8)

Q_CAP_DIFFBUS_C0201-DIFF BUS_0.22UF,6.3V,20%,X6S,SA  I261  C1793
   1 P5E_CPU0_G3_TX_C_DP<9>      1 @T6G_MB_LIB.T6G(SCH_1):P5E_CPU0_G3_TX_C_DP(9)
   2 P5E_CPU0_G3_TX_DP<9>      2 @T6G_MB_LIB.T6G(SCH_1):P5E_CPU0_G3_TX_DP(9)

Q_CAP_DIFFBUS_C0201-DIFF BUS_0.22UF,6.3V,20%,X6S,SA  I262  C1560
   1 P5E_CPU0_G3_TX_C_DN<9>      1 @T6G_MB_LIB.T6G(SCH_1):P5E_CPU0_G3_TX_C_DN(9)
   2 P5E_CPU0_G3_TX_DN<9>      2 @T6G_MB_LIB.T6G(SCH_1):P5E_CPU0_G3_TX_DN(9)

Q_CAP_DIFFBUS_C0201-DIFF BUS_0.22UF,6.3V,20%,X6S,SA  I263  C1559
   1 P5E_CPU0_G3_TX_C_DP<10>      1 @T6G_MB_LIB.T6G(SCH_1):P5E_CPU0_G3_TX_C_DP(10)
   2 P5E_CPU0_G3_TX_DP<10>      2 @T6G_MB_LIB.T6G(SCH_1):P5E_CPU0_G3_TX_DP(10)

Q_CAP_DIFFBUS_C0201-DIFF BUS_0.22UF,6.3V,20%,X6S,SA  I264  C1558
   1 P5E_CPU0_G3_TX_C_DN<10>      1 @T6G_MB_LIB.T6G(SCH_1):P5E_CPU0_G3_TX_C_DN(10)
   2 P5E_CPU0_G3_TX_DN<10>      2 @T6G_MB_LIB.T6G(SCH_1):P5E_CPU0_G3_TX_DN(10)

Q_CAP_DIFFBUS_C0201-DIFF BUS_0.22UF,6.3V,20%,X6S,SA  I265  C1556
   1 P5E_CPU0_G3_TX_C_DN<11>      1 @T6G_MB_LIB.T6G(SCH_1):P5E_CPU0_G3_TX_C_DN(11)
   2 P5E_CPU0_G3_TX_DN<11>      2 @T6G_MB_LIB.T6G(SCH_1):P5E_CPU0_G3_TX_DN(11)

Q_CAP_DIFFBUS_C0201-DIFF BUS_0.22UF,6.3V,20%,X6S,SA  I266  C1557
   1 P5E_CPU0_G3_TX_C_DP<11>      1 @T6G_MB_LIB.T6G(SCH_1):P5E_CPU0_G3_TX_C_DP(11)
   2 P5E_CPU0_G3_TX_DP<11>      2 @T6G_MB_LIB.T6G(SCH_1):P5E_CPU0_G3_TX_DP(11)

Q_CAP_DIFFBUS_C0201-DIFF BUS_0.22UF,6.3V,20%,X6S,SA  I267  C1555
   1 P5E_CPU0_G3_TX_C_DP<12>      1 @T6G_MB_LIB.T6G(SCH_1):P5E_CPU0_G3_TX_C_DP(12)
   2 P5E_CPU0_G3_TX_DP<12>      2 @T6G_MB_LIB.T6G(SCH_1):P5E_CPU0_G3_TX_DP(12)

Q_CAP_DIFFBUS_C0201-DIFF BUS_0.22UF,6.3V,20%,X6S,SA  I268  C41
   1 P5E_CPU0_G3_TX_C_DN<12>      1 @T6G_MB_LIB.T6G(SCH_1):P5E_CPU0_G3_TX_C_DN(12)
   2 P5E_CPU0_G3_TX_DN<12>      2 @T6G_MB_LIB.T6G(SCH_1):P5E_CPU0_G3_TX_DN(12)

Q_CAP_DIFFBUS_C0201-DIFF BUS_0.22UF,6.3V,20%,X6S,SA  I269  C1553
   1 P5E_CPU0_G3_TX_C_DP<13>      1 @T6G_MB_LIB.T6G(SCH_1):P5E_CPU0_G3_TX_C_DP(13)
   2 P5E_CPU0_G3_TX_DP<13>      2 @T6G_MB_LIB.T6G(SCH_1):P5E_CPU0_G3_TX_DP(13)

Q_CAP_DIFFBUS_C0201-DIFF BUS_0.22UF,6.3V,20%,X6S,SA  I270  C1552
   1 P5E_CPU0_G3_TX_C_DN<13>      1 @T6G_MB_LIB.T6G(SCH_1):P5E_CPU0_G3_TX_C_DN(13)
   2 P5E_CPU0_G3_TX_DN<13>      2 @T6G_MB_LIB.T6G(SCH_1):P5E_CPU0_G3_TX_DN(13)

Q_CAP_DIFFBUS_C0201-DIFF BUS_0.22UF,6.3V,20%,X6S,SA  I271  C1792
   1 P5E_CPU0_G3_TX_C_DP<14>      1 @T6G_MB_LIB.T6G(SCH_1):P5E_CPU0_G3_TX_C_DP(14)
   2 P5E_CPU0_G3_TX_DP<14>      2 @T6G_MB_LIB.T6G(SCH_1):P5E_CPU0_G3_TX_DP(14)

Q_CAP_DIFFBUS_C0201-DIFF BUS_0.22UF,6.3V,20%,X6S,SA  I272  C1550
   1 P5E_CPU0_G3_TX_C_DN<14>      1 @T6G_MB_LIB.T6G(SCH_1):P5E_CPU0_G3_TX_C_DN(14)
   2 P5E_CPU0_G3_TX_DN<14>      2 @T6G_MB_LIB.T6G(SCH_1):P5E_CPU0_G3_TX_DN(14)

Q_CAP_DIFFBUS_C0201-DIFF BUS_0.22UF,6.3V,20%,X6S,SA  I273  C1548
   1 P5E_CPU0_G3_TX_C_DN<15>      1 @T6G_MB_LIB.T6G(SCH_1):P5E_CPU0_G3_TX_C_DN(15)
   2 P5E_CPU0_G3_TX_DN<15>      2 @T6G_MB_LIB.T6G(SCH_1):P5E_CPU0_G3_TX_DN(15)

Q_CAP_DIFFBUS_C0201-DIFF BUS_0.22UF,6.3V,20%,X6S,SA  I274  C1549
   1 P5E_CPU0_G3_TX_C_DP<15>      1 @T6G_MB_LIB.T6G(SCH_1):P5E_CPU0_G3_TX_C_DP(15)
   2 P5E_CPU0_G3_TX_DP<15>      2 @T6G_MB_LIB.T6G(SCH_1):P5E_CPU0_G3_TX_DP(15)

Q_CAP_DIFFBUS_C0201-DIFF BUS_0.22UF,6.3V,20%,X6S,SA  I311  C1577
   1 P5E_CPU0_G3_TX_C_DP<1>      1 @T6G_MB_LIB.T6G(SCH_1):P5E_CPU0_G3_TX_C_DP(1)
   2 P5E_CPU0_G3_TX_DP<1>      2 @T6G_MB_LIB.T6G(SCH_1):P5E_CPU0_G3_TX_DP(1)

Q_CAP_DIFFBUS_C0201-DIFF BUS_0.22UF,6.3V,20%,X6S,SA  I312  C1576
   1 P5E_CPU0_G3_TX_C_DN<1>      1 @T6G_MB_LIB.T6G(SCH_1):P5E_CPU0_G3_TX_C_DN(1)
   2 P5E_CPU0_G3_TX_DN<1>      2 @T6G_MB_LIB.T6G(SCH_1):P5E_CPU0_G3_TX_DN(1)

Q_CAP_DIFFBUS_C0201-DIFF BUS_0.22UF,6.3V,20%,X6S,SA  I333  C836
   1 P5E_CPU1_P0_TX_C_DN<0>      1 @T6G_MB_LIB.T6G(SCH_1):P5E_CPU1_P0_TX_C_DN(0)
   2 P5E_CPU1_P0_TX_DN<0>      2 @T6G_MB_LIB.T6G(SCH_1):P5E_CPU1_P0_TX_DN(0)

Q_CAP_DIFFBUS_C0201-DIFF BUS_0.22UF,6.3V,20%,X6S,SA  I334  C837
   1 P5E_CPU1_P0_TX_C_DP<0>      1 @T6G_MB_LIB.T6G(SCH_1):P5E_CPU1_P0_TX_C_DP(0)
   2 P5E_CPU1_P0_TX_DP<0>      2 @T6G_MB_LIB.T6G(SCH_1):P5E_CPU1_P0_TX_DP(0)

Q_CAP_DIFFBUS_C0201-DIFF BUS_0.22UF,6.3V,20%,X6S,SA  I335  C834
   1 P5E_CPU1_P0_TX_C_DN<1>      1 @T6G_MB_LIB.T6G(SCH_1):P5E_CPU1_P0_TX_C_DN(1)
   2 P5E_CPU1_P0_TX_DN<1>      2 @T6G_MB_LIB.T6G(SCH_1):P5E_CPU1_P0_TX_DN(1)

Q_CAP_DIFFBUS_C0201-DIFF BUS_0.22UF,6.3V,20%,X6S,SA  I336  C835
   1 P5E_CPU1_P0_TX_C_DP<1>      1 @T6G_MB_LIB.T6G(SCH_1):P5E_CPU1_P0_TX_C_DP(1)
   2 P5E_CPU1_P0_TX_DP<1>      2 @T6G_MB_LIB.T6G(SCH_1):P5E_CPU1_P0_TX_DP(1)

Q_CAP_DIFFBUS_C0201-DIFF BUS_0.22UF,6.3V,20%,X6S,SA  I337  C831
   1 P5E_CPU1_P0_TX_C_DP<3>      1 @T6G_MB_LIB.T6G(SCH_1):P5E_CPU1_P0_TX_C_DP(3)
   2 P5E_CPU1_P0_TX_DP<3>      2 @T6G_MB_LIB.T6G(SCH_1):P5E_CPU1_P0_TX_DP(3)

Q_CAP_DIFFBUS_C0201-DIFF BUS_0.22UF,6.3V,20%,X6S,SA  I338  C832
   1 P5E_CPU1_P0_TX_C_DN<2>      1 @T6G_MB_LIB.T6G(SCH_1):P5E_CPU1_P0_TX_C_DN(2)
   2 P5E_CPU1_P0_TX_DN<2>      2 @T6G_MB_LIB.T6G(SCH_1):P5E_CPU1_P0_TX_DN(2)

Q_CAP_DIFFBUS_C0201-DIFF BUS_0.22UF,6.3V,20%,X6S,SA  I339  C833
   1 P5E_CPU1_P0_TX_C_DP<2>      1 @T6G_MB_LIB.T6G(SCH_1):P5E_CPU1_P0_TX_C_DP(2)
   2 P5E_CPU1_P0_TX_DP<2>      2 @T6G_MB_LIB.T6G(SCH_1):P5E_CPU1_P0_TX_DP(2)

Q_CAP_DIFFBUS_C0201-DIFF BUS_0.22UF,6.3V,20%,X6S,SA  I340  C828
   1 P5E_CPU1_P0_TX_C_DN<4>      1 @T6G_MB_LIB.T6G(SCH_1):P5E_CPU1_P0_TX_C_DN(4)
   2 P5E_CPU1_P0_TX_DN<4>      2 @T6G_MB_LIB.T6G(SCH_1):P5E_CPU1_P0_TX_DN(4)

Q_CAP_DIFFBUS_C0201-DIFF BUS_0.22UF,6.3V,20%,X6S,SA  I341  C830
   1 P5E_CPU1_P0_TX_C_DN<3>      1 @T6G_MB_LIB.T6G(SCH_1):P5E_CPU1_P0_TX_C_DN(3)
   2 P5E_CPU1_P0_TX_DN<3>      2 @T6G_MB_LIB.T6G(SCH_1):P5E_CPU1_P0_TX_DN(3)

Q_CAP_DIFFBUS_C0201-DIFF BUS_0.22UF,6.3V,20%,X6S,SA  I342  C829
   1 P5E_CPU1_P0_TX_C_DP<4>      1 @T6G_MB_LIB.T6G(SCH_1):P5E_CPU1_P0_TX_C_DP(4)
   2 P5E_CPU1_P0_TX_DP<4>      2 @T6G_MB_LIB.T6G(SCH_1):P5E_CPU1_P0_TX_DP(4)

Q_CAP_DIFFBUS_C0201-DIFF BUS_0.22UF,6.3V,20%,X6S,SA  I343  C827
   1 P5E_CPU1_P0_TX_C_DP<5>      1 @T6G_MB_LIB.T6G(SCH_1):P5E_CPU1_P0_TX_C_DP(5)
   2 P5E_CPU1_P0_TX_DP<5>      2 @T6G_MB_LIB.T6G(SCH_1):P5E_CPU1_P0_TX_DP(5)

Q_CAP_DIFFBUS_C0201-DIFF BUS_0.22UF,6.3V,20%,X6S,SA  I344  C826
   1 P5E_CPU1_P0_TX_C_DN<5>      1 @T6G_MB_LIB.T6G(SCH_1):P5E_CPU1_P0_TX_C_DN(5)
   2 P5E_CPU1_P0_TX_DN<5>      2 @T6G_MB_LIB.T6G(SCH_1):P5E_CPU1_P0_TX_DN(5)

Q_CAP_DIFFBUS_C0201-DIFF BUS_0.22UF,6.3V,20%,X6S,SA  I345  C822
   1 P5E_CPU1_P0_TX_C_DN<7>      1 @T6G_MB_LIB.T6G(SCH_1):P5E_CPU1_P0_TX_C_DN(7)
   2 P5E_CPU1_P0_TX_DN<7>      2 @T6G_MB_LIB.T6G(SCH_1):P5E_CPU1_P0_TX_DN(7)

Q_CAP_DIFFBUS_C0201-DIFF BUS_0.22UF,6.3V,20%,X6S,SA  I346  C823
   1 P5E_CPU1_P0_TX_C_DP<7>      1 @T6G_MB_LIB.T6G(SCH_1):P5E_CPU1_P0_TX_C_DP(7)
   2 P5E_CPU1_P0_TX_DP<7>      2 @T6G_MB_LIB.T6G(SCH_1):P5E_CPU1_P0_TX_DP(7)

Q_CAP_DIFFBUS_C0201-DIFF BUS_0.22UF,6.3V,20%,X6S,SA  I363  C820
   1 P5E_CPU1_P0_TX_C_DN<8>      1 @T6G_MB_LIB.T6G(SCH_1):P5E_CPU1_P0_TX_C_DN(8)
   2 P5E_CPU1_P0_TX_DN<8>      2 @T6G_MB_LIB.T6G(SCH_1):P5E_CPU1_P0_TX_DN(8)

Q_CAP_DIFFBUS_C0201-DIFF BUS_0.22UF,6.3V,20%,X6S,SA  I364  C821
   1 P5E_CPU1_P0_TX_C_DP<8>      1 @T6G_MB_LIB.T6G(SCH_1):P5E_CPU1_P0_TX_C_DP(8)
   2 P5E_CPU1_P0_TX_DP<8>      2 @T6G_MB_LIB.T6G(SCH_1):P5E_CPU1_P0_TX_DP(8)

Q_CAP_DIFFBUS_C0201-DIFF BUS_0.22UF,6.3V,20%,X6S,SA  I365  C818
   1 P5E_CPU1_P0_TX_C_DN<9>      1 @T6G_MB_LIB.T6G(SCH_1):P5E_CPU1_P0_TX_C_DN(9)
   2 P5E_CPU1_P0_TX_DN<9>      2 @T6G_MB_LIB.T6G(SCH_1):P5E_CPU1_P0_TX_DN(9)

Q_CAP_DIFFBUS_C0201-DIFF BUS_0.22UF,6.3V,20%,X6S,SA  I366  C819
   1 P5E_CPU1_P0_TX_C_DP<9>      1 @T6G_MB_LIB.T6G(SCH_1):P5E_CPU1_P0_TX_C_DP(9)
   2 P5E_CPU1_P0_TX_DP<9>      2 @T6G_MB_LIB.T6G(SCH_1):P5E_CPU1_P0_TX_DP(9)

Q_CAP_DIFFBUS_C0201-DIFF BUS_0.22UF,6.3V,20%,X6S,SA  I367  C817
   1 P5E_CPU1_P0_TX_C_DP<10>      1 @T6G_MB_LIB.T6G(SCH_1):P5E_CPU1_P0_TX_C_DP(10)
   2 P5E_CPU1_P0_TX_DP<10>      2 @T6G_MB_LIB.T6G(SCH_1):P5E_CPU1_P0_TX_DP(10)

Q_CAP_DIFFBUS_C0201-DIFF BUS_0.22UF,6.3V,20%,X6S,SA  I368  C816
   1 P5E_CPU1_P0_TX_C_DN<10>      1 @T6G_MB_LIB.T6G(SCH_1):P5E_CPU1_P0_TX_C_DN(10)
   2 P5E_CPU1_P0_TX_DN<10>      2 @T6G_MB_LIB.T6G(SCH_1):P5E_CPU1_P0_TX_DN(10)

Q_CAP_DIFFBUS_C0201-DIFF BUS_0.22UF,6.3V,20%,X6S,SA  I369  C815
   1 P5E_CPU1_P0_TX_C_DP<11>      1 @T6G_MB_LIB.T6G(SCH_1):P5E_CPU1_P0_TX_C_DP(11)
   2 P5E_CPU1_P0_TX_DP<11>      2 @T6G_MB_LIB.T6G(SCH_1):P5E_CPU1_P0_TX_DP(11)

Q_CAP_DIFFBUS_C0201-DIFF BUS_0.22UF,6.3V,20%,X6S,SA  I370  C814
   1 P5E_CPU1_P0_TX_C_DN<11>      1 @T6G_MB_LIB.T6G(SCH_1):P5E_CPU1_P0_TX_C_DN(11)
   2 P5E_CPU1_P0_TX_DN<11>      2 @T6G_MB_LIB.T6G(SCH_1):P5E_CPU1_P0_TX_DN(11)

Q_CAP_DIFFBUS_C0201-DIFF BUS_0.22UF,6.3V,20%,X6S,SA  I371  C812
   1 P5E_CPU1_P0_TX_C_DN<12>      1 @T6G_MB_LIB.T6G(SCH_1):P5E_CPU1_P0_TX_C_DN(12)
   2 P5E_CPU1_P0_TX_DN<12>      2 @T6G_MB_LIB.T6G(SCH_1):P5E_CPU1_P0_TX_DN(12)

Q_CAP_DIFFBUS_C0201-DIFF BUS_0.22UF,6.3V,20%,X6S,SA  I372  C813
   1 P5E_CPU1_P0_TX_C_DP<12>      1 @T6G_MB_LIB.T6G(SCH_1):P5E_CPU1_P0_TX_C_DP(12)
   2 P5E_CPU1_P0_TX_DP<12>      2 @T6G_MB_LIB.T6G(SCH_1):P5E_CPU1_P0_TX_DP(12)

Q_CAP_DIFFBUS_C0201-DIFF BUS_0.22UF,6.3V,20%,X6S,SA  I373  C811
   1 P5E_CPU1_P0_TX_C_DP<13>      1 @T6G_MB_LIB.T6G(SCH_1):P5E_CPU1_P0_TX_C_DP(13)
   2 P5E_CPU1_P0_TX_DP<13>      2 @T6G_MB_LIB.T6G(SCH_1):P5E_CPU1_P0_TX_DP(13)

Q_CAP_DIFFBUS_C0201-DIFF BUS_0.22UF,6.3V,20%,X6S,SA  I374  C810
   1 P5E_CPU1_P0_TX_C_DN<13>      1 @T6G_MB_LIB.T6G(SCH_1):P5E_CPU1_P0_TX_C_DN(13)
   2 P5E_CPU1_P0_TX_DN<13>      2 @T6G_MB_LIB.T6G(SCH_1):P5E_CPU1_P0_TX_DN(13)

Q_CAP_DIFFBUS_C0201-DIFF BUS_0.22UF,6.3V,20%,X6S,SA  I375  C809
   1 P5E_CPU1_P0_TX_C_DP<14>      1 @T6G_MB_LIB.T6G(SCH_1):P5E_CPU1_P0_TX_C_DP(14)
   2 P5E_CPU1_P0_TX_DP<14>      2 @T6G_MB_LIB.T6G(SCH_1):P5E_CPU1_P0_TX_DP(14)

Q_CAP_DIFFBUS_C0201-DIFF BUS_0.22UF,6.3V,20%,X6S,SA  I376  C808
   1 P5E_CPU1_P0_TX_C_DN<14>      1 @T6G_MB_LIB.T6G(SCH_1):P5E_CPU1_P0_TX_C_DN(14)
   2 P5E_CPU1_P0_TX_DN<14>      2 @T6G_MB_LIB.T6G(SCH_1):P5E_CPU1_P0_TX_DN(14)

Q_CAP_DIFFBUS_C0201-DIFF BUS_0.22UF,6.3V,20%,X6S,SA  I377  C806
   1 P5E_CPU1_P0_TX_C_DN<15>      1 @T6G_MB_LIB.T6G(SCH_1):P5E_CPU1_P0_TX_C_DN(15)
   2 P5E_CPU1_P0_TX_DN<15>      2 @T6G_MB_LIB.T6G(SCH_1):P5E_CPU1_P0_TX_DN(15)

Q_CAP_DIFFBUS_C0201-DIFF BUS_0.22UF,6.3V,20%,X6S,SA  I378  C807
   1 P5E_CPU1_P0_TX_C_DP<15>      1 @T6G_MB_LIB.T6G(SCH_1):P5E_CPU1_P0_TX_C_DP(15)
   2 P5E_CPU1_P0_TX_DP<15>      2 @T6G_MB_LIB.T6G(SCH_1):P5E_CPU1_P0_TX_DP(15)

Q_CAP_DIFFBUS_C0201-DIFF BUS_0.22UF,6.3V,20%,X6S,SA  I415  C825
   1 P5E_CPU1_P0_TX_C_DP<6>      1 @T6G_MB_LIB.T6G(SCH_1):P5E_CPU1_P0_TX_C_DP(6)
   2 P5E_CPU1_P0_TX_DP<6>      2 @T6G_MB_LIB.T6G(SCH_1):P5E_CPU1_P0_TX_DP(6)

Q_CAP_DIFFBUS_C0201-DIFF BUS_0.22UF,6.3V,20%,X6S,SA  I416  C824
   1 P5E_CPU1_P0_TX_C_DN<6>      1 @T6G_MB_LIB.T6G(SCH_1):P5E_CPU1_P0_TX_C_DN(6)
   2 P5E_CPU1_P0_TX_DN<6>      2 @T6G_MB_LIB.T6G(SCH_1):P5E_CPU1_P0_TX_DN(6)


DRAWING: @T6G_MB_LIB.T6G(SCH_1):PAGE354 

Q_CAP_DIFFBUS_C0201-DIFF BUS_0.22UF,6.3V,20%,X6S,SA  I122  C773
   1 P5E_CPU1_P2_TX_C_DP<0>      1 @T6G_MB_LIB.T6G(SCH_1):P5E_CPU1_P2_TX_C_DP(0)
   2 P5E_CPU1_P2_TX_DP<0>      2 @T6G_MB_LIB.T6G(SCH_1):P5E_CPU1_P2_TX_DP(0)

Q_CAP_DIFFBUS_C0201-DIFF BUS_0.22UF,6.3V,20%,X6S,SA  I123  C772
   1 P5E_CPU1_P2_TX_C_DN<0>      1 @T6G_MB_LIB.T6G(SCH_1):P5E_CPU1_P2_TX_C_DN(0)
   2 P5E_CPU1_P2_TX_DN<0>      2 @T6G_MB_LIB.T6G(SCH_1):P5E_CPU1_P2_TX_DN(0)

Q_CAP_DIFFBUS_C0201-DIFF BUS_0.22UF,6.3V,20%,X6S,SA  I124  C771
   1 P5E_CPU1_P2_TX_C_DP<1>      1 @T6G_MB_LIB.T6G(SCH_1):P5E_CPU1_P2_TX_C_DP(1)
   2 P5E_CPU1_P2_TX_DP<1>      2 @T6G_MB_LIB.T6G(SCH_1):P5E_CPU1_P2_TX_DP(1)

Q_CAP_DIFFBUS_C0201-DIFF BUS_0.22UF,6.3V,20%,X6S,SA  I125  C770
   1 P5E_CPU1_P2_TX_C_DN<1>      1 @T6G_MB_LIB.T6G(SCH_1):P5E_CPU1_P2_TX_C_DN(1)
   2 P5E_CPU1_P2_TX_DN<1>      2 @T6G_MB_LIB.T6G(SCH_1):P5E_CPU1_P2_TX_DN(1)

Q_CAP_DIFFBUS_C0201-DIFF BUS_0.22UF,6.3V,20%,X6S,SA  I126  C769
   1 P5E_CPU1_P2_TX_C_DP<2>      1 @T6G_MB_LIB.T6G(SCH_1):P5E_CPU1_P2_TX_C_DP(2)
   2 P5E_CPU1_P2_TX_DP<2>      2 @T6G_MB_LIB.T6G(SCH_1):P5E_CPU1_P2_TX_DP(2)

Q_CAP_DIFFBUS_C0201-DIFF BUS_0.22UF,6.3V,20%,X6S,SA  I127  C768
   1 P5E_CPU1_P2_TX_C_DN<2>      1 @T6G_MB_LIB.T6G(SCH_1):P5E_CPU1_P2_TX_C_DN(2)
   2 P5E_CPU1_P2_TX_DN<2>      2 @T6G_MB_LIB.T6G(SCH_1):P5E_CPU1_P2_TX_DN(2)

Q_CAP_DIFFBUS_C0201-DIFF BUS_0.22UF,6.3V,20%,X6S,SA  I128  C767
   1 P5E_CPU1_P2_TX_C_DP<3>      1 @T6G_MB_LIB.T6G(SCH_1):P5E_CPU1_P2_TX_C_DP(3)
   2 P5E_CPU1_P2_TX_DP<3>      2 @T6G_MB_LIB.T6G(SCH_1):P5E_CPU1_P2_TX_DP(3)

Q_CAP_DIFFBUS_C0201-DIFF BUS_0.22UF,6.3V,20%,X6S,SA  I129  C766
   1 P5E_CPU1_P2_TX_C_DN<3>      1 @T6G_MB_LIB.T6G(SCH_1):P5E_CPU1_P2_TX_C_DN(3)
   2 P5E_CPU1_P2_TX_DN<3>      2 @T6G_MB_LIB.T6G(SCH_1):P5E_CPU1_P2_TX_DN(3)

Q_CAP_DIFFBUS_C0201-DIFF BUS_0.22UF,6.3V,20%,X6S,SA  I130  C764
   1 P5E_CPU1_P2_TX_C_DN<4>      1 @T6G_MB_LIB.T6G(SCH_1):P5E_CPU1_P2_TX_C_DN(4)
   2 P5E_CPU1_P2_TX_DN<4>      2 @T6G_MB_LIB.T6G(SCH_1):P5E_CPU1_P2_TX_DN(4)

Q_CAP_DIFFBUS_C0201-DIFF BUS_0.22UF,6.3V,20%,X6S,SA  I131  C765
   1 P5E_CPU1_P2_TX_C_DP<4>      1 @T6G_MB_LIB.T6G(SCH_1):P5E_CPU1_P2_TX_C_DP(4)
   2 P5E_CPU1_P2_TX_DP<4>      2 @T6G_MB_LIB.T6G(SCH_1):P5E_CPU1_P2_TX_DP(4)

Q_CAP_DIFFBUS_C0201-DIFF BUS_0.22UF,6.3V,20%,X6S,SA  I135  C763
   1 P5E_CPU1_P2_TX_C_DP<5>      1 @T6G_MB_LIB.T6G(SCH_1):P5E_CPU1_P2_TX_C_DP(5)
   2 P5E_CPU1_P2_TX_DP<5>      2 @T6G_MB_LIB.T6G(SCH_1):P5E_CPU1_P2_TX_DP(5)

Q_CAP_DIFFBUS_C0201-DIFF BUS_0.22UF,6.3V,20%,X6S,SA  I136  C762
   1 P5E_CPU1_P2_TX_C_DN<5>      1 @T6G_MB_LIB.T6G(SCH_1):P5E_CPU1_P2_TX_C_DN(5)
   2 P5E_CPU1_P2_TX_DN<5>      2 @T6G_MB_LIB.T6G(SCH_1):P5E_CPU1_P2_TX_DN(5)

Q_CAP_DIFFBUS_C0201-DIFF BUS_0.22UF,6.3V,20%,X6S,SA  I137  C761
   1 P5E_CPU1_P2_TX_C_DP<6>      1 @T6G_MB_LIB.T6G(SCH_1):P5E_CPU1_P2_TX_C_DP(6)
   2 P5E_CPU1_P2_TX_DP<6>      2 @T6G_MB_LIB.T6G(SCH_1):P5E_CPU1_P2_TX_DP(6)

Q_CAP_DIFFBUS_C0201-DIFF BUS_0.22UF,6.3V,20%,X6S,SA  I138  C760
   1 P5E_CPU1_P2_TX_C_DN<6>      1 @T6G_MB_LIB.T6G(SCH_1):P5E_CPU1_P2_TX_C_DN(6)
   2 P5E_CPU1_P2_TX_DN<6>      2 @T6G_MB_LIB.T6G(SCH_1):P5E_CPU1_P2_TX_DN(6)

Q_CAP_DIFFBUS_C0201-DIFF BUS_0.22UF,6.3V,20%,X6S,SA  I139  C759
   1 P5E_CPU1_P2_TX_C_DP<7>      1 @T6G_MB_LIB.T6G(SCH_1):P5E_CPU1_P2_TX_C_DP(7)
   2 P5E_CPU1_P2_TX_DP<7>      2 @T6G_MB_LIB.T6G(SCH_1):P5E_CPU1_P2_TX_DP(7)

Q_CAP_DIFFBUS_C0201-DIFF BUS_0.22UF,6.3V,20%,X6S,SA  I140  C758
   1 P5E_CPU1_P2_TX_C_DN<7>      1 @T6G_MB_LIB.T6G(SCH_1):P5E_CPU1_P2_TX_C_DN(7)
   2 P5E_CPU1_P2_TX_DN<7>      2 @T6G_MB_LIB.T6G(SCH_1):P5E_CPU1_P2_TX_DN(7)

Q_CAP_DIFFBUS_C0201-DIFF BUS_0.22UF,6.3V,20%,X6S,SA  I154  C756
   1 P5E_CPU1_P2_TX_C_DN<8>      1 @T6G_MB_LIB.T6G(SCH_1):P5E_CPU1_P2_TX_C_DN(8)
   2 P5E_CPU1_P2_TX_DN<8>      2 @T6G_MB_LIB.T6G(SCH_1):P5E_CPU1_P2_TX_DN(8)

Q_CAP_DIFFBUS_C0201-DIFF BUS_0.22UF,6.3V,20%,X6S,SA  I155  C757
   1 P5E_CPU1_P2_TX_C_DP<8>      1 @T6G_MB_LIB.T6G(SCH_1):P5E_CPU1_P2_TX_C_DP(8)
   2 P5E_CPU1_P2_TX_DP<8>      2 @T6G_MB_LIB.T6G(SCH_1):P5E_CPU1_P2_TX_DP(8)

Q_CAP_DIFFBUS_C0201-DIFF BUS_0.22UF,6.3V,20%,X6S,SA  I156  C755
   1 P5E_CPU1_P2_TX_C_DP<9>      1 @T6G_MB_LIB.T6G(SCH_1):P5E_CPU1_P2_TX_C_DP(9)
   2 P5E_CPU1_P2_TX_DP<9>      2 @T6G_MB_LIB.T6G(SCH_1):P5E_CPU1_P2_TX_DP(9)

Q_CAP_DIFFBUS_C0201-DIFF BUS_0.22UF,6.3V,20%,X6S,SA  I157  C754
   1 P5E_CPU1_P2_TX_C_DN<9>      1 @T6G_MB_LIB.T6G(SCH_1):P5E_CPU1_P2_TX_C_DN(9)
   2 P5E_CPU1_P2_TX_DN<9>      2 @T6G_MB_LIB.T6G(SCH_1):P5E_CPU1_P2_TX_DN(9)

Q_CAP_DIFFBUS_C0201-DIFF BUS_0.22UF,6.3V,20%,X6S,SA  I158  C753
   1 P5E_CPU1_P2_TX_C_DP<10>      1 @T6G_MB_LIB.T6G(SCH_1):P5E_CPU1_P2_TX_C_DP(10)
   2 P5E_CPU1_P2_TX_DP<10>      2 @T6G_MB_LIB.T6G(SCH_1):P5E_CPU1_P2_TX_DP(10)

Q_CAP_DIFFBUS_C0201-DIFF BUS_0.22UF,6.3V,20%,X6S,SA  I159  C752
   1 P5E_CPU1_P2_TX_C_DN<10>      1 @T6G_MB_LIB.T6G(SCH_1):P5E_CPU1_P2_TX_C_DN(10)
   2 P5E_CPU1_P2_TX_DN<10>      2 @T6G_MB_LIB.T6G(SCH_1):P5E_CPU1_P2_TX_DN(10)

Q_CAP_DIFFBUS_C0201-DIFF BUS_0.22UF,6.3V,20%,X6S,SA  I160  C750
   1 P5E_CPU1_P2_TX_C_DN<11>      1 @T6G_MB_LIB.T6G(SCH_1):P5E_CPU1_P2_TX_C_DN(11)
   2 P5E_CPU1_P2_TX_DN<11>      2 @T6G_MB_LIB.T6G(SCH_1):P5E_CPU1_P2_TX_DN(11)

Q_CAP_DIFFBUS_C0201-DIFF BUS_0.22UF,6.3V,20%,X6S,SA  I161  C751
   1 P5E_CPU1_P2_TX_C_DP<11>      1 @T6G_MB_LIB.T6G(SCH_1):P5E_CPU1_P2_TX_C_DP(11)
   2 P5E_CPU1_P2_TX_DP<11>      2 @T6G_MB_LIB.T6G(SCH_1):P5E_CPU1_P2_TX_DP(11)

Q_CAP_DIFFBUS_C0201-DIFF BUS_0.22UF,6.3V,20%,X6S,SA  I162  C749
   1 P5E_CPU1_P2_TX_C_DP<12>      1 @T6G_MB_LIB.T6G(SCH_1):P5E_CPU1_P2_TX_C_DP(12)
   2 P5E_CPU1_P2_TX_DP<12>      2 @T6G_MB_LIB.T6G(SCH_1):P5E_CPU1_P2_TX_DP(12)

Q_CAP_DIFFBUS_C0201-DIFF BUS_0.22UF,6.3V,20%,X6S,SA  I163  C748
   1 P5E_CPU1_P2_TX_C_DN<12>      1 @T6G_MB_LIB.T6G(SCH_1):P5E_CPU1_P2_TX_C_DN(12)
   2 P5E_CPU1_P2_TX_DN<12>      2 @T6G_MB_LIB.T6G(SCH_1):P5E_CPU1_P2_TX_DN(12)

Q_CAP_DIFFBUS_C0201-DIFF BUS_0.22UF,6.3V,20%,X6S,SA  I167  C747
   1 P5E_CPU1_P2_TX_C_DP<13>      1 @T6G_MB_LIB.T6G(SCH_1):P5E_CPU1_P2_TX_C_DP(13)
   2 P5E_CPU1_P2_TX_DP<13>      2 @T6G_MB_LIB.T6G(SCH_1):P5E_CPU1_P2_TX_DP(13)

Q_CAP_DIFFBUS_C0201-DIFF BUS_0.22UF,6.3V,20%,X6S,SA  I168  C746
   1 P5E_CPU1_P2_TX_C_DN<13>      1 @T6G_MB_LIB.T6G(SCH_1):P5E_CPU1_P2_TX_C_DN(13)
   2 P5E_CPU1_P2_TX_DN<13>      2 @T6G_MB_LIB.T6G(SCH_1):P5E_CPU1_P2_TX_DN(13)

Q_CAP_DIFFBUS_C0201-DIFF BUS_0.22UF,6.3V,20%,X6S,SA  I169  C745
   1 P5E_CPU1_P2_TX_C_DP<14>      1 @T6G_MB_LIB.T6G(SCH_1):P5E_CPU1_P2_TX_C_DP(14)
   2 P5E_CPU1_P2_TX_DP<14>      2 @T6G_MB_LIB.T6G(SCH_1):P5E_CPU1_P2_TX_DP(14)

Q_CAP_DIFFBUS_C0201-DIFF BUS_0.22UF,6.3V,20%,X6S,SA  I170  C744
   1 P5E_CPU1_P2_TX_C_DN<14>      1 @T6G_MB_LIB.T6G(SCH_1):P5E_CPU1_P2_TX_C_DN(14)
   2 P5E_CPU1_P2_TX_DN<14>      2 @T6G_MB_LIB.T6G(SCH_1):P5E_CPU1_P2_TX_DN(14)

Q_CAP_DIFFBUS_C0201-DIFF BUS_0.22UF,6.3V,20%,X6S,SA  I171  C743
   1 P5E_CPU1_P2_TX_C_DP<15>      1 @T6G_MB_LIB.T6G(SCH_1):P5E_CPU1_P2_TX_C_DP(15)
   2 P5E_CPU1_P2_TX_DP<15>      2 @T6G_MB_LIB.T6G(SCH_1):P5E_CPU1_P2_TX_DP(15)

Q_CAP_DIFFBUS_C0201-DIFF BUS_0.22UF,6.3V,20%,X6S,SA  I172  C742
   1 P5E_CPU1_P2_TX_C_DN<15>      1 @T6G_MB_LIB.T6G(SCH_1):P5E_CPU1_P2_TX_C_DN(15)
   2 P5E_CPU1_P2_TX_DN<15>      2 @T6G_MB_LIB.T6G(SCH_1):P5E_CPU1_P2_TX_DN(15)

Q_CAP_DIFFBUS_C0201-DIFF BUS_0.22UF,6.3V,20%,X6S,SA  I229  C740
   1 P5E_CPU1_P1_TX_C_DN<0>      1 @T6G_MB_LIB.T6G(SCH_1):P5E_CPU1_P1_TX_C_DN(0)
   2 P5E_CPU1_P1_TX_DN<0>      2 @T6G_MB_LIB.T6G(SCH_1):P5E_CPU1_P1_TX_DN(0)

Q_CAP_DIFFBUS_C0201-DIFF BUS_0.22UF,6.3V,20%,X6S,SA  I230  C741
   1 P5E_CPU1_P1_TX_C_DP<0>      1 @T6G_MB_LIB.T6G(SCH_1):P5E_CPU1_P1_TX_C_DP(0)
   2 P5E_CPU1_P1_TX_DP<0>      2 @T6G_MB_LIB.T6G(SCH_1):P5E_CPU1_P1_TX_DP(0)

Q_CAP_DIFFBUS_C0201-DIFF BUS_0.22UF,6.3V,20%,X6S,SA  I231  C739
   1 P5E_CPU1_P1_TX_C_DP<1>      1 @T6G_MB_LIB.T6G(SCH_1):P5E_CPU1_P1_TX_C_DP(1)
   2 P5E_CPU1_P1_TX_DP<1>      2 @T6G_MB_LIB.T6G(SCH_1):P5E_CPU1_P1_TX_DP(1)

Q_CAP_DIFFBUS_C0201-DIFF BUS_0.22UF,6.3V,20%,X6S,SA  I232  C738
   1 P5E_CPU1_P1_TX_C_DN<1>      1 @T6G_MB_LIB.T6G(SCH_1):P5E_CPU1_P1_TX_C_DN(1)
   2 P5E_CPU1_P1_TX_DN<1>      2 @T6G_MB_LIB.T6G(SCH_1):P5E_CPU1_P1_TX_DN(1)

Q_CAP_DIFFBUS_C0201-DIFF BUS_0.22UF,6.3V,20%,X6S,SA  I233  C737
   1 P5E_CPU1_P1_TX_C_DP<2>      1 @T6G_MB_LIB.T6G(SCH_1):P5E_CPU1_P1_TX_C_DP(2)
   2 P5E_CPU1_P1_TX_DP<2>      2 @T6G_MB_LIB.T6G(SCH_1):P5E_CPU1_P1_TX_DP(2)

Q_CAP_DIFFBUS_C0201-DIFF BUS_0.22UF,6.3V,20%,X6S,SA  I234  C736
   1 P5E_CPU1_P1_TX_C_DN<2>      1 @T6G_MB_LIB.T6G(SCH_1):P5E_CPU1_P1_TX_C_DN(2)
   2 P5E_CPU1_P1_TX_DN<2>      2 @T6G_MB_LIB.T6G(SCH_1):P5E_CPU1_P1_TX_DN(2)

Q_CAP_DIFFBUS_C0201-DIFF BUS_0.22UF,6.3V,20%,X6S,SA  I235  C734
   1 P5E_CPU1_P1_TX_C_DN<3>      1 @T6G_MB_LIB.T6G(SCH_1):P5E_CPU1_P1_TX_C_DN(3)
   2 P5E_CPU1_P1_TX_DN<3>      2 @T6G_MB_LIB.T6G(SCH_1):P5E_CPU1_P1_TX_DN(3)

Q_CAP_DIFFBUS_C0201-DIFF BUS_0.22UF,6.3V,20%,X6S,SA  I236  C735
   1 P5E_CPU1_P1_TX_C_DP<3>      1 @T6G_MB_LIB.T6G(SCH_1):P5E_CPU1_P1_TX_C_DP(3)
   2 P5E_CPU1_P1_TX_DP<3>      2 @T6G_MB_LIB.T6G(SCH_1):P5E_CPU1_P1_TX_DP(3)

Q_CAP_DIFFBUS_C0201-DIFF BUS_0.22UF,6.3V,20%,X6S,SA  I237  C733
   1 P5E_CPU1_P1_TX_C_DP<4>      1 @T6G_MB_LIB.T6G(SCH_1):P5E_CPU1_P1_TX_C_DP(4)
   2 P5E_CPU1_P1_TX_DP<4>      2 @T6G_MB_LIB.T6G(SCH_1):P5E_CPU1_P1_TX_DP(4)

Q_CAP_DIFFBUS_C0201-DIFF BUS_0.22UF,6.3V,20%,X6S,SA  I246  C732
   1 P5E_CPU1_P1_TX_C_DN<4>      1 @T6G_MB_LIB.T6G(SCH_1):P5E_CPU1_P1_TX_C_DN(4)
   2 P5E_CPU1_P1_TX_DN<4>      2 @T6G_MB_LIB.T6G(SCH_1):P5E_CPU1_P1_TX_DN(4)

Q_CAP_DIFFBUS_C0201-DIFF BUS_0.22UF,6.3V,20%,X6S,SA  I247  C731
   1 P5E_CPU1_P1_TX_C_DP<5>      1 @T6G_MB_LIB.T6G(SCH_1):P5E_CPU1_P1_TX_C_DP(5)
   2 P5E_CPU1_P1_TX_DP<5>      2 @T6G_MB_LIB.T6G(SCH_1):P5E_CPU1_P1_TX_DP(5)

Q_CAP_DIFFBUS_C0201-DIFF BUS_0.22UF,6.3V,20%,X6S,SA  I248  C730
   1 P5E_CPU1_P1_TX_C_DN<5>      1 @T6G_MB_LIB.T6G(SCH_1):P5E_CPU1_P1_TX_C_DN(5)
   2 P5E_CPU1_P1_TX_DN<5>      2 @T6G_MB_LIB.T6G(SCH_1):P5E_CPU1_P1_TX_DN(5)

Q_CAP_DIFFBUS_C0201-DIFF BUS_0.22UF,6.3V,20%,X6S,SA  I249  C729
   1 P5E_CPU1_P1_TX_C_DP<6>      1 @T6G_MB_LIB.T6G(SCH_1):P5E_CPU1_P1_TX_C_DP(6)
   2 P5E_CPU1_P1_TX_DP<6>      2 @T6G_MB_LIB.T6G(SCH_1):P5E_CPU1_P1_TX_DP(6)

Q_CAP_DIFFBUS_C0201-DIFF BUS_0.22UF,6.3V,20%,X6S,SA  I250  C728
   1 P5E_CPU1_P1_TX_C_DN<6>      1 @T6G_MB_LIB.T6G(SCH_1):P5E_CPU1_P1_TX_C_DN(6)
   2 P5E_CPU1_P1_TX_DN<6>      2 @T6G_MB_LIB.T6G(SCH_1):P5E_CPU1_P1_TX_DN(6)

Q_CAP_DIFFBUS_C0201-DIFF BUS_0.22UF,6.3V,20%,X6S,SA  I251  C727
   1 P5E_CPU1_P1_TX_C_DP<7>      1 @T6G_MB_LIB.T6G(SCH_1):P5E_CPU1_P1_TX_C_DP(7)
   2 P5E_CPU1_P1_TX_DP<7>      2 @T6G_MB_LIB.T6G(SCH_1):P5E_CPU1_P1_TX_DP(7)

Q_CAP_DIFFBUS_C0201-DIFF BUS_0.22UF,6.3V,20%,X6S,SA  I274  C725
   1 P5E_CPU1_P1_TX_C_DP<8>      1 @T6G_MB_LIB.T6G(SCH_1):P5E_CPU1_P1_TX_C_DP(8)
   2 P5E_CPU1_P1_TX_DP<8>      2 @T6G_MB_LIB.T6G(SCH_1):P5E_CPU1_P1_TX_DP(8)

Q_CAP_DIFFBUS_C0201-DIFF BUS_0.22UF,6.3V,20%,X6S,SA  I275  C724
   1 P5E_CPU1_P1_TX_C_DN<8>      1 @T6G_MB_LIB.T6G(SCH_1):P5E_CPU1_P1_TX_C_DN(8)
   2 P5E_CPU1_P1_TX_DN<8>      2 @T6G_MB_LIB.T6G(SCH_1):P5E_CPU1_P1_TX_DN(8)

Q_CAP_DIFFBUS_C0201-DIFF BUS_0.22UF,6.3V,20%,X6S,SA  I276  C722
   1 P5E_CPU1_P1_TX_C_DN<9>      1 @T6G_MB_LIB.T6G(SCH_1):P5E_CPU1_P1_TX_C_DN(9)
   2 P5E_CPU1_P1_TX_DN<9>      2 @T6G_MB_LIB.T6G(SCH_1):P5E_CPU1_P1_TX_DN(9)

Q_CAP_DIFFBUS_C0201-DIFF BUS_0.22UF,6.3V,20%,X6S,SA  I277  C723
   1 P5E_CPU1_P1_TX_C_DP<9>      1 @T6G_MB_LIB.T6G(SCH_1):P5E_CPU1_P1_TX_C_DP(9)
   2 P5E_CPU1_P1_TX_DP<9>      2 @T6G_MB_LIB.T6G(SCH_1):P5E_CPU1_P1_TX_DP(9)

Q_CAP_DIFFBUS_C0201-DIFF BUS_0.22UF,6.3V,20%,X6S,SA  I278  C721
   1 P5E_CPU1_P1_TX_C_DP<10>      1 @T6G_MB_LIB.T6G(SCH_1):P5E_CPU1_P1_TX_C_DP(10)
   2 P5E_CPU1_P1_TX_DP<10>      2 @T6G_MB_LIB.T6G(SCH_1):P5E_CPU1_P1_TX_DP(10)

Q_CAP_DIFFBUS_C0201-DIFF BUS_0.22UF,6.3V,20%,X6S,SA  I279  C720
   1 P5E_CPU1_P1_TX_C_DN<10>      1 @T6G_MB_LIB.T6G(SCH_1):P5E_CPU1_P1_TX_C_DN(10)
   2 P5E_CPU1_P1_TX_DN<10>      2 @T6G_MB_LIB.T6G(SCH_1):P5E_CPU1_P1_TX_DN(10)

Q_CAP_DIFFBUS_C0201-DIFF BUS_0.22UF,6.3V,20%,X6S,SA  I280  C719
   1 P5E_CPU1_P1_TX_C_DP<11>      1 @T6G_MB_LIB.T6G(SCH_1):P5E_CPU1_P1_TX_C_DP(11)
   2 P5E_CPU1_P1_TX_DP<11>      2 @T6G_MB_LIB.T6G(SCH_1):P5E_CPU1_P1_TX_DP(11)

Q_CAP_DIFFBUS_C0201-DIFF BUS_0.22UF,6.3V,20%,X6S,SA  I281  C718
   1 P5E_CPU1_P1_TX_C_DN<11>      1 @T6G_MB_LIB.T6G(SCH_1):P5E_CPU1_P1_TX_C_DN(11)
   2 P5E_CPU1_P1_TX_DN<11>      2 @T6G_MB_LIB.T6G(SCH_1):P5E_CPU1_P1_TX_DN(11)

Q_CAP_DIFFBUS_C0201-DIFF BUS_0.22UF,6.3V,20%,X6S,SA  I282  C717
   1 P5E_CPU1_P1_TX_C_DP<12>      1 @T6G_MB_LIB.T6G(SCH_1):P5E_CPU1_P1_TX_C_DP(12)
   2 P5E_CPU1_P1_TX_DP<12>      2 @T6G_MB_LIB.T6G(SCH_1):P5E_CPU1_P1_TX_DP(12)

Q_CAP_DIFFBUS_C0201-DIFF BUS_0.22UF,6.3V,20%,X6S,SA  I283  C716
   1 P5E_CPU1_P1_TX_C_DN<12>      1 @T6G_MB_LIB.T6G(SCH_1):P5E_CPU1_P1_TX_C_DN(12)
   2 P5E_CPU1_P1_TX_DN<12>      2 @T6G_MB_LIB.T6G(SCH_1):P5E_CPU1_P1_TX_DN(12)

Q_CAP_DIFFBUS_C0201-DIFF BUS_0.22UF,6.3V,20%,X6S,SA  I294  C715
   1 P5E_CPU1_P1_TX_C_DP<13>      1 @T6G_MB_LIB.T6G(SCH_1):P5E_CPU1_P1_TX_C_DP(13)
   2 P5E_CPU1_P1_TX_DP<13>      2 @T6G_MB_LIB.T6G(SCH_1):P5E_CPU1_P1_TX_DP(13)

Q_CAP_DIFFBUS_C0201-DIFF BUS_0.22UF,6.3V,20%,X6S,SA  I295  C714
   1 P5E_CPU1_P1_TX_C_DN<13>      1 @T6G_MB_LIB.T6G(SCH_1):P5E_CPU1_P1_TX_C_DN(13)
   2 P5E_CPU1_P1_TX_DN<13>      2 @T6G_MB_LIB.T6G(SCH_1):P5E_CPU1_P1_TX_DN(13)

Q_CAP_DIFFBUS_C0201-DIFF BUS_0.22UF,6.3V,20%,X6S,SA  I296  C712
   1 P5E_CPU1_P1_TX_C_DN<14>      1 @T6G_MB_LIB.T6G(SCH_1):P5E_CPU1_P1_TX_C_DN(14)
   2 P5E_CPU1_P1_TX_DN<14>      2 @T6G_MB_LIB.T6G(SCH_1):P5E_CPU1_P1_TX_DN(14)

Q_CAP_DIFFBUS_C0201-DIFF BUS_0.22UF,6.3V,20%,X6S,SA  I297  C713
   1 P5E_CPU1_P1_TX_C_DP<14>      1 @T6G_MB_LIB.T6G(SCH_1):P5E_CPU1_P1_TX_C_DP(14)
   2 P5E_CPU1_P1_TX_DP<14>      2 @T6G_MB_LIB.T6G(SCH_1):P5E_CPU1_P1_TX_DP(14)

Q_CAP_DIFFBUS_C0201-DIFF BUS_0.22UF,6.3V,20%,X6S,SA  I298  C711
   1 P5E_CPU1_P1_TX_C_DP<15>      1 @T6G_MB_LIB.T6G(SCH_1):P5E_CPU1_P1_TX_C_DP(15)
   2 P5E_CPU1_P1_TX_DP<15>      2 @T6G_MB_LIB.T6G(SCH_1):P5E_CPU1_P1_TX_DP(15)

Q_CAP_DIFFBUS_C0201-DIFF BUS_0.22UF,6.3V,20%,X6S,SA  I299  C710
   1 P5E_CPU1_P1_TX_C_DN<15>      1 @T6G_MB_LIB.T6G(SCH_1):P5E_CPU1_P1_TX_C_DN(15)
   2 P5E_CPU1_P1_TX_DN<15>      2 @T6G_MB_LIB.T6G(SCH_1):P5E_CPU1_P1_TX_DN(15)

Q_CAP_DIFFBUS_C0201-DIFF BUS_0.22UF,6.3V,20%,X6S,SA  I312  C726
   1 P5E_CPU1_P1_TX_C_DN<7>      1 @T6G_MB_LIB.T6G(SCH_1):P5E_CPU1_P1_TX_C_DN(7)
   2 P5E_CPU1_P1_TX_DN<7>      2 @T6G_MB_LIB.T6G(SCH_1):P5E_CPU1_P1_TX_DN(7)


DRAWING: @T6G_MB_LIB.T6G(SCH_1):PAGE273 

Q_RES_0402LF-0,5%,1/16W,CHIP,CS00002JB13  I4  R333
   1 FM_P5V_EN      A @T6G_MB_LIB.T6G(SCH_1):FM_P5V_EN
   2 VR_P5V_EN      B @T6G_MB_LIB.T6G(SCH_1):VR_P5V_EN

MOSFET_NCH_DUAL-PJT138K,SMLF,IC,BAM138K0003  I9  Q37
   1    GND     S1 @T6G_MB_LIB.T6G(SCH_1):GND
   2 VR_P5V_EN     G1 @T6G_MB_LIB.T6G(SCH_1):VR_P5V_EN
   6 VR_P5V_EN_N     D1 @T6G_MB_LIB.T6G(SCH_1):VR_P5V_EN_N

Q_RES_0402LF-100K,1%,1/16W,CHIP,CS41002FB09  I10  R336
   1 P12V_AUX      A @T6G_MB_LIB.T6G(SCH_1):P12V_AUX
   2 VR_P5V_EN_N      B @T6G_MB_LIB.T6G(SCH_1):VR_P5V_EN_N

MOSFET_NCH_DUAL-PJT138K,SMLF,IC,BAM138K0003  I14  Q37
   3 VR_P5V_EN_D_R1     D2 @T6G_MB_LIB.T6G(SCH_1):VR_P5V_EN_D_R1
   5 VR_P5V_EN_N     G2 @T6G_MB_LIB.T6G(SCH_1):VR_P5V_EN_N
   4    GND     S2 @T6G_MB_LIB.T6G(SCH_1):GND

Q_RES_0402LF-1K,1%,1/16W,CHIP,CS21002FB06  I22  R1654
   1 VR_P5V_EN_D_R      A @T6G_MB_LIB.T6G(SCH_1):VR_P5V_EN_D_R
   2 VR_P5V_EN_D_R1      B @T6G_MB_LIB.T6G(SCH_1):VR_P5V_EN_D_R1

BAT547F-BAT547F,SMLF,IC,BC0BAT54Z53  I27  D1
   1   P3V3      1 @T6G_MB_LIB.T6G(SCH_1):P3V3
   3    P5V      3 @T6G_MB_LIB.T6G(SCH_1):P5V

Q_CAP_C0402-100NF,50V,10%,X7R,CH4106K1B01  I41  C1227
   1    P5V      A @T6G_MB_LIB.T6G(SCH_1):P5V
   2    GND      B @T6G_MB_LIB.T6G(SCH_1):GND

Q_RES_1206LF-243,1%,1/4W,CHIP,CS12436F201  I45  R4638
   1    P5V      A @T6G_MB_LIB.T6G(SCH_1):P5V
   2 VR_P5V_EN_D      B @T6G_MB_LIB.T6G(SCH_1):VR_P5V_EN_D

Q_CAP_C0402-100NF,50V,10%,X7R,CH4106K1B01  I48  C1332
   1 P3V3_AUX      A @T6G_MB_LIB.T6G(SCH_1):P3V3_AUX
   2    GND      B @T6G_MB_LIB.T6G(SCH_1):GND

Q_CAP_C0805-10UF,16V,10%,X6S,CH6103KEA00  I49  C1333
   1 P3V3_AUX      A @T6G_MB_LIB.T6G(SCH_1):P3V3_AUX
   2    GND      B @T6G_MB_LIB.T6G(SCH_1):GND

MOSFET_NCH_1D3S-PSMNR58-30YLH,SMLF,IC,BAMNR580000  I50  Q56
   3   P3V3      3 @T6G_MB_LIB.T6G(SCH_1):P3V3
   5 P3V3_AUX      5 @T6G_MB_LIB.T6G(SCH_1):P3V3_AUX
   2   P3V3      2 @T6G_MB_LIB.T6G(SCH_1):P3V3
   4 SW_P3V3_EN_ISO_R      4 @T6G_MB_LIB.T6G(SCH_1):SW_P3V3_EN_ISO_R
   1   P3V3      1 @T6G_MB_LIB.T6G(SCH_1):P3V3

Q_CAP_C0805-10UF,16V,10%,EMPTY,CH6103KEA00  I51  C60
   1 P3V3_AUX      A @T6G_MB_LIB.T6G(SCH_1):P3V3_AUX
   2    GND      B @T6G_MB_LIB.T6G(SCH_1):GND

Q_CAP_C0805-10UF,16V,10%,X6S,CH6103KEA00  I61  C1340
   1   P3V3      A @T6G_MB_LIB.T6G(SCH_1):P3V3
   2    GND      B @T6G_MB_LIB.T6G(SCH_1):GND

Q_RES_0402LF-100K,1%,1/16W,CHIP,CS41002FB09  I7  R334
   1 VR_P5V_EN      A @T6G_MB_LIB.T6G(SCH_1):VR_P5V_EN
   2    GND      B @T6G_MB_LIB.T6G(SCH_1):GND

Q_RES_0402LF-10K,1%,1/16W,CHIP,CS31002FB08  I15  R335
   1 P12V_AUX      A @T6G_MB_LIB.T6G(SCH_1):P12V_AUX
   2 VR_P5V_EN_D_R      B @T6G_MB_LIB.T6G(SCH_1):VR_P5V_EN_D_R

Q_CAP_C0402-100NF,50V,10%,X7R,CH4106K1B01  I18  C1042
   1 P5V_AUX      A @T6G_MB_LIB.T6G(SCH_1):P5V_AUX
   2    GND      B @T6G_MB_LIB.T6G(SCH_1):GND

Q_CAP_C0805-10UF,16V,10%,X6S,CH6103KEA00  I19  C1170
   1 P5V_AUX      A @T6G_MB_LIB.T6G(SCH_1):P5V_AUX
   2    GND      B @T6G_MB_LIB.T6G(SCH_1):GND

Q_CAP_C0805-10UF,16V,10%,EMPTY,CH6103KEA00  I20  C57
   1 P5V_AUX      A @T6G_MB_LIB.T6G(SCH_1):P5V_AUX
   2    GND      B @T6G_MB_LIB.T6G(SCH_1):GND

MOSFET_NCH_1D3S-PSMNR58-30YLH,SMLF,IC,BAMNR580000  I23  Q57
   3    P5V      3 @T6G_MB_LIB.T6G(SCH_1):P5V
   5 P5V_AUX      5 @T6G_MB_LIB.T6G(SCH_1):P5V_AUX
   2    P5V      2 @T6G_MB_LIB.T6G(SCH_1):P5V
   4 VR_P5V_EN_D_R      4 @T6G_MB_LIB.T6G(SCH_1):VR_P5V_EN_D_R
   1    P5V      1 @T6G_MB_LIB.T6G(SCH_1):P5V

Q_CAP_C0402-0.22UF,25V,10%,X7R,CH4224K1B01  I38  C9226
   1 VR_P5V_EN_D_R      A @T6G_MB_LIB.T6G(SCH_1):VR_P5V_EN_D_R
   2    GND      B @T6G_MB_LIB.T6G(SCH_1):GND

Q_CAP_C0805-10UF,16V,10%,X6S,CH6103KEA00  I43  C1331
   1    P5V      A @T6G_MB_LIB.T6G(SCH_1):P5V
   2    GND      B @T6G_MB_LIB.T6G(SCH_1):GND

Q_CAP_C0402-100NF,50V,10%,X7R,CH4106K1B01  I59  C61
   1   P3V3      A @T6G_MB_LIB.T6G(SCH_1):P3V3
   2    GND      B @T6G_MB_LIB.T6G(SCH_1):GND

MOSFET_NCH_GDS_ESD_PROTECTED-2N7002K,SMLF,IC,BAM70A  I62  U324
   D VR_P5V_EN_D      D @T6G_MB_LIB.T6G(SCH_1):VR_P5V_EN_D
   G VR_P5V_EN_N      G @T6G_MB_LIB.T6G(SCH_1):VR_P5V_EN_N
   S    GND      S @T6G_MB_LIB.T6G(SCH_1):GND

Q_RES_1206LF-243,1%,1/4W,CHIP,CS12436F201  I74  R4639
   1    P5V      A @T6G_MB_LIB.T6G(SCH_1):P5V
   2 VR_P5V_EN_D      B @T6G_MB_LIB.T6G(SCH_1):VR_P5V_EN_D

Q_RES_1206LF-243,1%,1/4W,CHIP,CS12436F201  I75  R4640
   1    P5V      A @T6G_MB_LIB.T6G(SCH_1):P5V
   2 VR_P5V_EN_D      B @T6G_MB_LIB.T6G(SCH_1):VR_P5V_EN_D

Q_RES_1206LF-243,1%,1/4W,CHIP,CS12436F201  I76  R4641
   1    P5V      A @T6G_MB_LIB.T6G(SCH_1):P5V
   2 VR_P5V_EN_D      B @T6G_MB_LIB.T6G(SCH_1):VR_P5V_EN_D

RT9818C44GV-RT9818C-44GV,SMLF,IC,AL009818001  I77  U100
   3    P5V    VDD @T6G_MB_LIB.T6G(SCH_1):P5V
   1 PWRGD_P5V_R RESET# @T6G_MB_LIB.T6G(SCH_1):PWRGD_P5V_R
   2    GND    GND @T6G_MB_LIB.T6G(SCH_1):GND

Q_CAP_C0402-100NF,50V,10%,X7R,CH4106K1B01  I79  C6122
   1    P5V      A @T6G_MB_LIB.T6G(SCH_1):P5V
   2    GND      B @T6G_MB_LIB.T6G(SCH_1):GND

Q_RES_0402LF-10K,1%,1/16W,CHIP,CS31002FB08  I83  R479
   1    P5V      A @T6G_MB_LIB.T6G(SCH_1):P5V
   2 PWRGD_P5V_R      B @T6G_MB_LIB.T6G(SCH_1):PWRGD_P5V_R

Q_RES_0402LF-100K,1%,1/16W,CHIP,CS41002FB09  I84  R480
   1 PWRGD_P5V_R      A @T6G_MB_LIB.T6G(SCH_1):PWRGD_P5V_R
   2    GND      B @T6G_MB_LIB.T6G(SCH_1):GND

Q_RES_0402LF-0,5%,1/16W,EMPTY,CS00002JB13  I88  R490
   1 PWRGD_P5V_R      A @T6G_MB_LIB.T6G(SCH_1):PWRGD_P5V_R
   2 SW_P3V3_EN_R      B @T6G_MB_LIB.T6G(SCH_1):SW_P3V3_EN_R

Q_RES_0402LF-100K,1%,1/16W,EMPTY,CS41002FB09  I91  R6050
   1 SW_P3V3_EN      A @T6G_MB_LIB.T6G(SCH_1):SW_P3V3_EN
   2    GND      B @T6G_MB_LIB.T6G(SCH_1):GND

Q_RES_0402LF-10K,1%,1/16W,EMPTY,CS31002FB08  I93  R496
   1 P3V3_AUX      A @T6G_MB_LIB.T6G(SCH_1):P3V3_AUX
   2 SW_P3V3_EN      B @T6G_MB_LIB.T6G(SCH_1):SW_P3V3_EN

Q_RES_0402LF-0,5%,1/16W,CHIP,CS00002JB13  I95  R487
   1 SW_P3V3_EN      A @T6G_MB_LIB.T6G(SCH_1):SW_P3V3_EN
   2 SW_P3V3_EN_R      B @T6G_MB_LIB.T6G(SCH_1):SW_P3V3_EN_R

Q_RES_0402LF-0,5%,1/16W,CHIP,CS00002JB13  I96  R482
   1 PWRGD_P5V_R      A @T6G_MB_LIB.T6G(SCH_1):PWRGD_P5V_R
   2 PWRGD_P5V_R1      B @T6G_MB_LIB.T6G(SCH_1):PWRGD_P5V_R1

MOSFET_NCH_DUAL-PJT138K,SMLF,IC,BAM138K0003  I97  Q1
   1    GND     S1 @T6G_MB_LIB.T6G(SCH_1):GND
   2 PWRGD_P5V_R1     G1 @T6G_MB_LIB.T6G(SCH_1):PWRGD_P5V_R1
   6 PWRGD_P5V_R_N     D1 @T6G_MB_LIB.T6G(SCH_1):PWRGD_P5V_R_N

MOSFET_NCH_DUAL-PJT138K,SMLF,IC,BAM138K0003  I98  Q1
   3 PWRGD_P5V_R2     D2 @T6G_MB_LIB.T6G(SCH_1):PWRGD_P5V_R2
   5 PWRGD_P5V_N     G2 @T6G_MB_LIB.T6G(SCH_1):PWRGD_P5V_N
   4    GND     S2 @T6G_MB_LIB.T6G(SCH_1):GND

Q_RES_0402LF-4.7K,5%,1/16W,CHIP,CS24702JB10  I99  R492
   1 P3V3_AUX      A @T6G_MB_LIB.T6G(SCH_1):P3V3_AUX
   2 PWRGD_P5V_R_N      B @T6G_MB_LIB.T6G(SCH_1):PWRGD_P5V_R_N

Q_RES_0402LF-0,5%,1/16W,CHIP,CS00002JB13  I102  R494
   1 PWRGD_P5V_R_N      A @T6G_MB_LIB.T6G(SCH_1):PWRGD_P5V_R_N
   2 PWRGD_P5V_N      B @T6G_MB_LIB.T6G(SCH_1):PWRGD_P5V_N

Q_RES_0402LF-4.7K,5%,1/16W,CHIP,CS24702JB10  I104  R552
   1 P3V3_AUX      A @T6G_MB_LIB.T6G(SCH_1):P3V3_AUX
   2 PWRGD_P5V_R2      B @T6G_MB_LIB.T6G(SCH_1):PWRGD_P5V_R2

MOSFET_NCH_DUAL-PJT138K,SMLF,IC,BAM138K0003  I107  Q3
   1    GND     S1 @T6G_MB_LIB.T6G(SCH_1):GND
   2 SW_P3V3_EN_R     G1 @T6G_MB_LIB.T6G(SCH_1):SW_P3V3_EN_R
   6 SW_P3V3_EN_N     D1 @T6G_MB_LIB.T6G(SCH_1):SW_P3V3_EN_N

MOSFET_NCH_DUAL-PJT138K,SMLF,IC,BAM138K0003  I108  Q3
   3 SW_P3V3_EN_ISO     D2 @T6G_MB_LIB.T6G(SCH_1):SW_P3V3_EN_ISO
   5 SW_P3V3_EN_N     G2 @T6G_MB_LIB.T6G(SCH_1):SW_P3V3_EN_N
   4    GND     S2 @T6G_MB_LIB.T6G(SCH_1):GND

Q_RES_0402LF-100K,1%,1/16W,CHIP,CS41002FB09  I111  R554
   1 P12V_AUX      A @T6G_MB_LIB.T6G(SCH_1):P12V_AUX
   2 SW_P3V3_EN_N      B @T6G_MB_LIB.T6G(SCH_1):SW_P3V3_EN_N

Q_RES_0402LF-1K,1%,1/16W,CHIP,CS21002FB06  I113  R569
   1 SW_P3V3_EN_ISO_R      A @T6G_MB_LIB.T6G(SCH_1):SW_P3V3_EN_ISO_R
   2 SW_P3V3_EN_ISO      B @T6G_MB_LIB.T6G(SCH_1):SW_P3V3_EN_ISO

Q_RES_0402LF-10K,1%,1/16W,CHIP,CS31002FB08  I114  R568
   1 P12V_AUX      A @T6G_MB_LIB.T6G(SCH_1):P12V_AUX
   2 SW_P3V3_EN_ISO_R      B @T6G_MB_LIB.T6G(SCH_1):SW_P3V3_EN_ISO_R

Q_CAP_C0402-0.22UF,25V,10%,X7R,CH4224K1B01  I116  C29
   1 SW_P3V3_EN_ISO_R      A @T6G_MB_LIB.T6G(SCH_1):SW_P3V3_EN_ISO_R
   2    GND      B @T6G_MB_LIB.T6G(SCH_1):GND

Q_RES_0402LF-10K,5%,1/16W,CHIP,CS31002JB08  I120  R1492
   1 P3V3_AUX      A @T6G_MB_LIB.T6G(SCH_1):P3V3_AUX
   2 PWRGD_P3V3_EN_N      B @T6G_MB_LIB.T6G(SCH_1):PWRGD_P3V3_EN_N

BSS138DW7F-BSS138DW-7-F,SMLF,IC,BAM01380032  I123  Q27
   2 PWRGD_P3V3_EN     G1 @T6G_MB_LIB.T6G(SCH_1):PWRGD_P3V3_EN
   5 PWRGD_P3V3_EN_N     G2 @T6G_MB_LIB.T6G(SCH_1):PWRGD_P3V3_EN_N
   1    GND     S1 @T6G_MB_LIB.T6G(SCH_1):GND
   4    GND     S2 @T6G_MB_LIB.T6G(SCH_1):GND
   6 PWRGD_P3V3_EN_N     D1 @T6G_MB_LIB.T6G(SCH_1):PWRGD_P3V3_EN_N
   3 PWRGD_P3V3_R1     D2 @T6G_MB_LIB.T6G(SCH_1):PWRGD_P3V3_R1

Q_RES_0402LF-10K,5%,1/16W,CHIP,CS31002JB08  I125  R1493
   1 P1V8_AUX      A @T6G_MB_LIB.T6G(SCH_1):P1V8_AUX
   2 PWRGD_P3V3_R1      B @T6G_MB_LIB.T6G(SCH_1):PWRGD_P3V3_R1

Q_RES_0402LF-33,5%,1/16W,CHIP,CS03302JB10  I130  R1362
   1 PWRGD_P3V3_R1      A @T6G_MB_LIB.T6G(SCH_1):PWRGD_P3V3_R1
   2 PWRGD_P3V3_R2      B @T6G_MB_LIB.T6G(SCH_1):PWRGD_P3V3_R2

APX80929SAG7-APX809-29SAG-7,SMLF,IC,AL080929000  I131  U6006
   3   P3V3    VCC @T6G_MB_LIB.T6G(SCH_1):P3V3
   2 PWRGD_P3V3_EN_R RESET_L @T6G_MB_LIB.T6G(SCH_1):PWRGD_P3V3_EN_R
   1    GND    GND @T6G_MB_LIB.T6G(SCH_1):GND

Q_CAP_0402-0.1UF,25V,10%,X7R,CH4104K1B00  I133  C6500
   1   P3V3      A @T6G_MB_LIB.T6G(SCH_1):P3V3
   2    GND      B @T6G_MB_LIB.T6G(SCH_1):GND

Q_RES_0402LF-0,5%,1/16W,CHIP,CS00002JB13  I136  R6500
   1 PWRGD_P3V3_EN_R      A @T6G_MB_LIB.T6G(SCH_1):PWRGD_P3V3_EN_R
   2 PWRGD_P3V3_EN      B @T6G_MB_LIB.T6G(SCH_1):PWRGD_P3V3_EN

Q_RES_0402LF-100K,1%,1/16W,CHIP,CS41002FB09  I139  R6501
   1 PWRGD_P3V3_EN_R      A @T6G_MB_LIB.T6G(SCH_1):PWRGD_P3V3_EN_R
   2    GND      B @T6G_MB_LIB.T6G(SCH_1):GND

Q_RES_0402LF-10K,5%,1/16W,EMPTY,CS31002JB08  I141  R1491
   1   P3V3      A @T6G_MB_LIB.T6G(SCH_1):P3V3
   2 PWRGD_P3V3_EN_R      B @T6G_MB_LIB.T6G(SCH_1):PWRGD_P3V3_EN_R


DRAWING: @T6G_MB_LIB.T6G(SCH_1):PAGE295 

ISL28022FRZT-ISL28022FRZ-T,SMLF,IC,AL028022003  I30  U266
   9 P3V3_AUX    VCC @T6G_MB_LIB.T6G(SCH_1):P3V3_AUX
   1 INA230_1_A1     A1 @T6G_MB_LIB.T6G(SCH_1):INA230_1_A1
   2 INA230_1_A0     A0 @T6G_MB_LIB.T6G(SCH_1):INA230_1_A0
   5 SMB_INA230_1_3V3AUX_SCL_R1 SCL|||SMBCLK @T6G_MB_LIB.T6G(SCH_1):SMB_INA230_1_3V3AUX_SCL_R1
   4 SMB_INA230_1_3V3AUX_SDA_R1 SDA||SMBDAT @T6G_MB_LIB.T6G(SCH_1):SMB_INA230_1_3V3AUX_SDA_R1
  11 P3V3_OCP_SFF_R   VBUS @T6G_MB_LIB.T6G(SCH_1):P3V3_OCP_SFF_R
  13 VSENSE_P3V3_INA230_1_INP   VINP @T6G_MB_LIB.T6G(SCH_1):VSENSE_P3V3_INA230_1_INP
  12 VSENSE_P3V3_INA230_1_INN   VINM @T6G_MB_LIB.T6G(SCH_1):VSENSE_P3V3_INA230_1_INN
   3 OCP_SFF_P3V3_ADC_ALERT_R EXT_CLK||INT @T6G_MB_LIB.T6G(SCH_1):OCP_SFF_P3V3_ADC_ALERT_R
   6 NC_INA230_1_NC0    NC0 @T6G_MB_LIB.T6G(SCH_1):NC_INA230_1_NC0
   7 NC_INA230_1_NC1    NC1 @T6G_MB_LIB.T6G(SCH_1):NC_INA230_1_NC1
   8 NC_INA230_1_NC2    NC2 @T6G_MB_LIB.T6G(SCH_1):NC_INA230_1_NC2
  14 NC_INA230_1_NC3    NC3 @T6G_MB_LIB.T6G(SCH_1):NC_INA230_1_NC3
  15 NC_INA230_1_NC4    NC4 @T6G_MB_LIB.T6G(SCH_1):NC_INA230_1_NC4
  16 NC_INA230_1_NC5    NC5 @T6G_MB_LIB.T6G(SCH_1):NC_INA230_1_NC5
  10    GND    GND @T6G_MB_LIB.T6G(SCH_1):GND
  TH    GND TH_GND @T6G_MB_LIB.T6G(SCH_1):GND

Q_RES_0402LF-4.7K,1%,1/16W,CHIP,CS24702FB06  I31  R3616
   1    GND      A @T6G_MB_LIB.T6G(SCH_1):GND
   2 INA230_1_A1      B @T6G_MB_LIB.T6G(SCH_1):INA230_1_A1

Q_CAP_0402-0.1UF,25V,10%,X7R,CH4104K1B00  I34  C2015
   1 P3V3_AUX      A @T6G_MB_LIB.T6G(SCH_1):P3V3_AUX
   2    GND      B @T6G_MB_LIB.T6G(SCH_1):GND

Q_RES_0402LF-0,5%,1/16W,CHIP,CS00002JB13  I35  R3563
   1 OCP_SFF_P3V3_ADC_ALERT_R      A @T6G_MB_LIB.T6G(SCH_1):OCP_SFF_P3V3_ADC_ALERT_R
   2 OCP_SFF_P3V3_P12V_ADC_R_ALERT      B @T6G_MB_LIB.T6G(SCH_1):OCP_SFF_P3V3_P12V_ADC_R_ALERT

Q_RES_0402LF-4.7K,1%,1/16W,EMPTY,CS24702FB06  I40  R3617
   1    GND      A @T6G_MB_LIB.T6G(SCH_1):GND
   2 INA230_1_A0      B @T6G_MB_LIB.T6G(SCH_1):INA230_1_A0

Q_RES_0402LF-10,1%,1/16W,CHIP,CS01002FB07  I41  R3602
   1 P3V3_OCP_SFF_R      A @T6G_MB_LIB.T6G(SCH_1):P3V3_OCP_SFF_R
   2 VSENSE_P3V3_INA230_1_INP      B @T6G_MB_LIB.T6G(SCH_1):VSENSE_P3V3_INA230_1_INP

Q_RES_0402LF-10,1%,1/16W,CHIP,CS01002FB07  I43  R3603
   1 P3V3_OCP_SFF      A @T6G_MB_LIB.T6G(SCH_1):P3V3_OCP_SFF
   2 VSENSE_P3V3_INA230_1_INN      B @T6G_MB_LIB.T6G(SCH_1):VSENSE_P3V3_INA230_1_INN

Q_CAP_0402-0.1UF,25V,10%,X7R,CH4104K1B00  I50  C2024
   1 P3V3_OCP_SFF_R      A @T6G_MB_LIB.T6G(SCH_1):P3V3_OCP_SFF_R
   2    GND      B @T6G_MB_LIB.T6G(SCH_1):GND

Q_CAP_0402-0.1UF,25V,10%,X7R,CH4104K1B00  I77  C2027
   1 VSENSE_P3V3_INA230_1_INP      A @T6G_MB_LIB.T6G(SCH_1):VSENSE_P3V3_INA230_1_INP
   2 VSENSE_P3V3_INA230_1_INN      B @T6G_MB_LIB.T6G(SCH_1):VSENSE_P3V3_INA230_1_INN

Q_RES_0402LF-4.7K,1%,1/16W,EMPTY,CS24702FB06  I88  R3628
   1 P3V3_AUX      A @T6G_MB_LIB.T6G(SCH_1):P3V3_AUX
   2 INA230_1_A1      B @T6G_MB_LIB.T6G(SCH_1):INA230_1_A1

Q_RES_0402LF-4.7K,1%,1/16W,CHIP,CS24702FB06  I89  R3627
   1 P3V3_AUX      A @T6G_MB_LIB.T6G(SCH_1):P3V3_AUX
   2 INA230_1_A0      B @T6G_MB_LIB.T6G(SCH_1):INA230_1_A0

Q_RES_2512LF-0.002,1%,2W,CHIP,CS+002AFR06  I93  R3645
   1 P3V3_OCP_SFF      A @T6G_MB_LIB.T6G(SCH_1):P3V3_OCP_SFF
   2 P3V3_OCP_SFF_R      B @T6G_MB_LIB.T6G(SCH_1):P3V3_OCP_SFF_R

Q_RES_0402LF-0,5%,1/16W,CHIP,CS00002JB13  I122  R3752
   1 E1S_0_P3V3_ADC_ALERT_R      A @T6G_MB_LIB.T6G(SCH_1):E1S_0_P3V3_ADC_ALERT_R
   2 E1S_0_P3V3_P12V_ADC_R_ALERT      B @T6G_MB_LIB.T6G(SCH_1):E1S_0_P3V3_P12V_ADC_R_ALERT

Q_CAP_0402-0.1UF,25V,10%,X7R,CH4104K1B00  I125  C2067
   1 P3V3_AUX      A @T6G_MB_LIB.T6G(SCH_1):P3V3_AUX
   2    GND      B @T6G_MB_LIB.T6G(SCH_1):GND

ISL28022FRZT-ISL28022FRZ-T,SMLF,IC,AL028022003  I129  U276
   9 P3V3_AUX    VCC @T6G_MB_LIB.T6G(SCH_1):P3V3_AUX
   1 INA230_2_A1     A1 @T6G_MB_LIB.T6G(SCH_1):INA230_2_A1
   2 INA230_2_A0     A0 @T6G_MB_LIB.T6G(SCH_1):INA230_2_A0
   5 SMB_INA230_2_3V3AUX_SCL_R1 SCL|||SMBCLK @T6G_MB_LIB.T6G(SCH_1):SMB_INA230_2_3V3AUX_SCL_R1
   4 SMB_INA230_2_3V3AUX_SDA_R1 SDA||SMBDAT @T6G_MB_LIB.T6G(SCH_1):SMB_INA230_2_3V3AUX_SDA_R1
  11 P3V3_E1S_0_R   VBUS @T6G_MB_LIB.T6G(SCH_1):P3V3_E1S_0_R
  13 VSENSE_P3V3_INA230_2_INP   VINP @T6G_MB_LIB.T6G(SCH_1):VSENSE_P3V3_INA230_2_INP
  12 VSENSE_P3V3_INA230_2_INN   VINM @T6G_MB_LIB.T6G(SCH_1):VSENSE_P3V3_INA230_2_INN
   3 E1S_0_P3V3_ADC_ALERT_R EXT_CLK||INT @T6G_MB_LIB.T6G(SCH_1):E1S_0_P3V3_ADC_ALERT_R
   6 NC_INA230_2_NC0    NC0 @T6G_MB_LIB.T6G(SCH_1):NC_INA230_2_NC0
   7 NC_INA230_2_NC1    NC1 @T6G_MB_LIB.T6G(SCH_1):NC_INA230_2_NC1
   8 NC_INA230_2_NC2    NC2 @T6G_MB_LIB.T6G(SCH_1):NC_INA230_2_NC2
  14 NC_INA230_2_NC3    NC3 @T6G_MB_LIB.T6G(SCH_1):NC_INA230_2_NC3
  15 NC_INA230_2_NC4    NC4 @T6G_MB_LIB.T6G(SCH_1):NC_INA230_2_NC4
  16 NC_INA230_2_NC5    NC5 @T6G_MB_LIB.T6G(SCH_1):NC_INA230_2_NC5
  10    GND    GND @T6G_MB_LIB.T6G(SCH_1):GND
  TH    GND TH_GND @T6G_MB_LIB.T6G(SCH_1):GND

Q_RES_0402LF-10,1%,1/16W,CHIP,CS01002FB07  I132  R3758
   1 P3V3_E1S_0_R      A @T6G_MB_LIB.T6G(SCH_1):P3V3_E1S_0_R
   2 VSENSE_P3V3_INA230_2_INP      B @T6G_MB_LIB.T6G(SCH_1):VSENSE_P3V3_INA230_2_INP

Q_CAP_0402-0.1UF,25V,10%,X7R,CH4104K1B00  I133  C2071
   1 VSENSE_P3V3_INA230_2_INP      A @T6G_MB_LIB.T6G(SCH_1):VSENSE_P3V3_INA230_2_INP
   2 VSENSE_P3V3_INA230_2_INN      B @T6G_MB_LIB.T6G(SCH_1):VSENSE_P3V3_INA230_2_INN

Q_RES_0402LF-10,1%,1/16W,CHIP,CS01002FB07  I134  R3760
   1 P3V3_E1S_0      A @T6G_MB_LIB.T6G(SCH_1):P3V3_E1S_0
   2 VSENSE_P3V3_INA230_2_INN      B @T6G_MB_LIB.T6G(SCH_1):VSENSE_P3V3_INA230_2_INN

Q_RES_0402LF-4.7K,1%,1/16W,EMPTY,CS24702FB06  I135  R3764
   1    GND      A @T6G_MB_LIB.T6G(SCH_1):GND
   2 INA230_2_A0      B @T6G_MB_LIB.T6G(SCH_1):INA230_2_A0

Q_RES_0402LF-4.7K,1%,1/16W,CHIP,CS24702FB06  I136  R3763
   1    GND      A @T6G_MB_LIB.T6G(SCH_1):GND
   2 INA230_2_A1      B @T6G_MB_LIB.T6G(SCH_1):INA230_2_A1

Q_CAP_0402-0.1UF,25V,10%,X7R,CH4104K1B00  I142  C2069
   1 P3V3_E1S_0_R      A @T6G_MB_LIB.T6G(SCH_1):P3V3_E1S_0_R
   2    GND      B @T6G_MB_LIB.T6G(SCH_1):GND

Q_RES_2512LF-0.002,1%,2W,CHIP,CS+002AFR06  I144  R3767
   1 P3V3_E1S_0      A @T6G_MB_LIB.T6G(SCH_1):P3V3_E1S_0
   2 P3V3_E1S_0_R      B @T6G_MB_LIB.T6G(SCH_1):P3V3_E1S_0_R

Q_RES_0402LF-0,5%,1/16W,CHIP,CS00002JB13  I146  R3751
   1 INA230_2_A0      A @T6G_MB_LIB.T6G(SCH_1):INA230_2_A0
   2 SMB_INA230_2_3V3AUX_SDA_R1      B @T6G_MB_LIB.T6G(SCH_1):SMB_INA230_2_3V3AUX_SDA_R1

Q_RES_0402LF-1K,1%,1/16W,CHIP,CS21002FB06  I149  R4093
   1 P3V3_AUX      A @T6G_MB_LIB.T6G(SCH_1):P3V3_AUX
   2 E1S_0_P3V3_ADC_ALERT_R      B @T6G_MB_LIB.T6G(SCH_1):E1S_0_P3V3_ADC_ALERT_R

Q_RES_0402LF-1K,1%,1/16W,CHIP,CS21002FB06  I151  R4094
   1 P3V3_AUX      A @T6G_MB_LIB.T6G(SCH_1):P3V3_AUX
   2 OCP_SFF_P3V3_ADC_ALERT_R      B @T6G_MB_LIB.T6G(SCH_1):OCP_SFF_P3V3_ADC_ALERT_R

Q_RES_0402LF-0,5%,1/16W,CHIP,CS00002JB13  I152  R3600
   1 SMB_INA230_1_3V3AUX_SCL_R      A @T6G_MB_LIB.T6G(SCH_1):SMB_INA230_1_3V3AUX_SCL_R
   2 SMB_INA230_1_3V3AUX_SCL_R1      B @T6G_MB_LIB.T6G(SCH_1):SMB_INA230_1_3V3AUX_SCL_R1

Q_RES_0402LF-0,5%,1/16W,CHIP,CS00002JB13  I153  R3601
   1 SMB_INA230_1_3V3AUX_SDA_R      A @T6G_MB_LIB.T6G(SCH_1):SMB_INA230_1_3V3AUX_SDA_R
   2 SMB_INA230_1_3V3AUX_SDA_R1      B @T6G_MB_LIB.T6G(SCH_1):SMB_INA230_1_3V3AUX_SDA_R1

Q_RES_0402LF-0,5%,1/16W,CHIP,CS00002JB13  I154  R3756
   1 SMB_INA230_2_3V3AUX_SDA_R      A @T6G_MB_LIB.T6G(SCH_1):SMB_INA230_2_3V3AUX_SDA_R
   2 SMB_INA230_2_3V3AUX_SDA_R1      B @T6G_MB_LIB.T6G(SCH_1):SMB_INA230_2_3V3AUX_SDA_R1

Q_RES_0402LF-0,5%,1/16W,CHIP,CS00002JB13  I155  R3754
   1 SMB_INA230_2_3V3AUX_SCL_R      A @T6G_MB_LIB.T6G(SCH_1):SMB_INA230_2_3V3AUX_SCL_R
   2 SMB_INA230_2_3V3AUX_SCL_R1      B @T6G_MB_LIB.T6G(SCH_1):SMB_INA230_2_3V3AUX_SCL_R1


DRAWING: @T6G_MB_LIB.T6G(SCH_1):PAGE358 

Q_RES_0402LF-0,5%,1/16W,CHIP,CS00002JB13  I78  R2787
   1 USB2_HUB_SWB_DN      A @T6G_MB_LIB.T6G(SCH_1):USB2_HUB_SWB_DN
   2 USB2_HUB_BUF_SWB_R_DN      B @T6G_MB_LIB.T6G(SCH_1):USB2_HUB_BUF_SWB_R_DN

Q_RES_0402LF-0,5%,1/16W,CHIP,CS00002JB13  I79  R2786
   1 USB2_HUB_SWB_DP      A @T6G_MB_LIB.T6G(SCH_1):USB2_HUB_SWB_DP
   2 USB2_HUB_BUF_SWB_R_DP      B @T6G_MB_LIB.T6G(SCH_1):USB2_HUB_BUF_SWB_R_DP

Q_CAP_C0402-0.1UF,25V,10%,EMPTY,CH4104KEB00  I81  C5232
   1 PD_U5201_RSTN      A @T6G_MB_LIB.T6G(SCH_1):PD_U5201_RSTN
   2    GND      B @T6G_MB_LIB.T6G(SCH_1):GND

Q_RES_0402LF-3.9K,5%,1/16W,EMPTY,CS23902JB04  I83  R5238
   1 PD_U5201_EQ      A @T6G_MB_LIB.T6G(SCH_1):PD_U5201_EQ
   2    GND      B @T6G_MB_LIB.T6G(SCH_1):GND

TUSB211IRWBR-TUSB211IRWBR,SMLF,EMPTY,AL000211007  I84  U5201
   5 PD_U5201_RSTN   RSTN @T6G_MB_LIB.T6G(SCH_1):PD_U5201_RSTN
   8 USB2_HUB_BUF_SWB_R_DN    D2M @T6G_MB_LIB.T6G(SCH_1):USB2_HUB_BUF_SWB_R_DN
  11 PD_U5201_VREG   VREG @T6G_MB_LIB.T6G(SCH_1):PD_U5201_VREG
   3 TP_USB2_TEST   TEST @T6G_MB_LIB.T6G(SCH_1):TP_USB2_TEST
  12 P3V3_AUX    VCC @T6G_MB_LIB.T6G(SCH_1):P3V3_AUX
   9 TP_USB2_ENA_HS ENA_HS @T6G_MB_LIB.T6G(SCH_1):TP_USB2_ENA_HS
   4 TP_USB2_CD     CD @T6G_MB_LIB.T6G(SCH_1):TP_USB2_CD
   1 USB2_HUB_BUF_SWB_R_DN    D1M @T6G_MB_LIB.T6G(SCH_1):USB2_HUB_BUF_SWB_R_DN
   2 USB2_HUB_BUF_SWB_R_DP    D1P @T6G_MB_LIB.T6G(SCH_1):USB2_HUB_BUF_SWB_R_DP
   7 USB2_HUB_BUF_SWB_R_DP    D2P @T6G_MB_LIB.T6G(SCH_1):USB2_HUB_BUF_SWB_R_DP
   6 PD_U5201_EQ     EQ @T6G_MB_LIB.T6G(SCH_1):PD_U5201_EQ
  10    GND    GND @T6G_MB_LIB.T6G(SCH_1):GND

Q_CAP_C0402-0.1UF,25V,10%,EMPTY,CH4104KEB00  I87  C5236
   1 PD_U5201_VREG      A @T6G_MB_LIB.T6G(SCH_1):PD_U5201_VREG
   2    GND      B @T6G_MB_LIB.T6G(SCH_1):GND

Q_CAP_C0402-1UF,25V,10%,EMPTY,CH5104KEB02  I88  C5229
   1 P3V3_AUX      A @T6G_MB_LIB.T6G(SCH_1):P3V3_AUX
   2    GND      B @T6G_MB_LIB.T6G(SCH_1):GND

Q_RES_0402LF-0,5%,1/16W,CHIP,CS00002JB13  I90  R5236
   1 USB2_HUB_BUF_SWB_R_DN      A @T6G_MB_LIB.T6G(SCH_1):USB2_HUB_BUF_SWB_R_DN
   2 USB2_HUB_BUF_SWB_DN      B @T6G_MB_LIB.T6G(SCH_1):USB2_HUB_BUF_SWB_DN

Q_RES_0402LF-0,5%,1/16W,CHIP,CS00002JB13  I91  R5234
   1 USB2_HUB_BUF_SWB_R_DP      A @T6G_MB_LIB.T6G(SCH_1):USB2_HUB_BUF_SWB_R_DP
   2 USB2_HUB_BUF_SWB_DP      B @T6G_MB_LIB.T6G(SCH_1):USB2_HUB_BUF_SWB_DP

Q_CAP_C0402-0.1UF,25V,10%,EMPTY,CH4104KEB00  I92  C5234
   1 P3V3_AUX      A @T6G_MB_LIB.T6G(SCH_1):P3V3_AUX
   2    GND      B @T6G_MB_LIB.T6G(SCH_1):GND

Q_RES_0402LF-0,5%,1/16W,EMPTY,CS00002JB13  I96  R2790
   1 USB2_HOST_BMC_B_DP      A @T6G_MB_LIB.T6G(SCH_1):USB2_HOST_BMC_B_DP
   2 USB2_HOST_BMC_B_BUF_DP      B @T6G_MB_LIB.T6G(SCH_1):USB2_HOST_BMC_B_BUF_DP

Q_RES_0402LF-0,5%,1/16W,EMPTY,CS00002JB13  I97  R2791
   1 USB2_HOST_BMC_B_DN      A @T6G_MB_LIB.T6G(SCH_1):USB2_HOST_BMC_B_DN
   2 USB2_HOST_BMC_B_BUF_DN      B @T6G_MB_LIB.T6G(SCH_1):USB2_HOST_BMC_B_BUF_DN

Q_RES_0402LF-0,5%,1/16W,EMPTY,CS00002JB13  I98  R2789
   1 USB2_HOST_BMC_B_BUF_DN      A @T6G_MB_LIB.T6G(SCH_1):USB2_HOST_BMC_B_BUF_DN
   2 USB2_HUB_BUF_SWB_R_DN      B @T6G_MB_LIB.T6G(SCH_1):USB2_HUB_BUF_SWB_R_DN

Q_RES_0402LF-0,5%,1/16W,EMPTY,CS00002JB13  I99  R2788
   1 USB2_HOST_BMC_B_BUF_DP      A @T6G_MB_LIB.T6G(SCH_1):USB2_HOST_BMC_B_BUF_DP
   2 USB2_HUB_BUF_SWB_R_DP      B @T6G_MB_LIB.T6G(SCH_1):USB2_HUB_BUF_SWB_R_DP

GL852GOHY60-GL852G-OHY60,SMLF,IC,AL000852001  I100  U268
  10 USB_HUB_XTAL_IN     X1 @T6G_MB_LIB.T6G(SCH_1):USB_HUB_XTAL_IN
  11 USB_HUB_XTAL_OUT     X2 @T6G_MB_LIB.T6G(SCH_1):USB_HUB_XTAL_OUT
  18 USB_HUB_TEST TEST||SCL @T6G_MB_LIB.T6G(SCH_1):USB_HUB_TEST
  26 NC_USB_HUB_SDA    SDA @T6G_MB_LIB.T6G(SCH_1):NC_USB_HUB_SDA
  27 P3V3_AUX_USB_HUB     V5 @T6G_MB_LIB.T6G(SCH_1):P3V3_AUX_USB_HUB
  28 P3V3_AUX_USB_HUB    V33 @T6G_MB_LIB.T6G(SCH_1):P3V3_AUX_USB_HUB
   5 P3V3_AUX_USB_HUB AVDD<0> @T6G_MB_LIB.T6G(SCH_1):P3V3_AUX_USB_HUB
   9 P3V3_AUX_USB_HUB AVDD<1> @T6G_MB_LIB.T6G(SCH_1):P3V3_AUX_USB_HUB
  14 P3V3_AUX_USB_HUB AVDD<2> @T6G_MB_LIB.T6G(SCH_1):P3V3_AUX_USB_HUB
  21 USB_HUB_DVDD   DVDD @T6G_MB_LIB.T6G(SCH_1):USB_HUB_DVDD
  TH    GND     TH @T6G_MB_LIB.T6G(SCH_1):GND
  25 USB_HUB_OVCUR1 OVCUR1#||SMC @T6G_MB_LIB.T6G(SCH_1):USB_HUB_OVCUR1
  24 USB_HUB_OVCUR2 OVCUR2#||SMD @T6G_MB_LIB.T6G(SCH_1):USB_HUB_OVCUR2
  20 USB_HUB_OVCUR3 OVCUR3# @T6G_MB_LIB.T6G(SCH_1):USB_HUB_OVCUR3
  19 USB_HUB_OVCUR4 OVCUR4# @T6G_MB_LIB.T6G(SCH_1):USB_HUB_OVCUR4
  17 RST_USB_HUB_R_N RESET# @T6G_MB_LIB.T6G(SCH_1):RST_USB_HUB_R_N
  23 USB_HUB_PGANG  PGANG @T6G_MB_LIB.T6G(SCH_1):USB_HUB_PGANG
  22 USB_HUB_PSELF  PSELF @T6G_MB_LIB.T6G(SCH_1):USB_HUB_PSELF
   8 USB_HUB_RREF   RREF @T6G_MB_LIB.T6G(SCH_1):USB_HUB_RREF
   2 USB2_P0_R_DP    DP0 @T6G_MB_LIB.T6G(SCH_1):USB2_P0_R_DP
   1 USB2_P0_R_DN    DM0 @T6G_MB_LIB.T6G(SCH_1):USB2_P0_R_DN
   4 USB2_HUB_SWB_DP    DP1 @T6G_MB_LIB.T6G(SCH_1):USB2_HUB_SWB_DP
   3 USB2_HUB_SWB_DN    DM1 @T6G_MB_LIB.T6G(SCH_1):USB2_HUB_SWB_DN
   7 NC_USB_HUB_DP2    DP2 @T6G_MB_LIB.T6G(SCH_1):NC_USB_HUB_DP2
   6 NC_USB_HUB_DM2    DM2 @T6G_MB_LIB.T6G(SCH_1):NC_USB_HUB_DM2
  13 NC_USB_HUB_DP3    DP3 @T6G_MB_LIB.T6G(SCH_1):NC_USB_HUB_DP3
  12 NC_USB_HUB_DM3    DM3 @T6G_MB_LIB.T6G(SCH_1):NC_USB_HUB_DM3
  16 NC_USB_HUB_DP4    DP4 @T6G_MB_LIB.T6G(SCH_1):NC_USB_HUB_DP4
  15 NC_USB_HUB_DM4    DM4 @T6G_MB_LIB.T6G(SCH_1):NC_USB_HUB_DM4

Q_RES_0402LF-0,5%,1/16W,CHIP,CS00002JB13  I137  R3652
   1 USB2_P0_R_DN      A @T6G_MB_LIB.T6G(SCH_1):USB2_P0_R_DN
   2 USB2_HOST_BMC_B_DN      B @T6G_MB_LIB.T6G(SCH_1):USB2_HOST_BMC_B_DN

Q_RES_0402LF-0,5%,1/16W,CHIP,CS00002JB13  I138  R3651
   1 USB2_P0_R_DP      A @T6G_MB_LIB.T6G(SCH_1):USB2_P0_R_DP
   2 USB2_HOST_BMC_B_DP      B @T6G_MB_LIB.T6G(SCH_1):USB2_HOST_BMC_B_DP

Q_RES_0402LF-680,1%,1/16W,CHIP,CS16802FB03  I139  R3653
   1 USB_HUB_RREF      A @T6G_MB_LIB.T6G(SCH_1):USB_HUB_RREF
   2    GND      B @T6G_MB_LIB.T6G(SCH_1):GND

Q_CAP_0402-0.1UF,25V,10%,X7R,CH4104K1B00  I142  C2034
   1 P3V3_AUX_USB_HUB      A @T6G_MB_LIB.T6G(SCH_1):P3V3_AUX_USB_HUB
   2    GND      B @T6G_MB_LIB.T6G(SCH_1):GND

Q_CAP_0402-0.1UF,25V,10%,X7R,CH4104K1B00  I143  C2033
   1 P3V3_AUX_USB_HUB      A @T6G_MB_LIB.T6G(SCH_1):P3V3_AUX_USB_HUB
   2    GND      B @T6G_MB_LIB.T6G(SCH_1):GND

Q_CAP_0402-0.1UF,25V,10%,X7R,CH4104K1B00  I145  C2032
   1 P3V3_AUX_USB_HUB      A @T6G_MB_LIB.T6G(SCH_1):P3V3_AUX_USB_HUB
   2    GND      B @T6G_MB_LIB.T6G(SCH_1):GND

Q_CAP_C0402-1UF,25V,10%,X6S,CH5104KEB02  I147  C2035
   1 P3V3_AUX_USB_HUB      A @T6G_MB_LIB.T6G(SCH_1):P3V3_AUX_USB_HUB
   2    GND      B @T6G_MB_LIB.T6G(SCH_1):GND

Q_CAP_C0402-1UF,25V,10%,X6S,CH5104KEB02  I148  C2031
   1 P3V3_AUX_USB_HUB      A @T6G_MB_LIB.T6G(SCH_1):P3V3_AUX_USB_HUB
   2    GND      B @T6G_MB_LIB.T6G(SCH_1):GND

Q_RES_0402LF-33.2,1%,1/16W,CHIP,CS03322FB03  I155  R3654
   1 RST_USB_HUB_N      A @T6G_MB_LIB.T6G(SCH_1):RST_USB_HUB_N
   2 RST_USB_HUB_R_N      B @T6G_MB_LIB.T6G(SCH_1):RST_USB_HUB_R_N

Q_CAP_C0402-1UF,25V,10%,X6S,CH5104KEB02  I158  C2041
   1 RST_USB_HUB_R_N      A @T6G_MB_LIB.T6G(SCH_1):RST_USB_HUB_R_N
   2    GND      B @T6G_MB_LIB.T6G(SCH_1):GND

Q_RES_0402LF-10K,1%,1/16W,CHIP,CS31002FB08  I159  R3660
   1 P3V3_AUX      A @T6G_MB_LIB.T6G(SCH_1):P3V3_AUX
   2 RST_USB_HUB_R_N      B @T6G_MB_LIB.T6G(SCH_1):RST_USB_HUB_R_N

Q_RES_0402LF-0,5%,1/16W,CHIP,CS00002JB13  I161  R3655
   1 P3V3_AUX      A @T6G_MB_LIB.T6G(SCH_1):P3V3_AUX
   2 P3V3_AUX_USB_HUB      B @T6G_MB_LIB.T6G(SCH_1):P3V3_AUX_USB_HUB

Q_CAP_0402-0.1UF,25V,10%,X7R,CH4104K1B00  I162  C2040
   1 P3V3_AUX_USB_HUB      A @T6G_MB_LIB.T6G(SCH_1):P3V3_AUX_USB_HUB
   2    GND      B @T6G_MB_LIB.T6G(SCH_1):GND

Q_CAP_0402-0.1UF,25V,10%,X7R,CH4104K1B00  I163  C2039
   1 P3V3_AUX_USB_HUB      A @T6G_MB_LIB.T6G(SCH_1):P3V3_AUX_USB_HUB
   2    GND      B @T6G_MB_LIB.T6G(SCH_1):GND

Q_CAP_C0402-10UF,6.3V,20%,X6S,CH6101MEB01  I164  C2038
   1 P3V3_AUX_USB_HUB      A @T6G_MB_LIB.T6G(SCH_1):P3V3_AUX_USB_HUB
   2    GND      B @T6G_MB_LIB.T6G(SCH_1):GND

Q_RES_0402LF-0,5%,1/16W,CHIP,CS00002JB13  I167  R3662
   1 P3V3_AUX_USB_HUB      A @T6G_MB_LIB.T6G(SCH_1):P3V3_AUX_USB_HUB
   2 USB_HUB_DVDD      B @T6G_MB_LIB.T6G(SCH_1):USB_HUB_DVDD

Q_RES_0402LF-100K,1%,1/16W,CHIP,CS41002FB09  I182  R3665
   1 USB_HUB_PGANG      A @T6G_MB_LIB.T6G(SCH_1):USB_HUB_PGANG
   2    GND      B @T6G_MB_LIB.T6G(SCH_1):GND

Q_RES_0402LF-10K,1%,1/16W,CHIP,CS31002FB08  I186  R3663
   1 P3V3_AUX      A @T6G_MB_LIB.T6G(SCH_1):P3V3_AUX
   2 USB_HUB_PSELF      B @T6G_MB_LIB.T6G(SCH_1):USB_HUB_PSELF

Q_RES_0402LF-10K,1%,1/16W,EMPTY,CS31002FB08  I187  R3664
   1 USB_HUB_PSELF      A @T6G_MB_LIB.T6G(SCH_1):USB_HUB_PSELF
   2    GND      B @T6G_MB_LIB.T6G(SCH_1):GND

Q_RES_0402LF-10K,1%,1/16W,EMPTY,CS31002FB08  I194  R3656
   1 P3V3_AUX      A @T6G_MB_LIB.T6G(SCH_1):P3V3_AUX
   2 USB_HUB_OVCUR1      B @T6G_MB_LIB.T6G(SCH_1):USB_HUB_OVCUR1

Q_RES_0402LF-10K,1%,1/16W,EMPTY,CS31002FB08  I195  R3657
   1 P3V3_AUX      A @T6G_MB_LIB.T6G(SCH_1):P3V3_AUX
   2 USB_HUB_OVCUR2      B @T6G_MB_LIB.T6G(SCH_1):USB_HUB_OVCUR2

Q_RES_0402LF-10K,1%,1/16W,EMPTY,CS31002FB08  I196  R3658
   1 P3V3_AUX      A @T6G_MB_LIB.T6G(SCH_1):P3V3_AUX
   2 USB_HUB_OVCUR3      B @T6G_MB_LIB.T6G(SCH_1):USB_HUB_OVCUR3

Q_RES_0402LF-10K,1%,1/16W,EMPTY,CS31002FB08  I198  R3659
   1 P3V3_AUX      A @T6G_MB_LIB.T6G(SCH_1):P3V3_AUX
   2 USB_HUB_OVCUR4      B @T6G_MB_LIB.T6G(SCH_1):USB_HUB_OVCUR4

Q_RES_0402LF-0,5%,1/16W,CHIP,CS00002JB13  I199  R3666
   1 USB_HUB_TEST      A @T6G_MB_LIB.T6G(SCH_1):USB_HUB_TEST
   2    GND      B @T6G_MB_LIB.T6G(SCH_1):GND

Q_RES_0402LF-47K,0.1%,1/16W,EMPTY,CS34702BB05  I201  R3661
   1    GND      A @T6G_MB_LIB.T6G(SCH_1):GND
   2 RST_USB_HUB_R_N      B @T6G_MB_LIB.T6G(SCH_1):RST_USB_HUB_R_N

Q_RES_0402LF-49.9,1%,1/16W,EMPTY,CS04992FB07  I202  R4420
   1 USB2_HOST_BMC_B_DN      A @T6G_MB_LIB.T6G(SCH_1):USB2_HOST_BMC_B_DN
   2    GND      B @T6G_MB_LIB.T6G(SCH_1):GND

Q_RES_0402LF-49.9,1%,1/16W,EMPTY,CS04992FB07  I203  R4419
   1 USB2_HOST_BMC_B_DP      A @T6G_MB_LIB.T6G(SCH_1):USB2_HOST_BMC_B_DP
   2    GND      B @T6G_MB_LIB.T6G(SCH_1):GND

Q_RES_0402LF-49.9,1%,1/16W,EMPTY,CS04992FB07  I206  R4483
   1 USB2_HOST_BMC_B_BUF_DN      A @T6G_MB_LIB.T6G(SCH_1):USB2_HOST_BMC_B_BUF_DN
   2    GND      B @T6G_MB_LIB.T6G(SCH_1):GND

Q_RES_0402LF-49.9,1%,1/16W,EMPTY,CS04992FB07  I208  R4482
   1 USB2_HOST_BMC_B_BUF_DP      A @T6G_MB_LIB.T6G(SCH_1):USB2_HOST_BMC_B_BUF_DP
   2    GND      B @T6G_MB_LIB.T6G(SCH_1):GND

Q_XTAL_4P_13BI_24GND-12MHZ,SMLF,MISC,BG6120000B0  I210  Y8004
   1 USB_HUB_XTAL_IN     X1 @T6G_MB_LIB.T6G(SCH_1):USB_HUB_XTAL_IN
   2    GND     G1 @T6G_MB_LIB.T6G(SCH_1):GND
   4    GND     G2 @T6G_MB_LIB.T6G(SCH_1):GND
   3 USB_HUB_XTAL_OUT     X2 @T6G_MB_LIB.T6G(SCH_1):USB_HUB_XTAL_OUT

Q_CAP_0402-15PF,50V,5%,C0G,CH01506JB06  I211  C2030
   1 USB_HUB_XTAL_OUT      A @T6G_MB_LIB.T6G(SCH_1):USB_HUB_XTAL_OUT
   2    GND      B @T6G_MB_LIB.T6G(SCH_1):GND

Q_CAP_0402-15PF,50V,5%,C0G,CH01506JB06  I212  C2029
   1 USB_HUB_XTAL_IN      A @T6G_MB_LIB.T6G(SCH_1):USB_HUB_XTAL_IN
   2    GND      B @T6G_MB_LIB.T6G(SCH_1):GND


DRAWING: @T6G_MB_LIB.T6G(SCH_1):PAGE359 

Q_CAP_0402-0.1UF,25V,10%,X7R,CH4104K1B00  I16  C2010
   1 P3V3_AUX      A @T6G_MB_LIB.T6G(SCH_1):P3V3_AUX
   2    GND      B @T6G_MB_LIB.T6G(SCH_1):GND

Q_RES_0402LF-33.2,1%,1/16W,CHIP,CS03322FB03  I77  R4180
   1 SMB_LM75_0_3V3AUX_SCL      A @T6G_MB_LIB.T6G(SCH_1):SMB_LM75_0_3V3AUX_SCL
   2 SMB_LM75_0_3V3AUX_SCL_R1      B @T6G_MB_LIB.T6G(SCH_1):SMB_LM75_0_3V3AUX_SCL_R1

Q_RES_0402LF-33.2,1%,1/16W,CHIP,CS03322FB03  I78  R4183
   1 SMB_LM75_0_3V3AUX_SDA      A @T6G_MB_LIB.T6G(SCH_1):SMB_LM75_0_3V3AUX_SDA
   2 SMB_LM75_0_3V3AUX_SDA_R1      B @T6G_MB_LIB.T6G(SCH_1):SMB_LM75_0_3V3AUX_SDA_R1

Q_RES_0402LF-0,5%,1/16W,CHIP,CS00002JB13  I79  R4215
   1 FM_THERMAL_ALERT_N      A @T6G_MB_LIB.T6G(SCH_1):FM_THERMAL_ALERT_N
   2 FM_G751_0_ALERT_N      B @T6G_MB_LIB.T6G(SCH_1):FM_G751_0_ALERT_N

Q_RES_0402LF-1K,1%,1/16W,CHIP,CS21002FB06  I81  R4199
   1 U270_0_ADD1      A @T6G_MB_LIB.T6G(SCH_1):U270_0_ADD1
   2    GND      B @T6G_MB_LIB.T6G(SCH_1):GND

Q_RES_0402LF-1K,1%,1/16W,EMPTY,CS21002FB06  I82  R4198
   1 P3V3_AUX      A @T6G_MB_LIB.T6G(SCH_1):P3V3_AUX
   2 U270_0_ADD1      B @T6G_MB_LIB.T6G(SCH_1):U270_0_ADD1

Q_RES_0402LF-1K,1%,1/16W,CHIP,CS21002FB06  I85  R4207
   1 U270_0_ADD0      A @T6G_MB_LIB.T6G(SCH_1):U270_0_ADD0
   2    GND      B @T6G_MB_LIB.T6G(SCH_1):GND

Q_RES_0402LF-1K,1%,1/16W,EMPTY,CS21002FB06  I86  R4206
   1 P3V3_AUX      A @T6G_MB_LIB.T6G(SCH_1):P3V3_AUX
   2 U270_0_ADD0      B @T6G_MB_LIB.T6G(SCH_1):U270_0_ADD0

Q_RES_0402LF-1K,1%,1/16W,CHIP,CS21002FB06  I89  R4191
   1 U270_0_ADD2      A @T6G_MB_LIB.T6G(SCH_1):U270_0_ADD2
   2    GND      B @T6G_MB_LIB.T6G(SCH_1):GND

Q_RES_0402LF-1K,1%,1/16W,EMPTY,CS21002FB06  I91  R4190
   1 P3V3_AUX      A @T6G_MB_LIB.T6G(SCH_1):P3V3_AUX
   2 U270_0_ADD2      B @T6G_MB_LIB.T6G(SCH_1):U270_0_ADD2

Q_RES_0402LF-1K,1%,1/16W,EMPTY,CS21002FB06  I94  R4204
   1 P3V3_AUX      A @T6G_MB_LIB.T6G(SCH_1):P3V3_AUX
   2 U271_1_ADD0      B @T6G_MB_LIB.T6G(SCH_1):U271_1_ADD0

Q_RES_0402LF-1K,1%,1/16W,EMPTY,CS21002FB06  I95  R4196
   1 P3V3_AUX      A @T6G_MB_LIB.T6G(SCH_1):P3V3_AUX
   2 U271_1_ADD1      B @T6G_MB_LIB.T6G(SCH_1):U271_1_ADD1

Q_RES_0402LF-1K,1%,1/16W,CHIP,CS21002FB06  I96  R4205
   1 U271_1_ADD0      A @T6G_MB_LIB.T6G(SCH_1):U271_1_ADD0
   2    GND      B @T6G_MB_LIB.T6G(SCH_1):GND

Q_RES_0402LF-1K,1%,1/16W,CHIP,CS21002FB06  I98  R4197
   1 U271_1_ADD1      A @T6G_MB_LIB.T6G(SCH_1):U271_1_ADD1
   2    GND      B @T6G_MB_LIB.T6G(SCH_1):GND

Q_RES_0402LF-1K,1%,1/16W,EMPTY,CS21002FB06  I101  R4188
   1 P3V3_AUX      A @T6G_MB_LIB.T6G(SCH_1):P3V3_AUX
   2 U271_1_ADD2      B @T6G_MB_LIB.T6G(SCH_1):U271_1_ADD2

Q_RES_0402LF-1K,1%,1/16W,CHIP,CS21002FB06  I102  R4189
   1 U271_1_ADD2      A @T6G_MB_LIB.T6G(SCH_1):U271_1_ADD2
   2    GND      B @T6G_MB_LIB.T6G(SCH_1):GND

Q_CAP_0402-0.1UF,25V,10%,X7R,CH4104K1B00  I104  C73
   1 P3V3_AUX      A @T6G_MB_LIB.T6G(SCH_1):P3V3_AUX
   2    GND      B @T6G_MB_LIB.T6G(SCH_1):GND

Q_RES_0402LF-33.2,1%,1/16W,CHIP,CS03322FB03  I107  R4182
   1 SMB_LM75_1_3V3AUX_SDA      A @T6G_MB_LIB.T6G(SCH_1):SMB_LM75_1_3V3AUX_SDA
   2 SMB_LM75_1_3V3AUX_SDA_R1      B @T6G_MB_LIB.T6G(SCH_1):SMB_LM75_1_3V3AUX_SDA_R1

Q_RES_0402LF-0,5%,1/16W,CHIP,CS00002JB13  I108  R4214
   1 FM_THERMAL_ALERT_N      A @T6G_MB_LIB.T6G(SCH_1):FM_THERMAL_ALERT_N
   2 FM_G751_1_ALERT_N      B @T6G_MB_LIB.T6G(SCH_1):FM_G751_1_ALERT_N

Q_RES_0402LF-33.2,1%,1/16W,CHIP,CS03322FB03  I109  R4179
   1 SMB_LM75_1_3V3AUX_SCL      A @T6G_MB_LIB.T6G(SCH_1):SMB_LM75_1_3V3AUX_SCL
   2 SMB_LM75_1_3V3AUX_SCL_R1      B @T6G_MB_LIB.T6G(SCH_1):SMB_LM75_1_3V3AUX_SCL_R1

Q_RES_0402LF-33.2,1%,1/16W,CHIP,CS03322FB03  I114  R4178
   1 SMB_LM75_2_3V3AUX_SCL      A @T6G_MB_LIB.T6G(SCH_1):SMB_LM75_2_3V3AUX_SCL
   2 SMB_LM75_2_3V3AUX_SCL_R1      B @T6G_MB_LIB.T6G(SCH_1):SMB_LM75_2_3V3AUX_SCL_R1

Q_RES_0402LF-0,5%,1/16W,CHIP,CS00002JB13  I115  R4213
   1 FM_THERMAL_ALERT_N      A @T6G_MB_LIB.T6G(SCH_1):FM_THERMAL_ALERT_N
   2 FM_LM75_2_ALERT_N      B @T6G_MB_LIB.T6G(SCH_1):FM_LM75_2_ALERT_N

Q_RES_0402LF-33.2,1%,1/16W,CHIP,CS03322FB03  I116  R4181
   1 SMB_LM75_2_3V3AUX_SDA      A @T6G_MB_LIB.T6G(SCH_1):SMB_LM75_2_3V3AUX_SDA
   2 SMB_LM75_2_3V3AUX_SDA_R1      B @T6G_MB_LIB.T6G(SCH_1):SMB_LM75_2_3V3AUX_SDA_R1

Q_CAP_0402-0.1UF,25V,10%,X7R,CH4104K1B00  I119  C32
   1 P3V3_AUX      A @T6G_MB_LIB.T6G(SCH_1):P3V3_AUX
   2    GND      B @T6G_MB_LIB.T6G(SCH_1):GND

Q_RES_0402LF-1K,1%,1/16W,CHIP,CS21002FB06  I121  R4187
   1 U272_2_ADD2      A @T6G_MB_LIB.T6G(SCH_1):U272_2_ADD2
   2    GND      B @T6G_MB_LIB.T6G(SCH_1):GND

Q_RES_0402LF-1K,1%,1/16W,EMPTY,CS21002FB06  I122  R4186
   1 P3V3_AUX      A @T6G_MB_LIB.T6G(SCH_1):P3V3_AUX
   2 U272_2_ADD2      B @T6G_MB_LIB.T6G(SCH_1):U272_2_ADD2

Q_RES_0402LF-1K,1%,1/16W,CHIP,CS21002FB06  I125  R4195
   1 U272_2_ADD1      A @T6G_MB_LIB.T6G(SCH_1):U272_2_ADD1
   2    GND      B @T6G_MB_LIB.T6G(SCH_1):GND

Q_RES_0402LF-1K,1%,1/16W,CHIP,CS21002FB06  I127  R4203
   1 U272_2_ADD0      A @T6G_MB_LIB.T6G(SCH_1):U272_2_ADD0
   2    GND      B @T6G_MB_LIB.T6G(SCH_1):GND

Q_RES_0402LF-1K,1%,1/16W,EMPTY,CS21002FB06  I128  R4194
   1 P3V3_AUX      A @T6G_MB_LIB.T6G(SCH_1):P3V3_AUX
   2 U272_2_ADD1      B @T6G_MB_LIB.T6G(SCH_1):U272_2_ADD1

Q_RES_0402LF-1K,1%,1/16W,EMPTY,CS21002FB06  I129  R4202
   1 P3V3_AUX      A @T6G_MB_LIB.T6G(SCH_1):P3V3_AUX
   2 U272_2_ADD0      B @T6G_MB_LIB.T6G(SCH_1):U272_2_ADD0

Q_RES_0402LF-33.2,1%,1/16W,CHIP,CS03322FB03  I134  R3553
   1 SMB_LM75_3_3V3AUX_SCL      A @T6G_MB_LIB.T6G(SCH_1):SMB_LM75_3_3V3AUX_SCL
   2 SMB_LM75_3_3V3AUX_SCL_R1      B @T6G_MB_LIB.T6G(SCH_1):SMB_LM75_3_3V3AUX_SCL_R1

Q_RES_0402LF-0,5%,1/16W,CHIP,CS00002JB13  I135  R4212
   1 FM_THERMAL_ALERT_N      A @T6G_MB_LIB.T6G(SCH_1):FM_THERMAL_ALERT_N
   2 FM_LM75_3_ALERT_N      B @T6G_MB_LIB.T6G(SCH_1):FM_LM75_3_ALERT_N

Q_RES_0402LF-33.2,1%,1/16W,CHIP,CS03322FB03  I136  R3554
   1 SMB_LM75_3_3V3AUX_SDA      A @T6G_MB_LIB.T6G(SCH_1):SMB_LM75_3_3V3AUX_SDA
   2 SMB_LM75_3_3V3AUX_SDA_R1      B @T6G_MB_LIB.T6G(SCH_1):SMB_LM75_3_3V3AUX_SDA_R1

Q_CAP_0402-0.1UF,25V,10%,X7R,CH4104K1B00  I139  C31
   1 P3V3_AUX      A @T6G_MB_LIB.T6G(SCH_1):P3V3_AUX
   2    GND      B @T6G_MB_LIB.T6G(SCH_1):GND

Q_RES_0402LF-1K,1%,1/16W,CHIP,CS21002FB06  I141  R4185
   1 U273_3_ADD2      A @T6G_MB_LIB.T6G(SCH_1):U273_3_ADD2
   2    GND      B @T6G_MB_LIB.T6G(SCH_1):GND

Q_RES_0402LF-1K,1%,1/16W,EMPTY,CS21002FB06  I142  R4184
   1 P3V3_AUX      A @T6G_MB_LIB.T6G(SCH_1):P3V3_AUX
   2 U273_3_ADD2      B @T6G_MB_LIB.T6G(SCH_1):U273_3_ADD2

Q_RES_0402LF-1K,1%,1/16W,CHIP,CS21002FB06  I145  R4193
   1 U273_3_ADD1      A @T6G_MB_LIB.T6G(SCH_1):U273_3_ADD1
   2    GND      B @T6G_MB_LIB.T6G(SCH_1):GND

Q_RES_0402LF-1K,1%,1/16W,CHIP,CS21002FB06  I147  R4201
   1 U273_3_ADD0      A @T6G_MB_LIB.T6G(SCH_1):U273_3_ADD0
   2    GND      B @T6G_MB_LIB.T6G(SCH_1):GND

Q_RES_0402LF-1K,1%,1/16W,EMPTY,CS21002FB06  I148  R4192
   1 P3V3_AUX      A @T6G_MB_LIB.T6G(SCH_1):P3V3_AUX
   2 U273_3_ADD1      B @T6G_MB_LIB.T6G(SCH_1):U273_3_ADD1

Q_RES_0402LF-1K,1%,1/16W,EMPTY,CS21002FB06  I149  R4200
   1 P3V3_AUX      A @T6G_MB_LIB.T6G(SCH_1):P3V3_AUX
   2 U273_3_ADD0      B @T6G_MB_LIB.T6G(SCH_1):U273_3_ADD0

LM75BD-LM75BD,SMLF,IC,AL0075BD000  I164  U270
   1 SMB_LM75_0_3V3AUX_SDA_R1    SDA @T6G_MB_LIB.T6G(SCH_1):SMB_LM75_0_3V3AUX_SDA_R1
   2 SMB_LM75_0_3V3AUX_SCL_R1    SCL @T6G_MB_LIB.T6G(SCH_1):SMB_LM75_0_3V3AUX_SCL_R1
   3 FM_G751_0_ALERT_N     OS @T6G_MB_LIB.T6G(SCH_1):FM_G751_0_ALERT_N
   4    GND    GND @T6G_MB_LIB.T6G(SCH_1):GND
   5 U270_0_ADD2     A2 @T6G_MB_LIB.T6G(SCH_1):U270_0_ADD2
   6 U270_0_ADD1     A1 @T6G_MB_LIB.T6G(SCH_1):U270_0_ADD1
   7 U270_0_ADD0     A0 @T6G_MB_LIB.T6G(SCH_1):U270_0_ADD0
   8 P3V3_AUX    VCC @T6G_MB_LIB.T6G(SCH_1):P3V3_AUX

LM75BD-LM75BD,SMLF,IC,AL0075BD000  I165  U271
   1 SMB_LM75_1_3V3AUX_SDA_R1    SDA @T6G_MB_LIB.T6G(SCH_1):SMB_LM75_1_3V3AUX_SDA_R1
   2 SMB_LM75_1_3V3AUX_SCL_R1    SCL @T6G_MB_LIB.T6G(SCH_1):SMB_LM75_1_3V3AUX_SCL_R1
   3 FM_G751_1_ALERT_N     OS @T6G_MB_LIB.T6G(SCH_1):FM_G751_1_ALERT_N
   4    GND    GND @T6G_MB_LIB.T6G(SCH_1):GND
   5 U271_1_ADD2     A2 @T6G_MB_LIB.T6G(SCH_1):U271_1_ADD2
   6 U271_1_ADD1     A1 @T6G_MB_LIB.T6G(SCH_1):U271_1_ADD1
   7 U271_1_ADD0     A0 @T6G_MB_LIB.T6G(SCH_1):U271_1_ADD0
   8 P3V3_AUX    VCC @T6G_MB_LIB.T6G(SCH_1):P3V3_AUX

LM75BD-LM75BD,SMLF,IC,AL0075BD000  I166  U272
   1 SMB_LM75_2_3V3AUX_SDA_R1    SDA @T6G_MB_LIB.T6G(SCH_1):SMB_LM75_2_3V3AUX_SDA_R1
   2 SMB_LM75_2_3V3AUX_SCL_R1    SCL @T6G_MB_LIB.T6G(SCH_1):SMB_LM75_2_3V3AUX_SCL_R1
   3 FM_LM75_2_ALERT_N     OS @T6G_MB_LIB.T6G(SCH_1):FM_LM75_2_ALERT_N
   4    GND    GND @T6G_MB_LIB.T6G(SCH_1):GND
   5 U272_2_ADD2     A2 @T6G_MB_LIB.T6G(SCH_1):U272_2_ADD2
   6 U272_2_ADD1     A1 @T6G_MB_LIB.T6G(SCH_1):U272_2_ADD1
   7 U272_2_ADD0     A0 @T6G_MB_LIB.T6G(SCH_1):U272_2_ADD0
   8 P3V3_AUX    VCC @T6G_MB_LIB.T6G(SCH_1):P3V3_AUX

LM75BD-LM75BD,SMLF,IC,AL0075BD000  I167  U273
   1 SMB_LM75_3_3V3AUX_SDA_R1    SDA @T6G_MB_LIB.T6G(SCH_1):SMB_LM75_3_3V3AUX_SDA_R1
   2 SMB_LM75_3_3V3AUX_SCL_R1    SCL @T6G_MB_LIB.T6G(SCH_1):SMB_LM75_3_3V3AUX_SCL_R1
   3 FM_LM75_3_ALERT_N     OS @T6G_MB_LIB.T6G(SCH_1):FM_LM75_3_ALERT_N
   4    GND    GND @T6G_MB_LIB.T6G(SCH_1):GND
   5 U273_3_ADD2     A2 @T6G_MB_LIB.T6G(SCH_1):U273_3_ADD2
   6 U273_3_ADD1     A1 @T6G_MB_LIB.T6G(SCH_1):U273_3_ADD1
   7 U273_3_ADD0     A0 @T6G_MB_LIB.T6G(SCH_1):U273_3_ADD0
   8 P3V3_AUX    VCC @T6G_MB_LIB.T6G(SCH_1):P3V3_AUX

Q_RES_0402LF-200K,1%,1/16W,CHIP,CS42002FB05  I168  R4211
   1 P3V3_AUX      A @T6G_MB_LIB.T6G(SCH_1):P3V3_AUX
   2 FM_THERMAL_ALERT_N      B @T6G_MB_LIB.T6G(SCH_1):FM_THERMAL_ALERT_N

Q_RES_0402LF-200K,1%,1/16W,EMPTY,CS42002FB05  I169  R4209
   1 P3V3_AUX      A @T6G_MB_LIB.T6G(SCH_1):P3V3_AUX
   2 FM_THERMAL_ALERT_N      B @T6G_MB_LIB.T6G(SCH_1):FM_THERMAL_ALERT_N

Q_RES_0402LF-200K,1%,1/16W,EMPTY,CS42002FB05  I170  R4210
   1 P3V3_AUX      A @T6G_MB_LIB.T6G(SCH_1):P3V3_AUX
   2 FM_THERMAL_ALERT_N      B @T6G_MB_LIB.T6G(SCH_1):FM_THERMAL_ALERT_N

Q_RES_0402LF-200K,1%,1/16W,EMPTY,CS42002FB05  I171  R4208
   1 P3V3_AUX      A @T6G_MB_LIB.T6G(SCH_1):P3V3_AUX
   2 FM_THERMAL_ALERT_N      B @T6G_MB_LIB.T6G(SCH_1):FM_THERMAL_ALERT_N


DRAWING: @T6G_MB_LIB.T6G(SCH_1):PAGE360 

Q_CAP_0402-0.1UF,25V,10%,X7R,CH4104K1B00  I26  C2018
   1   P3V3      A @T6G_MB_LIB.T6G(SCH_1):P3V3
   2    GND      B @T6G_MB_LIB.T6G(SCH_1):GND

Q_RES_0402LF-10,1%,1/16W,CHIP,CS01002FB07  I33  R3575
   1 P3V3_M2_0      A @T6G_MB_LIB.T6G(SCH_1):P3V3_M2_0
   2 VSENSE_P12V_INA230_4_INN      B @T6G_MB_LIB.T6G(SCH_1):VSENSE_P12V_INA230_4_INN

Q_RES_0402LF-10,1%,1/16W,CHIP,CS01002FB07  I35  R3574
   1   P3V3      A @T6G_MB_LIB.T6G(SCH_1):P3V3
   2 VSENSE_P12V_INA230_4_INP      B @T6G_MB_LIB.T6G(SCH_1):VSENSE_P12V_INA230_4_INP

Q_RES_0402LF-4.7K,1%,1/16W,CHIP,CS24702FB06  I36  R3611
   1    GND      A @T6G_MB_LIB.T6G(SCH_1):GND
   2 INA230_4_A0      B @T6G_MB_LIB.T6G(SCH_1):INA230_4_A0

Q_RES_0402LF-0,5%,1/16W,CHIP,CS00002JB13  I41  R3560
   1 M2_0_P3V3_ADC_ALERT_R      A @T6G_MB_LIB.T6G(SCH_1):M2_0_P3V3_ADC_ALERT_R
   2 M2_0_P3V3_ADC_ALERT      B @T6G_MB_LIB.T6G(SCH_1):M2_0_P3V3_ADC_ALERT

Q_CAP_0402-0.1UF,25V,10%,X7R,CH4104K1B00  I42  C2013
   1 P3V3_AUX      A @T6G_MB_LIB.T6G(SCH_1):P3V3_AUX
   2    GND      B @T6G_MB_LIB.T6G(SCH_1):GND

Q_RES_0402LF-4.7K,1%,1/16W,EMPTY,CS24702FB06  I45  R3610
   1    GND      A @T6G_MB_LIB.T6G(SCH_1):GND
   2 INA230_4_A1      B @T6G_MB_LIB.T6G(SCH_1):INA230_4_A1

ISL28022FRZT-ISL28022FRZ-T,SMLF,IC,AL028022003  I46  U264
   9 P3V3_AUX    VCC @T6G_MB_LIB.T6G(SCH_1):P3V3_AUX
   1 INA230_4_A1     A1 @T6G_MB_LIB.T6G(SCH_1):INA230_4_A1
   2 INA230_4_A0     A0 @T6G_MB_LIB.T6G(SCH_1):INA230_4_A0
   5 SMB_INA230_4_3V3AUX_SCL_R1 SCL|||SMBCLK @T6G_MB_LIB.T6G(SCH_1):SMB_INA230_4_3V3AUX_SCL_R1
   4 SMB_INA230_4_3V3AUX_SDA_R1 SDA||SMBDAT @T6G_MB_LIB.T6G(SCH_1):SMB_INA230_4_3V3AUX_SDA_R1
  11   P3V3   VBUS @T6G_MB_LIB.T6G(SCH_1):P3V3
  13 VSENSE_P12V_INA230_4_INP   VINP @T6G_MB_LIB.T6G(SCH_1):VSENSE_P12V_INA230_4_INP
  12 VSENSE_P12V_INA230_4_INN   VINM @T6G_MB_LIB.T6G(SCH_1):VSENSE_P12V_INA230_4_INN
   3 M2_0_P3V3_ADC_ALERT_R EXT_CLK||INT @T6G_MB_LIB.T6G(SCH_1):M2_0_P3V3_ADC_ALERT_R
   6 NC_INA230_4_NC0    NC0 @T6G_MB_LIB.T6G(SCH_1):NC_INA230_4_NC0
   7 NC_INA230_4_NC1    NC1 @T6G_MB_LIB.T6G(SCH_1):NC_INA230_4_NC1
   8 NC_INA230_4_NC2    NC2 @T6G_MB_LIB.T6G(SCH_1):NC_INA230_4_NC2
  14 NC_INA230_4_NC3    NC3 @T6G_MB_LIB.T6G(SCH_1):NC_INA230_4_NC3
  15 NC_INA230_4_NC4    NC4 @T6G_MB_LIB.T6G(SCH_1):NC_INA230_4_NC4
  16 NC_INA230_4_NC5    NC5 @T6G_MB_LIB.T6G(SCH_1):NC_INA230_4_NC5
  10    GND    GND @T6G_MB_LIB.T6G(SCH_1):GND
  TH    GND TH_GND @T6G_MB_LIB.T6G(SCH_1):GND

Q_CAP_0402-0.1UF,25V,10%,X7R,CH4104K1B00  I49  C2019
   1 P12V_SCM_R      A @T6G_MB_LIB.T6G(SCH_1):P12V_SCM_R
   2    GND      B @T6G_MB_LIB.T6G(SCH_1):GND

Q_RES_0402LF-10,1%,1/16W,CHIP,CS01002FB07  I56  R3579
   1 P12V_SCM      A @T6G_MB_LIB.T6G(SCH_1):P12V_SCM
   2 VSENSE_P12V_INA230_5_INN      B @T6G_MB_LIB.T6G(SCH_1):VSENSE_P12V_INA230_5_INN

Q_RES_0402LF-10,1%,1/16W,CHIP,CS01002FB07  I58  R3578
   1 P12V_SCM_R      A @T6G_MB_LIB.T6G(SCH_1):P12V_SCM_R
   2 VSENSE_P12V_INA230_5_INP      B @T6G_MB_LIB.T6G(SCH_1):VSENSE_P12V_INA230_5_INP

Q_RES_0402LF-4.7K,1%,1/16W,EMPTY,CS24702FB06  I59  R3613
   1    GND      A @T6G_MB_LIB.T6G(SCH_1):GND
   2 INA230_5_A0      B @T6G_MB_LIB.T6G(SCH_1):INA230_5_A0

Q_RES_0402LF-0,5%,1/16W,CHIP,CS00002JB13  I64  R3561
   1 P12V_SCM_ADC_ALERT_R      A @T6G_MB_LIB.T6G(SCH_1):P12V_SCM_ADC_ALERT_R
   2 P12V_SCM_ADC_ALERT      B @T6G_MB_LIB.T6G(SCH_1):P12V_SCM_ADC_ALERT

Q_CAP_0402-0.1UF,25V,10%,X7R,CH4104K1B00  I65  C2014
   1 P3V3_AUX      A @T6G_MB_LIB.T6G(SCH_1):P3V3_AUX
   2    GND      B @T6G_MB_LIB.T6G(SCH_1):GND

Q_RES_0402LF-4.7K,1%,1/16W,EMPTY,CS24702FB06  I68  R3612
   1    GND      A @T6G_MB_LIB.T6G(SCH_1):GND
   2 INA230_5_A1      B @T6G_MB_LIB.T6G(SCH_1):INA230_5_A1

ISL28022FRZT-ISL28022FRZ-T,SMLF,IC,AL028022003  I69  U265
   9 P3V3_AUX    VCC @T6G_MB_LIB.T6G(SCH_1):P3V3_AUX
   1 INA230_5_A1     A1 @T6G_MB_LIB.T6G(SCH_1):INA230_5_A1
   2 INA230_5_A0     A0 @T6G_MB_LIB.T6G(SCH_1):INA230_5_A0
   5 SMB_INA230_5_3V3AUX_SCL_R1 SCL|||SMBCLK @T6G_MB_LIB.T6G(SCH_1):SMB_INA230_5_3V3AUX_SCL_R1
   4 SMB_INA230_5_3V3AUX_SDA_R1 SDA||SMBDAT @T6G_MB_LIB.T6G(SCH_1):SMB_INA230_5_3V3AUX_SDA_R1
  11 P12V_SCM_R   VBUS @T6G_MB_LIB.T6G(SCH_1):P12V_SCM_R
  13 VSENSE_P12V_INA230_5_INP   VINP @T6G_MB_LIB.T6G(SCH_1):VSENSE_P12V_INA230_5_INP
  12 VSENSE_P12V_INA230_5_INN   VINM @T6G_MB_LIB.T6G(SCH_1):VSENSE_P12V_INA230_5_INN
   3 P12V_SCM_ADC_ALERT_R EXT_CLK||INT @T6G_MB_LIB.T6G(SCH_1):P12V_SCM_ADC_ALERT_R
   6 NC_INA230_5_NC0    NC0 @T6G_MB_LIB.T6G(SCH_1):NC_INA230_5_NC0
   7 NC_INA230_5_NC1    NC1 @T6G_MB_LIB.T6G(SCH_1):NC_INA230_5_NC1
   8 NC_INA230_5_NC2    NC2 @T6G_MB_LIB.T6G(SCH_1):NC_INA230_5_NC2
  14 NC_INA230_5_NC3    NC3 @T6G_MB_LIB.T6G(SCH_1):NC_INA230_5_NC3
  15 NC_INA230_5_NC4    NC4 @T6G_MB_LIB.T6G(SCH_1):NC_INA230_5_NC4
  16 NC_INA230_5_NC5    NC5 @T6G_MB_LIB.T6G(SCH_1):NC_INA230_5_NC5
  10    GND    GND @T6G_MB_LIB.T6G(SCH_1):GND
  TH    GND TH_GND @T6G_MB_LIB.T6G(SCH_1):GND

Q_CAP_0402-0.1UF,25V,10%,X7R,CH4104K1B00  I71  C2021
   1 VSENSE_P12V_INA230_4_INP      A @T6G_MB_LIB.T6G(SCH_1):VSENSE_P12V_INA230_4_INP
   2 VSENSE_P12V_INA230_4_INN      B @T6G_MB_LIB.T6G(SCH_1):VSENSE_P12V_INA230_4_INN

Q_CAP_0402-0.1UF,25V,10%,X7R,CH4104K1B00  I72  C2022
   1 VSENSE_P12V_INA230_5_INP      A @T6G_MB_LIB.T6G(SCH_1):VSENSE_P12V_INA230_5_INP
   2 VSENSE_P12V_INA230_5_INN      B @T6G_MB_LIB.T6G(SCH_1):VSENSE_P12V_INA230_5_INN

Q_RES_0402LF-4.7K,1%,1/16W,CHIP,CS24702FB06  I86  R3623
   1 P3V3_AUX      A @T6G_MB_LIB.T6G(SCH_1):P3V3_AUX
   2 INA230_4_A1      B @T6G_MB_LIB.T6G(SCH_1):INA230_4_A1

Q_RES_0402LF-4.7K,1%,1/16W,EMPTY,CS24702FB06  I87  R3621
   1 P3V3_AUX      A @T6G_MB_LIB.T6G(SCH_1):P3V3_AUX
   2 INA230_4_A0      B @T6G_MB_LIB.T6G(SCH_1):INA230_4_A0

Q_RES_0402LF-4.7K,1%,1/16W,CHIP,CS24702FB06  I89  R3624
   1 P3V3_AUX      A @T6G_MB_LIB.T6G(SCH_1):P3V3_AUX
   2 INA230_5_A1      B @T6G_MB_LIB.T6G(SCH_1):INA230_5_A1

Q_RES_0402LF-4.7K,1%,1/16W,CHIP,CS24702FB06  I90  R3622
   1 P3V3_AUX      A @T6G_MB_LIB.T6G(SCH_1):P3V3_AUX
   2 INA230_5_A0      B @T6G_MB_LIB.T6G(SCH_1):INA230_5_A0

Q_RES_2512LF-0.002,1%,2W,CHIP,CS+002AFR06  I92  R3634
   1 P3V3_M2_0      A @T6G_MB_LIB.T6G(SCH_1):P3V3_M2_0
   2   P3V3      B @T6G_MB_LIB.T6G(SCH_1):P3V3

Q_RES_2512LF-0.002,1%,2W,CHIP,CS+002AFR06  I93  R3635
   1 P12V_SCM      A @T6G_MB_LIB.T6G(SCH_1):P12V_SCM
   2 P12V_SCM_R      B @T6G_MB_LIB.T6G(SCH_1):P12V_SCM_R

ISL28022FRZT-ISL28022FRZ-T,SMLF,IC,AL028022003  I94  U263
   9 P3V3_AUX    VCC @T6G_MB_LIB.T6G(SCH_1):P3V3_AUX
   1 INA230_3_A1     A1 @T6G_MB_LIB.T6G(SCH_1):INA230_3_A1
   2 INA230_3_A0     A0 @T6G_MB_LIB.T6G(SCH_1):INA230_3_A0
   5 SMB_INA230_3_3V3AUX_SCL_R1 SCL|||SMBCLK @T6G_MB_LIB.T6G(SCH_1):SMB_INA230_3_3V3AUX_SCL_R1
   4 SMB_INA230_3_3V3AUX_SDA_R1 SDA||SMBDAT @T6G_MB_LIB.T6G(SCH_1):SMB_INA230_3_3V3AUX_SDA_R1
  11 P3V3_OCP_V3_2_R   VBUS @T6G_MB_LIB.T6G(SCH_1):P3V3_OCP_V3_2_R
  13 VSENSE_P12V_INA230_3_INP   VINP @T6G_MB_LIB.T6G(SCH_1):VSENSE_P12V_INA230_3_INP
  12 VSENSE_P12V_INA230_3_INN   VINM @T6G_MB_LIB.T6G(SCH_1):VSENSE_P12V_INA230_3_INN
   3 OCP_V3_2_P3V3_ADC_ALERT_R EXT_CLK||INT @T6G_MB_LIB.T6G(SCH_1):OCP_V3_2_P3V3_ADC_ALERT_R
   6 NC_INA230_3_NC0    NC0 @T6G_MB_LIB.T6G(SCH_1):NC_INA230_3_NC0
   7 NC_INA230_3_NC1    NC1 @T6G_MB_LIB.T6G(SCH_1):NC_INA230_3_NC1
   8 NC_INA230_3_NC2    NC2 @T6G_MB_LIB.T6G(SCH_1):NC_INA230_3_NC2
  14 NC_INA230_3_NC3    NC3 @T6G_MB_LIB.T6G(SCH_1):NC_INA230_3_NC3
  15 NC_INA230_3_NC4    NC4 @T6G_MB_LIB.T6G(SCH_1):NC_INA230_3_NC4
  16 NC_INA230_3_NC5    NC5 @T6G_MB_LIB.T6G(SCH_1):NC_INA230_3_NC5
  10    GND    GND @T6G_MB_LIB.T6G(SCH_1):GND
  TH    GND TH_GND @T6G_MB_LIB.T6G(SCH_1):GND

Q_RES_0402LF-0,5%,1/16W,CHIP,CS00002JB13  I96  R3559
   1 OCP_V3_2_P3V3_ADC_ALERT_R      A @T6G_MB_LIB.T6G(SCH_1):OCP_V3_2_P3V3_ADC_ALERT_R
   2 OCP_V3_2_P3V3_P12V_ADC_R_ALERT      B @T6G_MB_LIB.T6G(SCH_1):OCP_V3_2_P3V3_P12V_ADC_R_ALERT

Q_CAP_0402-0.1UF,25V,10%,X7R,CH4104K1B00  I98  C2012
   1 P3V3_AUX      A @T6G_MB_LIB.T6G(SCH_1):P3V3_AUX
   2    GND      B @T6G_MB_LIB.T6G(SCH_1):GND

Q_RES_0402LF-0,5%,1/16W,CHIP,CS00002JB13  I100  R3620
   1 INA230_3_A0      A @T6G_MB_LIB.T6G(SCH_1):INA230_3_A0
   2 SMB_INA230_3_3V3AUX_SCL_R1      B @T6G_MB_LIB.T6G(SCH_1):SMB_INA230_3_3V3AUX_SCL_R1

Q_RES_0402LF-4.7K,1%,1/16W,CHIP,CS24702FB06  I103  R3608
   1    GND      A @T6G_MB_LIB.T6G(SCH_1):GND
   2 INA230_3_A1      B @T6G_MB_LIB.T6G(SCH_1):INA230_3_A1

Q_RES_0402LF-4.7K,1%,1/16W,EMPTY,CS24702FB06  I104  R3609
   1    GND      A @T6G_MB_LIB.T6G(SCH_1):GND
   2 INA230_3_A0      B @T6G_MB_LIB.T6G(SCH_1):INA230_3_A0

Q_CAP_0402-0.1UF,25V,10%,X7R,CH4104K1B00  I108  C2020
   1 VSENSE_P12V_INA230_3_INP      A @T6G_MB_LIB.T6G(SCH_1):VSENSE_P12V_INA230_3_INP
   2 VSENSE_P12V_INA230_3_INN      B @T6G_MB_LIB.T6G(SCH_1):VSENSE_P12V_INA230_3_INN

Q_RES_0402LF-10,1%,1/16W,CHIP,CS01002FB07  I109  R3570
   1 P3V3_OCP_V3_2_R      A @T6G_MB_LIB.T6G(SCH_1):P3V3_OCP_V3_2_R
   2 VSENSE_P12V_INA230_3_INP      B @T6G_MB_LIB.T6G(SCH_1):VSENSE_P12V_INA230_3_INP

Q_RES_0402LF-10,1%,1/16W,CHIP,CS01002FB07  I110  R3571
   1 P3V3_OCP_V3_2      A @T6G_MB_LIB.T6G(SCH_1):P3V3_OCP_V3_2
   2 VSENSE_P12V_INA230_3_INN      B @T6G_MB_LIB.T6G(SCH_1):VSENSE_P12V_INA230_3_INN

Q_CAP_0402-0.1UF,25V,10%,X7R,CH4104K1B00  I114  C2017
   1 P3V3_OCP_V3_2_R      A @T6G_MB_LIB.T6G(SCH_1):P3V3_OCP_V3_2_R
   2    GND      B @T6G_MB_LIB.T6G(SCH_1):GND

Q_RES_2512LF-0.002,1%,2W,CHIP,CS+002AFR06  I116  R3633
   1 P3V3_OCP_V3_2      A @T6G_MB_LIB.T6G(SCH_1):P3V3_OCP_V3_2
   2 P3V3_OCP_V3_2_R      B @T6G_MB_LIB.T6G(SCH_1):P3V3_OCP_V3_2_R

Q_RES_0402LF-1K,1%,1/16W,CHIP,CS21002FB06  I122  R4091
   1 P3V3_AUX      A @T6G_MB_LIB.T6G(SCH_1):P3V3_AUX
   2 P12V_SCM_ADC_ALERT_R      B @T6G_MB_LIB.T6G(SCH_1):P12V_SCM_ADC_ALERT_R

Q_RES_0402LF-1K,1%,1/16W,CHIP,CS21002FB06  I124  R4090
   1 P3V3_AUX      A @T6G_MB_LIB.T6G(SCH_1):P3V3_AUX
   2 M2_0_P3V3_ADC_ALERT_R      B @T6G_MB_LIB.T6G(SCH_1):M2_0_P3V3_ADC_ALERT_R

Q_RES_0402LF-1K,1%,1/16W,CHIP,CS21002FB06  I126  R4092
   1 P3V3_AUX      A @T6G_MB_LIB.T6G(SCH_1):P3V3_AUX
   2 OCP_V3_2_P3V3_ADC_ALERT_R      B @T6G_MB_LIB.T6G(SCH_1):OCP_V3_2_P3V3_ADC_ALERT_R

Q_RES_0402LF-0,5%,1/16W,CHIP,CS00002JB13  I127  R3569
   1 SMB_INA230_3_3V3AUX_SDA_R      A @T6G_MB_LIB.T6G(SCH_1):SMB_INA230_3_3V3AUX_SDA_R
   2 SMB_INA230_3_3V3AUX_SDA_R1      B @T6G_MB_LIB.T6G(SCH_1):SMB_INA230_3_3V3AUX_SDA_R1

Q_RES_0402LF-0,5%,1/16W,CHIP,CS00002JB13  I128  R3568
   1 SMB_INA230_3_3V3AUX_SCL_R      A @T6G_MB_LIB.T6G(SCH_1):SMB_INA230_3_3V3AUX_SCL_R
   2 SMB_INA230_3_3V3AUX_SCL_R1      B @T6G_MB_LIB.T6G(SCH_1):SMB_INA230_3_3V3AUX_SCL_R1

Q_RES_0402LF-0,5%,1/16W,CHIP,CS00002JB13  I129  R3573
   1 SMB_INA230_4_3V3AUX_SDA_R      A @T6G_MB_LIB.T6G(SCH_1):SMB_INA230_4_3V3AUX_SDA_R
   2 SMB_INA230_4_3V3AUX_SDA_R1      B @T6G_MB_LIB.T6G(SCH_1):SMB_INA230_4_3V3AUX_SDA_R1

Q_RES_0402LF-0,5%,1/16W,CHIP,CS00002JB13  I130  R3572
   1 SMB_INA230_4_3V3AUX_SCL_R      A @T6G_MB_LIB.T6G(SCH_1):SMB_INA230_4_3V3AUX_SCL_R
   2 SMB_INA230_4_3V3AUX_SCL_R1      B @T6G_MB_LIB.T6G(SCH_1):SMB_INA230_4_3V3AUX_SCL_R1

Q_RES_0402LF-0,5%,1/16W,CHIP,CS00002JB13  I131  R3576
   1 SMB_INA230_5_3V3AUX_SCL_R      A @T6G_MB_LIB.T6G(SCH_1):SMB_INA230_5_3V3AUX_SCL_R
   2 SMB_INA230_5_3V3AUX_SCL_R1      B @T6G_MB_LIB.T6G(SCH_1):SMB_INA230_5_3V3AUX_SCL_R1

Q_RES_0402LF-0,5%,1/16W,CHIP,CS00002JB13  I132  R3577
   1 SMB_INA230_5_3V3AUX_SDA_R      A @T6G_MB_LIB.T6G(SCH_1):SMB_INA230_5_3V3AUX_SDA_R
   2 SMB_INA230_5_3V3AUX_SDA_R1      B @T6G_MB_LIB.T6G(SCH_1):SMB_INA230_5_3V3AUX_SDA_R1


DRAWING: @T6G_MB_LIB.T6G(SCH_1):PAGE361 

M24128BWMN6TP-M24128-BWMN6TP,SMLF,IC,AKE30Z00613  I35  U64
   8 P3V3_AUX    VCC @T6G_MB_LIB.T6G(SCH_1):P3V3_AUX
   7 PD_MB_FRU_WP    WC# @T6G_MB_LIB.T6G(SCH_1):PD_MB_FRU_WP
   6 SMB_FRU_3V3AUX_R1_SCL    SCL @T6G_MB_LIB.T6G(SCH_1):SMB_FRU_3V3AUX_R1_SCL
   5 SMB_FRU_3V3AUX_R1_SDA    SDA @T6G_MB_LIB.T6G(SCH_1):SMB_FRU_3V3AUX_R1_SDA
   4    GND    VSS @T6G_MB_LIB.T6G(SCH_1):GND
   3 MB_FRU_ADDR2     E2 @T6G_MB_LIB.T6G(SCH_1):MB_FRU_ADDR2
   2 MB_FRU_ADDR1     E1 @T6G_MB_LIB.T6G(SCH_1):MB_FRU_ADDR1
   1 MB_FRU_ADDR0     E0 @T6G_MB_LIB.T6G(SCH_1):MB_FRU_ADDR0

Q_RES_0402LF-10K,1%,1/16W,EMPTY,CS31002FB08  I45  R717
   1 P3V3_AUX      A @T6G_MB_LIB.T6G(SCH_1):P3V3_AUX
   2 MB_FRU_ADDR1      B @T6G_MB_LIB.T6G(SCH_1):MB_FRU_ADDR1

Q_RES_0402LF-10K,1%,1/16W,EMPTY,CS31002FB08  I47  R713
   1 P3V3_AUX      A @T6G_MB_LIB.T6G(SCH_1):P3V3_AUX
   2 MB_FRU_ADDR2      B @T6G_MB_LIB.T6G(SCH_1):MB_FRU_ADDR2

Q_RES_0402LF-1K,1%,1/16W,CHIP,CS21002FB06  I50  R718
   1 MB_FRU_ADDR1      A @T6G_MB_LIB.T6G(SCH_1):MB_FRU_ADDR1
   2    GND      B @T6G_MB_LIB.T6G(SCH_1):GND

Q_RES_0402LF-1K,1%,1/16W,CHIP,CS21002FB06  I52  R714
   1 MB_FRU_ADDR2      A @T6G_MB_LIB.T6G(SCH_1):MB_FRU_ADDR2
   2    GND      B @T6G_MB_LIB.T6G(SCH_1):GND

Q_CAP_0402-0.1UF,25V,10%,X7R,CH4104K1B00  I55  C629
   1 P3V3_AUX      A @T6G_MB_LIB.T6G(SCH_1):P3V3_AUX
   2    GND      B @T6G_MB_LIB.T6G(SCH_1):GND

Q_RES_0402LF-1K,1%,1/16W,CHIP,CS21002FB06  I57  R710
   1 PD_MB_FRU_WP      A @T6G_MB_LIB.T6G(SCH_1):PD_MB_FRU_WP
   2    GND      B @T6G_MB_LIB.T6G(SCH_1):GND

Q_RES_0402LF-1K,1%,1/16W,EMPTY,CS21002FB06  I61  R722
   1 MB_FRU_ADDR0      A @T6G_MB_LIB.T6G(SCH_1):MB_FRU_ADDR0
   2    GND      B @T6G_MB_LIB.T6G(SCH_1):GND

Q_RES_0402LF-10K,1%,1/16W,CHIP,CS31002FB08  I62  R721
   1 P3V3_AUX      A @T6G_MB_LIB.T6G(SCH_1):P3V3_AUX
   2 MB_FRU_ADDR0      B @T6G_MB_LIB.T6G(SCH_1):MB_FRU_ADDR0

Q_RES_0402LF-4.7K,5%,1/16W,EMPTY,CS24702JB10  I93  R43
   1 P3V3_AUX      A @T6G_MB_LIB.T6G(SCH_1):P3V3_AUX
   2 SMB_FRU_3V3AUX_R1_SDA      B @T6G_MB_LIB.T6G(SCH_1):SMB_FRU_3V3AUX_R1_SDA

Q_RES_0402LF-4.7K,5%,1/16W,EMPTY,CS24702JB10  I95  R26
   1 P3V3_AUX      A @T6G_MB_LIB.T6G(SCH_1):P3V3_AUX
   2 SMB_FRU_3V3AUX_R1_SCL      B @T6G_MB_LIB.T6G(SCH_1):SMB_FRU_3V3AUX_R1_SCL

Q_RES_0402LF-10K,1%,1/16W,EMPTY,CS31002FB08  I103  R52
   1 P3V3_AUX      A @T6G_MB_LIB.T6G(SCH_1):P3V3_AUX
   2 CPU_FRU_ADDR2      B @T6G_MB_LIB.T6G(SCH_1):CPU_FRU_ADDR2

Q_CAP_0402-0.1UF,25V,10%,X7R,CH4104K1B00  I110  C1
   1 P3V3_AUX      A @T6G_MB_LIB.T6G(SCH_1):P3V3_AUX
   2    GND      B @T6G_MB_LIB.T6G(SCH_1):GND

Q_RES_0402LF-4.7K,5%,1/16W,EMPTY,CS24702JB10  I113  R24
   1 P3V3_AUX      A @T6G_MB_LIB.T6G(SCH_1):P3V3_AUX
   2 SMB_CPU_FRU_3V3AUX_SDA      B @T6G_MB_LIB.T6G(SCH_1):SMB_CPU_FRU_3V3AUX_SDA

Q_RES_0402LF-4.7K,5%,1/16W,EMPTY,CS24702JB10  I114  R4
   1 P3V3_AUX      A @T6G_MB_LIB.T6G(SCH_1):P3V3_AUX
   2 SMB_CPU_FRU_3V3AUX_SCL      B @T6G_MB_LIB.T6G(SCH_1):SMB_CPU_FRU_3V3AUX_SCL

Q_RES_0402LF-1K,1%,1/16W,CHIP,CS21002FB06  I115  R44
   1 PD_CPU_FRU_WP      A @T6G_MB_LIB.T6G(SCH_1):PD_CPU_FRU_WP
   2    GND      B @T6G_MB_LIB.T6G(SCH_1):GND

M24128BWMN6TP-M24128-BWMN6TP,SMLF,IC,AKE30Z00613  I97  U1
   8 P3V3_AUX    VCC @T6G_MB_LIB.T6G(SCH_1):P3V3_AUX
   7 PD_CPU_FRU_WP    WC# @T6G_MB_LIB.T6G(SCH_1):PD_CPU_FRU_WP
   6 SMB_CPU_FRU_3V3AUX_SCL    SCL @T6G_MB_LIB.T6G(SCH_1):SMB_CPU_FRU_3V3AUX_SCL
   5 SMB_CPU_FRU_3V3AUX_SDA    SDA @T6G_MB_LIB.T6G(SCH_1):SMB_CPU_FRU_3V3AUX_SDA
   4    GND    VSS @T6G_MB_LIB.T6G(SCH_1):GND
   3 CPU_FRU_ADDR2     E2 @T6G_MB_LIB.T6G(SCH_1):CPU_FRU_ADDR2
   2 CPU_FRU_ADDR1     E1 @T6G_MB_LIB.T6G(SCH_1):CPU_FRU_ADDR1
   1 CPU_FRU_ADDR0     E0 @T6G_MB_LIB.T6G(SCH_1):CPU_FRU_ADDR0

Q_RES_0402LF-10K,1%,1/16W,EMPTY,CS31002FB08  I101  R60
   1 P3V3_AUX      A @T6G_MB_LIB.T6G(SCH_1):P3V3_AUX
   2 CPU_FRU_ADDR1      B @T6G_MB_LIB.T6G(SCH_1):CPU_FRU_ADDR1

Q_RES_0402LF-1K,1%,1/16W,CHIP,CS21002FB06  I104  R62
   1 CPU_FRU_ADDR1      A @T6G_MB_LIB.T6G(SCH_1):CPU_FRU_ADDR1
   2    GND      B @T6G_MB_LIB.T6G(SCH_1):GND

Q_RES_0402LF-1K,1%,1/16W,CHIP,CS21002FB06  I107  R54
   1 CPU_FRU_ADDR2      A @T6G_MB_LIB.T6G(SCH_1):CPU_FRU_ADDR2
   2    GND      B @T6G_MB_LIB.T6G(SCH_1):GND

Q_RES_0402LF-1K,1%,1/16W,EMPTY,CS21002FB06  I120  R68
   1 P3V3_AUX      A @T6G_MB_LIB.T6G(SCH_1):P3V3_AUX
   2 CPU_FRU_ADDR0      B @T6G_MB_LIB.T6G(SCH_1):CPU_FRU_ADDR0

Q_RES_0402LF-10K,1%,1/16W,CHIP,CS31002FB08  I121  R69
   1 CPU_FRU_ADDR0      A @T6G_MB_LIB.T6G(SCH_1):CPU_FRU_ADDR0
   2    GND      B @T6G_MB_LIB.T6G(SCH_1):GND

Q_RES_0402LF-0,5%,1/16W,CHIP,CS00002JB13  I122  R121
   1 SMB_FRU_3V3AUX_SCL      A @T6G_MB_LIB.T6G(SCH_1):SMB_FRU_3V3AUX_SCL
   2 SMB_CPU_FRU_3V3AUX_SCL      B @T6G_MB_LIB.T6G(SCH_1):SMB_CPU_FRU_3V3AUX_SCL

Q_RES_0402LF-0,5%,1/16W,CHIP,CS00002JB13  I123  R125
   1 SMB_FRU_3V3AUX_SDA      A @T6G_MB_LIB.T6G(SCH_1):SMB_FRU_3V3AUX_SDA
   2 SMB_CPU_FRU_3V3AUX_SDA      B @T6G_MB_LIB.T6G(SCH_1):SMB_CPU_FRU_3V3AUX_SDA

Q_RES_0402LF-0,5%,1/16W,CHIP,CS00002JB13  I124  R85
   1 SMB_FRU_3V3AUX_SCL      A @T6G_MB_LIB.T6G(SCH_1):SMB_FRU_3V3AUX_SCL
   2 SMB_FRU_3V3AUX_R1_SCL      B @T6G_MB_LIB.T6G(SCH_1):SMB_FRU_3V3AUX_R1_SCL

Q_RES_0402LF-0,5%,1/16W,CHIP,CS00002JB13  I125  R86
   1 SMB_FRU_3V3AUX_SDA      A @T6G_MB_LIB.T6G(SCH_1):SMB_FRU_3V3AUX_SDA
   2 SMB_FRU_3V3AUX_R1_SDA      B @T6G_MB_LIB.T6G(SCH_1):SMB_FRU_3V3AUX_R1_SDA


DRAWING: @T6G_MB_LIB.T6G(SCH_1):PAGE363 

Q_RES_0402LF-0,5%,1/16W,CHIP,CS00002JB13  I387  R2802
   1 HPDB_HSC_PWRGD_R      A @T6G_MB_LIB.T6G(SCH_1):HPDB_HSC_PWRGD_R
   2 HPDB_HSC_PWRGD      B @T6G_MB_LIB.T6G(SCH_1):HPDB_HSC_PWRGD

Q_RES_0402LF-0,5%,1/16W,CHIP,CS00002JB13  I388  R2803
   1 FM_FAN_PWR_EN_R      A @T6G_MB_LIB.T6G(SCH_1):FM_FAN_PWR_EN_R
   2 FM_FAN_PWR_EN      B @T6G_MB_LIB.T6G(SCH_1):FM_FAN_PWR_EN

MOSFET_NCH_GDS_ESD_PROTECTED-2N7002K,SMLF,IC,BAM70A  I392  U190
   D FM_PDB_BUF_EN_R1      D @T6G_MB_LIB.T6G(SCH_1):FM_PDB_BUF_EN_R1
   G FM_PDB_BUF_EN_R1_N      G @T6G_MB_LIB.T6G(SCH_1):FM_PDB_BUF_EN_R1_N
   S    GND      S @T6G_MB_LIB.T6G(SCH_1):GND

Q_RES_0402LF-0,5%,1/16W,CHIP,CS00002JB13  I394  R2793
   1 FM_PDB_BUF_EN_R_N      A @T6G_MB_LIB.T6G(SCH_1):FM_PDB_BUF_EN_R_N
   2 FM_PDB_BUF_EN_R1_N      B @T6G_MB_LIB.T6G(SCH_1):FM_PDB_BUF_EN_R1_N

Q_RES_0402LF-4.7K,5%,1/16W,CHIP,CS24702JB10  I396  R2794
   1 P3V3_AUX      A @T6G_MB_LIB.T6G(SCH_1):P3V3_AUX
   2 FM_PDB_BUF_EN_R1      B @T6G_MB_LIB.T6G(SCH_1):FM_PDB_BUF_EN_R1

LTC4307CMS8-LTC4307CMS8,SMLF,IC,AL004307000  I398  U192
   1 MB_PDB_SMB9_R_EN ENABLE @T6G_MB_LIB.T6G(SCH_1):MB_PDB_SMB9_R_EN
   3 SMB_FAN_3V3AUX_R_SCL SCL_IN @T6G_MB_LIB.T6G(SCH_1):SMB_FAN_3V3AUX_R_SCL
   6 SMB_FAN_3V3AUX_R_SDA SDA_IN @T6G_MB_LIB.T6G(SCH_1):SMB_FAN_3V3AUX_R_SDA
   2 SMB_FAN_3V3AUX_BUF_SCL SCL_OUT @T6G_MB_LIB.T6G(SCH_1):SMB_FAN_3V3AUX_BUF_SCL
   7 SMB_FAN_3V3AUX_BUF_SDA SDA_OUT @T6G_MB_LIB.T6G(SCH_1):SMB_FAN_3V3AUX_BUF_SDA
   5     NC  READY     NC
   4    GND    GND @T6G_MB_LIB.T6G(SCH_1):GND
   8 P3V3_AUX    VCC @T6G_MB_LIB.T6G(SCH_1):P3V3_AUX

Q_CAP_0402-0.1UF,25V,10%,X7R,CH4104K1B00  I412  C1751
   1 P3V3_AUX      A @T6G_MB_LIB.T6G(SCH_1):P3V3_AUX
   2    GND      B @T6G_MB_LIB.T6G(SCH_1):GND

Q_RES_0402LF-0,5%,1/16W,CHIP,CS00002JB13  I420  R2796
   1 FM_PDB_BUF_EN_R1      A @T6G_MB_LIB.T6G(SCH_1):FM_PDB_BUF_EN_R1
   2 MB_PDB_SMB9_R_EN      B @T6G_MB_LIB.T6G(SCH_1):MB_PDB_SMB9_R_EN

Q_RES_0402LF-33.2,1%,1/16W,CHIP,CS03322FB03  I425  R2811
   1 SMB_FAN_3V3AUX_BUF_SCL      A @T6G_MB_LIB.T6G(SCH_1):SMB_FAN_3V3AUX_BUF_SCL
   2 SMB_FAN_3V3AUX_BUF_R_SCL      B @T6G_MB_LIB.T6G(SCH_1):SMB_FAN_3V3AUX_BUF_R_SCL

Q_RES_0402LF-33.2,1%,1/16W,CHIP,CS03322FB03  I426  R2812
   1 SMB_FAN_3V3AUX_BUF_SDA      A @T6G_MB_LIB.T6G(SCH_1):SMB_FAN_3V3AUX_BUF_SDA
   2 SMB_FAN_3V3AUX_BUF_R_SDA      B @T6G_MB_LIB.T6G(SCH_1):SMB_FAN_3V3AUX_BUF_R_SDA

Q_RES_0402LF-0,5%,1/16W,EMPTY,CS00002JB13  I429  R2800
   1 SMB_FAN_3V3AUX_R_SCL      A @T6G_MB_LIB.T6G(SCH_1):SMB_FAN_3V3AUX_R_SCL
   2 SMB_FAN_3V3AUX_BUF_SCL      B @T6G_MB_LIB.T6G(SCH_1):SMB_FAN_3V3AUX_BUF_SCL

Q_RES_0402LF-0,5%,1/16W,EMPTY,CS00002JB13  I430  R2801
   1 SMB_FAN_3V3AUX_R_SDA      A @T6G_MB_LIB.T6G(SCH_1):SMB_FAN_3V3AUX_R_SDA
   2 SMB_FAN_3V3AUX_BUF_SDA      B @T6G_MB_LIB.T6G(SCH_1):SMB_FAN_3V3AUX_BUF_SDA

Q_RES_0402LF-4.7K,5%,1/16W,EMPTY,CS24702JB10  I436  R2805
   1 P3V3_AUX      A @T6G_MB_LIB.T6G(SCH_1):P3V3_AUX
   2 SMB_FAN_3V3AUX_BUF_SCL      B @T6G_MB_LIB.T6G(SCH_1):SMB_FAN_3V3AUX_BUF_SCL

Q_RES_0402LF-4.7K,5%,1/16W,EMPTY,CS24702JB10  I438  R2807
   1 P3V3_AUX      A @T6G_MB_LIB.T6G(SCH_1):P3V3_AUX
   2 SMB_FAN_3V3AUX_BUF_SDA      B @T6G_MB_LIB.T6G(SCH_1):SMB_FAN_3V3AUX_BUF_SDA

Q_RES_0402LF-0,5%,1/16W,CHIP,CS00002JB13  I440  R2906
   1 FM_GPU_HSC_EN_BUF_R1      A @T6G_MB_LIB.T6G(SCH_1):FM_GPU_HSC_EN_BUF_R1
   2 FM_GPU_HSC_EN_BUF      B @T6G_MB_LIB.T6G(SCH_1):FM_GPU_HSC_EN_BUF

Q_RES_0402LF-0,5%,1/16W,CHIP,CS00002JB13  I441  R2905
   1 RST_SMB_SWITCH_N      A @T6G_MB_LIB.T6G(SCH_1):RST_SMB_SWITCH_N
   2 RST_SMB_SWITCH_R_N      B @T6G_MB_LIB.T6G(SCH_1):RST_SMB_SWITCH_R_N

Q_CAP_0402-0.1UF,25V,10%,EMPTY,CH4104K1B00  I452  C74
   1 RST_SMB_SWITCH_R_N      A @T6G_MB_LIB.T6G(SCH_1):RST_SMB_SWITCH_R_N
   2    GND      B @T6G_MB_LIB.T6G(SCH_1):GND

Q_CAP_0402-0.1UF,25V,10%,EMPTY,CH4104K1B00  I453  C64
   1 PDB_PRSNT_N      A @T6G_MB_LIB.T6G(SCH_1):PDB_PRSNT_N
   2    GND      B @T6G_MB_LIB.T6G(SCH_1):GND

Q_CAP_0402-0.1UF,25V,10%,EMPTY,CH4104K1B00  I454  C65
   1 HPDB_HSC_PWRGD_R      A @T6G_MB_LIB.T6G(SCH_1):HPDB_HSC_PWRGD_R
   2    GND      B @T6G_MB_LIB.T6G(SCH_1):GND

Q_CAP_0402-0.1UF,25V,10%,EMPTY,CH4104K1B00  I455  C66
   1 FM_FAN_PWR_EN_R      A @T6G_MB_LIB.T6G(SCH_1):FM_FAN_PWR_EN_R
   2    GND      B @T6G_MB_LIB.T6G(SCH_1):GND

Q_CAP_0402-0.1UF,25V,10%,EMPTY,CH4104K1B00  I456  C67
   1 FM_GPU_HSC_EN_BUF_R1      A @T6G_MB_LIB.T6G(SCH_1):FM_GPU_HSC_EN_BUF_R1
   2    GND      B @T6G_MB_LIB.T6G(SCH_1):GND

Q_RES_0402LF-33.2,1%,1/16W,CHIP,CS03322FB03  I463  R3113
   1 SMB_FAN_3V3AUX_SCL      A @T6G_MB_LIB.T6G(SCH_1):SMB_FAN_3V3AUX_SCL
   2 SMB_FAN_3V3AUX_R_SCL      B @T6G_MB_LIB.T6G(SCH_1):SMB_FAN_3V3AUX_R_SCL

Q_RES_0402LF-33.2,1%,1/16W,CHIP,CS03322FB03  I464  R3114
   1 SMB_FAN_3V3AUX_SDA      A @T6G_MB_LIB.T6G(SCH_1):SMB_FAN_3V3AUX_SDA
   2 SMB_FAN_3V3AUX_R_SDA      B @T6G_MB_LIB.T6G(SCH_1):SMB_FAN_3V3AUX_R_SDA

CONN60_101062636003K02LF-CONN60_10106263-6003K02LFA  I466  J45
  A2 FM_AC_PWR_BTN_PDB_N     A2 @T6G_MB_LIB.T6G(SCH_1):FM_AC_PWR_BTN_PDB_N
  B2 PWRGD_P3V3_AUX_PDB_BUF     B2 @T6G_MB_LIB.T6G(SCH_1):PWRGD_P3V3_AUX_PDB_BUF
  C2 SMB_FAN_3V3AUX_BUF_R_SDA     C2 @T6G_MB_LIB.T6G(SCH_1):SMB_FAN_3V3AUX_BUF_R_SDA
  D2 FM_GPU_HSC_EN_BUF_R1     D2 @T6G_MB_LIB.T6G(SCH_1):FM_GPU_HSC_EN_BUF_R1
P1_1    GND   P1_1 @T6G_MB_LIB.T6G(SCH_1):GND
P1_2    GND   P1_2 @T6G_MB_LIB.T6G(SCH_1):GND
P1_3    GND   P1_3 @T6G_MB_LIB.T6G(SCH_1):GND
P1_4    GND   P1_4 @T6G_MB_LIB.T6G(SCH_1):GND
P1_5    GND   P1_5 @T6G_MB_LIB.T6G(SCH_1):GND
P1_6    GND   P1_6 @T6G_MB_LIB.T6G(SCH_1):GND
P1_7    GND   P1_7 @T6G_MB_LIB.T6G(SCH_1):GND
P1_8    GND   P1_8 @T6G_MB_LIB.T6G(SCH_1):GND
P2_1    GND   P2_1 @T6G_MB_LIB.T6G(SCH_1):GND
P2_2    GND   P2_2 @T6G_MB_LIB.T6G(SCH_1):GND
P2_3    GND   P2_3 @T6G_MB_LIB.T6G(SCH_1):GND
P2_4    GND   P2_4 @T6G_MB_LIB.T6G(SCH_1):GND
P2_5    GND   P2_5 @T6G_MB_LIB.T6G(SCH_1):GND
P2_6    GND   P2_6 @T6G_MB_LIB.T6G(SCH_1):GND
P2_7    GND   P2_7 @T6G_MB_LIB.T6G(SCH_1):GND
P2_8    GND   P2_8 @T6G_MB_LIB.T6G(SCH_1):GND
P4_1 P12V_PSU   P4_1 @T6G_MB_LIB.T6G(SCH_1):P12V_PSU
P4_2 P12V_PSU   P4_2 @T6G_MB_LIB.T6G(SCH_1):P12V_PSU
P4_3 P12V_PSU   P4_3 @T6G_MB_LIB.T6G(SCH_1):P12V_PSU
P4_4 P12V_PSU   P4_4 @T6G_MB_LIB.T6G(SCH_1):P12V_PSU
P4_5 P12V_PSU   P4_5 @T6G_MB_LIB.T6G(SCH_1):P12V_PSU
P4_6 P12V_PSU   P4_6 @T6G_MB_LIB.T6G(SCH_1):P12V_PSU
P4_7 P12V_PSU   P4_7 @T6G_MB_LIB.T6G(SCH_1):P12V_PSU
P4_8 P12V_PSU   P4_8 @T6G_MB_LIB.T6G(SCH_1):P12V_PSU
  A1 TP_J45_A1     A1 @T6G_MB_LIB.T6G(SCH_1):TP_J45_A1
  B1 RST_SMB_SWITCH_R_N     B1 @T6G_MB_LIB.T6G(SCH_1):RST_SMB_SWITCH_R_N
  C1 SMB_FAN_3V3AUX_BUF_R_SCL     C1 @T6G_MB_LIB.T6G(SCH_1):SMB_FAN_3V3AUX_BUF_R_SCL
  D1 FM_FAN_PWR_EN_R     D1 @T6G_MB_LIB.T6G(SCH_1):FM_FAN_PWR_EN_R
P5_1 P12V_PSU   P5_1 @T6G_MB_LIB.T6G(SCH_1):P12V_PSU
P5_2 P12V_PSU   P5_2 @T6G_MB_LIB.T6G(SCH_1):P12V_PSU
P5_3 P12V_PSU   P5_3 @T6G_MB_LIB.T6G(SCH_1):P12V_PSU
P5_4 P12V_PSU   P5_4 @T6G_MB_LIB.T6G(SCH_1):P12V_PSU
P5_5 P12V_PSU   P5_5 @T6G_MB_LIB.T6G(SCH_1):P12V_PSU
P5_6 P12V_PSU   P5_6 @T6G_MB_LIB.T6G(SCH_1):P12V_PSU
P5_7 P12V_PSU   P5_7 @T6G_MB_LIB.T6G(SCH_1):P12V_PSU
P5_8 P12V_PSU   P5_8 @T6G_MB_LIB.T6G(SCH_1):P12V_PSU
P3_1    GND   P3_1 @T6G_MB_LIB.T6G(SCH_1):GND
P3_2    GND   P3_2 @T6G_MB_LIB.T6G(SCH_1):GND
P3_3    GND   P3_3 @T6G_MB_LIB.T6G(SCH_1):GND
P3_4    GND   P3_4 @T6G_MB_LIB.T6G(SCH_1):GND
P3_5    GND   P3_5 @T6G_MB_LIB.T6G(SCH_1):GND
P3_6    GND   P3_6 @T6G_MB_LIB.T6G(SCH_1):GND
P3_7    GND   P3_7 @T6G_MB_LIB.T6G(SCH_1):GND
P3_8    GND   P3_8 @T6G_MB_LIB.T6G(SCH_1):GND
P6_1 P12V_PSU   P6_1 @T6G_MB_LIB.T6G(SCH_1):P12V_PSU
P6_2 P12V_PSU   P6_2 @T6G_MB_LIB.T6G(SCH_1):P12V_PSU
P6_3 P12V_PSU   P6_3 @T6G_MB_LIB.T6G(SCH_1):P12V_PSU
P6_4 P12V_PSU   P6_4 @T6G_MB_LIB.T6G(SCH_1):P12V_PSU
P6_5 P12V_PSU   P6_5 @T6G_MB_LIB.T6G(SCH_1):P12V_PSU
P6_6 P12V_PSU   P6_6 @T6G_MB_LIB.T6G(SCH_1):P12V_PSU
P6_7 P12V_PSU   P6_7 @T6G_MB_LIB.T6G(SCH_1):P12V_PSU
P6_8 P12V_PSU   P6_8 @T6G_MB_LIB.T6G(SCH_1):P12V_PSU
  A3 P3V3_PDB_AUX_ADC     A3 @T6G_MB_LIB.T6G(SCH_1):P3V3_PDB_AUX_ADC
  B3    GND     B3 @T6G_MB_LIB.T6G(SCH_1):GND
  C3 HPDB_HSC_PWRGD_R     C3 @T6G_MB_LIB.T6G(SCH_1):HPDB_HSC_PWRGD_R
  D3 PDB_PRSNT_N     D3 @T6G_MB_LIB.T6G(SCH_1):PDB_PRSNT_N

Q_RES_0402LF-0,5%,1/16W,CHIP,CS00002JB13  I467  R8102
   1 FM_AC_PWR_BTN_R_N      A @T6G_MB_LIB.T6G(SCH_1):FM_AC_PWR_BTN_R_N
   2 FM_AC_PWR_BTN_PDB_N      B @T6G_MB_LIB.T6G(SCH_1):FM_AC_PWR_BTN_PDB_N

Q_CAP_0402-0.1UF,25V,10%,EMPTY,CH4104K1B00  I469  C8011
   1 FM_AC_PWR_BTN_PDB_N      A @T6G_MB_LIB.T6G(SCH_1):FM_AC_PWR_BTN_PDB_N
   2    GND      B @T6G_MB_LIB.T6G(SCH_1):GND

Q_RES_0402LF-1K,1%,1/16W,CHIP,CS21002FB06  I472  R9000
   1 P3V3_AUX      A @T6G_MB_LIB.T6G(SCH_1):P3V3_AUX
   2 FM_FAN_PWR_EN      B @T6G_MB_LIB.T6G(SCH_1):FM_FAN_PWR_EN

Q_RES_0402LF-1K,1%,1/16W,CHIP,CS21002FB06  I475  R2950
   1 P3V3_AUX      A @T6G_MB_LIB.T6G(SCH_1):P3V3_AUX
   2 FM_PDB_BUF_EN_R1_N      B @T6G_MB_LIB.T6G(SCH_1):FM_PDB_BUF_EN_R1_N

Q_RES_0402LF-0,5%,1/16W,CHIP,CS00002JB13  I476  R1526
   1 PDB_PRSNT_N      A @T6G_MB_LIB.T6G(SCH_1):PDB_PRSNT_N
   2 PDB_PRSNT_R_N      B @T6G_MB_LIB.T6G(SCH_1):PDB_PRSNT_R_N

Q_CAP_C0805-22UF,16V,20%,EMPTY,CH6223MEA00  I478  C1115
   1 PDB_PRSNT_R_N      A @T6G_MB_LIB.T6G(SCH_1):PDB_PRSNT_R_N
   2    GND      B @T6G_MB_LIB.T6G(SCH_1):GND


DRAWING: @T6G_MB_LIB.T6G(SCH_1):PAGE364 

Q_CAP_0402-0.1UF,25V,10%,X7R,CH4104K1B00  I14  C1775
   1 P3V3_AUX      A @T6G_MB_LIB.T6G(SCH_1):P3V3_AUX
   2    GND      B @T6G_MB_LIB.T6G(SCH_1):GND

Q_RES_0402LF-33.2,1%,1/16W,CHIP,CS03322FB03  I24  R2944
   1 FM_GPU_HSC_EN_BUF_R      A @T6G_MB_LIB.T6G(SCH_1):FM_GPU_HSC_EN_BUF_R
   2 FM_GPU_HSC_EN_BUF      B @T6G_MB_LIB.T6G(SCH_1):FM_GPU_HSC_EN_BUF

Q_RES_0402LF-4.7K,5%,1/16W,EMPTY,CS24702JB10  I25  R2946
   1 P3V3_AUX      A @T6G_MB_LIB.T6G(SCH_1):P3V3_AUX
   2 FM_GPU_HSC_EN_BUF_R      B @T6G_MB_LIB.T6G(SCH_1):FM_GPU_HSC_EN_BUF_R

Q_RES_0402LF-4.7K,5%,1/16W,EMPTY,CS24702JB10  I28  R2940
   1 P3V3_AUX      A @T6G_MB_LIB.T6G(SCH_1):P3V3_AUX
   2 FM_GPU_HSC_EN      B @T6G_MB_LIB.T6G(SCH_1):FM_GPU_HSC_EN

Q_RES_0402LF-100K,1%,1/16W,CHIP,CS41002FB09  I29  R2941
   1 FM_GPU_HSC_EN      A @T6G_MB_LIB.T6G(SCH_1):FM_GPU_HSC_EN
   2    GND      B @T6G_MB_LIB.T6G(SCH_1):GND

Q_RES_0402LF-4.7K,5%,1/16W,EMPTY,CS24702JB10  I30  R2948
   1 FM_GPU_HSC_EN_BUF_R      A @T6G_MB_LIB.T6G(SCH_1):FM_GPU_HSC_EN_BUF_R
   2    GND      B @T6G_MB_LIB.T6G(SCH_1):GND

74LVC1G08W57-74LVC1G08W5-7,SMLF,IC,AL1G0008020  I31  U278
   1 FM_GPU_HSC_EN      A @T6G_MB_LIB.T6G(SCH_1):FM_GPU_HSC_EN
   2 GPU_PRSNT_R      B @T6G_MB_LIB.T6G(SCH_1):GPU_PRSNT_R
   3    GND    GND @T6G_MB_LIB.T6G(SCH_1):GND
   4 FM_GPU_HSC_EN_BUF_R      Y @T6G_MB_LIB.T6G(SCH_1):FM_GPU_HSC_EN_BUF_R
   5 P3V3_AUX    VCC @T6G_MB_LIB.T6G(SCH_1):P3V3_AUX

Q_RES_0402LF-0,5%,1/16W,CHIP,CS00002JB13  I34  R3770
   1 GPU_PRSNT      A @T6G_MB_LIB.T6G(SCH_1):GPU_PRSNT
   2 GPU_PRSNT_R      B @T6G_MB_LIB.T6G(SCH_1):GPU_PRSNT_R

74LVC2G07DW7-74LVC2G07DW-7,SMLF,IC,AL002G07003  I37  U308
   1 PWRGD_P3V3_AUX_PDB_R     1A @T6G_MB_LIB.T6G(SCH_1):PWRGD_P3V3_AUX_PDB_R
   3     NC     2A     NC
   6 PWRGD_P3V3_AUX_PDB_BUF_R     1Y @T6G_MB_LIB.T6G(SCH_1):PWRGD_P3V3_AUX_PDB_BUF_R
   4     NC     2Y     NC
   2    GND    GND @T6G_MB_LIB.T6G(SCH_1):GND
   5 P3V3_AUX    VCC @T6G_MB_LIB.T6G(SCH_1):P3V3_AUX

Q_CAP_0402-0.1UF,25V,10%,X7R,CH4104K1B00  I40  C69
   1 P3V3_AUX      A @T6G_MB_LIB.T6G(SCH_1):P3V3_AUX
   2    GND      B @T6G_MB_LIB.T6G(SCH_1):GND

Q_RES_0402LF-0,5%,1/16W,CHIP,CS00002JB13  I41  R4268
   1 PWRGD_P3V3_AUX_PDB      A @T6G_MB_LIB.T6G(SCH_1):PWRGD_P3V3_AUX_PDB
   2 PWRGD_P3V3_AUX_PDB_R      B @T6G_MB_LIB.T6G(SCH_1):PWRGD_P3V3_AUX_PDB_R

Q_RES_0402LF-4.7K,5%,1/16W,EMPTY,CS24702JB10  I43  R4265
   1 PWRGD_P3V3_AUX_PDB_BUF_R      A @T6G_MB_LIB.T6G(SCH_1):PWRGD_P3V3_AUX_PDB_BUF_R
   2    GND      B @T6G_MB_LIB.T6G(SCH_1):GND

Q_RES_0402LF-4.7K,5%,1/16W,CHIP,CS24702JB10  I47  R4264
   1 P3V3_AUX      A @T6G_MB_LIB.T6G(SCH_1):P3V3_AUX
   2 PWRGD_P3V3_AUX_PDB_BUF_R      B @T6G_MB_LIB.T6G(SCH_1):PWRGD_P3V3_AUX_PDB_BUF_R

Q_RES_0402LF-33.2,1%,1/16W,CHIP,CS03322FB03  I48  R4266
   1 PWRGD_P3V3_AUX_PDB_BUF_R      A @T6G_MB_LIB.T6G(SCH_1):PWRGD_P3V3_AUX_PDB_BUF_R
   2 PWRGD_P3V3_AUX_PDB_BUF      B @T6G_MB_LIB.T6G(SCH_1):PWRGD_P3V3_AUX_PDB_BUF

Q_RES_0402LF-100K,1%,1/16W,CHIP,CS41002FB09  I50  R4552
   1 HPDB_HSC_PWRGD      A @T6G_MB_LIB.T6G(SCH_1):HPDB_HSC_PWRGD
   2    GND      B @T6G_MB_LIB.T6G(SCH_1):GND

Q_RES_0402LF-54.9K,1%,1/16W,EMPTY,CS35492FB03  I51  R4551
   1 P3V3_AUX      A @T6G_MB_LIB.T6G(SCH_1):P3V3_AUX
   2 HPDB_HSC_PWRGD      B @T6G_MB_LIB.T6G(SCH_1):HPDB_HSC_PWRGD

MOSFET_NCH_DUAL-PJT138K,SMLF,IC,BAM138K0003  I53  Q145
   1    GND     S1 @T6G_MB_LIB.T6G(SCH_1):GND
   2 HPDB_HSC_PWRGD     G1 @T6G_MB_LIB.T6G(SCH_1):HPDB_HSC_PWRGD
   6 HPDB_HSC_PWRGD_N     D1 @T6G_MB_LIB.T6G(SCH_1):HPDB_HSC_PWRGD_N

Q_RES_0402LF-4.7K,5%,1/16W,CHIP,CS24702JB10  I55  R4553
   1 P3V3_AUX      A @T6G_MB_LIB.T6G(SCH_1):P3V3_AUX
   2 HPDB_HSC_PWRGD_N      B @T6G_MB_LIB.T6G(SCH_1):HPDB_HSC_PWRGD_N

MOSFET_NCH_DUAL-PJT138K,SMLF,IC,BAM138K0003  I58  Q145
   3 HPDB_HSC_PWRGD_ISO     D2 @T6G_MB_LIB.T6G(SCH_1):HPDB_HSC_PWRGD_ISO
   5 HPDB_HSC_PWRGD_N     G2 @T6G_MB_LIB.T6G(SCH_1):HPDB_HSC_PWRGD_N
   4    GND     S2 @T6G_MB_LIB.T6G(SCH_1):GND

Q_RES_0402LF-100K,1%,1/16W,CHIP,CS41002FB09  I59  R4554
   1 P3V3_AUX      A @T6G_MB_LIB.T6G(SCH_1):P3V3_AUX
   2 HPDB_HSC_PWRGD_ISO      B @T6G_MB_LIB.T6G(SCH_1):HPDB_HSC_PWRGD_ISO

Q_CAP_0402-0.1UF,25V,10%,X7R,CH4104K1B00  I62  C70
   1 HPDB_HSC_PWRGD_ISO      A @T6G_MB_LIB.T6G(SCH_1):HPDB_HSC_PWRGD_ISO
   2    GND      B @T6G_MB_LIB.T6G(SCH_1):GND


DRAWING: @T6G_MB_LIB.T6G(SCH_1):PAGE365 

Q_RES_0402LF-0,5%,1/16W,CHIP,CS00002JB13  I3  R2531
   1 MB0_P12V_STBY_PWRGD      A @T6G_MB_LIB.T6G(SCH_1):MB0_P12V_STBY_PWRGD
   2 FM_P12V_HSC_EN_R      B @T6G_MB_LIB.T6G(SCH_1):FM_P12V_HSC_EN_R

MOSFET_NCH_GDS_ESD_PROTECTED-2N7002K,SMLF,IC,BAM70A  I6  U158
   D FM_P12V_HSC_EN_N      D @T6G_MB_LIB.T6G(SCH_1):FM_P12V_HSC_EN_N
   G FM_P12V_HSC_EN_R      G @T6G_MB_LIB.T6G(SCH_1):FM_P12V_HSC_EN_R
   S    GND      S @T6G_MB_LIB.T6G(SCH_1):GND

Q_RES_0402LF-0,5%,1/16W,CHIP,CS00002JB13  I7  R2529
   1 FM_P12V_HSC_EN_N      A @T6G_MB_LIB.T6G(SCH_1):FM_P12V_HSC_EN_N
   2 FM_P12V_HSC_EN_R_N      B @T6G_MB_LIB.T6G(SCH_1):FM_P12V_HSC_EN_R_N

Q_RES_0402LF-100K,1%,1/16W,CHIP,CS41002FB09  I8  R2528
   1 P12V_AUX      A @T6G_MB_LIB.T6G(SCH_1):P12V_AUX
   2 FM_P12V_HSC_EN_N      B @T6G_MB_LIB.T6G(SCH_1):FM_P12V_HSC_EN_N

Q_RES_0402LF-4.7K,5%,1/16W,CHIP,CS24702JB10  I10  R2530
   1 P12V_AUX      A @T6G_MB_LIB.T6G(SCH_1):P12V_AUX
   2 P12V_AUX_BLEEDING      B @T6G_MB_LIB.T6G(SCH_1):P12V_AUX_BLEEDING

MOSFET_NCH_GDS_ESD_PROTECTED-2N7002K,SMLF,IC,BAM70A  I14  Q54
   D P12V_AUX_BLEEDING      D @T6G_MB_LIB.T6G(SCH_1):P12V_AUX_BLEEDING
   G FM_P12V_HSC_EN_R_N      G @T6G_MB_LIB.T6G(SCH_1):FM_P12V_HSC_EN_R_N
   S    GND      S @T6G_MB_LIB.T6G(SCH_1):GND

74LVC2G07DW7-74LVC2G07DW-7,SMLF,EMPTY,AL002G07003  I16  U8004
   1 FM_AC_PWR_BTN_PLD_N     1A @T6G_MB_LIB.T6G(SCH_1):FM_AC_PWR_BTN_PLD_N
   3    GND     2A @T6G_MB_LIB.T6G(SCH_1):GND
   6 FM_AC_PWR_BTN_PLD_ISO_R_N     1Y @T6G_MB_LIB.T6G(SCH_1):FM_AC_PWR_BTN_PLD_ISO_R_N
   4 NC_U8004_2Y     2Y @T6G_MB_LIB.T6G(SCH_1):NC_U8004_2Y
   2    GND    GND @T6G_MB_LIB.T6G(SCH_1):GND
   5 P3V3_AUX    VCC @T6G_MB_LIB.T6G(SCH_1):P3V3_AUX

Q_RES_0402LF-0,5%,1/16W,EMPTY,CS00002JB13  I18  R8104
   1 FM_AC_PWR_BTN_R_N      A @T6G_MB_LIB.T6G(SCH_1):FM_AC_PWR_BTN_R_N
   2 FM_AC_PWR_BTN_PLD_N      B @T6G_MB_LIB.T6G(SCH_1):FM_AC_PWR_BTN_PLD_N

Q_RES_0402LF-0,5%,1/16W,EMPTY,CS00002JB13  I20  R8105
   1 FM_AC_PWR_BTN_PLD_ISO_R_N      A @T6G_MB_LIB.T6G(SCH_1):FM_AC_PWR_BTN_PLD_ISO_R_N
   2 FM_AC_PWR_BTN_PLD_ISO_N      B @T6G_MB_LIB.T6G(SCH_1):FM_AC_PWR_BTN_PLD_ISO_N

Q_CAP_0402-0.1UF,25V,10%,EMPTY,CH4104K1B00  I23  C8013
   1 P3V3_AUX      A @T6G_MB_LIB.T6G(SCH_1):P3V3_AUX
   2    GND      B @T6G_MB_LIB.T6G(SCH_1):GND

Q_CAP_C0402-1UF,25V,10%,EMPTY,CH5104KEB02  I25  C8012
   1 FM_AC_PWR_BTN_R_N      A @T6G_MB_LIB.T6G(SCH_1):FM_AC_PWR_BTN_R_N
   2    GND      B @T6G_MB_LIB.T6G(SCH_1):GND

Q_RES_0402LF-8.45K,1%,1/16W,EMPTY,CS28452FB06  I27  R8103
   1 P3V3_AUX      A @T6G_MB_LIB.T6G(SCH_1):P3V3_AUX
   2 FM_AC_PWR_BTN_R_N      B @T6G_MB_LIB.T6G(SCH_1):FM_AC_PWR_BTN_R_N

Q_RES_0402LF-1K,1%,1/16W,CHIP,CS21002FB06  I31  R8106
   1 P3V3_AUX      A @T6G_MB_LIB.T6G(SCH_1):P3V3_AUX
   2 FM_AC_PWR_BTN_PLD_ISO_N      B @T6G_MB_LIB.T6G(SCH_1):FM_AC_PWR_BTN_PLD_ISO_N


DRAWING: @T6G_MB_LIB.T6G(SCH_1):PAGE348 

Q_RES_0402LF-4.7K,5%,1/16W,EMPTY,CS24702JB10  I17  R6035
   1 SCM_ROT_CPU_RST_R_N      A @T6G_MB_LIB.T6G(SCH_1):SCM_ROT_CPU_RST_R_N
   2    GND      B @T6G_MB_LIB.T6G(SCH_1):GND

Q_RES_0402LF-1K,1%,1/16W,CHIP,CS21002FB06  I18  R6034
   1 P3V3_AUX      A @T6G_MB_LIB.T6G(SCH_1):P3V3_AUX
   2 SCM_ROT_CPU_RST_R_N      B @T6G_MB_LIB.T6G(SCH_1):SCM_ROT_CPU_RST_R_N

Q_RES_0402LF-0,5%,1/16W,CHIP,CS00002JB13  I24  R321
   1 SCM_IRQ_N      A @T6G_MB_LIB.T6G(SCH_1):SCM_IRQ_N
   2 IRQ0_A56      B @T6G_MB_LIB.T6G(SCH_1):IRQ0_A56

Q_RES_0402LF-0,5%,1/16W,CHIP,CS00002JB13  I25  R3777
   1 FM_UARTSW_LSB_N      A @T6G_MB_LIB.T6G(SCH_1):FM_UARTSW_LSB_N
   2 FM_UARTSW_LSB_R      B @T6G_MB_LIB.T6G(SCH_1):FM_UARTSW_LSB_R

Q_RES_0402LF-0,5%,1/16W,CHIP,CS00002JB13  I26  R1798
   1 SCM_ROT_CPU_RST_R_N      A @T6G_MB_LIB.T6G(SCH_1):SCM_ROT_CPU_RST_R_N
   2 SCM_ROT_CPU_RST_N      B @T6G_MB_LIB.T6G(SCH_1):SCM_ROT_CPU_RST_N

Q_RES_0402LF-0,5%,1/16W,CHIP,CS00002JB13  I27  R3776
   1 FM_UARTSW_MSB_N      A @T6G_MB_LIB.T6G(SCH_1):FM_UARTSW_MSB_N
   2 FM_UARTSW_MSB_R      B @T6G_MB_LIB.T6G(SCH_1):FM_UARTSW_MSB_R

Q_RES_0402LF-0,5%,1/16W,CHIP,CS00002JB13  I28  R6032
   1 JTAG_SCM_DBREQ_N      A @T6G_MB_LIB.T6G(SCH_1):JTAG_SCM_DBREQ_N
   2 SCM_HDT_DBREQ_N      B @T6G_MB_LIB.T6G(SCH_1):SCM_HDT_DBREQ_N

Q_RES_0402LF-0,5%,1/16W,CHIP,CS00002JB13  I29  R1815
   1 SCM_SYS_PWRBTN_N      A @T6G_MB_LIB.T6G(SCH_1):SCM_SYS_PWRBTN_N
   2 SCM_SYS_PWRBTN_R_N      B @T6G_MB_LIB.T6G(SCH_1):SCM_SYS_PWRBTN_R_N

Q_RES_0402LF-0,5%,1/16W,CHIP,CS00002JB13  I30  R6033
   1 RST_MB_STBY_N      A @T6G_MB_LIB.T6G(SCH_1):RST_MB_STBY_N
   2 RST_MB_STBY_R_N      B @T6G_MB_LIB.T6G(SCH_1):RST_MB_STBY_R_N

Q_RES_0402LF-0,5%,1/16W,CHIP,CS00002JB13  I31  R4087
   1 FW_RECOVERY_R      A @T6G_MB_LIB.T6G(SCH_1):FW_RECOVERY_R
   2 FW_RECOVERY      B @T6G_MB_LIB.T6G(SCH_1):FW_RECOVERY

Q_RES_0402LF-0,5%,1/16W,CHIP,CS00002JB13  I32  R1816
   1 PWRGD_PS_PWROK      A @T6G_MB_LIB.T6G(SCH_1):PWRGD_PS_PWROK
   2 PWRGD_PS_PWROK_R      B @T6G_MB_LIB.T6G(SCH_1):PWRGD_PS_PWROK_R

Q_RES_0402LF-0,5%,1/16W,CHIP,CS00002JB13  I43  R6025
   1 SGPIO_SCM_RESET_N      A @T6G_MB_LIB.T6G(SCH_1):SGPIO_SCM_RESET_N
   2 SGPIO_SCM_RESET_R_N      B @T6G_MB_LIB.T6G(SCH_1):SGPIO_SCM_RESET_R_N

Q_RES_0402LF-0,5%,1/16W,EMPTY,CS00002JB13  I50  R3254
   1 TP_PCIE_TXP<3>      A @T6G_MB_LIB.T6G(SCH_1):TP_PCIE_TXP(3)
   2 LED_HDD_ACTIVITY_B_N      B @T6G_MB_LIB.T6G(SCH_1):LED_HDD_ACTIVITY_B_N

Q_RES_0402LF-33.2,1%,1/16W,CHIP,CS03322FB03  I85  R2414
   1 SMB_2_BMC_GPU_SDA      A @T6G_MB_LIB.T6G(SCH_1):SMB_2_BMC_GPU_SDA
   2 SMB_PCIE2_3V3AUX_SDA_R0      B @T6G_MB_LIB.T6G(SCH_1):SMB_PCIE2_3V3AUX_SDA_R0

Q_RES_0402LF-33.2,1%,1/16W,CHIP,CS03322FB03  I86  R2413
   1 SMB_2_BMC_GPU_SCL      A @T6G_MB_LIB.T6G(SCH_1):SMB_2_BMC_GPU_SCL
   2 SMB_PCIE2_3V3AUX_SCL_R0      B @T6G_MB_LIB.T6G(SCH_1):SMB_PCIE2_3V3AUX_SCL_R0

Q_RES_0402LF-33.2,1%,1/16W,CHIP,CS03322FB03  I87  R4509
   1 SMB_1_PLD_3V3AUX_SDA      A @T6G_MB_LIB.T6G(SCH_1):SMB_1_PLD_3V3AUX_SDA
   2 SMB_1_PLD_3V3AUX_SDA_R3      B @T6G_MB_LIB.T6G(SCH_1):SMB_1_PLD_3V3AUX_SDA_R3

Q_RES_0402LF-33.2,1%,1/16W,CHIP,CS03322FB03  I88  R4508
   1 SMB_1_PLD_3V3AUX_SCL      A @T6G_MB_LIB.T6G(SCH_1):SMB_1_PLD_3V3AUX_SCL
   2 SMB_1_PLD_3V3AUX_SCL_R3      B @T6G_MB_LIB.T6G(SCH_1):SMB_1_PLD_3V3AUX_SCL_R3

Q_RES_0402LF-33.2,1%,1/16W,CHIP,CS03322FB03  I96  R3858
   1 SMB_OCP_V3_2_3V3AUX_SDA      A @T6G_MB_LIB.T6G(SCH_1):SMB_OCP_V3_2_3V3AUX_SDA
   2 SMB_OCP_V3_2_3V3AUX_SDA_R0      B @T6G_MB_LIB.T6G(SCH_1):SMB_OCP_V3_2_3V3AUX_SDA_R0

Q_RES_0402LF-33.2,1%,1/16W,CHIP,CS03322FB03  I97  R2425
   1 SMB_OCP_V3_2_3V3AUX_SCL      A @T6G_MB_LIB.T6G(SCH_1):SMB_OCP_V3_2_3V3AUX_SCL
   2 SMB_OCP_V3_2_3V3AUX_SCL_R0      B @T6G_MB_LIB.T6G(SCH_1):SMB_OCP_V3_2_3V3AUX_SCL_R0

Q_RES_0402LF-33.2,1%,1/16W,CHIP,CS03322FB03  I98  R2421
   1 SMB_VR_SENSOR_3V3AUX_SCL      A @T6G_MB_LIB.T6G(SCH_1):SMB_VR_SENSOR_3V3AUX_SCL
   2 SMB_VR_3V3AUX_SCL_R0      B @T6G_MB_LIB.T6G(SCH_1):SMB_VR_3V3AUX_SCL_R0

Q_RES_0402LF-0,5%,1/16W,CHIP,CS00002JB13  I117  R6006
   1 I3C_SCM_3_SCL      A @T6G_MB_LIB.T6G(SCH_1):I3C_SCM_3_SCL
   2 I3C_SCM_3_R_SCL      B @T6G_MB_LIB.T6G(SCH_1):I3C_SCM_3_R_SCL

Q_RES_0402LF-0,5%,1/16W,CHIP,CS00002JB13  I118  R6005
   1 I3C_SCM_2_SDA      A @T6G_MB_LIB.T6G(SCH_1):I3C_SCM_2_SDA
   2 I3C_SCM_2_R_SDA      B @T6G_MB_LIB.T6G(SCH_1):I3C_SCM_2_R_SDA

Q_RES_0402LF-0,5%,1/16W,CHIP,CS00002JB13  I119  R6007
   1 I3C_SCM_3_SDA      A @T6G_MB_LIB.T6G(SCH_1):I3C_SCM_3_SDA
   2 I3C_SCM_3_R_SDA      B @T6G_MB_LIB.T6G(SCH_1):I3C_SCM_3_R_SDA

Q_RES_0402LF-0,5%,1/16W,CHIP,CS00002JB13  I120  R6004
   1 I3C_SCM_2_SCL      A @T6G_MB_LIB.T6G(SCH_1):I3C_SCM_2_SCL
   2 I3C_SCM_2_R_SCL      B @T6G_MB_LIB.T6G(SCH_1):I3C_SCM_2_R_SCL

Q_RES_0402LF-0,5%,1/16W,CHIP,CS00002JB13  I121  R6003
   1 I3C_SCM_1_SDA      A @T6G_MB_LIB.T6G(SCH_1):I3C_SCM_1_SDA
   2 I3C_SCM_1_R_SDA      B @T6G_MB_LIB.T6G(SCH_1):I3C_SCM_1_R_SDA

Q_RES_0402LF-0,5%,1/16W,CHIP,CS00002JB13  I122  R6002
   1 I3C_SCM_1_SCL      A @T6G_MB_LIB.T6G(SCH_1):I3C_SCM_1_SCL
   2 I3C_SCM_1_R_SCL      B @T6G_MB_LIB.T6G(SCH_1):I3C_SCM_1_R_SCL

Q_RES_0402LF-0,5%,1/16W,CHIP,CS00002JB13  I124  R6001
   1 I3C_SCM_0_SDA      A @T6G_MB_LIB.T6G(SCH_1):I3C_SCM_0_SDA
   2 I3C_SCM_0_R_SDA      B @T6G_MB_LIB.T6G(SCH_1):I3C_SCM_0_R_SDA

Q_RES_0402LF-0,5%,1/16W,CHIP,CS00002JB13  I128  R6014
   1 SGPIO_SCM_DI_<1>      A @T6G_MB_LIB.T6G(SCH_1):SGPIO_SCM_DI_(1)
   2 SGPIO_SCM_DI_R_<1>      B @T6G_MB_LIB.T6G(SCH_1):SGPIO_SCM_DI_R_(1)

Q_RES_0402LF-0,5%,1/16W,CHIP,CS00002JB13  I129  R6015
   1 SGPIO_SCM_LD_<1>      A @T6G_MB_LIB.T6G(SCH_1):SGPIO_SCM_LD_(1)
   2 SGPIO_SCM_LD_R_<1>      B @T6G_MB_LIB.T6G(SCH_1):SGPIO_SCM_LD_R_(1)

Q_RES_0402LF-0,5%,1/16W,CHIP,CS00002JB13  I130  R6013
   1 SGPIO_SCM_CLK_<1>      A @T6G_MB_LIB.T6G(SCH_1):SGPIO_SCM_CLK_(1)
   2 SGPIO_SCM_CLK_R_<1>      B @T6G_MB_LIB.T6G(SCH_1):SGPIO_SCM_CLK_R_(1)

Q_RES_0402LF-0,5%,1/16W,CHIP,CS00002JB13  I171  R1801
   1 PRSNT0_N      A @T6G_MB_LIB.T6G(SCH_1):PRSNT0_N
   2    GND      B @T6G_MB_LIB.T6G(SCH_1):GND

SCONN168_ME1016810202011-SCONN168_ME1016810202011,A  I176  J41
 OB1 P12V_SCM NIC_PWR_GOOD @T6G_MB_LIB.T6G(SCH_1):P12V_SCM
 OB2 P12V_SCM MAIN_PWR_EN @T6G_MB_LIB.T6G(SCH_1):P12V_SCM
 OB3 PRSNT0_N    LD# @T6G_MB_LIB.T6G(SCH_1):PRSNT0_N
 OB4    GND DATA_IN @T6G_MB_LIB.T6G(SCH_1):GND
 OB5 UART_BMC_BIC_TX DATA_OUT @T6G_MB_LIB.T6G(SCH_1):UART_BMC_BIC_TX
 OB6 UART_BMC_BIC_BUF_RX    CLK @T6G_MB_LIB.T6G(SCH_1):UART_BMC_BIC_BUF_RX
 OB7    GND SLOT_ID0 @T6G_MB_LIB.T6G(SCH_1):GND
 OB8 UART_CPU0_SCM_LVC3_UART1_RX RBT_RXD1 @T6G_MB_LIB.T6G(SCH_1):UART_CPU0_SCM_LVC3_UART1_RX
 OB9 UART_CPU0_SCM_LVC3_UART1_R1_TX RBT_RXD0 @T6G_MB_LIB.T6G(SCH_1):UART_CPU0_SCM_LVC3_UART1_R1_TX
OB10    GND GND_OB10 @T6G_MB_LIB.T6G(SCH_1):GND
OB11 RST_SRST_PLD_BMC_N REFCLKN2 @T6G_MB_LIB.T6G(SCH_1):RST_SRST_PLD_BMC_N
OB12 SPI_CPU0_LVC3_TPM_CS_N REFCLKP2 @T6G_MB_LIB.T6G(SCH_1):SPI_CPU0_LVC3_TPM_CS_N
OB13 FPGA_IO3V3_RSVD_1 GND_OB13 @T6G_MB_LIB.T6G(SCH_1):FPGA_IO3V3_RSVD_1
OB14 FM_SOL_UART_CH_SEL_R RBT_CRS_DV @T6G_MB_LIB.T6G(SCH_1):FM_SOL_UART_CH_SEL_R
  B1 CLK_ESPI_CPU0_CLK1 +12V_EDGE_B1 @T6G_MB_LIB.T6G(SCH_1):CLK_ESPI_CPU0_CLK1
  B2 ESPI_CPU0_CS1_N +12V_EDGE_B2 @T6G_MB_LIB.T6G(SCH_1):ESPI_CPU0_CS1_N
  B3 ESPI_CPU0_ALERT_N +12V_EDGE_B3 @T6G_MB_LIB.T6G(SCH_1):ESPI_CPU0_ALERT_N
  B4 RST_ESPI_CPU0_RSTOUT_N +12V_EDGE_B4 @T6G_MB_LIB.T6G(SCH_1):RST_ESPI_CPU0_RSTOUT_N
  B5 ESPI_CPU0_D0 +12V_EDGE_B5 @T6G_MB_LIB.T6G(SCH_1):ESPI_CPU0_D0
  B6 ESPI_CPU0_D1 +12V_EDGE_B6 @T6G_MB_LIB.T6G(SCH_1):ESPI_CPU0_D1
  B7 ESPI_CPU0_D2  BIF0# @T6G_MB_LIB.T6G(SCH_1):ESPI_CPU0_D2
  B8 ESPI_CPU0_D3  BIF1# @T6G_MB_LIB.T6G(SCH_1):ESPI_CPU0_D3
  B9 FM_LPC_ESPI_SEL  BIF2# @T6G_MB_LIB.T6G(SCH_1):FM_LPC_ESPI_SEL
 B10    GND PERST0# @T6G_MB_LIB.T6G(SCH_1):GND
 B11 SPI_CPU0_LVC3_SCM_CLK +3.3V_EDGE @T6G_MB_LIB.T6G(SCH_1):SPI_CPU0_LVC3_SCM_CLK
 B12 SPI_CPU0_LVC3_SCM_CS0_N AUX_PWR_EN @T6G_MB_LIB.T6G(SCH_1):SPI_CPU0_LVC3_SCM_CS0_N
 B13 SPI_CPU0_LVC3_SCM_D0 GND_B13 @T6G_MB_LIB.T6G(SCH_1):SPI_CPU0_LVC3_SCM_D0
 B14 SPI_CPU0_LVC3_SCM_D1 REFCLKN0 @T6G_MB_LIB.T6G(SCH_1):SPI_CPU0_LVC3_SCM_D1
 B15 SPI_CPU0_LVC3_SCM_D2 REFCLKP0 @T6G_MB_LIB.T6G(SCH_1):SPI_CPU0_LVC3_SCM_D2
 B16 SPI_CPU0_LVC3_SCM_D3 GND_B16 @T6G_MB_LIB.T6G(SCH_1):SPI_CPU0_LVC3_SCM_D3
 B17    GND  PETN0 @T6G_MB_LIB.T6G(SCH_1):GND
 B18 CLK_50M_RMII_BMC_OCP  PETP0 @T6G_MB_LIB.T6G(SCH_1):CLK_50M_RMII_BMC_OCP
 B19 RMII_OCP_BMC_CRSDV GND_B19 @T6G_MB_LIB.T6G(SCH_1):RMII_OCP_BMC_CRSDV
 B20 RMII_BMC_OCP_TX_EN  PETN1 @T6G_MB_LIB.T6G(SCH_1):RMII_BMC_OCP_TX_EN
 B21 RMII_BMC_OCP_TXD_0  PETP1 @T6G_MB_LIB.T6G(SCH_1):RMII_BMC_OCP_TXD_0
 B22 RMII_BMC_OCP_TXD_1 GND_B22 @T6G_MB_LIB.T6G(SCH_1):RMII_BMC_OCP_TXD_1
 B23 RMII_BMC_OCP_RX_ER  PETN2 @T6G_MB_LIB.T6G(SCH_1):RMII_BMC_OCP_RX_ER
 B24 RMII_OCP_BMC_RXD_0  PETP2 @T6G_MB_LIB.T6G(SCH_1):RMII_OCP_BMC_RXD_0
 B25 RMII_OCP_BMC_RXD_1 GND_B25 @T6G_MB_LIB.T6G(SCH_1):RMII_OCP_BMC_RXD_1
 B26    GND  PETN3 @T6G_MB_LIB.T6G(SCH_1):GND
 B27 TP_PECI_BMC  PETP3 @T6G_MB_LIB.T6G(SCH_1):TP_PECI_BMC
 B28 TP_PVCCIO_PECI_BMC GND_B28 @T6G_MB_LIB.T6G(SCH_1):TP_PVCCIO_PECI_BMC
 B29 SGPIO_SCM_DO_R_<0> GND_B29 @T6G_MB_LIB.T6G(SCH_1):SGPIO_SCM_DO_R_(0)
 B30 SGPIO_SCM_CLK_R_<0>  PETN4 @T6G_MB_LIB.T6G(SCH_1):SGPIO_SCM_CLK_R_(0)
 B31 SGPIO_SCM_DI_R_<0>  PETP4 @T6G_MB_LIB.T6G(SCH_1):SGPIO_SCM_DI_R_(0)
 B32 SGPIO_SCM_LD_R_<0> GND_B32 @T6G_MB_LIB.T6G(SCH_1):SGPIO_SCM_LD_R_(0)
 B33    GND  PETN5 @T6G_MB_LIB.T6G(SCH_1):GND
 B34 SGPIO_SCM_DO_R_<1>  PETP5 @T6G_MB_LIB.T6G(SCH_1):SGPIO_SCM_DO_R_(1)
 B35 SGPIO_SCM_CLK_R_<1> GND_B35 @T6G_MB_LIB.T6G(SCH_1):SGPIO_SCM_CLK_R_(1)
 B36 SGPIO_SCM_DI_R_<1>  PETN6 @T6G_MB_LIB.T6G(SCH_1):SGPIO_SCM_DI_R_(1)
 B37 SGPIO_SCM_LD_R_<1>  PETP6 @T6G_MB_LIB.T6G(SCH_1):SGPIO_SCM_LD_R_(1)
 B38    GND GND_B38 @T6G_MB_LIB.T6G(SCH_1):GND
 B39 SGPIO_SCM_RESET_R_N  PETN7 @T6G_MB_LIB.T6G(SCH_1):SGPIO_SCM_RESET_R_N
 B40 SGPIO_SCM_INTR_R1_N  PETP7 @T6G_MB_LIB.T6G(SCH_1):SGPIO_SCM_INTR_R1_N
 B41 SCM_VDD_RTC GND_B41 @T6G_MB_LIB.T6G(SCH_1):SCM_VDD_RTC
 B42 FM_AC_PWR_BTN_N PRSNTB0# @T6G_MB_LIB.T6G(SCH_1):FM_AC_PWR_BTN_N
 B43 TP_SPI_2_PLD_CLK GND_B43 @T6G_MB_LIB.T6G(SCH_1):TP_SPI_2_PLD_CLK
 B44 TP_SPI_2_PLD_CS_N  PETN8 @T6G_MB_LIB.T6G(SCH_1):TP_SPI_2_PLD_CS_N
 B45 TP_SPI_2_PLD_IO0  PETP8 @T6G_MB_LIB.T6G(SCH_1):TP_SPI_2_PLD_IO0
 B46 TP_SPI_2_PLD_IO1 GND_B46 @T6G_MB_LIB.T6G(SCH_1):TP_SPI_2_PLD_IO1
 B47 TP_SPI_2_PLD_IO2  PETN9 @T6G_MB_LIB.T6G(SCH_1):TP_SPI_2_PLD_IO2
 B48 TP_SPI_2_PLD_IO3  PETP9 @T6G_MB_LIB.T6G(SCH_1):TP_SPI_2_PLD_IO3
 B49    GND GND_B49 @T6G_MB_LIB.T6G(SCH_1):GND
 B50 USB2_HOST_BMC_B_DP PETN10 @T6G_MB_LIB.T6G(SCH_1):USB2_HOST_BMC_B_DP
 B51 USB2_HOST_BMC_B_DN PETP10 @T6G_MB_LIB.T6G(SCH_1):USB2_HOST_BMC_B_DN
 B52    GND GND_B52 @T6G_MB_LIB.T6G(SCH_1):GND
 B53 USB2_CPU0_P1_DP PETN11 @T6G_MB_LIB.T6G(SCH_1):USB2_CPU0_P1_DP
 B54 USB2_CPU0_P1_DN PETP11 @T6G_MB_LIB.T6G(SCH_1):USB2_CPU0_P1_DN
 B55    GND GND_B55 @T6G_MB_LIB.T6G(SCH_1):GND
 B56 USB2_HUB_EXT_DP PETN12 @T6G_MB_LIB.T6G(SCH_1):USB2_HUB_EXT_DP
 OA1 P12V_SCM PERST2# @T6G_MB_LIB.T6G(SCH_1):P12V_SCM
 OA2 P12V_SCM PERST3# @T6G_MB_LIB.T6G(SCH_1):P12V_SCM
 OA3    GND  WAKE# @T6G_MB_LIB.T6G(SCH_1):GND
 OA4    GND RBT_ARB_IN @T6G_MB_LIB.T6G(SCH_1):GND
 OA5 I3C_SCM_0_SCL RBT_ARB_OUT @T6G_MB_LIB.T6G(SCH_1):I3C_SCM_0_SCL
 OA6 I3C_SCM_0_SDA SLOT_ID1 @T6G_MB_LIB.T6G(SCH_1):I3C_SCM_0_SDA
 OA7 I3C_SCM_1_SCL RBT_TX_EN @T6G_MB_LIB.T6G(SCH_1):I3C_SCM_1_SCL
 OA8 I3C_SCM_1_SDA RBT_TXD1 @T6G_MB_LIB.T6G(SCH_1):I3C_SCM_1_SDA
 OA9 I3C_SCM_2_SCL RBT_TXD0 @T6G_MB_LIB.T6G(SCH_1):I3C_SCM_2_SCL
OA10 I3C_SCM_2_SDA GND_OA10 @T6G_MB_LIB.T6G(SCH_1):I3C_SCM_2_SDA
OA11 I3C_SCM_3_SCL REFCLKN3 @T6G_MB_LIB.T6G(SCH_1):I3C_SCM_3_SCL
OA12 I3C_SCM_3_SDA REFCLKP3 @T6G_MB_LIB.T6G(SCH_1):I3C_SCM_3_SDA
OA13    GND GND_OA13 @T6G_MB_LIB.T6G(SCH_1):GND
OA14 VIRTUAL_RESEAT RBT_CLK_IN @T6G_MB_LIB.T6G(SCH_1):VIRTUAL_RESEAT
  A1 SMB_OCP_SFF_3V3AUX_SCL_R0 GND_A1 @T6G_MB_LIB.T6G(SCH_1):SMB_OCP_SFF_3V3AUX_SCL_R0
  A2 SMB_OCP_SFF_3V3AUX_SDA_R0 GND_A2 @T6G_MB_LIB.T6G(SCH_1):SMB_OCP_SFF_3V3AUX_SDA_R0
  A3 SMB_CPU0_CPU1_APML_SCL_R GND_A3 @T6G_MB_LIB.T6G(SCH_1):SMB_CPU0_CPU1_APML_SCL_R
  A4 SMB_CPU0_CPU1_APML_SDA_R GND_A4 @T6G_MB_LIB.T6G(SCH_1):SMB_CPU0_CPU1_APML_SDA_R
  A5 SMB_VR_3V3AUX_SCL_R0 GND_A5 @T6G_MB_LIB.T6G(SCH_1):SMB_VR_3V3AUX_SCL_R0
  A6 SMB_VR_3V3AUX_SDA_R0 GND_A6 @T6G_MB_LIB.T6G(SCH_1):SMB_VR_3V3AUX_SDA_R0
  A7 SMB_CPU0_CPU1_SEC_SCL_R  SMCLK @T6G_MB_LIB.T6G(SCH_1):SMB_CPU0_CPU1_SEC_SCL_R
  A8 SMB_CPU0_CPU1_SEC_SDA_R  SMDAT @T6G_MB_LIB.T6G(SCH_1):SMB_CPU0_CPU1_SEC_SDA_R
  A9 I3C_BMC_SWB_SCL SMRST# @T6G_MB_LIB.T6G(SCH_1):I3C_BMC_SWB_SCL
 A10 I3C_BMC_SWB_SDA PRSNTA# @T6G_MB_LIB.T6G(SCH_1):I3C_BMC_SWB_SDA
 A11 SMB_OCP_V3_2_3V3AUX_SCL_R0 PERST1# @T6G_MB_LIB.T6G(SCH_1):SMB_OCP_V3_2_3V3AUX_SCL_R0
 A12 SMB_OCP_V3_2_3V3AUX_SDA_R0 PRSNTB2# @T6G_MB_LIB.T6G(SCH_1):SMB_OCP_V3_2_3V3AUX_SDA_R0
 A13    GND GND_A13 @T6G_MB_LIB.T6G(SCH_1):GND
 A14 CLK_100M_CPU0_CLK01_DP REFCLKN1 @T6G_MB_LIB.T6G(SCH_1):CLK_100M_CPU0_CLK01_DP
 A15 CLK_100M_CPU0_CLK01_DN REFCLKP1 @T6G_MB_LIB.T6G(SCH_1):CLK_100M_CPU0_CLK01_DN
 A16    GND GND_A16 @T6G_MB_LIB.T6G(SCH_1):GND
 A17 P2E_CPU0_P5_TX_C_DP  PERN0 @T6G_MB_LIB.T6G(SCH_1):P2E_CPU0_P5_TX_C_DP
 A18 P2E_CPU0_P5_TX_C_DN  PERP0 @T6G_MB_LIB.T6G(SCH_1):P2E_CPU0_P5_TX_C_DN
 A19    GND GND_A19 @T6G_MB_LIB.T6G(SCH_1):GND
 A20 P2E_CPU0_P5_RX_DP  PERN1 @T6G_MB_LIB.T6G(SCH_1):P2E_CPU0_P5_RX_DP
 A21 P2E_CPU0_P5_RX_DN  PERP1 @T6G_MB_LIB.T6G(SCH_1):P2E_CPU0_P5_RX_DN
 A22    GND GND_A22 @T6G_MB_LIB.T6G(SCH_1):GND
 A23 SMB_PCIE0_3V3AUX_SCL  PERN2 @T6G_MB_LIB.T6G(SCH_1):SMB_PCIE0_3V3AUX_SCL
 A24 SMB_PCIE0_3V3AUX_SDA  PERP2 @T6G_MB_LIB.T6G(SCH_1):SMB_PCIE0_3V3AUX_SDA
 A25 SMB_PMBUS_3V3AUX_SCL_R0 GND_A25 @T6G_MB_LIB.T6G(SCH_1):SMB_PMBUS_3V3AUX_SCL_R0
 A26 SMB_PMBUS_3V3AUX_SDA_R0  PERN3 @T6G_MB_LIB.T6G(SCH_1):SMB_PMBUS_3V3AUX_SDA_R0
 A27 SMB_1_PLD_3V3AUX_SCL_R3  PERP3 @T6G_MB_LIB.T6G(SCH_1):SMB_1_PLD_3V3AUX_SCL_R3
 A28 SMB_1_PLD_3V3AUX_SDA_R3 GND_A28 @T6G_MB_LIB.T6G(SCH_1):SMB_1_PLD_3V3AUX_SDA_R3
 A29 SMB_FAN_3V3AUX_SCL GND_A29 @T6G_MB_LIB.T6G(SCH_1):SMB_FAN_3V3AUX_SCL
 A30 SMB_FAN_3V3AUX_SDA  PERN4 @T6G_MB_LIB.T6G(SCH_1):SMB_FAN_3V3AUX_SDA
 A31 SMB_PCIE2_3V3AUX_SCL_R0  PERP4 @T6G_MB_LIB.T6G(SCH_1):SMB_PCIE2_3V3AUX_SCL_R0
 A32 SMB_PCIE2_3V3AUX_SDA_R0 GND_A32 @T6G_MB_LIB.T6G(SCH_1):SMB_PCIE2_3V3AUX_SDA_R0
 A33    GND  PERN5 @T6G_MB_LIB.T6G(SCH_1):GND
 A34 JTAG_SCM_TCK  PERP5 @T6G_MB_LIB.T6G(SCH_1):JTAG_SCM_TCK
 A35 JTAG_SCM_TMS GND_A35 @T6G_MB_LIB.T6G(SCH_1):JTAG_SCM_TMS
 A36 JTAG_SCM_TDI_R  PERN6 @T6G_MB_LIB.T6G(SCH_1):JTAG_SCM_TDI_R
 A37 JTAG_SCM_TDO_R  PERP6 @T6G_MB_LIB.T6G(SCH_1):JTAG_SCM_TDO_R
 A38 SMB_PCIE3_3V3AUX_SCL_R GND_A38 @T6G_MB_LIB.T6G(SCH_1):SMB_PCIE3_3V3AUX_SCL_R
 A39 SMB_PCIE3_3V3AUX_SDA_R  PERN7 @T6G_MB_LIB.T6G(SCH_1):SMB_PCIE3_3V3AUX_SDA_R
 A40 SMB_HOST_CLK_3V3AUX_SCL_R0  PERP7 @T6G_MB_LIB.T6G(SCH_1):SMB_HOST_CLK_3V3AUX_SCL_R0
 A41 SMB_HOST_CLK_3V3AUX_SDA_R0 GND_A41 @T6G_MB_LIB.T6G(SCH_1):SMB_HOST_CLK_3V3AUX_SDA_R0
 A42    GND PRSNTB1# @T6G_MB_LIB.T6G(SCH_1):GND
 A43 FW_RECOVERY GND_A43 @T6G_MB_LIB.T6G(SCH_1):FW_RECOVERY
 A44 PWRGD_PS_PWROK_R  PERN8 @T6G_MB_LIB.T6G(SCH_1):PWRGD_PS_PWROK_R
 A45 TP_STBY_EN  PERP8 @T6G_MB_LIB.T6G(SCH_1):TP_STBY_EN
 A46 RST_MB_STBY_R_N GND_A46 @T6G_MB_LIB.T6G(SCH_1):RST_MB_STBY_R_N
 A47 SCM_SYS_PWRBTN_R_N  PERN9 @T6G_MB_LIB.T6G(SCH_1):SCM_SYS_PWRBTN_R_N
 A48 SCM_SYS_PWROK_R1  PERP9 @T6G_MB_LIB.T6G(SCH_1):SCM_SYS_PWROK_R1
 A49 SCM_HDT_DBREQ_N GND_A49 @T6G_MB_LIB.T6G(SCH_1):SCM_HDT_DBREQ_N
 A50 PU_JTAG_DBP_BMC_PRDY_N PERN10 @T6G_MB_LIB.T6G(SCH_1):PU_JTAG_DBP_BMC_PRDY_N
 A51 FM_RST_PERST_SCM_N PERP10 @T6G_MB_LIB.T6G(SCH_1):FM_RST_PERST_SCM_N
 A52 FM_UARTSW_MSB_R GND_A52 @T6G_MB_LIB.T6G(SCH_1):FM_UARTSW_MSB_R
 A53 SCM_ROT_CPU_RST_N PERN11 @T6G_MB_LIB.T6G(SCH_1):SCM_ROT_CPU_RST_N
 A54 TP_CHASI PERP11 @T6G_MB_LIB.T6G(SCH_1):TP_CHASI
 A55 FM_UARTSW_LSB_R GND_A55 @T6G_MB_LIB.T6G(SCH_1):FM_UARTSW_LSB_R
 A56 IRQ0_A56 PERN12 @T6G_MB_LIB.T6G(SCH_1):IRQ0_A56
 A57 FM_SCM_PRSNT1_N PERP12 @T6G_MB_LIB.T6G(SCH_1):FM_SCM_PRSNT1_N
 A58    GND GND_A58 @T6G_MB_LIB.T6G(SCH_1):GND
 A59 USB3_CPU0_BMC_RX_DP PERN13 @T6G_MB_LIB.T6G(SCH_1):USB3_CPU0_BMC_RX_DP
 A60 USB3_CPU0_BMC_RX_DN PERP13 @T6G_MB_LIB.T6G(SCH_1):USB3_CPU0_BMC_RX_DN
 A61    GND GND_A61 @T6G_MB_LIB.T6G(SCH_1):GND
 A62 TP_PCIE_RXP<1> PERN14 @T6G_MB_LIB.T6G(SCH_1):TP_PCIE_RXP(1)
 A63 TP_PCIE_RXN<1> PERP14 @T6G_MB_LIB.T6G(SCH_1):TP_PCIE_RXN(1)
 A64    GND GND_A64 @T6G_MB_LIB.T6G(SCH_1):GND
 A65 P2E_MB_BMC_RX_BUF_DP<0> PERN15 @T6G_MB_LIB.T6G(SCH_1):P2E_MB_BMC_RX_BUF_DP(0)
 A66 P2E_MB_BMC_RX_BUF_DN<0> PERP15 @T6G_MB_LIB.T6G(SCH_1):P2E_MB_BMC_RX_BUF_DN(0)
 A67    GND GND_A67 @T6G_MB_LIB.T6G(SCH_1):GND
 A68 CLK_100M_BMC_RC_DP USB_DATN @T6G_MB_LIB.T6G(SCH_1):CLK_100M_BMC_RC_DP
 A69 CLK_100M_BMC_RC_DN USB_DATP @T6G_MB_LIB.T6G(SCH_1):CLK_100M_BMC_RC_DN
 A70    GND PWRBRK0# @T6G_MB_LIB.T6G(SCH_1):GND
 B57 USB2_HUB_EXT_DN PETP12 @T6G_MB_LIB.T6G(SCH_1):USB2_HUB_EXT_DN
 B58    GND GND_B58 @T6G_MB_LIB.T6G(SCH_1):GND
 B59 USB3_CPU0_BMC_TX_BUF_C_DP PETN13 @T6G_MB_LIB.T6G(SCH_1):USB3_CPU0_BMC_TX_BUF_C_DP
 B60 USB3_CPU0_BMC_TX_BUF_C_DN PETP13 @T6G_MB_LIB.T6G(SCH_1):USB3_CPU0_BMC_TX_BUF_C_DN
 B61    GND GND_B61 @T6G_MB_LIB.T6G(SCH_1):GND
 B62 TP_PCIE_TXP<1> PETN14 @T6G_MB_LIB.T6G(SCH_1):TP_PCIE_TXP(1)
 B63 TP_PCIE_TXN<1> PETP14 @T6G_MB_LIB.T6G(SCH_1):TP_PCIE_TXN(1)
 B64    GND GND_B64 @T6G_MB_LIB.T6G(SCH_1):GND
 B65 P2E_MB_BMC_TX_C_DP<0> PETN15 @T6G_MB_LIB.T6G(SCH_1):P2E_MB_BMC_TX_C_DP(0)
 B66 P2E_MB_BMC_TX_C_DN<0> PETP15 @T6G_MB_LIB.T6G(SCH_1):P2E_MB_BMC_TX_C_DN(0)
 B67    GND GND_B67 @T6G_MB_LIB.T6G(SCH_1):GND
 B68 TP_PCIE_TXP<3> RFU1_NC_B68 @T6G_MB_LIB.T6G(SCH_1):TP_PCIE_TXP(3)
 B69 TP_BEEP_LED RFU1_NC_B69 @T6G_MB_LIB.T6G(SCH_1):TP_BEEP_LED
 B70    GND PRSNTB3# @T6G_MB_LIB.T6G(SCH_1):GND
  G1    GND     G1 @T6G_MB_LIB.T6G(SCH_1):GND
  G2    GND     G2 @T6G_MB_LIB.T6G(SCH_1):GND
  G3    GND     G3 @T6G_MB_LIB.T6G(SCH_1):GND
  G4    GND     G4 @T6G_MB_LIB.T6G(SCH_1):GND
  G5    GND     G5 @T6G_MB_LIB.T6G(SCH_1):GND

Q_RES_0402LF-33.2,1%,1/16W,CHIP,CS03322FB03  I33  R2416
   1 SMB_1_BMC_GPU_SDA      A @T6G_MB_LIB.T6G(SCH_1):SMB_1_BMC_GPU_SDA
   2 SMB_PCIE3_3V3AUX_SDA_R      B @T6G_MB_LIB.T6G(SCH_1):SMB_PCIE3_3V3AUX_SDA_R

Q_RES_0402LF-33.2,1%,1/16W,CHIP,CS03322FB03  I34  R2418
   1 SMB_HOST_CLK_3V3AUX_SDA      A @T6G_MB_LIB.T6G(SCH_1):SMB_HOST_CLK_3V3AUX_SDA
   2 SMB_HOST_CLK_3V3AUX_SDA_R0      B @T6G_MB_LIB.T6G(SCH_1):SMB_HOST_CLK_3V3AUX_SDA_R0

Q_RES_0402LF-33.2,1%,1/16W,CHIP,CS03322FB03  I35  R2417
   1 SMB_HOST_CLK_3V3AUX_SCL      A @T6G_MB_LIB.T6G(SCH_1):SMB_HOST_CLK_3V3AUX_SCL
   2 SMB_HOST_CLK_3V3AUX_SCL_R0      B @T6G_MB_LIB.T6G(SCH_1):SMB_HOST_CLK_3V3AUX_SCL_R0

Q_RES_0402LF-0,5%,1/16W,CHIP,CS00002JB13  I42  R6026
   1 SGPIO_SCM_INTR_N      A @T6G_MB_LIB.T6G(SCH_1):SGPIO_SCM_INTR_N
   2 SGPIO_SCM_INTR_R1_N      B @T6G_MB_LIB.T6G(SCH_1):SGPIO_SCM_INTR_R1_N

Q_RES_0402LF-33.2,1%,1/16W,CHIP,CS03322FB03  I60  R2415
   1 SMB_1_BMC_GPU_SCL      A @T6G_MB_LIB.T6G(SCH_1):SMB_1_BMC_GPU_SCL
   2 SMB_PCIE3_3V3AUX_SCL_R      B @T6G_MB_LIB.T6G(SCH_1):SMB_PCIE3_3V3AUX_SCL_R

Q_RES_0402LF-33.2,1%,1/16W,CHIP,CS03322FB03  I101  R2422
   1 SMB_VR_SENSOR_3V3AUX_SDA      A @T6G_MB_LIB.T6G(SCH_1):SMB_VR_SENSOR_3V3AUX_SDA
   2 SMB_VR_3V3AUX_SDA_R0      B @T6G_MB_LIB.T6G(SCH_1):SMB_VR_3V3AUX_SDA_R0

Q_RES_0402LF-33.2,1%,1/16W,CHIP,CS03322FB03  I102  R3239
   1 SMB_OCP_SFF_3V3AUX_SDA      A @T6G_MB_LIB.T6G(SCH_1):SMB_OCP_SFF_3V3AUX_SDA
   2 SMB_OCP_SFF_3V3AUX_SDA_R0      B @T6G_MB_LIB.T6G(SCH_1):SMB_OCP_SFF_3V3AUX_SDA_R0

Q_RES_0402LF-33.2,1%,1/16W,CHIP,CS03322FB03  I103  R3238
   1 SMB_OCP_SFF_3V3AUX_SCL      A @T6G_MB_LIB.T6G(SCH_1):SMB_OCP_SFF_3V3AUX_SCL
   2 SMB_OCP_SFF_3V3AUX_SCL_R0      B @T6G_MB_LIB.T6G(SCH_1):SMB_OCP_SFF_3V3AUX_SCL_R0

Q_RES_0402LF-33.2,1%,1/16W,CHIP,CS03322FB03  I104  R2419
   1 SMB_CPU0_CPU1_APML_SCL      A @T6G_MB_LIB.T6G(SCH_1):SMB_CPU0_CPU1_APML_SCL
   2 SMB_CPU0_CPU1_APML_SCL_R      B @T6G_MB_LIB.T6G(SCH_1):SMB_CPU0_CPU1_APML_SCL_R

Q_RES_0402LF-33.2,1%,1/16W,CHIP,CS03322FB03  I105  R2420
   1 SMB_CPU0_CPU1_APML_SDA      A @T6G_MB_LIB.T6G(SCH_1):SMB_CPU0_CPU1_APML_SDA
   2 SMB_CPU0_CPU1_APML_SDA_R      B @T6G_MB_LIB.T6G(SCH_1):SMB_CPU0_CPU1_APML_SDA_R

Q_RES_0402LF-0,5%,1/16W,CHIP,CS00002JB13  I123  R6000
   1 I3C_SCM_0_SCL      A @T6G_MB_LIB.T6G(SCH_1):I3C_SCM_0_SCL
   2 I3C_SCM_0_R_SCL      B @T6G_MB_LIB.T6G(SCH_1):I3C_SCM_0_R_SCL

Q_RES_0402LF-0,5%,1/16W,CHIP,CS00002JB13  I131  R6012
   1 SGPIO_SCM_DO_<1>      A @T6G_MB_LIB.T6G(SCH_1):SGPIO_SCM_DO_(1)
   2 SGPIO_SCM_DO_R_<1>      B @T6G_MB_LIB.T6G(SCH_1):SGPIO_SCM_DO_R_(1)

Q_RES_0402LF-0,5%,1/16W,CHIP,CS00002JB13  I132  R6011
   1 SGPIO_SCM_LD_<0>      A @T6G_MB_LIB.T6G(SCH_1):SGPIO_SCM_LD_(0)
   2 SGPIO_SCM_LD_R_<0>      B @T6G_MB_LIB.T6G(SCH_1):SGPIO_SCM_LD_R_(0)

Q_RES_0402LF-0,5%,1/16W,CHIP,CS00002JB13  I133  R6010
   1 SGPIO_SCM_DI_<0>      A @T6G_MB_LIB.T6G(SCH_1):SGPIO_SCM_DI_(0)
   2 SGPIO_SCM_DI_R_<0>      B @T6G_MB_LIB.T6G(SCH_1):SGPIO_SCM_DI_R_(0)

Q_RES_0402LF-0,5%,1/16W,CHIP,CS00002JB13  I134  R6009
   1 SGPIO_SCM_CLK_<0>      A @T6G_MB_LIB.T6G(SCH_1):SGPIO_SCM_CLK_(0)
   2 SGPIO_SCM_CLK_R_<0>      B @T6G_MB_LIB.T6G(SCH_1):SGPIO_SCM_CLK_R_(0)

Q_RES_0402LF-0,5%,1/16W,CHIP,CS00002JB13  I135  R6008
   1 SGPIO_SCM_DO_<0>      A @T6G_MB_LIB.T6G(SCH_1):SGPIO_SCM_DO_(0)
   2 SGPIO_SCM_DO_R_<0>      B @T6G_MB_LIB.T6G(SCH_1):SGPIO_SCM_DO_R_(0)

Q_RES_0402LF-0,5%,1/16W,CHIP,CS00002JB13  I169  R3778
   1 FM_SOL_UART_CH_SEL_R      A @T6G_MB_LIB.T6G(SCH_1):FM_SOL_UART_CH_SEL_R
   2 FM_SOL_UART_CH_SEL      B @T6G_MB_LIB.T6G(SCH_1):FM_SOL_UART_CH_SEL

Q_RES_0402LF-0,5%,1/16W,CHIP,CS00002JB13  I174  R6028
   1 FM_LPC_ESPI_SEL      A @T6G_MB_LIB.T6G(SCH_1):FM_LPC_ESPI_SEL
   2    GND      B @T6G_MB_LIB.T6G(SCH_1):GND

Q_RES_0402LF-0,5%,1/16W,EMPTY,CS00002JB13  I177  R6064
   1 UART_CPU0_SCM_LVC3_UART1_RX      A @T6G_MB_LIB.T6G(SCH_1):UART_CPU0_SCM_LVC3_UART1_RX
   2 UART_CPU0_SCM_LVC3_UART1_R_RX      B @T6G_MB_LIB.T6G(SCH_1):UART_CPU0_SCM_LVC3_UART1_R_RX

Q_RES_0402LF-0,5%,1/16W,EMPTY,CS00002JB13  I178  R6065
   1 UART_CPU0_SCM_LVC3_UART1_R1_TX      A @T6G_MB_LIB.T6G(SCH_1):UART_CPU0_SCM_LVC3_UART1_R1_TX
   2 UART_CPU0_SCM_LVC3_UART1_TX      B @T6G_MB_LIB.T6G(SCH_1):UART_CPU0_SCM_LVC3_UART1_TX

Q_RES_0402LF-33.2,1%,1/16W,CHIP,CS03322FB03  I190  R4507
   1 SMB_CPU0_CPU1_SEC_SDA      A @T6G_MB_LIB.T6G(SCH_1):SMB_CPU0_CPU1_SEC_SDA
   2 SMB_CPU0_CPU1_SEC_SDA_R      B @T6G_MB_LIB.T6G(SCH_1):SMB_CPU0_CPU1_SEC_SDA_R

Q_RES_0402LF-33.2,1%,1/16W,CHIP,CS03322FB03  I191  R4506
   1 SMB_CPU0_CPU1_SEC_SCL      A @T6G_MB_LIB.T6G(SCH_1):SMB_CPU0_CPU1_SEC_SCL
   2 SMB_CPU0_CPU1_SEC_SCL_R      B @T6G_MB_LIB.T6G(SCH_1):SMB_CPU0_CPU1_SEC_SCL_R

Q_RES_0402LF-33.2,1%,1/16W,CHIP,CS03322FB03  I195  R2424
   1 SMB_PMBUS_3V3AUX_SDA      A @T6G_MB_LIB.T6G(SCH_1):SMB_PMBUS_3V3AUX_SDA
   2 SMB_PMBUS_3V3AUX_SDA_R0      B @T6G_MB_LIB.T6G(SCH_1):SMB_PMBUS_3V3AUX_SDA_R0

Q_RES_0402LF-33.2,1%,1/16W,CHIP,CS03322FB03  I196  R2423
   1 SMB_PMBUS_3V3AUX_SCL      A @T6G_MB_LIB.T6G(SCH_1):SMB_PMBUS_3V3AUX_SCL
   2 SMB_PMBUS_3V3AUX_SCL_R0      B @T6G_MB_LIB.T6G(SCH_1):SMB_PMBUS_3V3AUX_SCL_R0

Q_RES_0402LF-4.7K,5%,1/16W,EMPTY,CS24702JB10  I214  R6071
   1 P3V3_AUX      A @T6G_MB_LIB.T6G(SCH_1):P3V3_AUX
   2 PU_JTAG_DBP_BMC_PRDY_N      B @T6G_MB_LIB.T6G(SCH_1):PU_JTAG_DBP_BMC_PRDY_N

Q_RES_0402LF-0,5%,1/16W,CHIP,CS00002JB13  I215  R8101
   1 FM_AC_PWR_BTN_R_N      A @T6G_MB_LIB.T6G(SCH_1):FM_AC_PWR_BTN_R_N
   2 FM_AC_PWR_BTN_N      B @T6G_MB_LIB.T6G(SCH_1):FM_AC_PWR_BTN_N

Q_CAP_0402-0.1UF,25V,10%,X7R,CH4104K1B00  I219  C6000
   1 SCM_VDD_RTC      A @T6G_MB_LIB.T6G(SCH_1):SCM_VDD_RTC
   2    GND      B @T6G_MB_LIB.T6G(SCH_1):GND

Q_RES_0402LF-0,5%,1/16W,CHIP,CS00002JB13  I220  R4809
   1 TP_CHASI      A @T6G_MB_LIB.T6G(SCH_1):TP_CHASI
   2    GND      B @T6G_MB_LIB.T6G(SCH_1):GND


DRAWING: @T6G_MB_LIB.T6G(SCH_1):PAGE349 

Q_RES_0402LF-2K,5%,1/16W,EMPTY,TMP_QCS22002JB29  I28  R6017
   1 P3V3_AUX      A @T6G_MB_LIB.T6G(SCH_1):P3V3_AUX
   2 SGPIO_SCM_CLK_<0>      B @T6G_MB_LIB.T6G(SCH_1):SGPIO_SCM_CLK_(0)

Q_RES_0402LF-2K,5%,1/16W,EMPTY,TMP_QCS22002JB29  I29  R6016
   1 P3V3_AUX      A @T6G_MB_LIB.T6G(SCH_1):P3V3_AUX
   2 SGPIO_SCM_DO_<0>      B @T6G_MB_LIB.T6G(SCH_1):SGPIO_SCM_DO_(0)

Q_RES_0402LF-1K,1%,1/16W,CHIP,CS21002FB06  I30  R1546
   1 P3V3_AUX      A @T6G_MB_LIB.T6G(SCH_1):P3V3_AUX
   2 RST_MB_STBY_N      B @T6G_MB_LIB.T6G(SCH_1):RST_MB_STBY_N

Q_RES_0402LF-4.7K,5%,1/16W,EMPTY,CS24702JB10  I32  R6027
   1 SGPIO_SCM_RESET_N      A @T6G_MB_LIB.T6G(SCH_1):SGPIO_SCM_RESET_N
   2    GND      B @T6G_MB_LIB.T6G(SCH_1):GND

Q_RES_0402LF-0,5%,1/16W,CHIP,CS00002JB13  I57  R1447
   1 SMB_CPU_5_SCL      A @T6G_MB_LIB.T6G(SCH_1):SMB_CPU_5_SCL
   2 SMB_CPU_5_R1_SCL      B @T6G_MB_LIB.T6G(SCH_1):SMB_CPU_5_R1_SCL

Q_RES_0402LF-33.2,1%,1/16W,CHIP,CS03322FB03  I84  R4152
   1 SMB_1_PLD_3V3AUX_SDA      A @T6G_MB_LIB.T6G(SCH_1):SMB_1_PLD_3V3AUX_SDA
   2 SMB_2_PLD_3V3AUX_SDA_R1      B @T6G_MB_LIB.T6G(SCH_1):SMB_2_PLD_3V3AUX_SDA_R1

Q_CAP_C0402-220PF,50V,5%,C0G,CH12206JB00  I112  C63
   1 UART_CPU0_SCM_LVC3_UART1_R_RX      A @T6G_MB_LIB.T6G(SCH_1):UART_CPU0_SCM_LVC3_UART1_R_RX
   2    GND      B @T6G_MB_LIB.T6G(SCH_1):GND

Q_RES_0402LF-2.2K,5%,1/16W,EMPTY,CS22202JB07  I115  R3243
   1 SMB_OCP_V3_2_3V3AUX_SDA      A @T6G_MB_LIB.T6G(SCH_1):SMB_OCP_V3_2_3V3AUX_SDA
   2 P3V3_AUX      B @T6G_MB_LIB.T6G(SCH_1):P3V3_AUX

Q_RES_0402LF-10K,5%,1/16W,CHIP,CS31002JB08  I116  R131
   1 P3V3_AUX      A @T6G_MB_LIB.T6G(SCH_1):P3V3_AUX
   2 UART_VCC_J8      B @T6G_MB_LIB.T6G(SCH_1):UART_VCC_J8

Q_RES_0402LF-2.2K,5%,1/16W,EMPTY,CS22202JB07  I120  R3240
   1 SMB_OCP_SFF_3V3AUX_SCL      A @T6G_MB_LIB.T6G(SCH_1):SMB_OCP_SFF_3V3AUX_SCL
   2 P3V3_AUX      B @T6G_MB_LIB.T6G(SCH_1):P3V3_AUX

Q_RES_0402LF-2.2K,5%,1/16W,EMPTY,CS22202JB07  I121  R3227
   1 SMB_1_BMC_GPU_SDA      A @T6G_MB_LIB.T6G(SCH_1):SMB_1_BMC_GPU_SDA
   2 P3V3_AUX      B @T6G_MB_LIB.T6G(SCH_1):P3V3_AUX

Q_RES_0402LF-2.2K,5%,1/16W,EMPTY,CS22202JB07  I122  R3226
   1 SMB_1_BMC_GPU_SCL      A @T6G_MB_LIB.T6G(SCH_1):SMB_1_BMC_GPU_SCL
   2 P3V3_AUX      B @T6G_MB_LIB.T6G(SCH_1):P3V3_AUX

Q_RES_0402LF-2.2K,5%,1/16W,EMPTY,CS22202JB07  I123  R3004
   1 SMB_2_BMC_GPU_SDA      A @T6G_MB_LIB.T6G(SCH_1):SMB_2_BMC_GPU_SDA
   2 P3V3_AUX      B @T6G_MB_LIB.T6G(SCH_1):P3V3_AUX

Q_RES_0402LF-2.2K,5%,1/16W,EMPTY,CS22202JB07  I124  R2999
   1 SMB_2_BMC_GPU_SCL      A @T6G_MB_LIB.T6G(SCH_1):SMB_2_BMC_GPU_SCL
   2 P3V3_AUX      B @T6G_MB_LIB.T6G(SCH_1):P3V3_AUX

Q_RES_0402LF-2.2K,5%,1/16W,EMPTY,CS22202JB07  I125  R2213
   1 SMB_HOST_CLK_3V3AUX_SDA      A @T6G_MB_LIB.T6G(SCH_1):SMB_HOST_CLK_3V3AUX_SDA
   2 P3V3_AUX      B @T6G_MB_LIB.T6G(SCH_1):P3V3_AUX

Q_RES_0402LF-2.2K,5%,1/16W,EMPTY,CS22202JB07  I126  R2212
   1 SMB_HOST_CLK_3V3AUX_SCL      A @T6G_MB_LIB.T6G(SCH_1):SMB_HOST_CLK_3V3AUX_SCL
   2 P3V3_AUX      B @T6G_MB_LIB.T6G(SCH_1):P3V3_AUX

Q_RES_0402LF-2.2K,5%,1/16W,EMPTY,CS22202JB07  I127  R1460
   1 I3C_BMC_SWB_SDA      A @T6G_MB_LIB.T6G(SCH_1):I3C_BMC_SWB_SDA
   2 P3V3_AUX      B @T6G_MB_LIB.T6G(SCH_1):P3V3_AUX

Q_RES_0402LF-2.2K,5%,1/16W,EMPTY,CS22202JB07  I128  R332
   1 I3C_BMC_SWB_SCL      A @T6G_MB_LIB.T6G(SCH_1):I3C_BMC_SWB_SCL
   2 P3V3_AUX      B @T6G_MB_LIB.T6G(SCH_1):P3V3_AUX

Q_RES_0402LF-2.2K,5%,1/16W,EMPTY,CS22202JB07  I129  R331
   1 SMB_FAN_3V3AUX_SDA      A @T6G_MB_LIB.T6G(SCH_1):SMB_FAN_3V3AUX_SDA
   2 P3V3_AUX      B @T6G_MB_LIB.T6G(SCH_1):P3V3_AUX

Q_RES_0402LF-2.2K,5%,1/16W,EMPTY,CS22202JB07  I130  R330
   1 SMB_FAN_3V3AUX_SCL      A @T6G_MB_LIB.T6G(SCH_1):SMB_FAN_3V3AUX_SCL
   2 P3V3_AUX      B @T6G_MB_LIB.T6G(SCH_1):P3V3_AUX

Q_RES_0402LF-2K,1%,1/16W,EMPTY,CS22002FB07  I131  R6036
   1 SMB_1_PLD_3V3AUX_SCL      A @T6G_MB_LIB.T6G(SCH_1):SMB_1_PLD_3V3AUX_SCL
   2 P3V3_AUX      B @T6G_MB_LIB.T6G(SCH_1):P3V3_AUX

Q_RES_0402LF-2K,1%,1/16W,EMPTY,CS22002FB07  I132  R6037
   1 SMB_1_PLD_3V3AUX_SDA      A @T6G_MB_LIB.T6G(SCH_1):SMB_1_PLD_3V3AUX_SDA
   2 P3V3_AUX      B @T6G_MB_LIB.T6G(SCH_1):P3V3_AUX

Q_RES_0402LF-2K,1%,1/16W,EMPTY,CS22002FB07  I133  R329
   1 SMB_PMBUS_3V3AUX_SDA      A @T6G_MB_LIB.T6G(SCH_1):SMB_PMBUS_3V3AUX_SDA
   2 P3V3_AUX      B @T6G_MB_LIB.T6G(SCH_1):P3V3_AUX

Q_RES_0402LF-2K,1%,1/16W,EMPTY,CS22002FB07  I134  R1386
   1 SMB_PMBUS_3V3AUX_SCL      A @T6G_MB_LIB.T6G(SCH_1):SMB_PMBUS_3V3AUX_SCL
   2 P3V3_AUX      B @T6G_MB_LIB.T6G(SCH_1):P3V3_AUX

Q_RES_0402LF-2K,1%,1/16W,EMPTY,CS22002FB07  I135  R1385
   1 SMB_CPU0_CPU1_SEC_SDA      A @T6G_MB_LIB.T6G(SCH_1):SMB_CPU0_CPU1_SEC_SDA
   2 P3V3_AUX      B @T6G_MB_LIB.T6G(SCH_1):P3V3_AUX

Q_RES_0402LF-2K,1%,1/16W,EMPTY,CS22002FB07  I136  R1384
   1 SMB_CPU0_CPU1_SEC_SCL      A @T6G_MB_LIB.T6G(SCH_1):SMB_CPU0_CPU1_SEC_SCL
   2 P3V3_AUX      B @T6G_MB_LIB.T6G(SCH_1):P3V3_AUX

Q_RES_0402LF-2K,1%,1/16W,EMPTY,CS22002FB07  I137  R3062
   1 SMB_CPU0_CPU1_APML_SDA      A @T6G_MB_LIB.T6G(SCH_1):SMB_CPU0_CPU1_APML_SDA
   2 P3V3_AUX      B @T6G_MB_LIB.T6G(SCH_1):P3V3_AUX

Q_RES_0402LF-2K,1%,1/16W,EMPTY,CS22002FB07  I138  R1319
   1 SMB_CPU0_CPU1_APML_SCL      A @T6G_MB_LIB.T6G(SCH_1):SMB_CPU0_CPU1_APML_SCL
   2 P3V3_AUX      B @T6G_MB_LIB.T6G(SCH_1):P3V3_AUX

Q_RES_0402LF-10K,5%,1/16W,EMPTY,CS31002JB08  I145  R888
   1 P3V3_AUX      A @T6G_MB_LIB.T6G(SCH_1):P3V3_AUX
   2 SCM_SPARE_0      B @T6G_MB_LIB.T6G(SCH_1):SCM_SPARE_0

Q_RES_0402LF-10K,5%,1/16W,EMPTY,CS31002JB08  I147  R890
   1 P3V3_AUX      A @T6G_MB_LIB.T6G(SCH_1):P3V3_AUX
   2 SCM_SPARE_1      B @T6G_MB_LIB.T6G(SCH_1):SCM_SPARE_1

CONN4_HFK1040L0P1L7H-CONN4_HFK1040-L0P1L-7H,THLF,IA  I148  J8
   4    GND      4 @T6G_MB_LIB.T6G(SCH_1):GND
   3 UART_CPU0_SCM_LVC3_UART1_TX      3 @T6G_MB_LIB.T6G(SCH_1):UART_CPU0_SCM_LVC3_UART1_TX
   2 UART_CPU0_SCM_LVC3_UART1_R_RX      2 @T6G_MB_LIB.T6G(SCH_1):UART_CPU0_SCM_LVC3_UART1_R_RX
   1 UART_VCC_J8      1 @T6G_MB_LIB.T6G(SCH_1):UART_VCC_J8

Q_RES_0402LF-33,5%,1/16W,CHIP,CS03302JB10  I9  R1494
   1 SMB_VR_3V3STBY_SDA      A @T6G_MB_LIB.T6G(SCH_1):SMB_VR_3V3STBY_SDA
   2 SMB_SCM_2_R1_SDA      B @T6G_MB_LIB.T6G(SCH_1):SMB_SCM_2_R1_SDA

Q_RES_0402LF-33,5%,1/16W,CHIP,CS03302JB10  I10  R1321
   1 SMB_VR_3V3STBY_SCL      A @T6G_MB_LIB.T6G(SCH_1):SMB_VR_3V3STBY_SCL
   2 SMB_SCM_2_R1_SCL      B @T6G_MB_LIB.T6G(SCH_1):SMB_SCM_2_R1_SCL

Q_RES_0402LF-2.2K,5%,1/16W,CHIP,CS22202JB07  I17  R633
   1 PVDD18_S5_P0      A @T6G_MB_LIB.T6G(SCH_1):PVDD18_S5_P0
   2 SMB_CPU_5_SDA      B @T6G_MB_LIB.T6G(SCH_1):SMB_CPU_5_SDA

Q_RES_0402LF-2.2K,5%,1/16W,CHIP,CS22202JB07  I18  R632
   1 PVDD18_S5_P0      A @T6G_MB_LIB.T6G(SCH_1):PVDD18_S5_P0
   2 SMB_CPU_5_SCL      B @T6G_MB_LIB.T6G(SCH_1):SMB_CPU_5_SCL

Q_RES_0402LF-4.7K,5%,1/16W,EMPTY,CS24702JB10  I20  R6024
   1 P3V3_AUX      A @T6G_MB_LIB.T6G(SCH_1):P3V3_AUX
   2 SGPIO_SCM_INTR_N      B @T6G_MB_LIB.T6G(SCH_1):SGPIO_SCM_INTR_N

Q_RES_0402LF-2K,5%,1/16W,EMPTY,TMP_QCS22002JB29  I21  R6023
   1 P3V3_AUX      A @T6G_MB_LIB.T6G(SCH_1):P3V3_AUX
   2 SGPIO_SCM_LD_<1>      B @T6G_MB_LIB.T6G(SCH_1):SGPIO_SCM_LD_(1)

Q_RES_0402LF-2K,5%,1/16W,EMPTY,TMP_QCS22002JB29  I22  R6021
   1 P3V3_AUX      A @T6G_MB_LIB.T6G(SCH_1):P3V3_AUX
   2 SGPIO_SCM_CLK_<1>      B @T6G_MB_LIB.T6G(SCH_1):SGPIO_SCM_CLK_(1)

Q_RES_0402LF-2K,5%,1/16W,EMPTY,TMP_QCS22002JB29  I23  R6022
   1 P3V3_AUX      A @T6G_MB_LIB.T6G(SCH_1):P3V3_AUX
   2 SGPIO_SCM_DI_<1>      B @T6G_MB_LIB.T6G(SCH_1):SGPIO_SCM_DI_(1)

Q_RES_0402LF-2K,5%,1/16W,EMPTY,TMP_QCS22002JB29  I24  R6020
   1 P3V3_AUX      A @T6G_MB_LIB.T6G(SCH_1):P3V3_AUX
   2 SGPIO_SCM_DO_<1>      B @T6G_MB_LIB.T6G(SCH_1):SGPIO_SCM_DO_(1)

Q_RES_0402LF-2K,5%,1/16W,EMPTY,TMP_QCS22002JB29  I25  R6019
   1 P3V3_AUX      A @T6G_MB_LIB.T6G(SCH_1):P3V3_AUX
   2 SGPIO_SCM_LD_<0>      B @T6G_MB_LIB.T6G(SCH_1):SGPIO_SCM_LD_(0)

Q_RES_0402LF-2K,5%,1/16W,EMPTY,TMP_QCS22002JB29  I27  R6018
   1 P3V3_AUX      A @T6G_MB_LIB.T6G(SCH_1):P3V3_AUX
   2 SGPIO_SCM_DI_<0>      B @T6G_MB_LIB.T6G(SCH_1):SGPIO_SCM_DI_(0)

Q_RES_0402LF-33,5%,1/16W,CHIP,CS03302JB10  I48  R1496
   1 SMB_SCM_2_R1_SDA      A @T6G_MB_LIB.T6G(SCH_1):SMB_SCM_2_R1_SDA
   2 SMB_SCM_2_R2_SDA      B @T6G_MB_LIB.T6G(SCH_1):SMB_SCM_2_R2_SDA

Q_RES_0402LF-33,5%,1/16W,CHIP,CS03302JB10  I49  R1495
   1 SMB_SCM_2_R1_SCL      A @T6G_MB_LIB.T6G(SCH_1):SMB_SCM_2_R1_SCL
   2 SMB_SCM_2_R2_SCL      B @T6G_MB_LIB.T6G(SCH_1):SMB_SCM_2_R2_SCL

Q_RES_0402LF-0,5%,1/16W,CHIP,CS00002JB13  I56  R1453
   1 SMB_CPU_5_SDA      A @T6G_MB_LIB.T6G(SCH_1):SMB_CPU_5_SDA
   2 SMB_CPU_5_R1_SDA      B @T6G_MB_LIB.T6G(SCH_1):SMB_CPU_5_R1_SDA

Q_CAP_C0402-220PF,50V,5%,C0G,CH12206JB00  I69  C62
   1 UART_CPU0_SCM_LVC3_UART1_TX      A @T6G_MB_LIB.T6G(SCH_1):UART_CPU0_SCM_LVC3_UART1_TX
   2    GND      B @T6G_MB_LIB.T6G(SCH_1):GND

Q_RES_0402LF-33.2,1%,1/16W,CHIP,CS03322FB03  I81  R3340
   1 SMB_HOST_CLK_3V3AUX_SCL      A @T6G_MB_LIB.T6G(SCH_1):SMB_HOST_CLK_3V3AUX_SCL
   2 SMB_HOST_CLK_GEN2_3V3AUX_SCL      B @T6G_MB_LIB.T6G(SCH_1):SMB_HOST_CLK_GEN2_3V3AUX_SCL

Q_RES_0402LF-33.2,1%,1/16W,CHIP,CS03322FB03  I82  R3341
   1 SMB_HOST_CLK_3V3AUX_SDA      A @T6G_MB_LIB.T6G(SCH_1):SMB_HOST_CLK_3V3AUX_SDA
   2 SMB_HOST_CLK_GEN2_3V3AUX_SDA      B @T6G_MB_LIB.T6G(SCH_1):SMB_HOST_CLK_GEN2_3V3AUX_SDA

Q_RES_0402LF-33.2,1%,1/16W,CHIP,CS03322FB03  I83  R4151
   1 SMB_1_PLD_3V3AUX_SCL      A @T6G_MB_LIB.T6G(SCH_1):SMB_1_PLD_3V3AUX_SCL
   2 SMB_2_PLD_3V3AUX_SCL_R1      B @T6G_MB_LIB.T6G(SCH_1):SMB_2_PLD_3V3AUX_SCL_R1

Q_RES_0402LF-33.2,1%,1/16W,CHIP,CS03322FB03  I89  R4149
   1 SMB_1_PLD_3V3AUX_SCL      A @T6G_MB_LIB.T6G(SCH_1):SMB_1_PLD_3V3AUX_SCL
   2 SMB_1_PLD_3V3AUX_SCL_R1      B @T6G_MB_LIB.T6G(SCH_1):SMB_1_PLD_3V3AUX_SCL_R1

Q_RES_0402LF-33.2,1%,1/16W,CHIP,CS03322FB03  I90  R4150
   1 SMB_1_PLD_3V3AUX_SDA      A @T6G_MB_LIB.T6G(SCH_1):SMB_1_PLD_3V3AUX_SDA
   2 SMB_1_PLD_3V3AUX_SDA_R1      B @T6G_MB_LIB.T6G(SCH_1):SMB_1_PLD_3V3AUX_SDA_R1

Q_RES_0402LF-33.2,1%,1/16W,CHIP,CS03322FB03  I91  R2995
   1 SMB_PMBUS_3V3AUX_SCL      A @T6G_MB_LIB.T6G(SCH_1):SMB_PMBUS_3V3AUX_SCL
   2 SMB_SML1_PMBUS_HSC_SCL      B @T6G_MB_LIB.T6G(SCH_1):SMB_SML1_PMBUS_HSC_SCL

Q_RES_0402LF-33.2,1%,1/16W,CHIP,CS03322FB03  I92  R2996
   1 SMB_PMBUS_3V3AUX_SDA      A @T6G_MB_LIB.T6G(SCH_1):SMB_PMBUS_3V3AUX_SDA
   2 SMB_SML1_PMBUS_HSC_SDA      B @T6G_MB_LIB.T6G(SCH_1):SMB_SML1_PMBUS_HSC_SDA

Q_RES_0402LF-10K,5%,1/16W,EMPTY,CS31002JB08  I113  R130
   1 UART_VCC_J8      A @T6G_MB_LIB.T6G(SCH_1):UART_VCC_J8
   2 P5V_AUX      B @T6G_MB_LIB.T6G(SCH_1):P5V_AUX

Q_RES_0402LF-2.2K,5%,1/16W,EMPTY,CS22202JB07  I119  R3242
   1 SMB_OCP_V3_2_3V3AUX_SCL      A @T6G_MB_LIB.T6G(SCH_1):SMB_OCP_V3_2_3V3AUX_SCL
   2 P3V3_AUX      B @T6G_MB_LIB.T6G(SCH_1):P3V3_AUX

Q_RES_0402LF-10K,5%,1/16W,EMPTY,CS31002JB08  I142  R889
   1 SCM_SPARE_0      A @T6G_MB_LIB.T6G(SCH_1):SCM_SPARE_0
   2    GND      B @T6G_MB_LIB.T6G(SCH_1):GND

Q_RES_0402LF-10K,5%,1/16W,EMPTY,CS31002JB08  I144  R891
   1 SCM_SPARE_1      A @T6G_MB_LIB.T6G(SCH_1):SCM_SPARE_1
   2    GND      B @T6G_MB_LIB.T6G(SCH_1):GND

Q_RES_0402LF-2.2K,5%,1/16W,EMPTY,CS22202JB07  I149  R3241
   1 SMB_OCP_SFF_3V3AUX_SDA      A @T6G_MB_LIB.T6G(SCH_1):SMB_OCP_SFF_3V3AUX_SDA
   2 P3V3_AUX      B @T6G_MB_LIB.T6G(SCH_1):P3V3_AUX

Q_RES_0402LF-0,5%,1/16W,EMPTY,CS00002JB13  I150  R6066
   1 JTAG_SCM_TDI_R      A @T6G_MB_LIB.T6G(SCH_1):JTAG_SCM_TDI_R
   2 JTAG_SCM_TDI      B @T6G_MB_LIB.T6G(SCH_1):JTAG_SCM_TDI

Q_RES_0402LF-0,5%,1/16W,EMPTY,CS00002JB13  I151  R6068
   1 JTAG_SCM_TDO_R      A @T6G_MB_LIB.T6G(SCH_1):JTAG_SCM_TDO_R
   2 JTAG_SCM_TDO      B @T6G_MB_LIB.T6G(SCH_1):JTAG_SCM_TDO

Q_RES_0402LF-0,5%,1/16W,CHIP,CS00002JB13  I158  R6069
   1 JTAG_SCM_TDI_R      A @T6G_MB_LIB.T6G(SCH_1):JTAG_SCM_TDI_R
   2 JTAG_SCM_TDO      B @T6G_MB_LIB.T6G(SCH_1):JTAG_SCM_TDO

Q_RES_0402LF-0,5%,1/16W,CHIP,CS00002JB13  I159  R6067
   1 JTAG_SCM_TDO_R      A @T6G_MB_LIB.T6G(SCH_1):JTAG_SCM_TDO_R
   2 JTAG_SCM_TDI      B @T6G_MB_LIB.T6G(SCH_1):JTAG_SCM_TDI

Q_RES_0402LF-4.7K,5%,1/16W,EMPTY,CS24702JB10  I161  R6070
   1 P3V3_AUX      A @T6G_MB_LIB.T6G(SCH_1):P3V3_AUX
   2 JTAG_SCM_DBREQ_N      B @T6G_MB_LIB.T6G(SCH_1):JTAG_SCM_DBREQ_N

Q_RES_0402LF-33.2,1%,1/16W,CHIP,CS03322FB03  I172  R348
   1 SMB_SML1_PMBUS_HSC_SDA      A @T6G_MB_LIB.T6G(SCH_1):SMB_SML1_PMBUS_HSC_SDA
   2 SMB_SML1_PMBUS_HSC_R1_SDA      B @T6G_MB_LIB.T6G(SCH_1):SMB_SML1_PMBUS_HSC_R1_SDA

Q_RES_0402LF-33.2,1%,1/16W,CHIP,CS03322FB03  I173  R347
   1 SMB_SML1_PMBUS_HSC_SCL      A @T6G_MB_LIB.T6G(SCH_1):SMB_SML1_PMBUS_HSC_SCL
   2 SMB_SML1_PMBUS_HSC_R1_SCL      B @T6G_MB_LIB.T6G(SCH_1):SMB_SML1_PMBUS_HSC_R1_SCL

Q_RES_0402LF-33,5%,1/16W,CHIP,CS03302JB10  I176  R1497
   1 SMB_VR_3V3AUX_SCL      A @T6G_MB_LIB.T6G(SCH_1):SMB_VR_3V3AUX_SCL
   2 SMB_SCM_2_R3_SCL      B @T6G_MB_LIB.T6G(SCH_1):SMB_SCM_2_R3_SCL

Q_RES_0402LF-33,5%,1/16W,CHIP,CS03302JB10  I181  R6076
   1 SMB_SCM_2_R3_SCL      A @T6G_MB_LIB.T6G(SCH_1):SMB_SCM_2_R3_SCL
   2 SMB_SCM_2_R4_SCL      B @T6G_MB_LIB.T6G(SCH_1):SMB_SCM_2_R4_SCL

Q_RES_0402LF-33,5%,1/16W,CHIP,CS03302JB10  I182  R6077
   1 SMB_SCM_2_R3_SDA      A @T6G_MB_LIB.T6G(SCH_1):SMB_SCM_2_R3_SDA
   2 SMB_SCM_2_R4_SDA      B @T6G_MB_LIB.T6G(SCH_1):SMB_SCM_2_R4_SDA

Q_RES_0402LF-33,5%,1/16W,CHIP,CS03302JB10  I183  R1498
   1 SMB_VR_3V3AUX_SDA      A @T6G_MB_LIB.T6G(SCH_1):SMB_VR_3V3AUX_SDA
   2 SMB_SCM_2_R3_SDA      B @T6G_MB_LIB.T6G(SCH_1):SMB_SCM_2_R3_SDA

Q_RES_0402LF-33,5%,1/16W,CHIP,CS03302JB10  I184  R350
   1 SMB_SCM_2_R2_SDA      A @T6G_MB_LIB.T6G(SCH_1):SMB_SCM_2_R2_SDA
   2 SMB_SCM_2_R5_SDA      B @T6G_MB_LIB.T6G(SCH_1):SMB_SCM_2_R5_SDA

Q_RES_0402LF-33,5%,1/16W,CHIP,CS03302JB10  I185  R349
   1 SMB_SCM_2_R2_SCL      A @T6G_MB_LIB.T6G(SCH_1):SMB_SCM_2_R2_SCL
   2 SMB_SCM_2_R5_SCL      B @T6G_MB_LIB.T6G(SCH_1):SMB_SCM_2_R5_SCL

Q_RES_0402LF-33,5%,1/16W,CHIP,CS03302JB10  I186  R352
   1 SMB_SCM_2_R5_SDA      A @T6G_MB_LIB.T6G(SCH_1):SMB_SCM_2_R5_SDA
   2 SMB_SCM_2_R6_SDA      B @T6G_MB_LIB.T6G(SCH_1):SMB_SCM_2_R6_SDA

Q_RES_0402LF-33,5%,1/16W,CHIP,CS03302JB10  I187  R351
   1 SMB_SCM_2_R5_SCL      A @T6G_MB_LIB.T6G(SCH_1):SMB_SCM_2_R5_SCL
   2 SMB_SCM_2_R6_SCL      B @T6G_MB_LIB.T6G(SCH_1):SMB_SCM_2_R6_SCL

Q_RES_0402LF-0,5%,1/16W,CHIP,CS00002JB13  I198  R6784
   1 SMB_MUX_RT_R1_SCL      A @T6G_MB_LIB.T6G(SCH_1):SMB_MUX_RT_R1_SCL
   2 SMB_SML1_PMBUS_HSC_SCL      B @T6G_MB_LIB.T6G(SCH_1):SMB_SML1_PMBUS_HSC_SCL

Q_RES_0402LF-0,5%,1/16W,CHIP,CS00002JB13  I199  R6785
   1 SMB_MUX_RT_R1_SDA      A @T6G_MB_LIB.T6G(SCH_1):SMB_MUX_RT_R1_SDA
   2 SMB_SML1_PMBUS_HSC_SDA      B @T6G_MB_LIB.T6G(SCH_1):SMB_SML1_PMBUS_HSC_SDA

Q_RES_0402LF-0,5%,1/16W,CHIP,CS00002JB13  I206  R6859
   1 SMB_VR_3V3STBY_SDA      A @T6G_MB_LIB.T6G(SCH_1):SMB_VR_3V3STBY_SDA
   2 P0V9_RETIMER_CPU1_PMSDA      B @T6G_MB_LIB.T6G(SCH_1):P0V9_RETIMER_CPU1_PMSDA

Q_RES_0402LF-0,5%,1/16W,CHIP,CS00002JB13  I207  R6858
   1 SMB_VR_3V3STBY_SCL      A @T6G_MB_LIB.T6G(SCH_1):SMB_VR_3V3STBY_SCL
   2 P0V9_RETIMER_CPU1_PMSCL      B @T6G_MB_LIB.T6G(SCH_1):P0V9_RETIMER_CPU1_PMSCL

Q_RES_0402LF-33,5%,1/16W,CHIP,CS03302JB10  I218  R6862
   1 SMB_HOST_CLK_3V3AUX_SCL_R1      A @T6G_MB_LIB.T6G(SCH_1):SMB_HOST_CLK_3V3AUX_SCL_R1
   2 SMB_9ZXL045_P1_SCL      B @T6G_MB_LIB.T6G(SCH_1):SMB_9ZXL045_P1_SCL

Q_RES_0402LF-33,5%,1/16W,CHIP,CS03302JB10  I219  R6863
   1 SMB_HOST_CLK_3V3AUX_SDA_R1      A @T6G_MB_LIB.T6G(SCH_1):SMB_HOST_CLK_3V3AUX_SDA_R1
   2 SMB_9ZXL045_P1_SDA      B @T6G_MB_LIB.T6G(SCH_1):SMB_9ZXL045_P1_SDA

Q_RES_0402LF-33,5%,1/16W,CHIP,CS03302JB10  I220  R6864
   1 SMB_HOST_CLK_3V3AUX_SCL_R1      A @T6G_MB_LIB.T6G(SCH_1):SMB_HOST_CLK_3V3AUX_SCL_R1
   2 SMB_9ZXL045_P0_SCL      B @T6G_MB_LIB.T6G(SCH_1):SMB_9ZXL045_P0_SCL

Q_RES_0402LF-33,5%,1/16W,CHIP,CS03302JB10  I221  R6865
   1 SMB_HOST_CLK_3V3AUX_SDA_R1      A @T6G_MB_LIB.T6G(SCH_1):SMB_HOST_CLK_3V3AUX_SDA_R1
   2 SMB_9ZXL045_P0_SDA      B @T6G_MB_LIB.T6G(SCH_1):SMB_9ZXL045_P0_SDA

Q_RES_0402LF-33.2,1%,1/16W,CHIP,CS03322FB03  I222  R1516
   1 SMB_HOST_CLK_3V3AUX_SCL      A @T6G_MB_LIB.T6G(SCH_1):SMB_HOST_CLK_3V3AUX_SCL
   2 SMB_HOST_CLK_3V3AUX_SCL_R1      B @T6G_MB_LIB.T6G(SCH_1):SMB_HOST_CLK_3V3AUX_SCL_R1

Q_RES_0402LF-33.2,1%,1/16W,CHIP,CS03322FB03  I223  R1517
   1 SMB_HOST_CLK_3V3AUX_SDA      A @T6G_MB_LIB.T6G(SCH_1):SMB_HOST_CLK_3V3AUX_SDA
   2 SMB_HOST_CLK_3V3AUX_SDA_R1      B @T6G_MB_LIB.T6G(SCH_1):SMB_HOST_CLK_3V3AUX_SDA_R1

Q_RES_0402LF-33,5%,1/16W,CHIP,CS03302JB10  I224  R308
   1 SMB_VR_3V3AUX_SCL      A @T6G_MB_LIB.T6G(SCH_1):SMB_VR_3V3AUX_SCL
   2 SMB_VR_3V3STBY_SCL      B @T6G_MB_LIB.T6G(SCH_1):SMB_VR_3V3STBY_SCL

Q_RES_0402LF-33,5%,1/16W,CHIP,CS03302JB10  I225  R309
   1 SMB_VR_3V3AUX_SDA      A @T6G_MB_LIB.T6G(SCH_1):SMB_VR_3V3AUX_SDA
   2 SMB_VR_3V3STBY_SDA      B @T6G_MB_LIB.T6G(SCH_1):SMB_VR_3V3STBY_SDA

Q_RES_0402LF-33,5%,1/16W,CHIP,CS03302JB10  I226  R6856
   1 SMB_SCM_2_R6_SCL      A @T6G_MB_LIB.T6G(SCH_1):SMB_SCM_2_R6_SCL
   2 P0V9_RETIMER_CPU0_PMSCL      B @T6G_MB_LIB.T6G(SCH_1):P0V9_RETIMER_CPU0_PMSCL

Q_RES_0402LF-33,5%,1/16W,CHIP,CS03302JB10  I227  R6857
   1 SMB_SCM_2_R6_SDA      A @T6G_MB_LIB.T6G(SCH_1):SMB_SCM_2_R6_SDA
   2 P0V9_RETIMER_CPU0_PMSDA      B @T6G_MB_LIB.T6G(SCH_1):P0V9_RETIMER_CPU0_PMSDA

Q_RES_0402LF-33,5%,1/16W,CHIP,CS03302JB10  I228  R6782
   1 SMB_MUX_RT_ROM_R1_SCL      A @T6G_MB_LIB.T6G(SCH_1):SMB_MUX_RT_ROM_R1_SCL
   2 SMB_HOST_CLK_3V3AUX_SCL_R1      B @T6G_MB_LIB.T6G(SCH_1):SMB_HOST_CLK_3V3AUX_SCL_R1

Q_RES_0402LF-33,5%,1/16W,CHIP,CS03302JB10  I229  R6783
   1 SMB_MUX_RT_ROM_R1_SDA      A @T6G_MB_LIB.T6G(SCH_1):SMB_MUX_RT_ROM_R1_SDA
   2 SMB_HOST_CLK_3V3AUX_SDA_R1      B @T6G_MB_LIB.T6G(SCH_1):SMB_HOST_CLK_3V3AUX_SDA_R1

Q_RES_0402LF-0,5%,1/16W,CHIP,CS00002JB13  I231  R364
   1 P3V_BAT_R      A @T6G_MB_LIB.T6G(SCH_1):P3V_BAT_R
   2 SCM_VDD_RTC      B @T6G_MB_LIB.T6G(SCH_1):SCM_VDD_RTC


DRAWING: @T6G_MB_LIB.T6G(SCH_1):PAGE246 

Q_RES_0402LF-1K,1%,1/16W,CHIP,CS21002FB06  I2  R2694
   1 TCA9539_0_ADD1      A @T6G_MB_LIB.T6G(SCH_1):TCA9539_0_ADD1
   2    GND      B @T6G_MB_LIB.T6G(SCH_1):GND

Q_RES_0402LF-1K,1%,1/16W,EMPTY,CS21002FB06  I3  R2693
   1 P3V3_AUX      A @T6G_MB_LIB.T6G(SCH_1):P3V3_AUX
   2 TCA9539_0_ADD1      B @T6G_MB_LIB.T6G(SCH_1):TCA9539_0_ADD1

Q_RES_0402LF-1K,1%,1/16W,CHIP,CS21002FB06  I6  R2696
   1 TCA9539_0_ADD0      A @T6G_MB_LIB.T6G(SCH_1):TCA9539_0_ADD0
   2    GND      B @T6G_MB_LIB.T6G(SCH_1):GND

Q_RES_0402LF-1K,1%,1/16W,EMPTY,CS21002FB06  I7  R2695
   1 P3V3_AUX      A @T6G_MB_LIB.T6G(SCH_1):P3V3_AUX
   2 TCA9539_0_ADD0      B @T6G_MB_LIB.T6G(SCH_1):TCA9539_0_ADD0

Q_RES_0402LF-10K,1%,1/16W,EMPTY,CS31002FB08  I35  R2921
   1 P3V3_AUX      A @T6G_MB_LIB.T6G(SCH_1):P3V3_AUX
   2 RST_SMB_SWITCH_N      B @T6G_MB_LIB.T6G(SCH_1):RST_SMB_SWITCH_N

Q_RES_0402LF-0,5%,1/16W,CHIP,CS00002JB13  I31  R2922
   1 RST_SMB_SWITCH_N      A @T6G_MB_LIB.T6G(SCH_1):RST_SMB_SWITCH_N
   2 PU_RST_SMB_U181_N      B @T6G_MB_LIB.T6G(SCH_1):PU_RST_SMB_U181_N

Q_RES_0402LF-4.7K,5%,1/16W,EMPTY,CS24702JB10  I37  R2923
   1 P3V3_AUX      A @T6G_MB_LIB.T6G(SCH_1):P3V3_AUX
   2 PU_U181_INT      B @T6G_MB_LIB.T6G(SCH_1):PU_U181_INT

Q_RES_0402LF-0,5%,1/16W,CHIP,CS00002JB13  I39  R9012
   1 PRSNT_CABLE_SWB_B2_ISO_N      A @T6G_MB_LIB.T6G(SCH_1):PRSNT_CABLE_SWB_B2_ISO_N
   2 PRSNT_CABLE_SWB_B2_ISO_R_N      B @T6G_MB_LIB.T6G(SCH_1):PRSNT_CABLE_SWB_B2_ISO_R_N

Q_RES_0402LF-0,5%,1/16W,CHIP,CS00002JB13  I40  R9010
   1 PRSNT_CABLE_SWB_B1_ISO_N      A @T6G_MB_LIB.T6G(SCH_1):PRSNT_CABLE_SWB_B1_ISO_N
   2 PRSNT_CABLE_SWB_B1_ISO_R_N      B @T6G_MB_LIB.T6G(SCH_1):PRSNT_CABLE_SWB_B1_ISO_R_N

Q_RES_0402LF-0,5%,1/16W,CHIP,CS00002JB13  I41  R8004
   1 PRSNT_SWB_ISO_N      A @T6G_MB_LIB.T6G(SCH_1):PRSNT_SWB_ISO_N
   2 PRSNT_SWB_ISO_R1_N      B @T6G_MB_LIB.T6G(SCH_1):PRSNT_SWB_ISO_R1_N

Q_RES_0402LF-0,5%,1/16W,CHIP,CS00002JB13  I42  R9019
   1 PRSNT_CABLE_GPU_A1_ISO_N      A @T6G_MB_LIB.T6G(SCH_1):PRSNT_CABLE_GPU_A1_ISO_N
   2 PRSNT_CABLE_GPU_A1_ISO_R1_N      B @T6G_MB_LIB.T6G(SCH_1):PRSNT_CABLE_GPU_A1_ISO_R1_N

Q_RES_0402LF-0,5%,1/16W,CHIP,CS00002JB13  I43  R9013
   1 PRSNT_CABLE_GPU_A2_ISO_N      A @T6G_MB_LIB.T6G(SCH_1):PRSNT_CABLE_GPU_A2_ISO_N
   2 PRSNT_CABLE_GPU_A2_ISO_R1_N      B @T6G_MB_LIB.T6G(SCH_1):PRSNT_CABLE_GPU_A2_ISO_R1_N

Q_RES_0402LF-0,5%,1/16W,CHIP,CS00002JB13  I44  R9018
   1 PRSNT_CABLE_GPU_A3_ISO_N      A @T6G_MB_LIB.T6G(SCH_1):PRSNT_CABLE_GPU_A3_ISO_N
   2 PRSNT_CABLE_GPU_A3_ISO_R_N      B @T6G_MB_LIB.T6G(SCH_1):PRSNT_CABLE_GPU_A3_ISO_R_N

Q_RES_0402LF-0,5%,1/16W,CHIP,CS00002JB13  I45  R9011
   1 PRSNT_CABLE_GPU_B3_ISO_N      A @T6G_MB_LIB.T6G(SCH_1):PRSNT_CABLE_GPU_B3_ISO_N
   2 PRSNT_CABLE_GPU_B3_ISO_R1_N      B @T6G_MB_LIB.T6G(SCH_1):PRSNT_CABLE_GPU_B3_ISO_R1_N

Q_RES_0402LF-0,5%,1/16W,CHIP,CS00002JB13  I46  R9001
   1 GPU_PRSNT_N_ISO      A @T6G_MB_LIB.T6G(SCH_1):GPU_PRSNT_N_ISO
   2 GPU_PRSNT_N_ISO_R1      B @T6G_MB_LIB.T6G(SCH_1):GPU_PRSNT_N_ISO_R1

Q_RES_0402LF-0,5%,1/16W,CHIP,CS00002JB13  I47  R3518
   1 GPU_PEX_STRAP0      A @T6G_MB_LIB.T6G(SCH_1):GPU_PEX_STRAP0
   2 GPU_PEX_STRAP0_R      B @T6G_MB_LIB.T6G(SCH_1):GPU_PEX_STRAP0_R

Q_RES_0402LF-0,5%,1/16W,CHIP,CS00002JB13  I55  R3517
   1 GPU_PEX_STRAP1      A @T6G_MB_LIB.T6G(SCH_1):GPU_PEX_STRAP1
   2 GPU_PEX_STRAP1_R      B @T6G_MB_LIB.T6G(SCH_1):GPU_PEX_STRAP1_R

Q_RES_0402LF-0,5%,1/16W,CHIP,CS00002JB13  I56  R3516
   1 GPU_BASE_ID0      A @T6G_MB_LIB.T6G(SCH_1):GPU_BASE_ID0
   2 GPU_BASE_ID0_R      B @T6G_MB_LIB.T6G(SCH_1):GPU_BASE_ID0_R

Q_RES_0402LF-0,5%,1/16W,CHIP,CS00002JB13  I57  R3499
   1 GPU_BASE_ID1      A @T6G_MB_LIB.T6G(SCH_1):GPU_BASE_ID1
   2 GPU_BASE_ID1_R      B @T6G_MB_LIB.T6G(SCH_1):GPU_BASE_ID1_R

Q_RES_0402LF-0,5%,1/16W,CHIP,CS00002JB13  I58  R2983
   1 SMB_IOEXP_3V3AUX_SDA      A @T6G_MB_LIB.T6G(SCH_1):SMB_IOEXP_3V3AUX_SDA
   2 SMB_IOEXP_3V3AUX_SDA_R1      B @T6G_MB_LIB.T6G(SCH_1):SMB_IOEXP_3V3AUX_SDA_R1

Q_RES_0402LF-0,5%,1/16W,CHIP,CS00002JB13  I59  R2848
   1 RST_SWB_BIC_N      A @T6G_MB_LIB.T6G(SCH_1):RST_SWB_BIC_N
   2 RST_SWB_BIC_R_N      B @T6G_MB_LIB.T6G(SCH_1):RST_SWB_BIC_R_N

Q_CAP_0402-0.1UF,25V,10%,X7R,CH4104K1B00  I61  C1713
   1 P3V3_AUX      A @T6G_MB_LIB.T6G(SCH_1):P3V3_AUX
   2    GND      B @T6G_MB_LIB.T6G(SCH_1):GND

Q_RES_0402LF-0,5%,1/16W,CHIP,CS00002JB13  I82  R2982
   1 SMB_IOEXP_3V3AUX_SCL      A @T6G_MB_LIB.T6G(SCH_1):SMB_IOEXP_3V3AUX_SCL
   2 SMB_IOEXP_3V3AUX_SCL_R1      B @T6G_MB_LIB.T6G(SCH_1):SMB_IOEXP_3V3AUX_SCL_R1

PCA9539RPW-PCA9539RPW,SMLF,IC,AL009539K07  I83  U181
   1 PU_U181_INT    INT @T6G_MB_LIB.T6G(SCH_1):PU_U181_INT
   2 TCA9539_0_ADD1     A1 @T6G_MB_LIB.T6G(SCH_1):TCA9539_0_ADD1
   3 PU_RST_SMB_U181_N  RESET @T6G_MB_LIB.T6G(SCH_1):PU_RST_SMB_U181_N
   4 RST_USB_HUB_N  IO0_0 @T6G_MB_LIB.T6G(SCH_1):RST_USB_HUB_N
   5 RST_SWB_BIC_N  IO0_1 @T6G_MB_LIB.T6G(SCH_1):RST_SWB_BIC_N
   6 TP_TCA9539_0_P0_2  IO0_2 @T6G_MB_LIB.T6G(SCH_1):TP_TCA9539_0_P0_2
   7 TP_TCA9539_0_P0_3  IO0_3 @T6G_MB_LIB.T6G(SCH_1):TP_TCA9539_0_P0_3
   8 PRSNT_SWB_ISO_R1_N  IO0_4 @T6G_MB_LIB.T6G(SCH_1):PRSNT_SWB_ISO_R1_N
   9 GPU_PRSNT_N_ISO_R1  IO0_5 @T6G_MB_LIB.T6G(SCH_1):GPU_PRSNT_N_ISO_R1
  10 PRSNT_CABLE_GPU_B3_ISO_R1_N  IO0_6 @T6G_MB_LIB.T6G(SCH_1):PRSNT_CABLE_GPU_B3_ISO_R1_N
  11 PRSNT_CABLE_SWB_B2_ISO_R_N  IO0_7 @T6G_MB_LIB.T6G(SCH_1):PRSNT_CABLE_SWB_B2_ISO_R_N
  12    GND    VSS @T6G_MB_LIB.T6G(SCH_1):GND
  13 PRSNT_CABLE_GPU_A2_ISO_R1_N  IO1_0 @T6G_MB_LIB.T6G(SCH_1):PRSNT_CABLE_GPU_A2_ISO_R1_N
  14 PRSNT_CABLE_SWB_B1_ISO_R_N  IO1_1 @T6G_MB_LIB.T6G(SCH_1):PRSNT_CABLE_SWB_B1_ISO_R_N
  15 GPU_BASE_ID0_R  IO1_2 @T6G_MB_LIB.T6G(SCH_1):GPU_BASE_ID0_R
  16 GPU_BASE_ID1_R  IO1_3 @T6G_MB_LIB.T6G(SCH_1):GPU_BASE_ID1_R
  17 GPU_PEX_STRAP0_R  IO1_4 @T6G_MB_LIB.T6G(SCH_1):GPU_PEX_STRAP0_R
  18 GPU_PEX_STRAP1_R  IO1_5 @T6G_MB_LIB.T6G(SCH_1):GPU_PEX_STRAP1_R
  19 PRSNT_CABLE_GPU_A1_ISO_R1_N  IO1_6 @T6G_MB_LIB.T6G(SCH_1):PRSNT_CABLE_GPU_A1_ISO_R1_N
  20 PRSNT_CABLE_GPU_A3_ISO_R_N  IO1_7 @T6G_MB_LIB.T6G(SCH_1):PRSNT_CABLE_GPU_A3_ISO_R_N
  21 TCA9539_0_ADD0     A0 @T6G_MB_LIB.T6G(SCH_1):TCA9539_0_ADD0
  22 SMB_IOEXP_3V3AUX_SCL_R1    SCL @T6G_MB_LIB.T6G(SCH_1):SMB_IOEXP_3V3AUX_SCL_R1
  23 SMB_IOEXP_3V3AUX_SDA_R1    SDA @T6G_MB_LIB.T6G(SCH_1):SMB_IOEXP_3V3AUX_SDA_R1
  24 P3V3_AUX    VDD @T6G_MB_LIB.T6G(SCH_1):P3V3_AUX


DRAWING: @T6G_MB_LIB.T6G(SCH_1):PAGE232 

Q_RES_0402LF-0,5%,1/16W,CHIP,CS00002JB13  I6  R3327
   1 CLK_GEN2_GPU_FPGA_OE_N      A @T6G_MB_LIB.T6G(SCH_1):CLK_GEN2_GPU_FPGA_OE_N
   2 CLK_GEN2_GPU_FPGA_OE_R2_N      B @T6G_MB_LIB.T6G(SCH_1):CLK_GEN2_GPU_FPGA_OE_R2_N

Q_RES_0402LF-0,5%,1/16W,CHIP,CS00002JB13  I7  R3326
   1 GPU_FPGA_READY_N      A @T6G_MB_LIB.T6G(SCH_1):GPU_FPGA_READY_N
   2 GPU_FPGA_READY_R_N      B @T6G_MB_LIB.T6G(SCH_1):GPU_FPGA_READY_R_N

Q_RES_0402LF-4.7K,1%,1/16W,EMPTY,CS24702FB06  I8  R4514
   1 CLK_GEN2_GPU_FPGA_OE_R2_N      A @T6G_MB_LIB.T6G(SCH_1):CLK_GEN2_GPU_FPGA_OE_R2_N
   2    GND      B @T6G_MB_LIB.T6G(SCH_1):GND

Q_XTAL_4P_13BI_24GND-25MHZ,SMLF,MISC,BG6250000L4  I14  Y8003
   1 CLK_GEN2_XTAL_IN_R     X1 @T6G_MB_LIB.T6G(SCH_1):CLK_GEN2_XTAL_IN_R
   2    GND     G1 @T6G_MB_LIB.T6G(SCH_1):GND
   4    GND     G2 @T6G_MB_LIB.T6G(SCH_1):GND
   3 CLK_GEN2_XTAL_OUT     X2 @T6G_MB_LIB.T6G(SCH_1):CLK_GEN2_XTAL_OUT

Q_RES_0402LF-0,5%,1/16W,CHIP,CS00002JB13  I16  R4076
   1 CLK_GEN2_GPU_FPGA_OE_OR_N      A @T6G_MB_LIB.T6G(SCH_1):CLK_GEN2_GPU_FPGA_OE_OR_N
   2 CLK_GEN2_GPU_OE_N      B @T6G_MB_LIB.T6G(SCH_1):CLK_GEN2_GPU_OE_N

Q_RES_0402LF-0,5%,1/16W,CHIP,CS00002JB13  I22  R4075
   1 CLK_GEN2_BMC_RC_OE_N      A @T6G_MB_LIB.T6G(SCH_1):CLK_GEN2_BMC_RC_OE_N
   2 CLK_GEN2_BMC_RC_OE_R3_N      B @T6G_MB_LIB.T6G(SCH_1):CLK_GEN2_BMC_RC_OE_R3_N

74LVC1G32GW_SMLF-74LVC1G32GW,IC,ALVC1G32007  I26  U248
   1 GPU_FPGA_READY_R_N     I0 @T6G_MB_LIB.T6G(SCH_1):GPU_FPGA_READY_R_N
   2 CLK_GEN2_GPU_FPGA_OE_R2_N     I1 @T6G_MB_LIB.T6G(SCH_1):CLK_GEN2_GPU_FPGA_OE_R2_N
   4 CLK_GEN2_GPU_FPGA_OE_OR_N      O @T6G_MB_LIB.T6G(SCH_1):CLK_GEN2_GPU_FPGA_OE_OR_N
   5 P3V3_AUX    VCC @T6G_MB_LIB.T6G(SCH_1):P3V3_AUX
   3    GND    GND @T6G_MB_LIB.T6G(SCH_1):GND

Q_CAP_0402-0.1UF,25V,10%,X7R,CH4104K1B00  I28  C1882
   1 P3V3_AUX      A @T6G_MB_LIB.T6G(SCH_1):P3V3_AUX
   2    GND      B @T6G_MB_LIB.T6G(SCH_1):GND

Q_RES_0402LF-0,5%,1/16W,CHIP,CS00002JB13  I31  R4501
   1 CLK_GEN2_XTAL_IN_R      A @T6G_MB_LIB.T6G(SCH_1):CLK_GEN2_XTAL_IN_R
   2 CLK_GEN2_XTAL_IN      B @T6G_MB_LIB.T6G(SCH_1):CLK_GEN2_XTAL_IN

Q_INDUCTOR_SMLF-FCM2012KF-601T/0.5A,IND,CX601T05003  I33  L17
   2 VFG3P3_CLK_GEN      2 @T6G_MB_LIB.T6G(SCH_1):VFG3P3_CLK_GEN
   1 P3V3_AUX      1 @T6G_MB_LIB.T6G(SCH_1):P3V3_AUX

Q_CAP_C0805-10UF,25V,10%,X6S,CH6104KEA00  I36  C1883
   1 VFG3P3_CLK_GEN      A @T6G_MB_LIB.T6G(SCH_1):VFG3P3_CLK_GEN
   2    GND      B @T6G_MB_LIB.T6G(SCH_1):GND

Q_CAP_0402-0.1UF,25V,10%,X7R,CH4104K1B00  I37  C2257
   1 VFG3P3_CLK_GEN      A @T6G_MB_LIB.T6G(SCH_1):VFG3P3_CLK_GEN
   2    GND      B @T6G_MB_LIB.T6G(SCH_1):GND

Q_CAP_0402-0.1UF,25V,10%,X7R,CH4104K1B00  I40  C1886
   1 VFG3P3_CLK_GEN      A @T6G_MB_LIB.T6G(SCH_1):VFG3P3_CLK_GEN
   2    GND      B @T6G_MB_LIB.T6G(SCH_1):GND

Q_CAP_0402-0.1UF,25V,10%,X7R,CH4104K1B00  I41  C1889
   1 VFG3P3_CLK_GEN      A @T6G_MB_LIB.T6G(SCH_1):VFG3P3_CLK_GEN
   2    GND      B @T6G_MB_LIB.T6G(SCH_1):GND

Q_CAP_0402-0.1UF,25V,10%,X7R,CH4104K1B00  I42  C95
   1 VFG3P3_CLK_GEN      A @T6G_MB_LIB.T6G(SCH_1):VFG3P3_CLK_GEN
   2    GND      B @T6G_MB_LIB.T6G(SCH_1):GND

Q_RES_0402LF-1,1%,1/16W,CHIP,CS-1002FB04  I43  R4077
   1 VFG3P3_CLK_GEN      A @T6G_MB_LIB.T6G(SCH_1):VFG3P3_CLK_GEN
   2 VFG_3P3A_CLK_GEN      B @T6G_MB_LIB.T6G(SCH_1):VFG_3P3A_CLK_GEN

Q_RES_0402LF-10K,1%,1/16W,CHIP,CS31002FB08  I46  R4079
   1 FG_SS_EN      A @T6G_MB_LIB.T6G(SCH_1):FG_SS_EN
   2    GND      B @T6G_MB_LIB.T6G(SCH_1):GND

Q_RES_0402LF-10K,1%,1/16W,EMPTY,CS31002FB08  I47  R4078
   1 P3V3_AUX      A @T6G_MB_LIB.T6G(SCH_1):P3V3_AUX
   2 FG_SS_EN      B @T6G_MB_LIB.T6G(SCH_1):FG_SS_EN

Q_RES_0402LF-0,5%,1/16W,CHIP,CS00002JB13  I50  R3338
   1 CLK_100M_GPU_FPGA_DN_R      A @T6G_MB_LIB.T6G(SCH_1):CLK_100M_GPU_FPGA_DN_R
   2 CLK_100M_GPU_FPGA_DN      B @T6G_MB_LIB.T6G(SCH_1):CLK_100M_GPU_FPGA_DN

Q_RES_0402LF-0,5%,1/16W,CHIP,CS00002JB13  I51  R3337
   1 CLK_100M_GPU_FPGA_DP_R      A @T6G_MB_LIB.T6G(SCH_1):CLK_100M_GPU_FPGA_DP_R
   2 CLK_100M_GPU_FPGA_DP      B @T6G_MB_LIB.T6G(SCH_1):CLK_100M_GPU_FPGA_DP

Q_RES_0402LF-0,5%,1/16W,CHIP,CS00002JB13  I52  R3336
   1 CLK_100M_BMC_RC_DN_R      A @T6G_MB_LIB.T6G(SCH_1):CLK_100M_BMC_RC_DN_R
   2 CLK_100M_BMC_RC_DN      B @T6G_MB_LIB.T6G(SCH_1):CLK_100M_BMC_RC_DN

Q_RES_0402LF-0,5%,1/16W,CHIP,CS00002JB13  I53  R3335
   1 CLK_100M_BMC_RC_DP_R      A @T6G_MB_LIB.T6G(SCH_1):CLK_100M_BMC_RC_DP_R
   2 CLK_100M_BMC_RC_DP      B @T6G_MB_LIB.T6G(SCH_1):CLK_100M_BMC_RC_DP

Q_RES_0402LF-10K,1%,1/16W,EMPTY,CS31002FB08  I55  R4082
   1 CLK_GEN2_SMB_SADR      A @T6G_MB_LIB.T6G(SCH_1):CLK_GEN2_SMB_SADR
   2    GND      B @T6G_MB_LIB.T6G(SCH_1):GND

Q_RES_0402LF-10K,1%,1/16W,CHIP,CS31002FB08  I56  R4081
   1 P3V3_AUX      A @T6G_MB_LIB.T6G(SCH_1):P3V3_AUX
   2 CLK_GEN2_SMB_SADR      B @T6G_MB_LIB.T6G(SCH_1):CLK_GEN2_SMB_SADR

Q_RES_0402LF-10K,1%,1/16W,CHIP,CS31002FB08  I59  R4080
   1 P3V3_AUX      A @T6G_MB_LIB.T6G(SCH_1):P3V3_AUX
   2 P3V3_PWRGD_CLKGEN      B @T6G_MB_LIB.T6G(SCH_1):P3V3_PWRGD_CLKGEN

Q_CAP_C0402-1UF,25V,10%,X6S,CH5104KEB02  I68  C1884
   1 VFG_3P3A_CLK_GEN      A @T6G_MB_LIB.T6G(SCH_1):VFG_3P3A_CLK_GEN
   2    GND      B @T6G_MB_LIB.T6G(SCH_1):GND

Q_CAP_0402-0.1UF,25V,10%,X7R,CH4104K1B00  I69  C97
   1 VFG_3P3A_CLK_GEN      A @T6G_MB_LIB.T6G(SCH_1):VFG_3P3A_CLK_GEN
   2    GND      B @T6G_MB_LIB.T6G(SCH_1):GND

Q_RES_0402LF-1K,1%,1/16W,CHIP,CS21002FB06  I73  R4521
   1 P3V3_AUX      A @T6G_MB_LIB.T6G(SCH_1):P3V3_AUX
   2 CLK_GEN2_BMC_RC_OE_N      B @T6G_MB_LIB.T6G(SCH_1):CLK_GEN2_BMC_RC_OE_N

Q_RES_0402LF-1K,1%,1/16W,CHIP,CS21002FB06  I74  R3322
   1 P3V3_AUX      A @T6G_MB_LIB.T6G(SCH_1):P3V3_AUX
   2 CLK_GEN2_GPU_FPGA_OE_R2_N      B @T6G_MB_LIB.T6G(SCH_1):CLK_GEN2_GPU_FPGA_OE_R2_N

Q_CAP_C0402-4.7PF,50V,0.1P,NPO,CH-4716TB06  I75  C71
   1 CLK_GEN2_XTAL_IN_R      A @T6G_MB_LIB.T6G(SCH_1):CLK_GEN2_XTAL_IN_R
   2    GND      B @T6G_MB_LIB.T6G(SCH_1):GND

Q_CAP_C0402-4.7PF,50V,0.1P,NPO,CH-4716TB06  I76  C94
   1 CLK_GEN2_XTAL_OUT      A @T6G_MB_LIB.T6G(SCH_1):CLK_GEN2_XTAL_OUT
   2    GND      B @T6G_MB_LIB.T6G(SCH_1):GND

9FGL0251DKILFT-9FGL0251DKILFT,SMLF,IC,AL000251002  I77  U247
   1 CLK_GEN2_XTAL_IN XIN||CLKIN_25 @T6G_MB_LIB.T6G(SCH_1):CLK_GEN2_XTAL_IN
   2 CLK_GEN2_XTAL_OUT     X2 @T6G_MB_LIB.T6G(SCH_1):CLK_GEN2_XTAL_OUT
   3 VFG3P3_CLK_GEN VDDXTAL3.3 @T6G_MB_LIB.T6G(SCH_1):VFG3P3_CLK_GEN
   4 CLK_GEN2_SMB_SADR VSADR||REF3.3 @T6G_MB_LIB.T6G(SCH_1):CLK_GEN2_SMB_SADR
   5    GND GNDREF @T6G_MB_LIB.T6G(SCH_1):GND
   6    GND GNDDIG @T6G_MB_LIB.T6G(SCH_1):GND
   7 VFG3P3_CLK_GEN VDDDIG3.3 @T6G_MB_LIB.T6G(SCH_1):VFG3P3_CLK_GEN
   8 SMB_HOST_CLK_GEN2_3V3AUX_SCL SCLK_3.3 @T6G_MB_LIB.T6G(SCH_1):SMB_HOST_CLK_GEN2_3V3AUX_SCL
   9 SMB_HOST_CLK_GEN2_3V3AUX_SDA SDATA_3.3 @T6G_MB_LIB.T6G(SCH_1):SMB_HOST_CLK_GEN2_3V3AUX_SDA
  10    GND GND_10 @T6G_MB_LIB.T6G(SCH_1):GND
  11 VFG3P3_CLK_GEN VDD3.3_11 @T6G_MB_LIB.T6G(SCH_1):VFG3P3_CLK_GEN
  12 CLK_GEN2_BMC_RC_OE_R3_N  VOE0# @T6G_MB_LIB.T6G(SCH_1):CLK_GEN2_BMC_RC_OE_R3_N
  13 CLK_100M_BMC_RC_DP_R   DIF0 @T6G_MB_LIB.T6G(SCH_1):CLK_100M_BMC_RC_DP_R
  14 CLK_100M_BMC_RC_DN_R  DIF0# @T6G_MB_LIB.T6G(SCH_1):CLK_100M_BMC_RC_DN_R
  15    GND   GNDA @T6G_MB_LIB.T6G(SCH_1):GND
  16 VFG_3P3A_CLK_GEN VDDA3.3 @T6G_MB_LIB.T6G(SCH_1):VFG_3P3A_CLK_GEN
  17 CLK_100M_GPU_FPGA_DP_R   DIF1 @T6G_MB_LIB.T6G(SCH_1):CLK_100M_GPU_FPGA_DP_R
  18 CLK_100M_GPU_FPGA_DN_R  DIF1# @T6G_MB_LIB.T6G(SCH_1):CLK_100M_GPU_FPGA_DN_R
  19 CLK_GEN2_GPU_OE_N  VOE1# @T6G_MB_LIB.T6G(SCH_1):CLK_GEN2_GPU_OE_N
  20 VFG3P3_CLK_GEN VDD3.3_20 @T6G_MB_LIB.T6G(SCH_1):VFG3P3_CLK_GEN
  21    GND GND_21 @T6G_MB_LIB.T6G(SCH_1):GND
  22 P3V3_PWRGD_CLKGEN ^CKPWRGD_PD# @T6G_MB_LIB.T6G(SCH_1):P3V3_PWRGD_CLKGEN
  23 FG_SS_EN ^VSS_EN_TRI @T6G_MB_LIB.T6G(SCH_1):FG_SS_EN
  24    GND GNDXTAL @T6G_MB_LIB.T6G(SCH_1):GND
  25    GND TH_GND @T6G_MB_LIB.T6G(SCH_1):GND


DRAWING: @T6G_MB_LIB.T6G(SCH_1):PAGE80 

Q_RES_0402LF-0,5%,1/16W,CHIP,CS00002JB13  I30  R283
   1 PWRGD_PVDDIO_P1      A @T6G_MB_LIB.T6G(SCH_1):PWRGD_PVDDIO_P1
   2 FM_PWRGD_PVDDIO_P1      B @T6G_MB_LIB.T6G(SCH_1):FM_PWRGD_PVDDIO_P1

Q_RES_0402LF-33,5%,1/16W,CHIP,CS03302JB10  I31  R282
   1 PVDDIO_P1_EN      A @T6G_MB_LIB.T6G(SCH_1):PVDDIO_P1_EN
   2 FM_PVDDIO_P1_EN      B @T6G_MB_LIB.T6G(SCH_1):FM_PVDDIO_P1_EN

Q_RES_0402LF-33,5%,1/16W,CHIP,CS03302JB10  I32  R218
   1 CPU0_PWR_GOOD      A @T6G_MB_LIB.T6G(SCH_1):CPU0_PWR_GOOD
   2 FM_CPU0_PWR_GOOD      B @T6G_MB_LIB.T6G(SCH_1):FM_CPU0_PWR_GOOD

Q_RES_0402LF-33,5%,1/16W,CHIP,CS03302JB10  I33  R176
   1 PVDD18_S5_P0_EN      A @T6G_MB_LIB.T6G(SCH_1):PVDD18_S5_P0_EN
   2 FM_PVDD18_S5_P0_EN      B @T6G_MB_LIB.T6G(SCH_1):FM_PVDD18_S5_P0_EN

Q_RES_0402LF-0,5%,1/16W,CHIP,CS00002JB13  I34  R6047
   1 PWRGD_P3V3_AUX      A @T6G_MB_LIB.T6G(SCH_1):PWRGD_P3V3_AUX
   2 PWRGD_P3V3_AUX_R      B @T6G_MB_LIB.T6G(SCH_1):PWRGD_P3V3_AUX_R

Q_RES_0402LF-0,5%,1/16W,CHIP,CS00002JB13  I35  R5099
   1 FPGA_DEBUG_SW_SPARE      A @T6G_MB_LIB.T6G(SCH_1):FPGA_DEBUG_SW_SPARE
   2 FM_FPGA_DEBUG_SW_SPARE      B @T6G_MB_LIB.T6G(SCH_1):FM_FPGA_DEBUG_SW_SPARE

Q_RES_0402LF-33,5%,1/16W,CHIP,CS03302JB10  I36  R224
   1 PVDD33_S5_EN      A @T6G_MB_LIB.T6G(SCH_1):PVDD33_S5_EN
   2 FM_PVDD33_S5_EN      B @T6G_MB_LIB.T6G(SCH_1):FM_PVDD33_S5_EN

Q_RES_0402LF-33,5%,1/16W,CHIP,CS03302JB10  I125  R798
   1 RST_PERST_M2_0_R_N      A @T6G_MB_LIB.T6G(SCH_1):RST_PERST_M2_0_R_N
   2 RST_PERST_M2_0_N      B @T6G_MB_LIB.T6G(SCH_1):RST_PERST_M2_0_N

Q_RES_0402LF-33,5%,1/16W,CHIP,CS03302JB10  I126  R265
   1 FM_CPU1_FORCE_SELFREFRESH      A @T6G_MB_LIB.T6G(SCH_1):FM_CPU1_FORCE_SELFREFRESH
   2 CPU1_FORCE_SELFREFRESH      B @T6G_MB_LIB.T6G(SCH_1):CPU1_FORCE_SELFREFRESH

Q_RES_0402LF-0,5%,1/16W,CHIP,CS00002JB13  I127  R1202
   1 FM_FORCE_ALL_PWRON_R      A @T6G_MB_LIB.T6G(SCH_1):FM_FORCE_ALL_PWRON_R
   2 FM_FORCE_ALL_PWRON      B @T6G_MB_LIB.T6G(SCH_1):FM_FORCE_ALL_PWRON

Q_RES_0402LF-0,5%,1/16W,CHIP,CS00002JB13  I128  R252
   1 FM_CPU1_PWR_GD_IN      A @T6G_MB_LIB.T6G(SCH_1):FM_CPU1_PWR_GD_IN
   2 CPU1_PWR_GD_IN      B @T6G_MB_LIB.T6G(SCH_1):CPU1_PWR_GD_IN

Q_RES_0402LF-33,5%,1/16W,CHIP,CS03302JB10  I129  R186
   1 FM_CPU0_FORCE_SELFREFRESH      A @T6G_MB_LIB.T6G(SCH_1):FM_CPU0_FORCE_SELFREFRESH
   2 CPU0_FORCE_SELFREFRESH      B @T6G_MB_LIB.T6G(SCH_1):CPU0_FORCE_SELFREFRESH

Q_RES_0402LF-33,5%,1/16W,CHIP,CS03302JB10  I130  R957
   1 FM_RST_PERST_SCM_R_N      A @T6G_MB_LIB.T6G(SCH_1):FM_RST_PERST_SCM_R_N
   2 FM_RST_PERST_SCM_N      B @T6G_MB_LIB.T6G(SCH_1):FM_RST_PERST_SCM_N

Q_RES_0402LF-33,5%,1/16W,CHIP,CS03302JB10  I154  R158
   1 FM_PLD_CPU0_PRSNT_HDT      A @T6G_MB_LIB.T6G(SCH_1):FM_PLD_CPU0_PRSNT_HDT
   2 CPU0_HDT_BYPASS_SEL      B @T6G_MB_LIB.T6G(SCH_1):CPU0_HDT_BYPASS_SEL

Q_RES_0402LF-0,5%,1/16W,CHIP,CS00002JB13  I155  R395
   1 FM_SPD_CPU0_SWITCH_CTRL_R_N      A @T6G_MB_LIB.T6G(SCH_1):FM_SPD_CPU0_SWITCH_CTRL_R_N
   2 FM_SPD_CPU0_SWITCH_CTRL_N      B @T6G_MB_LIB.T6G(SCH_1):FM_SPD_CPU0_SWITCH_CTRL_N

Q_RES_0402LF-33,5%,1/16W,CHIP,CS03302JB10  I156  R1564
   1 FM_ROM_LS_EN      A @T6G_MB_LIB.T6G(SCH_1):FM_ROM_LS_EN
   2 ROM_LS_EN      B @T6G_MB_LIB.T6G(SCH_1):ROM_LS_EN

Q_RES_0402LF-33,5%,1/16W,CHIP,CS03302JB10  I157  R1616
   1 FM_ROM_SD_LS_OE      A @T6G_MB_LIB.T6G(SCH_1):FM_ROM_SD_LS_OE
   2 ROM_SD_LS_OE      B @T6G_MB_LIB.T6G(SCH_1):ROM_SD_LS_OE

Q_RES_0402LF-0,5%,1/16W,CHIP,CS00002JB13  I158  R1359
   1 BMC_JTAG_SEL_R      A @T6G_MB_LIB.T6G(SCH_1):BMC_JTAG_SEL_R
   2 BMC_JTAG_SEL      B @T6G_MB_LIB.T6G(SCH_1):BMC_JTAG_SEL

Q_RES_0402LF-33,5%,1/16W,CHIP,CS03302JB10  I159  R372
   1 P12V_ALL_PWROK_R      A @T6G_MB_LIB.T6G(SCH_1):P12V_ALL_PWROK_R
   2 P12V_ALL_PWROK      B @T6G_MB_LIB.T6G(SCH_1):P12V_ALL_PWROK

Q_RES_0402LF-33,5%,1/16W,CHIP,CS03302JB10  I160  R174
   1 SCM_IRQ_1V8_R_N      A @T6G_MB_LIB.T6G(SCH_1):SCM_IRQ_1V8_R_N
   2 SCM_IRQ_1V8_N      B @T6G_MB_LIB.T6G(SCH_1):SCM_IRQ_1V8_N

Q_RES_0402LF-33,5%,1/16W,CHIP,CS03302JB10  I161  R161
   1 CPU1_JTAG_BUF_R_OE      A @T6G_MB_LIB.T6G(SCH_1):CPU1_JTAG_BUF_R_OE
   2 CPU1_JTAG_BUF_OE      B @T6G_MB_LIB.T6G(SCH_1):CPU1_JTAG_BUF_OE

Q_RES_0402LF-0,5%,1/16W,CHIP,CS00002JB13  I162  R251
   1 CPU0_SPD_HOST_CTRL_R1_N      A @T6G_MB_LIB.T6G(SCH_1):CPU0_SPD_HOST_CTRL_R1_N
   2 CPU0_SPD_HOST_CTRL_N      B @T6G_MB_LIB.T6G(SCH_1):CPU0_SPD_HOST_CTRL_N

Q_RES_0402LF-33,5%,1/16W,CHIP,CS03302JB10  I163  R173
   1 FM_PLD_CPU1_PRSNT_HDT      A @T6G_MB_LIB.T6G(SCH_1):FM_PLD_CPU1_PRSNT_HDT
   2 CPU1_HDT_BYPASS_SEL      B @T6G_MB_LIB.T6G(SCH_1):CPU1_HDT_BYPASS_SEL

Q_RES_0402LF-33,5%,1/16W,CHIP,CS03302JB10  I164  R588
   1 SCM_USB_OC_R_N      A @T6G_MB_LIB.T6G(SCH_1):SCM_USB_OC_R_N
   2 SCM_USB_OC_N      B @T6G_MB_LIB.T6G(SCH_1):SCM_USB_OC_N

Q_RES_0402LF-33,5%,1/16W,CHIP,CS03302JB10  I165  R277
   1 FM_CPU1_NMI_SYNC_FLOOD_N      A @T6G_MB_LIB.T6G(SCH_1):FM_CPU1_NMI_SYNC_FLOOD_N
   2 CPU1_NMI_SYNC_FLOOD_N      B @T6G_MB_LIB.T6G(SCH_1):CPU1_NMI_SYNC_FLOOD_N

Q_RES_0402LF-0,5%,1/16W,CHIP,CS00002JB13  I166  R937
   1 FM_BIOS_POST_CMPLT_BUF_R_N      A @T6G_MB_LIB.T6G(SCH_1):FM_BIOS_POST_CMPLT_BUF_R_N
   2 FM_BIOS_POST_CMPLT_BUF_N      B @T6G_MB_LIB.T6G(SCH_1):FM_BIOS_POST_CMPLT_BUF_N

Q_RES_0402LF-0,5%,1/16W,CHIP,CS00002JB13  I167  R856
   1 FM_HDT_HDR_RESET_N      A @T6G_MB_LIB.T6G(SCH_1):FM_HDT_HDR_RESET_N
   2 HDT_HDR_RESET_N      B @T6G_MB_LIB.T6G(SCH_1):HDT_HDR_RESET_N

Q_RES_0402LF-33,5%,1/16W,CHIP,CS03302JB10  I168  R708
   1 FM_HDT_HDR_PWROK      A @T6G_MB_LIB.T6G(SCH_1):FM_HDT_HDR_PWROK
   2 HDT_HDR_PWROK      B @T6G_MB_LIB.T6G(SCH_1):HDT_HDR_PWROK

Q_RES_0402LF-33,5%,1/16W,CHIP,CS03302JB10  I169  R1551
   1 ESPI_CPU0_R1_D2      A @T6G_MB_LIB.T6G(SCH_1):ESPI_CPU0_R1_D2
   2 ESPI_CPU0_D2      B @T6G_MB_LIB.T6G(SCH_1):ESPI_CPU0_D2

Q_RES_0402LF-33,5%,1/16W,CHIP,CS03302JB10  I170  R1552
   1 ESPI_CPU0_R1_D3      A @T6G_MB_LIB.T6G(SCH_1):ESPI_CPU0_R1_D3
   2 ESPI_CPU0_D3      B @T6G_MB_LIB.T6G(SCH_1):ESPI_CPU0_D3

Q_RES_0402LF-33,5%,1/16W,CHIP,CS03302JB10  I171  R1550
   1 ESPI_CPU0_R1_D1      A @T6G_MB_LIB.T6G(SCH_1):ESPI_CPU0_R1_D1
   2 ESPI_CPU0_D1      B @T6G_MB_LIB.T6G(SCH_1):ESPI_CPU0_D1

Q_RES_0402LF-33,5%,1/16W,CHIP,CS03302JB10  I172  R1558
   1 RST_ESPI_CPU0_RSTOUT_R_N      A @T6G_MB_LIB.T6G(SCH_1):RST_ESPI_CPU0_RSTOUT_R_N
   2 RST_ESPI_CPU0_RSTOUT_N      B @T6G_MB_LIB.T6G(SCH_1):RST_ESPI_CPU0_RSTOUT_N

Q_RES_0402LF-33,5%,1/16W,CHIP,CS03302JB10  I173  R1549
   1 ESPI_CPU0_R1_D0      A @T6G_MB_LIB.T6G(SCH_1):ESPI_CPU0_R1_D0
   2 ESPI_CPU0_D0      B @T6G_MB_LIB.T6G(SCH_1):ESPI_CPU0_D0

Q_RES_0402LF-33,5%,1/16W,CHIP,CS03302JB10  I174  R1553
   1 ESPI_CPU0_CS1_R_N      A @T6G_MB_LIB.T6G(SCH_1):ESPI_CPU0_CS1_R_N
   2 ESPI_CPU0_CS1_N      B @T6G_MB_LIB.T6G(SCH_1):ESPI_CPU0_CS1_N

Q_RES_0402LF-33,5%,1/16W,CHIP,CS03302JB10  I22  R199
   1 E1S_0_P12V_EN      A @T6G_MB_LIB.T6G(SCH_1):E1S_0_P12V_EN
   2 P12V_E1S_0_EN      B @T6G_MB_LIB.T6G(SCH_1):P12V_E1S_0_EN

Q_RES_0402LF-33,5%,1/16W,CHIP,CS03302JB10  I25  R648
   1 E1S_0_P3V3_EN      A @T6G_MB_LIB.T6G(SCH_1):E1S_0_P3V3_EN
   2 P3V3_E1S_0_EN_R      B @T6G_MB_LIB.T6G(SCH_1):P3V3_E1S_0_EN_R

Q_RES_0402LF-0,5%,1/16W,CHIP,CS00002JB13  I28  R6048
   1 HP_LVC3_E1S_0_HSC_PWRGD      A @T6G_MB_LIB.T6G(SCH_1):HP_LVC3_E1S_0_HSC_PWRGD
   2 P12V_E1S_0_PWRGD      B @T6G_MB_LIB.T6G(SCH_1):P12V_E1S_0_PWRGD

Q_RES_0402LF-33,5%,1/16W,CHIP,CS03302JB10  I29  R1282
   1 FM_NCSI_OCP_SFF_R_OE      A @T6G_MB_LIB.T6G(SCH_1):FM_NCSI_OCP_SFF_R_OE
   2 FM_PLD_OCP_SFF_PWR_GOOD_R      B @T6G_MB_LIB.T6G(SCH_1):FM_PLD_OCP_SFF_PWR_GOOD_R

Q_RES_0402LF-33,5%,1/16W,CHIP,CS03302JB10  I57  R289
   1 PVDD18_S5_P1_EN      A @T6G_MB_LIB.T6G(SCH_1):PVDD18_S5_P1_EN
   2 PVDD18_S5_P1_R_EN      B @T6G_MB_LIB.T6G(SCH_1):PVDD18_S5_P1_R_EN

Q_RES_0402LF-33,5%,1/16W,CHIP,CS03302JB10  I58  R279
   1 PVDD11_S3_P1_EN      A @T6G_MB_LIB.T6G(SCH_1):PVDD11_S3_P1_EN
   2 FM_PVDD11_S3_P1_EN      B @T6G_MB_LIB.T6G(SCH_1):FM_PVDD11_S3_P1_EN

Q_RES_0402LF-0,5%,1/16W,CHIP,CS00002JB13  I59  R280
   1 PWRGD_PVDD11_S3_P1      A @T6G_MB_LIB.T6G(SCH_1):PWRGD_PVDD11_S3_P1
   2 FM_PWRGD_PVDD11_S3_P1      B @T6G_MB_LIB.T6G(SCH_1):FM_PWRGD_PVDD11_S3_P1

Q_RES_0402LF-0,5%,1/16W,CHIP,CS00002JB13  I60  R6055
   1 HP_LVC3_SCM_HSC_PWRGD      A @T6G_MB_LIB.T6G(SCH_1):HP_LVC3_SCM_HSC_PWRGD
   2 P12V_SCM_PWRGD_R      B @T6G_MB_LIB.T6G(SCH_1):P12V_SCM_PWRGD_R

Q_RES_0402LF-0,5%,1/16W,CHIP,CS00002JB13  I61  R209
   1 PWRGD_PVDDCR_CPU0_P1      A @T6G_MB_LIB.T6G(SCH_1):PWRGD_PVDDCR_CPU0_P1
   2 FM_PWRGD_PVDDCR_CPU0_P1      B @T6G_MB_LIB.T6G(SCH_1):FM_PWRGD_PVDDCR_CPU0_P1

Q_RES_0402LF-0,5%,1/16W,CHIP,CS00002JB13  I62  R286
   1 PWRGD_PVDDCR_CPU1_P1      A @T6G_MB_LIB.T6G(SCH_1):PWRGD_PVDDCR_CPU1_P1
   2 FM_PWRGD_PVDDCR_CPU1_P1      B @T6G_MB_LIB.T6G(SCH_1):FM_PWRGD_PVDDCR_CPU1_P1

Q_RES_0402LF-33,5%,1/16W,CHIP,CS03302JB10  I63  R1563
   1 UART_LS_EN      A @T6G_MB_LIB.T6G(SCH_1):UART_LS_EN
   2 FM_UART_LS_EN      B @T6G_MB_LIB.T6G(SCH_1):FM_UART_LS_EN

Q_RES_0402LF-100,1%,1/16W,CHIP,CS11002FB07  I64  R6046
   1 HP_LVC3_OCP_SFF_PRSNT2_PLD_N      A @T6G_MB_LIB.T6G(SCH_1):HP_LVC3_OCP_SFF_PRSNT2_PLD_N
   2 PRSNT_OCP_SFF_N      B @T6G_MB_LIB.T6G(SCH_1):PRSNT_OCP_SFF_N

Q_RES_0402LF-33,5%,1/16W,CHIP,CS03302JB10  I65  R208
   1 PVDDCR_CPU0_P1_EN      A @T6G_MB_LIB.T6G(SCH_1):PVDDCR_CPU0_P1_EN
   2 FM_PVDDCR_CPU0_P1_R_EN      B @T6G_MB_LIB.T6G(SCH_1):FM_PVDDCR_CPU0_P1_R_EN

Q_RES_0402LF-0,5%,1/16W,CHIP,CS00002JB13  I66  R228
   1 PWRGD_PVDD11_S3_P0      A @T6G_MB_LIB.T6G(SCH_1):PWRGD_PVDD11_S3_P0
   2 FM_PWRGD_PVDD11_S3_P0      B @T6G_MB_LIB.T6G(SCH_1):FM_PWRGD_PVDD11_S3_P0

Q_RES_0402LF-0,5%,1/16W,CHIP,CS00002JB13  I100  R194
   1 CPU1_SPD_HOST_CTRL_N      A @T6G_MB_LIB.T6G(SCH_1):CPU1_SPD_HOST_CTRL_N
   2 CPU1_SPD_HOST_CTRL_R1_N      B @T6G_MB_LIB.T6G(SCH_1):CPU1_SPD_HOST_CTRL_R1_N

Q_RES_0402LF-33,5%,1/16W,CHIP,CS03302JB10  I101  R1281
   1 FM_P0_PCC1_N      A @T6G_MB_LIB.T6G(SCH_1):FM_P0_PCC1_N
   2 FM_P0_PCC1_R_N      B @T6G_MB_LIB.T6G(SCH_1):FM_P0_PCC1_R_N

Q_RES_0402LF-33,5%,1/16W,CHIP,CS03302JB10  I102  R1280
   1 FM_P0_PCC0_N      A @T6G_MB_LIB.T6G(SCH_1):FM_P0_PCC0_N
   2 FM_P0_PCC0_R_N      B @T6G_MB_LIB.T6G(SCH_1):FM_P0_PCC0_R_N

Q_RES_0402LF-33,5%,1/16W,CHIP,CS03302JB10  I103  R1279
   1 FM_P1_PCC1_N      A @T6G_MB_LIB.T6G(SCH_1):FM_P1_PCC1_N
   2 FM_P1_PCC1_R_N      B @T6G_MB_LIB.T6G(SCH_1):FM_P1_PCC1_R_N

Q_RES_0402LF-33,5%,1/16W,CHIP,CS03302JB10  I104  R215
   1 CPU0_PWR_BTN_N      A @T6G_MB_LIB.T6G(SCH_1):CPU0_PWR_BTN_N
   2 FM_CPU0_PWR_BTN_N      B @T6G_MB_LIB.T6G(SCH_1):FM_CPU0_PWR_BTN_N

Q_RES_0402LF-33,5%,1/16W,CHIP,CS03302JB10  I105  R1278
   1 FM_P1_PCC0_N      A @T6G_MB_LIB.T6G(SCH_1):FM_P1_PCC0_N
   2 FM_P1_PCC0_R_N      B @T6G_MB_LIB.T6G(SCH_1):FM_P1_PCC0_R_N

Q_RES_0402LF-0,5%,1/16W,CHIP,CS00002JB13  I106  R203
   1 PWRGD_CPU1_PWROK      A @T6G_MB_LIB.T6G(SCH_1):PWRGD_CPU1_PWROK
   2 FM_PWRGD_CPU1_PWROK      B @T6G_MB_LIB.T6G(SCH_1):FM_PWRGD_CPU1_PWROK

Q_RES_0402LF-33,5%,1/16W,CHIP,CS03302JB10  I107  R371
   1 FPGA_DEBUG_LED_CTRL      A @T6G_MB_LIB.T6G(SCH_1):FPGA_DEBUG_LED_CTRL
   2 FM_FPGA_DEBUG_LED_CTRL      B @T6G_MB_LIB.T6G(SCH_1):FM_FPGA_DEBUG_LED_CTRL

Q_RES_0402LF-33,5%,1/16W,CHIP,CS03302JB10  I108  R219
   1 CPU0_NMI_SYNC_FLOOD_N      A @T6G_MB_LIB.T6G(SCH_1):CPU0_NMI_SYNC_FLOOD_N
   2 FM_CPU0_NMI_SYNC_FLOOD_N      B @T6G_MB_LIB.T6G(SCH_1):FM_CPU0_NMI_SYNC_FLOOD_N

Q_RES_0402LF-0,5%,1/16W,CHIP,CS00002JB13  I109  R196
   1 CPU1_NV_SAVE_N      A @T6G_MB_LIB.T6G(SCH_1):CPU1_NV_SAVE_N
   2 FM_CPU1_NV_SAVE_N      B @T6G_MB_LIB.T6G(SCH_1):FM_CPU1_NV_SAVE_N

Q_RES_0402LF-0,5%,1/16W,CHIP,CS00002JB13  I110  R242
   1 PWRGD_CPU0_PWROK      A @T6G_MB_LIB.T6G(SCH_1):PWRGD_CPU0_PWROK
   2 FM_PWRGD_CPU0_PWROK      B @T6G_MB_LIB.T6G(SCH_1):FM_PWRGD_CPU0_PWROK

Q_RES_0402LF-33,5%,1/16W,CHIP,CS03302JB10  I111  R159
   1 CPU0_JTAG_BUF_OE      A @T6G_MB_LIB.T6G(SCH_1):CPU0_JTAG_BUF_OE
   2 CPU0_JTAG_BUF_R_OE      B @T6G_MB_LIB.T6G(SCH_1):CPU0_JTAG_BUF_R_OE

Q_RES_0402LF-33,5%,1/16W,CHIP,CS03302JB10  I112  R463
   1 RST_CPU0_KBRST_R_N      A @T6G_MB_LIB.T6G(SCH_1):RST_CPU0_KBRST_R_N
   2 RST_CPU0_KBRST_N      B @T6G_MB_LIB.T6G(SCH_1):RST_CPU0_KBRST_N

Q_RES_0402LF-0,5%,1/16W,CHIP,CS00002JB13  I113  R57
   1 RST_CPU1_RESETL_N      A @T6G_MB_LIB.T6G(SCH_1):RST_CPU1_RESETL_N
   2 FM_RST_CPU1_RESETL_N      B @T6G_MB_LIB.T6G(SCH_1):FM_RST_CPU1_RESETL_N

Q_RES_0402LF-0,5%,1/16W,CHIP,CS00002JB13  I114  R241
   1 RST_CPU0_RESETL_N      A @T6G_MB_LIB.T6G(SCH_1):RST_CPU0_RESETL_N
   2 FM_RST_CPU0_RESETL_N      B @T6G_MB_LIB.T6G(SCH_1):FM_RST_CPU0_RESETL_N

Q_RES_0402LF-0,5%,1/16W,EMPTY,CS00002JB13  I115  R272
   1 RST_CPU1_SYS_N      A @T6G_MB_LIB.T6G(SCH_1):RST_CPU1_SYS_N
   2 FM_CPU1_SYS_RESET_N      B @T6G_MB_LIB.T6G(SCH_1):FM_CPU1_SYS_RESET_N

Q_RES_0402LF-0,5%,1/16W,CHIP,CS00002JB13  I116  R253
   1 CPU0_NV_SAVE_N      A @T6G_MB_LIB.T6G(SCH_1):CPU0_NV_SAVE_N
   2 FM_CPU0_NV_SAVE_N      B @T6G_MB_LIB.T6G(SCH_1):FM_CPU0_NV_SAVE_N

Q_RES_0402LF-33,5%,1/16W,CHIP,CS03302JB10  I117  R216
   1 RST_CPU0_SYS_N      A @T6G_MB_LIB.T6G(SCH_1):RST_CPU0_SYS_N
   2 FM_CPU0_SYS_RESET_N      B @T6G_MB_LIB.T6G(SCH_1):FM_CPU0_SYS_RESET_N

Q_RES_0402LF-33,5%,1/16W,CHIP,CS03302JB10  I118  R217
   1 RST_CPU0_RSMRST_N      A @T6G_MB_LIB.T6G(SCH_1):RST_CPU0_RSMRST_N
   2 FM_CPU0_RSMRST_N      B @T6G_MB_LIB.T6G(SCH_1):FM_CPU0_RSMRST_N

Q_RES_0402LF-33,5%,1/16W,CHIP,CS03302JB10  I119  R273
   1 RST_CPU1_RSMRST_N      A @T6G_MB_LIB.T6G(SCH_1):RST_CPU1_RSMRST_N
   2 FM_CPU1_RSMRST_N      B @T6G_MB_LIB.T6G(SCH_1):FM_CPU1_RSMRST_N

Q_RES_0402LF-0,5%,1/16W,CHIP,CS00002JB13  I120  R197
   1 RST_CPU1_PERST0_N      A @T6G_MB_LIB.T6G(SCH_1):RST_CPU1_PERST0_N
   2 RST_CPU1_PERST0_R_N      B @T6G_MB_LIB.T6G(SCH_1):RST_CPU1_PERST0_R_N

Q_RES_0402LF-0,5%,1/16W,CHIP,CS00002JB13  I121  R255
   1 RST_CPU0_PERST1_N      A @T6G_MB_LIB.T6G(SCH_1):RST_CPU0_PERST1_N
   2 RST_CPU0_PERST1_R_N      B @T6G_MB_LIB.T6G(SCH_1):RST_CPU0_PERST1_R_N

Q_RES_0402LF-0,5%,1/16W,CHIP,CS00002JB13  I122  R198
   1 RST_CPU1_PERST1_N      A @T6G_MB_LIB.T6G(SCH_1):RST_CPU1_PERST1_N
   2 RST_CPU1_PERST1_R_N      B @T6G_MB_LIB.T6G(SCH_1):RST_CPU1_PERST1_R_N

Q_RES_0402LF-0,5%,1/16W,CHIP,CS00002JB13  I67  R230
   1 PWRGD_PVDDIO_P0      A @T6G_MB_LIB.T6G(SCH_1):PWRGD_PVDDIO_P0
   2 FM_PWRGD_PVDDIO_P0      B @T6G_MB_LIB.T6G(SCH_1):FM_PWRGD_PVDDIO_P0

Q_RES_0402LF-33,5%,1/16W,CHIP,CS03302JB10  I68  R229
   1 PVDDIO_P0_EN      A @T6G_MB_LIB.T6G(SCH_1):PVDDIO_P0_EN
   2 FM_PVDDIO_P0_EN      B @T6G_MB_LIB.T6G(SCH_1):FM_PVDDIO_P0_EN

Q_RES_0402LF-0,5%,1/16W,CHIP,CS00002JB13  I123  R254
   1 RST_CPU0_PERST0_N      A @T6G_MB_LIB.T6G(SCH_1):RST_CPU0_PERST0_N
   2 RST_CPU0_PERST0_R_N      B @T6G_MB_LIB.T6G(SCH_1):RST_CPU0_PERST0_R_N

Q_RES_0402LF-33,5%,1/16W,CHIP,CS03302JB10  I131  R685
   1 RST_PERST_E1S_0_R_N      A @T6G_MB_LIB.T6G(SCH_1):RST_PERST_E1S_0_R_N
   2 RST_PERST_E1S_0_N      B @T6G_MB_LIB.T6G(SCH_1):RST_PERST_E1S_0_N

Q_RES_0402LF-33,5%,1/16W,CHIP,CS03302JB10  I175  R1557
   1 ESPI_CPU0_ALERT_R_N      A @T6G_MB_LIB.T6G(SCH_1):ESPI_CPU0_ALERT_R_N
   2 ESPI_CPU0_ALERT_PLD_N      B @T6G_MB_LIB.T6G(SCH_1):ESPI_CPU0_ALERT_PLD_N

Q_RES_0402LF-33,5%,1/16W,CHIP,CS03302JB10  I176  R1556
   1 CLK_ESPI_CPU0_R1_CLK1      A @T6G_MB_LIB.T6G(SCH_1):CLK_ESPI_CPU0_R1_CLK1
   2 CLK_ESPI_CPU0_CLK1      B @T6G_MB_LIB.T6G(SCH_1):CLK_ESPI_CPU0_CLK1

Q_RES_0402LF-0,5%,1/16W,CHIP,CS00002JB13  I177  R258
   1 FM_CPU0_HDT_CONN_TESTEN      A @T6G_MB_LIB.T6G(SCH_1):FM_CPU0_HDT_CONN_TESTEN
   2 CPU0_HDT_CONN_TESTEN      B @T6G_MB_LIB.T6G(SCH_1):CPU0_HDT_CONN_TESTEN

Q_RES_0402LF-33,5%,1/16W,CHIP,CS03302JB10  I178  R1203
   1 BIOS_DEBUG_MODE_R      A @T6G_MB_LIB.T6G(SCH_1):BIOS_DEBUG_MODE_R
   2 BIOS_DEBUG_MODE      B @T6G_MB_LIB.T6G(SCH_1):BIOS_DEBUG_MODE

Q_RES_0402LF-0,5%,1/16W,CHIP,CS00002JB13  I179  R193
   1 FM_CPU1_SMERR_N      A @T6G_MB_LIB.T6G(SCH_1):FM_CPU1_SMERR_N
   2 CPU1_SMERR_N      B @T6G_MB_LIB.T6G(SCH_1):CPU1_SMERR_N

Q_RES_0402LF-0,5%,1/16W,CHIP,CS00002JB13  I180  R250
   1 FM_CPU0_SMERR_N      A @T6G_MB_LIB.T6G(SCH_1):FM_CPU0_SMERR_N
   2 CPU0_SMERR_N      B @T6G_MB_LIB.T6G(SCH_1):CPU0_SMERR_N

Q_RES_0402LF-33,5%,1/16W,CHIP,CS03302JB10  I215  R933
   1 FM_SMERR_LED_R_N      A @T6G_MB_LIB.T6G(SCH_1):FM_SMERR_LED_R_N
   2 FM_SMERR_LED_N      B @T6G_MB_LIB.T6G(SCH_1):FM_SMERR_LED_N

LCMXO3LF9400C5BG484C-LCMXO3LF-9400C-5BG484C,SMLF,IA  I216  U18
 AA2 FM_SWB_PWR_EN   PB5A @T6G_MB_LIB.T6G(SCH_1):FM_SWB_PWR_EN
 AB2 GPU_NVS_PWR_BRAKE_R_N   PB5B @T6G_MB_LIB.T6G(SCH_1):GPU_NVS_PWR_BRAKE_R_N
  V6 FM_PVDDIO_P0_EN   PB5C @T6G_MB_LIB.T6G(SCH_1):FM_PVDDIO_P0_EN
  U6 FM_PWRGD_PVDDIO_P0   PB5D @T6G_MB_LIB.T6G(SCH_1):FM_PWRGD_PVDDIO_P0
 AA3 PRSNT_OCP_SFF_N PB7A||CSSPIN @T6G_MB_LIB.T6G(SCH_1):PRSNT_OCP_SFF_N
 AB3 PVDDCR_CPU0_P0_PMALERT   PB7B @T6G_MB_LIB.T6G(SCH_1):PVDDCR_CPU0_P0_PMALERT
  Y4 FM_PWRGD_PVDD11_S3_P0   PB7C @T6G_MB_LIB.T6G(SCH_1):FM_PWRGD_PVDD11_S3_P0
  W5 FM_PVDDCR_CPU0_P1_R_EN   PB7D @T6G_MB_LIB.T6G(SCH_1):FM_PVDDCR_CPU0_P1_R_EN
  U7 FM_UART_LS_EN   PB8C @T6G_MB_LIB.T6G(SCH_1):FM_UART_LS_EN
  T8 FM_PWRGD_PVDDCR_CPU1_P1   PB8D @T6G_MB_LIB.T6G(SCH_1):FM_PWRGD_PVDDCR_CPU1_P1
 AA4 GPU_FPGA_EROT_RST_R_N   PB8A @T6G_MB_LIB.T6G(SCH_1):GPU_FPGA_EROT_RST_R_N
 AB4 PRSNT_SWB_ISO_R_N   PB8B @T6G_MB_LIB.T6G(SCH_1):PRSNT_SWB_ISO_R_N
 AA5 GPU_FPGA_EROT_RECOV_R_N  PB10A @T6G_MB_LIB.T6G(SCH_1):GPU_FPGA_EROT_RECOV_R_N
 AB5 BMC_MONITER  PB10B @T6G_MB_LIB.T6G(SCH_1):BMC_MONITER
  Y5 FM_PWRGD_PVDDCR_CPU0_P1  PB10C @T6G_MB_LIB.T6G(SCH_1):FM_PWRGD_PVDDCR_CPU0_P1
  Y6 P12V_SCM_PWRGD_R  PB10D @T6G_MB_LIB.T6G(SCH_1):P12V_SCM_PWRGD_R
  V8 PVDD18_S5_P1_R_EN  PB13C @T6G_MB_LIB.T6G(SCH_1):PVDD18_S5_P1_R_EN
  U8 FM_FPGA_DEBUG_SW_SPARE  PB13D @T6G_MB_LIB.T6G(SCH_1):FM_FPGA_DEBUG_SW_SPARE
  T9 FM_PWRGD_P1V8_RETIMER_CPU0 PB16A||MCLK||CCLK @T6G_MB_LIB.T6G(SCH_1):FM_PWRGD_P1V8_RETIMER_CPU0
  U9 FM_PWRGD_P1V8_RETIMER_CPU1 PB16B||SO||SPISO @T6G_MB_LIB.T6G(SCH_1):FM_PWRGD_P1V8_RETIMER_CPU1
 AA8 FM_PVDD18_S5_P0_EN  PB18A @T6G_MB_LIB.T6G(SCH_1):FM_PVDD18_S5_P0_EN
 AB8 FM_PWRGD_PVDD18_S5_P0  PB18B @T6G_MB_LIB.T6G(SCH_1):FM_PWRGD_PVDD18_S5_P0
 V10 FM_LED_PWRGD_PVDDCR_CPU0_P1  PB21A @T6G_MB_LIB.T6G(SCH_1):FM_LED_PWRGD_PVDDCR_CPU0_P1
 W10 FM_PLD_OCP_SFF_PWR_GOOD_R  PB21B @T6G_MB_LIB.T6G(SCH_1):FM_PLD_OCP_SFF_PWR_GOOD_R
AA10 P0V9_RETIMER_CPU0_EN_R2 PB22A||PCLKT2_0 @T6G_MB_LIB.T6G(SCH_1):P0V9_RETIMER_CPU0_EN_R2
AB10 BMC_FPGA_LED1 PB22B||PCLKC2_0 @T6G_MB_LIB.T6G(SCH_1):BMC_FPGA_LED1
AA11 P12V_E1S_0_EN  PB24A @T6G_MB_LIB.T6G(SCH_1):P12V_E1S_0_EN
AB11 FM_LED_PWRGD_PVDD18_S5_P0  PB24B @T6G_MB_LIB.T6G(SCH_1):FM_LED_PWRGD_PVDD18_S5_P0
 V11 RST_PERST_CPU1_SWB_1_N  PB24C @T6G_MB_LIB.T6G(SCH_1):RST_PERST_CPU1_SWB_1_N
 Y11 FM_LED_PWRGD_PVDDIO_P0  PB24D @T6G_MB_LIB.T6G(SCH_1):FM_LED_PWRGD_PVDDIO_P0
AB12 GPU_3V3IO_RSVD1_ISO_R PB29A||PCLKT2_1 @T6G_MB_LIB.T6G(SCH_1):GPU_3V3IO_RSVD1_ISO_R
AA12 GPU_3V3IO_RSVD3_ISO_R PB29B||PCLKC2_1 @T6G_MB_LIB.T6G(SCH_1):GPU_3V3IO_RSVD3_ISO_R
AB13 FM_RST_PERST_SCM_R_N  PB30A @T6G_MB_LIB.T6G(SCH_1):FM_RST_PERST_SCM_R_N
AA13 RST_PERST_E1S_0_R_N  PB30B @T6G_MB_LIB.T6G(SCH_1):RST_PERST_E1S_0_R_N
AB14 GPU_3V3IO_RSVD5_FFU_ISO_R  PB33A @T6G_MB_LIB.T6G(SCH_1):GPU_3V3IO_RSVD5_FFU_ISO_R
AA14 PRSNT_CABLE_GPU_A1_ISO_R_N  PB33B @T6G_MB_LIB.T6G(SCH_1):PRSNT_CABLE_GPU_A1_ISO_R_N
AB19 GPU_FPGA_READY_ISO_R  PB43A @T6G_MB_LIB.T6G(SCH_1):GPU_FPGA_READY_ISO_R
AA19 RST_PERST_OCP_V3_2_N  PB43B @T6G_MB_LIB.T6G(SCH_1):RST_PERST_OCP_V3_2_N
AB20 PRSNT_HDT_N  PB44A @T6G_MB_LIB.T6G(SCH_1):PRSNT_HDT_N
AA20 P12V_OCP_V3_2_EN_R  PB44B @T6G_MB_LIB.T6G(SCH_1):P12V_OCP_V3_2_EN_R
AB21 PU_SPI_PLD_CS_N PB46A||SN @T6G_MB_LIB.T6G(SCH_1):PU_SPI_PLD_CS_N
AA21 P0V9_RETIMER_CPU1_EN_R2 PB46B||SI||SISPI @T6G_MB_LIB.T6G(SCH_1):P0V9_RETIMER_CPU1_EN_R2
AB15 GPU_BASE_HMC_READY_ISO_R  PB35A @T6G_MB_LIB.T6G(SCH_1):GPU_BASE_HMC_READY_ISO_R
AA15 GPU_HMC_PRSNT_ISO_R_N  PB35B @T6G_MB_LIB.T6G(SCH_1):GPU_HMC_PRSNT_ISO_R_N
 AA6 PWRGD_PVDD18_S5_R_P1  PB11A @T6G_MB_LIB.T6G(SCH_1):PWRGD_PVDD18_S5_R_P1
 AB6 FM_PWRGD_PVDD33_S5  PB11B @T6G_MB_LIB.T6G(SCH_1):FM_PWRGD_PVDD33_S5
  W6 FM_GPU_PWR_EN  PB11C @T6G_MB_LIB.T6G(SCH_1):FM_GPU_PWR_EN
  V7 GPU_FPGA_RST_N  PB11D @T6G_MB_LIB.T6G(SCH_1):GPU_FPGA_RST_N
 AA7 FM_PVDD11_S3_P1_EN  PB13A @T6G_MB_LIB.T6G(SCH_1):FM_PVDD11_S3_P1_EN
 AB7 FM_PWRGD_PVDD11_S3_P1  PB13B @T6G_MB_LIB.T6G(SCH_1):FM_PWRGD_PVDD11_S3_P1
  V9 FM_PVDD33_S5_EN  PB16C @T6G_MB_LIB.T6G(SCH_1):FM_PVDD33_S5_EN
  W8 PWRGD_P3V3_AUX_R  PB16D @T6G_MB_LIB.T6G(SCH_1):PWRGD_P3V3_AUX_R
  Y8 PWRGD_P1V8_AUX_R  PB18C @T6G_MB_LIB.T6G(SCH_1):PWRGD_P1V8_AUX_R
  W9 FM_CPU0_PWR_GOOD  PB18D @T6G_MB_LIB.T6G(SCH_1):FM_CPU0_PWR_GOOD
 AA9 FM_PVDDIO_P1_EN  PB19A @T6G_MB_LIB.T6G(SCH_1):FM_PVDDIO_P1_EN
 AB9 FM_PWRGD_PVDDIO_P1  PB19B @T6G_MB_LIB.T6G(SCH_1):FM_PWRGD_PVDDIO_P1
 T10 FM_GPU_HSC_EN_R  PB19C @T6G_MB_LIB.T6G(SCH_1):FM_GPU_HSC_EN_R
 U10 P12V_E1S_0_PWRGD  PB19D @T6G_MB_LIB.T6G(SCH_1):P12V_E1S_0_PWRGD
 T11 FM_LED_PWRGD_PVDD33_S5  PB22C @T6G_MB_LIB.T6G(SCH_1):FM_LED_PWRGD_PVDD33_S5
 U11 P3V3_E1S_PWRGD_0_R  PB22D @T6G_MB_LIB.T6G(SCH_1):P3V3_E1S_PWRGD_0_R
 Y12 FM_LED_PWRGD_PVDD11_S3_P0  PB27A @T6G_MB_LIB.T6G(SCH_1):FM_LED_PWRGD_PVDD11_S3_P0
 T12 HPDB_HSC_PWRGD_ISO_R  PB27B @T6G_MB_LIB.T6G(SCH_1):HPDB_HSC_PWRGD_ISO_R
 U12     NC  PB27C     NC
 V12 P3V3_E1S_0_EN_R  PB27D @T6G_MB_LIB.T6G(SCH_1):P3V3_E1S_0_EN_R
 V13 GPU_3V3IO_RSVD4_ISO_R  PB29C @T6G_MB_LIB.T6G(SCH_1):GPU_3V3IO_RSVD4_ISO_R
 U13 HGX_DETECT_N_R  PB29D @T6G_MB_LIB.T6G(SCH_1):HGX_DETECT_N_R
 Y13 SWB_HSC_EN_R  PB30C @T6G_MB_LIB.T6G(SCH_1):SWB_HSC_EN_R
 W13 GPU_3V3IO_RSVD0_FFU_ISO_R  PB30D @T6G_MB_LIB.T6G(SCH_1):GPU_3V3IO_RSVD0_FFU_ISO_R
 Y14 SWB_HSC_PWRGD_ISO_R  PB33C @T6G_MB_LIB.T6G(SCH_1):SWB_HSC_PWRGD_ISO_R
 W14 GPU_FPGA_THERM_OVERT_ISO_R_N  PB33D @T6G_MB_LIB.T6G(SCH_1):GPU_FPGA_THERM_OVERT_ISO_R_N
 T13 GPU_3V3IO_RSVD1_FFU_ISO_R  PB32A @T6G_MB_LIB.T6G(SCH_1):GPU_3V3IO_RSVD1_FFU_ISO_R
 T14 RST_PERST_CPU0_SWB_N  PB32B @T6G_MB_LIB.T6G(SCH_1):RST_PERST_CPU0_SWB_N
 U14 RST_PERST_CPU1_SWB_N  PB32C @T6G_MB_LIB.T6G(SCH_1):RST_PERST_CPU1_SWB_N
 V14 PRSNT_CABLE_GPU_A2_ISO_R_N  PB32D @T6G_MB_LIB.T6G(SCH_1):PRSNT_CABLE_GPU_A2_ISO_R_N
 Y15 GPU_FPGA_OVERT_ISO_R_N  PB35C @T6G_MB_LIB.T6G(SCH_1):GPU_FPGA_OVERT_ISO_R_N
 W15 GPU_WP_HW_CTRL_R_N  PB35D @T6G_MB_LIB.T6G(SCH_1):GPU_WP_HW_CTRL_R_N
AB16 GPU_PRSNT_N_ISO_R  PB38A @T6G_MB_LIB.T6G(SCH_1):GPU_PRSNT_N_ISO_R
AA16 GPU_FPGA_EROT_FATALERR_ISO_R_N  PB38B @T6G_MB_LIB.T6G(SCH_1):GPU_FPGA_EROT_FATALERR_ISO_R_N
 V15 BIC_MONITER_ISO_R  PB38C @T6G_MB_LIB.T6G(SCH_1):BIC_MONITER_ISO_R
 U15 RST_BMC_FROM_SWB_ISO_R_N  PB38D @T6G_MB_LIB.T6G(SCH_1):RST_BMC_FROM_SWB_ISO_R_N
AB17 FM_SWB_BIC_READY_ISO_R_N  PB40A @T6G_MB_LIB.T6G(SCH_1):FM_SWB_BIC_READY_ISO_R_N
AA17 FM_SMB_1_ALERT_GPU_ISO_R_N  PB40B @T6G_MB_LIB.T6G(SCH_1):FM_SMB_1_ALERT_GPU_ISO_R_N
 Y17 SW_P3V3_EN  PB40C @T6G_MB_LIB.T6G(SCH_1):SW_P3V3_EN
 V16 RST_PERST_M2_0_R_N  PB40D @T6G_MB_LIB.T6G(SCH_1):RST_PERST_M2_0_R_N
AB18 FM_SWB_PWRGD_ISO_R  PB41A @T6G_MB_LIB.T6G(SCH_1):FM_SWB_PWRGD_ISO_R
AA18 FM_GPU_PWRGD_ISO_R  PB41B @T6G_MB_LIB.T6G(SCH_1):FM_GPU_PWRGD_ISO_R
 Y18 FM_SMB_2_ALERT_GPU_ISO_R_N  PB41C @T6G_MB_LIB.T6G(SCH_1):FM_SMB_2_ALERT_GPU_ISO_R_N
 W17 RST_PERST_OCP_SFF_N  PB41D @T6G_MB_LIB.T6G(SCH_1):RST_PERST_OCP_SFF_N
 T15 GPU_FPGA_BOOT_EN_R  PB43C @T6G_MB_LIB.T6G(SCH_1):GPU_FPGA_BOOT_EN_R
 U16 FM_NCSI_OCP_V3_2_R_OE  PB43D @T6G_MB_LIB.T6G(SCH_1):FM_NCSI_OCP_V3_2_R_OE
 Y19 GPU_BASE_STBY_EN_R  PB44C @T6G_MB_LIB.T6G(SCH_1):GPU_BASE_STBY_EN_R
 W18 FM_AC_PWR_BTN_PLD_ISO_N  PB44D @T6G_MB_LIB.T6G(SCH_1):FM_AC_PWR_BTN_PLD_ISO_N
 V17 P3V3_OCP_V3_2_EN_R  PB46C @T6G_MB_LIB.T6G(SCH_1):P3V3_OCP_V3_2_EN_R
 T16 FM_P5V_EN  PB46D @T6G_MB_LIB.T6G(SCH_1):FM_P5V_EN
  Y9 PWRGD_P1V2_AUX_R  PB21C @T6G_MB_LIB.T6G(SCH_1):PWRGD_P1V2_AUX_R
 Y10 BMC_FPGA_LED2  PB21D @T6G_MB_LIB.T6G(SCH_1):BMC_FPGA_LED2

LCMXO3LF9400C5BG484C-LCMXO3LF-9400C-5BG484C,SMLF,IA  I217  U18
 W20 FM_FORCE_ALL_PWRON_R  PR30B @T6G_MB_LIB.T6G(SCH_1):FM_FORCE_ALL_PWRON_R
 V18 RST_SMB_RT_ROM_R2_N  PR30A @T6G_MB_LIB.T6G(SCH_1):RST_SMB_RT_ROM_R2_N
 V19 TP_FM_CLK_BUFFER_EN_R  PR29D @T6G_MB_LIB.T6G(SCH_1):TP_FM_CLK_BUFFER_EN_R
 Y21 FM_CPU1_PWR_GD_IN  PR29B @T6G_MB_LIB.T6G(SCH_1):FM_CPU1_PWR_GD_IN
 U17 FM_CPU0_FORCE_SELFREFRESH  PR29C @T6G_MB_LIB.T6G(SCH_1):FM_CPU0_FORCE_SELFREFRESH
AA22 FM_CPU1_PWRGD_OUT  PR29A @T6G_MB_LIB.T6G(SCH_1):FM_CPU1_PWRGD_OUT
 W22 FM_CPU1_NMI_SYNC_FLOOD_N  PR25B @T6G_MB_LIB.T6G(SCH_1):FM_CPU1_NMI_SYNC_FLOOD_N
 V22 FM_BIOS_USB_RECOVERY  PR25A @T6G_MB_LIB.T6G(SCH_1):FM_BIOS_USB_RECOVERY
 R21 CLK_ESPI_CPU0_R1_CLK1  PR20B @T6G_MB_LIB.T6G(SCH_1):CLK_ESPI_CPU0_R1_CLK1
 R22 FM_JTAG_BMC_OE  PR20A @T6G_MB_LIB.T6G(SCH_1):FM_JTAG_BMC_OE
 P21 FM_CPU0_HDT_CONN_TESTEN  PR19B @T6G_MB_LIB.T6G(SCH_1):FM_CPU0_HDT_CONN_TESTEN
 N22 BIOS_DEBUG_MODE_R  PR19A @T6G_MB_LIB.T6G(SCH_1):BIOS_DEBUG_MODE_R
 M21 FM_CPU0_SMERR_N PR17B||PCLKC1_0 @T6G_MB_LIB.T6G(SCH_1):FM_CPU0_SMERR_N
 M22 FM_SMERR_LED_R_N PR17A||PCLKT1_0 @T6G_MB_LIB.T6G(SCH_1):FM_SMERR_LED_R_N
 L21 RST_RT_CPU0_P0_RESET_R2_N  PR16B @T6G_MB_LIB.T6G(SCH_1):RST_RT_CPU0_P0_RESET_R2_N
 K22 RST_RT_CPU0_P0_PERST_R2_N  PR16A @T6G_MB_LIB.T6G(SCH_1):RST_RT_CPU0_P0_PERST_R2_N
 L16 CPU1_SPD_HOST_CTRL_R1_N  PR14B @T6G_MB_LIB.T6G(SCH_1):CPU1_SPD_HOST_CTRL_R1_N
 L17 APML_CPU0_ALERT_R_N  PR14A @T6G_MB_LIB.T6G(SCH_1):APML_CPU0_ALERT_R_N
 H21 FM_RST_CPU1_RESETL_N   PR7B @T6G_MB_LIB.T6G(SCH_1):FM_RST_CPU1_RESETL_N
 H22 FM_RST_CPU0_RESETL_N   PR7A @T6G_MB_LIB.T6G(SCH_1):FM_RST_CPU0_RESETL_N
 D21 FM_CPU1_SLP_S3_N PR3B||R_GPLLC_IN @T6G_MB_LIB.T6G(SCH_1):FM_CPU1_SLP_S3_N
 D22 FM_CPU1_SLP_S5_N PR3A||R_GPLLT_IN @T6G_MB_LIB.T6G(SCH_1):FM_CPU1_SLP_S5_N
 C22 FM_CPU0_SLP_S3_N PR2B||R_GPLLC_FB @T6G_MB_LIB.T6G(SCH_1):FM_CPU0_SLP_S3_N
 C21 FM_CPU0_SLP_S5_N PR2A||R_GPLLT_FB @T6G_MB_LIB.T6G(SCH_1):FM_CPU0_SLP_S5_N
 F17 RST_CPU0_PERST0_R_N   PR2C @T6G_MB_LIB.T6G(SCH_1):RST_CPU0_PERST0_R_N
 G16 RST_CPU1_PERST1_R_N   PR2D @T6G_MB_LIB.T6G(SCH_1):RST_CPU1_PERST1_R_N
 D19 PWRGD_P0V9_RETIMER_CPU0_R2   PR3C @T6G_MB_LIB.T6G(SCH_1):PWRGD_P0V9_RETIMER_CPU0_R2
 D20 RST_CPU0_PERST1_R_N   PR3D @T6G_MB_LIB.T6G(SCH_1):RST_CPU0_PERST1_R_N
 E19 RST_CPU1_PERST0_R_N   PR4C @T6G_MB_LIB.T6G(SCH_1):RST_CPU1_PERST0_R_N
 E20 PWRGD_P0V9_RETIMER_CPU1_R2   PR4D @T6G_MB_LIB.T6G(SCH_1):PWRGD_P0V9_RETIMER_CPU1_R2
 E22 RST_RT_CPU1_P0_PERST_R2_N   PR4A @T6G_MB_LIB.T6G(SCH_1):RST_RT_CPU1_P0_PERST_R2_N
 E21 RST_RT_CPU1_P0_RESET_R2_N   PR4B @T6G_MB_LIB.T6G(SCH_1):RST_RT_CPU1_P0_RESET_R2_N
 F22 FM_CPU1_RSMRST_N   PR5A @T6G_MB_LIB.T6G(SCH_1):FM_CPU1_RSMRST_N
 G22 FM_CPU0_RSMRST_N   PR5B @T6G_MB_LIB.T6G(SCH_1):FM_CPU0_RSMRST_N
 F18 TP_SLOT1_CLKREQ_0_R_N   PR5C @T6G_MB_LIB.T6G(SCH_1):TP_SLOT1_CLKREQ_0_R_N
 F19 FM_CPU0_SYS_RESET_N   PR5D @T6G_MB_LIB.T6G(SCH_1):FM_CPU0_SYS_RESET_N
 G21 FM_CPU1_SYS_RESET_N   PR6A @T6G_MB_LIB.T6G(SCH_1):FM_CPU1_SYS_RESET_N
 G20 FM_CPU0_NV_SAVE_N   PR6B @T6G_MB_LIB.T6G(SCH_1):FM_CPU0_NV_SAVE_N
 G19 RST_RT_CPU1_P1_PERST_R2_N   PR6C @T6G_MB_LIB.T6G(SCH_1):RST_RT_CPU1_P1_PERST_R2_N
 G18 RST_RT_CPU1_P1_RESET_R2_N   PR6D @T6G_MB_LIB.T6G(SCH_1):RST_RT_CPU1_P1_RESET_R2_N
 G17 RST_CPU0_KBRST_N   PR7C @T6G_MB_LIB.T6G(SCH_1):RST_CPU0_KBRST_N
 H20 CPU0_JTAG_BUF_R_OE   PR7D @T6G_MB_LIB.T6G(SCH_1):CPU0_JTAG_BUF_R_OE
 H19 FM_PWRGD_CPU0_PWROK  PR10A @T6G_MB_LIB.T6G(SCH_1):FM_PWRGD_CPU0_PWROK
 H18 FM_CPU1_NV_SAVE_N  PR10B @T6G_MB_LIB.T6G(SCH_1):FM_CPU1_NV_SAVE_N
 H17 PVDD11_S3_P0_RESET_N  PR10C @T6G_MB_LIB.T6G(SCH_1):PVDD11_S3_P0_RESET_N
 H16 PVDD11_S3_P1_RESET_N  PR10D @T6G_MB_LIB.T6G(SCH_1):PVDD11_S3_P1_RESET_N
 J16 FM_CPU0_NMI_SYNC_FLOOD_N  PR11A @T6G_MB_LIB.T6G(SCH_1):FM_CPU0_NMI_SYNC_FLOOD_N
 J17 FM_FPGA_DEBUG_LED_CTRL  PR11B @T6G_MB_LIB.T6G(SCH_1):FM_FPGA_DEBUG_LED_CTRL
 J18 FM_PWRGD_CPU1_PWROK  PR11C @T6G_MB_LIB.T6G(SCH_1):FM_PWRGD_CPU1_PWROK
 J19 FM_P1_PCC0_R_N  PR11D @T6G_MB_LIB.T6G(SCH_1):FM_P1_PCC0_R_N
 J21 TP_SLOT2_CLKREQ_0_R_N  PR12A @T6G_MB_LIB.T6G(SCH_1):TP_SLOT2_CLKREQ_0_R_N
 J22 FM_CPU0_PWR_BTN_N  PR12B @T6G_MB_LIB.T6G(SCH_1):FM_CPU0_PWR_BTN_N
 J20 FM_P1_PCC1_R_N  PR12C @T6G_MB_LIB.T6G(SCH_1):FM_P1_PCC1_R_N
 K20 RST_RT_CPU1_P2_PERST_R2_N  PR12D @T6G_MB_LIB.T6G(SCH_1):RST_RT_CPU1_P2_PERST_R2_N
 K19 RST_RT_CPU1_P2_RESET_R2_N  PR13A @T6G_MB_LIB.T6G(SCH_1):RST_RT_CPU1_P2_RESET_R2_N
 K18 FM_P0_PCC1_R_N  PR13B @T6G_MB_LIB.T6G(SCH_1):FM_P0_PCC1_R_N
 K17 FM_P0_PCC0_R_N  PR13C @T6G_MB_LIB.T6G(SCH_1):FM_P0_PCC0_R_N
 K16 APML_CPU1_ALERT_R_N  PR13D @T6G_MB_LIB.T6G(SCH_1):APML_CPU1_ALERT_R_N
 L19 RST_RT_CPU1_P3_PERST_R2_N  PR14C @T6G_MB_LIB.T6G(SCH_1):RST_RT_CPU1_P3_PERST_R2_N
 L20 RST_RT_CPU1_P3_RESET_R2_N  PR14D @T6G_MB_LIB.T6G(SCH_1):RST_RT_CPU1_P3_RESET_R2_N
 L22 RST_RT_CPU0_P1_PERST_R2_N  PR16C @T6G_MB_LIB.T6G(SCH_1):RST_RT_CPU0_P1_PERST_R2_N
 M17 RST_RT_CPU0_P1_RESET_R2_N  PR16D @T6G_MB_LIB.T6G(SCH_1):RST_RT_CPU0_P1_RESET_R2_N
 M20 SMB_CPU_5_R1_SCL  PR17C @T6G_MB_LIB.T6G(SCH_1):SMB_CPU_5_R1_SCL
 M19 SMB_CPU_5_R1_SDA  PR17D @T6G_MB_LIB.T6G(SCH_1):SMB_CPU_5_R1_SDA
 M16 PWRGD_P3V3_R2  PR18A @T6G_MB_LIB.T6G(SCH_1):PWRGD_P3V3_R2
 N16 FM_CPU1_SMERR_N  PR18B @T6G_MB_LIB.T6G(SCH_1):FM_CPU1_SMERR_N
 N17 FM_ESPI_CPU0_ALERT_SEL  PR18C @T6G_MB_LIB.T6G(SCH_1):FM_ESPI_CPU0_ALERT_SEL
 N18 RST_RT_CPU0_P2_PERST_R2_N  PR18D @T6G_MB_LIB.T6G(SCH_1):RST_RT_CPU0_P2_PERST_R2_N
 N20 TP_PWRGD_P12V_FAN_DR_R  PR19C @T6G_MB_LIB.T6G(SCH_1):TP_PWRGD_P12V_FAN_DR_R
 N19 PWRGD_P12V_MEM_R  PR19D @T6G_MB_LIB.T6G(SCH_1):PWRGD_P12V_MEM_R
 P22 ESPI_CPU0_CS1_R_N  PR20C @T6G_MB_LIB.T6G(SCH_1):ESPI_CPU0_CS1_R_N
 P20 ESPI_CPU0_ALERT_R_N  PR20D @T6G_MB_LIB.T6G(SCH_1):ESPI_CPU0_ALERT_R_N
 T22 RST_ESPI_CPU0_RSTOUT_R_N  PR21A @T6G_MB_LIB.T6G(SCH_1):RST_ESPI_CPU0_RSTOUT_R_N
 T21 ESPI_CPU0_R1_D0  PR21B @T6G_MB_LIB.T6G(SCH_1):ESPI_CPU0_R1_D0
 P19 ESPI_CPU0_R1_D1  PR21C @T6G_MB_LIB.T6G(SCH_1):ESPI_CPU0_R1_D1
 P18 ESPI_CPU0_R1_D2  PR21D @T6G_MB_LIB.T6G(SCH_1):ESPI_CPU0_R1_D2
 P17 ESPI_CPU0_R1_D3  PR24A @T6G_MB_LIB.T6G(SCH_1):ESPI_CPU0_R1_D3
 P16 FM_HDT_HDR_PWROK  PR24B @T6G_MB_LIB.T6G(SCH_1):FM_HDT_HDR_PWROK
 U22 FM_HDT_HDR_RESET_N  PR24C @T6G_MB_LIB.T6G(SCH_1):FM_HDT_HDR_RESET_N
 U21 FM_BIOS_POST_CMPLT_BUF_R_N  PR24D @T6G_MB_LIB.T6G(SCH_1):FM_BIOS_POST_CMPLT_BUF_R_N
 R20 RST_RT_CPU0_P2_RESET_R2_N  PR25C @T6G_MB_LIB.T6G(SCH_1):RST_RT_CPU0_P2_RESET_R2_N
 R19 SCM_USB_OC_R_N  PR25D @T6G_MB_LIB.T6G(SCH_1):SCM_USB_OC_R_N
 R18 CPU0_SPD_HOST_CTRL_R1_N  PR26A @T6G_MB_LIB.T6G(SCH_1):CPU0_SPD_HOST_CTRL_R1_N
 R17 FM_PLD_CPU1_PRSNT_HDT  PR26B @T6G_MB_LIB.T6G(SCH_1):FM_PLD_CPU1_PRSNT_HDT
 R16 CPU1_JTAG_BUF_R_OE  PR26C @T6G_MB_LIB.T6G(SCH_1):CPU1_JTAG_BUF_R_OE
 T20 SCM_IRQ_1V8_R_N  PR26D @T6G_MB_LIB.T6G(SCH_1):SCM_IRQ_1V8_R_N
 T19 RST_RT_CPU0_P3_PERST_R2_N  PR27A @T6G_MB_LIB.T6G(SCH_1):RST_RT_CPU0_P3_PERST_R2_N
 T18 P12V_ALL_PWROK_R  PR27B @T6G_MB_LIB.T6G(SCH_1):P12V_ALL_PWROK_R
 T17 RST_RT_CPU0_P3_RESET_R2_N  PR27C @T6G_MB_LIB.T6G(SCH_1):RST_RT_CPU0_P3_RESET_R2_N
 U20 BMC_JTAG_SEL_R  PR27D @T6G_MB_LIB.T6G(SCH_1):BMC_JTAG_SEL_R
 Y22 FM_ROM_LS_EN  PR28A @T6G_MB_LIB.T6G(SCH_1):FM_ROM_LS_EN
 W21 FM_ROM_SD_LS_OE  PR28B @T6G_MB_LIB.T6G(SCH_1):FM_ROM_SD_LS_OE
 U19 FM_SPD_CPU0_SWITCH_CTRL_R_N  PR28C @T6G_MB_LIB.T6G(SCH_1):FM_SPD_CPU0_SWITCH_CTRL_R_N
 U18 FM_PLD_CPU0_PRSNT_HDT  PR28D @T6G_MB_LIB.T6G(SCH_1):FM_PLD_CPU0_PRSNT_HDT
 W19 FM_CPU1_FORCE_SELFREFRESH  PR30C @T6G_MB_LIB.T6G(SCH_1):FM_CPU1_FORCE_SELFREFRESH
 Y20 RST_SMB_RT_R2_N  PR30D @T6G_MB_LIB.T6G(SCH_1):RST_SMB_RT_R2_N

Q_RES_0402LF-33.2,1%,1/16W,CHIP,CS03322FB03  I220  R4170
   1 GPU_3V3IO_RSVD1_ISO_R      A @T6G_MB_LIB.T6G(SCH_1):GPU_3V3IO_RSVD1_ISO_R
   2 GPU_3V3IO_RSVD1_ISO      B @T6G_MB_LIB.T6G(SCH_1):GPU_3V3IO_RSVD1_ISO

Q_RES_0402LF-33.2,1%,1/16W,CHIP,CS03322FB03  I223  R4171
   1 GPU_3V3IO_RSVD3_ISO_R      A @T6G_MB_LIB.T6G(SCH_1):GPU_3V3IO_RSVD3_ISO_R
   2 GPU_3V3IO_RSVD3_ISO      B @T6G_MB_LIB.T6G(SCH_1):GPU_3V3IO_RSVD3_ISO

Q_RES_0402LF-33.2,1%,1/16W,CHIP,CS03322FB03  I224  R4172
   1 GPU_3V3IO_RSVD4_ISO_R      A @T6G_MB_LIB.T6G(SCH_1):GPU_3V3IO_RSVD4_ISO_R
   2 GPU_3V3IO_RSVD4_ISO      B @T6G_MB_LIB.T6G(SCH_1):GPU_3V3IO_RSVD4_ISO

Q_RES_0402LF-33.2,1%,1/16W,CHIP,CS03322FB03  I226  R4556
   1 HGX_DETECT_N_R      A @T6G_MB_LIB.T6G(SCH_1):HGX_DETECT_N_R
   2 HGX_DETECT_N      B @T6G_MB_LIB.T6G(SCH_1):HGX_DETECT_N

Q_RES_0402LF-33.2,1%,1/16W,CHIP,CS03322FB03  I228  R4558
   1 SWB_HSC_EN_R      A @T6G_MB_LIB.T6G(SCH_1):SWB_HSC_EN_R
   2 SWB_HSC_EN      B @T6G_MB_LIB.T6G(SCH_1):SWB_HSC_EN

Q_RES_0402LF-33.2,1%,1/16W,CHIP,CS03322FB03  I231  R4143
   1 GPU_3V3IO_RSVD0_FFU_ISO_R      A @T6G_MB_LIB.T6G(SCH_1):GPU_3V3IO_RSVD0_FFU_ISO_R
   2 GPU_3V3IO_RSVD0_FFU_ISO      B @T6G_MB_LIB.T6G(SCH_1):GPU_3V3IO_RSVD0_FFU_ISO

Q_RES_0402LF-33.2,1%,1/16W,CHIP,CS03322FB03  I233  R4144
   1 GPU_3V3IO_RSVD1_FFU_ISO_R      A @T6G_MB_LIB.T6G(SCH_1):GPU_3V3IO_RSVD1_FFU_ISO_R
   2 GPU_3V3IO_RSVD1_FFU_ISO      B @T6G_MB_LIB.T6G(SCH_1):GPU_3V3IO_RSVD1_FFU_ISO

Q_RES_0402LF-33.2,1%,1/16W,CHIP,CS03322FB03  I240  R4147
   1 PRSNT_CABLE_GPU_A2_ISO_R_N      A @T6G_MB_LIB.T6G(SCH_1):PRSNT_CABLE_GPU_A2_ISO_R_N
   2 PRSNT_CABLE_GPU_A2_ISO_N      B @T6G_MB_LIB.T6G(SCH_1):PRSNT_CABLE_GPU_A2_ISO_N

Q_RES_0402LF-33.2,1%,1/16W,CHIP,CS03322FB03  I242  R4148
   1 GPU_3V3IO_RSVD5_FFU_ISO_R      A @T6G_MB_LIB.T6G(SCH_1):GPU_3V3IO_RSVD5_FFU_ISO_R
   2 GPU_3V3IO_RSVD5_FFU_ISO      B @T6G_MB_LIB.T6G(SCH_1):GPU_3V3IO_RSVD5_FFU_ISO

Q_RES_0402LF-33.2,1%,1/16W,CHIP,CS03322FB03  I243  R4563
   1 SWB_HSC_PWRGD_ISO_R      A @T6G_MB_LIB.T6G(SCH_1):SWB_HSC_PWRGD_ISO_R
   2 SWB_HSC_PWRGD_ISO      B @T6G_MB_LIB.T6G(SCH_1):SWB_HSC_PWRGD_ISO

Q_RES_0402LF-33.2,1%,1/16W,CHIP,CS03322FB03  I246  R4157
   1 PRSNT_CABLE_GPU_A1_ISO_R_N      A @T6G_MB_LIB.T6G(SCH_1):PRSNT_CABLE_GPU_A1_ISO_R_N
   2 PRSNT_CABLE_GPU_A1_ISO_N      B @T6G_MB_LIB.T6G(SCH_1):PRSNT_CABLE_GPU_A1_ISO_N

Q_RES_0402LF-33.2,1%,1/16W,CHIP,CS03322FB03  I247  R3480
   1 GPU_BASE_HMC_READY_ISO_R      A @T6G_MB_LIB.T6G(SCH_1):GPU_BASE_HMC_READY_ISO_R
   2 GPU_BASE_HMC_READY_ISO      B @T6G_MB_LIB.T6G(SCH_1):GPU_BASE_HMC_READY_ISO

Q_RES_0402LF-33.2,1%,1/16W,CHIP,CS03322FB03  I250  R3476
   1 GPU_FPGA_THERM_OVERT_ISO_R_N      A @T6G_MB_LIB.T6G(SCH_1):GPU_FPGA_THERM_OVERT_ISO_R_N
   2 GPU_FPGA_THERM_OVERT_ISO_N      B @T6G_MB_LIB.T6G(SCH_1):GPU_FPGA_THERM_OVERT_ISO_N

Q_RES_0402LF-33.2,1%,1/16W,CHIP,CS03322FB03  I251  R3481
   1 GPU_HMC_PRSNT_ISO_R_N      A @T6G_MB_LIB.T6G(SCH_1):GPU_HMC_PRSNT_ISO_R_N
   2 GPU_HMC_PRSNT_ISO_N      B @T6G_MB_LIB.T6G(SCH_1):GPU_HMC_PRSNT_ISO_N

Q_RES_0402LF-33.2,1%,1/16W,CHIP,CS03322FB03  I254  R3484
   1 GPU_FPGA_OVERT_ISO_R_N      A @T6G_MB_LIB.T6G(SCH_1):GPU_FPGA_OVERT_ISO_R_N
   2 GPU_FPGA_OVERT_ISO_N      B @T6G_MB_LIB.T6G(SCH_1):GPU_FPGA_OVERT_ISO_N

Q_RES_0402LF-33.2,1%,1/16W,CHIP,CS03322FB03  I255  R3485
   1 GPU_WP_HW_CTRL_R_N      A @T6G_MB_LIB.T6G(SCH_1):GPU_WP_HW_CTRL_R_N
   2 GPU_WP_HW_CTRL_N      B @T6G_MB_LIB.T6G(SCH_1):GPU_WP_HW_CTRL_N

Q_RES_0402LF-33.2,1%,1/16W,CHIP,CS03322FB03  I258  R3486
   1 GPU_PRSNT_N_ISO_R      A @T6G_MB_LIB.T6G(SCH_1):GPU_PRSNT_N_ISO_R
   2 GPU_PRSNT_N_ISO      B @T6G_MB_LIB.T6G(SCH_1):GPU_PRSNT_N_ISO

Q_RES_0402LF-33.2,1%,1/16W,CHIP,CS03322FB03  I259  R3505
   1 GPU_FPGA_EROT_FATALERR_ISO_R_N      A @T6G_MB_LIB.T6G(SCH_1):GPU_FPGA_EROT_FATALERR_ISO_R_N
   2 GPU_FPGA_EROT_FATALERR_ISO_N      B @T6G_MB_LIB.T6G(SCH_1):GPU_FPGA_EROT_FATALERR_ISO_N

Q_RES_0402LF-33.2,1%,1/16W,CHIP,CS03322FB03  I262  R2846
   1 BIC_MONITER_ISO_R      A @T6G_MB_LIB.T6G(SCH_1):BIC_MONITER_ISO_R
   2 BIC_MONITER_ISO      B @T6G_MB_LIB.T6G(SCH_1):BIC_MONITER_ISO

Q_RES_0402LF-33.2,1%,1/16W,CHIP,CS03322FB03  I263  R2844
   1 FM_SWB_BIC_READY_ISO_R_N      A @T6G_MB_LIB.T6G(SCH_1):FM_SWB_BIC_READY_ISO_R_N
   2 FM_SWB_BIC_READY_ISO_N      B @T6G_MB_LIB.T6G(SCH_1):FM_SWB_BIC_READY_ISO_N

Q_RES_0402LF-33.2,1%,1/16W,CHIP,CS03322FB03  I266  R2847
   1 RST_BMC_FROM_SWB_ISO_R_N      A @T6G_MB_LIB.T6G(SCH_1):RST_BMC_FROM_SWB_ISO_R_N
   2 RST_BMC_FROM_SWB_ISO_N      B @T6G_MB_LIB.T6G(SCH_1):RST_BMC_FROM_SWB_ISO_N

Q_RES_0402LF-33.2,1%,1/16W,CHIP,CS03322FB03  I268  R3066
   1 FM_SMB_1_ALERT_GPU_ISO_R_N      A @T6G_MB_LIB.T6G(SCH_1):FM_SMB_1_ALERT_GPU_ISO_R_N
   2 FM_SMB_1_ALERT_GPU_ISO_N      B @T6G_MB_LIB.T6G(SCH_1):FM_SMB_1_ALERT_GPU_ISO_N

Q_RES_0402LF-33.2,1%,1/16W,CHIP,CS03322FB03  I271  R2663
   1 FM_SWB_PWRGD_ISO_R      A @T6G_MB_LIB.T6G(SCH_1):FM_SWB_PWRGD_ISO_R
   2 FM_SWB_PWRGD_ISO      B @T6G_MB_LIB.T6G(SCH_1):FM_SWB_PWRGD_ISO

Q_RES_0402LF-33.2,1%,1/16W,CHIP,CS03322FB03  I272  R2664
   1 FM_GPU_PWRGD_ISO_R      A @T6G_MB_LIB.T6G(SCH_1):FM_GPU_PWRGD_ISO_R
   2 FM_GPU_PWRGD_ISO      B @T6G_MB_LIB.T6G(SCH_1):FM_GPU_PWRGD_ISO

Q_RES_0402LF-33.2,1%,1/16W,CHIP,CS03322FB03  I274  R11667
   1 FM_SMB_2_ALERT_GPU_ISO_R_N      A @T6G_MB_LIB.T6G(SCH_1):FM_SMB_2_ALERT_GPU_ISO_R_N
   2 FM_SMB_2_ALERT_GPU_ISO_N      B @T6G_MB_LIB.T6G(SCH_1):FM_SMB_2_ALERT_GPU_ISO_N

Q_RES_0402LF-33.2,1%,1/16W,CHIP,CS03322FB03  I276  R3324
   1 GPU_FPGA_READY_ISO_R      A @T6G_MB_LIB.T6G(SCH_1):GPU_FPGA_READY_ISO_R
   2 GPU_FPGA_READY_ISO      B @T6G_MB_LIB.T6G(SCH_1):GPU_FPGA_READY_ISO

Q_RES_0402LF-33.2,1%,1/16W,CHIP,CS03322FB03  I278  R3482
   1 GPU_FPGA_BOOT_EN_R      A @T6G_MB_LIB.T6G(SCH_1):GPU_FPGA_BOOT_EN_R
   2 GPU_FPGA_BOOT_EN      B @T6G_MB_LIB.T6G(SCH_1):GPU_FPGA_BOOT_EN

Q_RES_0402LF-33.2,1%,1/16W,CHIP,CS03322FB03  I281  R3479
   1 GPU_BASE_STBY_EN_R      A @T6G_MB_LIB.T6G(SCH_1):GPU_BASE_STBY_EN_R
   2 GPU_BASE_STBY_EN      B @T6G_MB_LIB.T6G(SCH_1):GPU_BASE_STBY_EN

Q_RES_0402LF-33.2,1%,1/16W,CHIP,CS03322FB03  I284  R2261
   1 FM_SWB_PWR_EN_R      A @T6G_MB_LIB.T6G(SCH_1):FM_SWB_PWR_EN_R
   2 FM_SWB_PWR_EN      B @T6G_MB_LIB.T6G(SCH_1):FM_SWB_PWR_EN

Q_RES_0402LF-33.2,1%,1/16W,CHIP,CS03322FB03  I286  R3477
   1 GPU_NVS_PWR_BRAKE_N      A @T6G_MB_LIB.T6G(SCH_1):GPU_NVS_PWR_BRAKE_N
   2 GPU_NVS_PWR_BRAKE_R_N      B @T6G_MB_LIB.T6G(SCH_1):GPU_NVS_PWR_BRAKE_R_N

Q_RES_0402LF-33.2,1%,1/16W,CHIP,CS03322FB03  I288  R3478
   1 GPU_FPGA_EROT_RST_N      A @T6G_MB_LIB.T6G(SCH_1):GPU_FPGA_EROT_RST_N
   2 GPU_FPGA_EROT_RST_R_N      B @T6G_MB_LIB.T6G(SCH_1):GPU_FPGA_EROT_RST_R_N

Q_RES_0402LF-33.2,1%,1/16W,CHIP,CS03322FB03  I290  R3483
   1 GPU_FPGA_EROT_RECOV_N      A @T6G_MB_LIB.T6G(SCH_1):GPU_FPGA_EROT_RECOV_N
   2 GPU_FPGA_EROT_RECOV_R_N      B @T6G_MB_LIB.T6G(SCH_1):GPU_FPGA_EROT_RECOV_R_N

Q_RES_0402LF-33.2,1%,1/16W,CHIP,CS03322FB03  I293  R2845
   1 BMC_MONITER_R      A @T6G_MB_LIB.T6G(SCH_1):BMC_MONITER_R
   2 BMC_MONITER      B @T6G_MB_LIB.T6G(SCH_1):BMC_MONITER

Q_RES_0402LF-33.2,1%,1/16W,CHIP,CS03322FB03  I294  R2262
   1 FM_GPU_PWR_EN_R      A @T6G_MB_LIB.T6G(SCH_1):FM_GPU_PWR_EN_R
   2 FM_GPU_PWR_EN      B @T6G_MB_LIB.T6G(SCH_1):FM_GPU_PWR_EN

Q_RES_0402LF-33.2,1%,1/16W,CHIP,CS03322FB03  I295  R4608
   1 GPU_FPGA_RST_R_N      A @T6G_MB_LIB.T6G(SCH_1):GPU_FPGA_RST_R_N
   2 GPU_FPGA_RST_N      B @T6G_MB_LIB.T6G(SCH_1):GPU_FPGA_RST_N

Q_RES_0402LF-10K,1%,1/16W,CHIP,CS31002FB08  I298  R6085
   1 P3V3_AUX      A @T6G_MB_LIB.T6G(SCH_1):P3V3_AUX
   2 PU_SPI_PLD_CS_N      B @T6G_MB_LIB.T6G(SCH_1):PU_SPI_PLD_CS_N

Q_RES_0402LF-33.2,1%,1/16W,CHIP,CS03322FB03  I301  R4557
   1 HPDB_HSC_PWRGD_ISO      A @T6G_MB_LIB.T6G(SCH_1):HPDB_HSC_PWRGD_ISO
   2 HPDB_HSC_PWRGD_ISO_R      B @T6G_MB_LIB.T6G(SCH_1):HPDB_HSC_PWRGD_ISO_R

Q_RES_0402LF-33,5%,1/16W,CHIP,CS03302JB10  I303  R195
   1 FM_CPU1_PWRGD_OUT      A @T6G_MB_LIB.T6G(SCH_1):FM_CPU1_PWRGD_OUT
   2 CPU1_PWRGD_OUT      B @T6G_MB_LIB.T6G(SCH_1):CPU1_PWRGD_OUT

Q_RES_0402LF-33.2,1%,1/16W,CHIP,CS03322FB03  I311  R2939
   1 FM_GPU_HSC_EN      A @T6G_MB_LIB.T6G(SCH_1):FM_GPU_HSC_EN
   2 FM_GPU_HSC_EN_R      B @T6G_MB_LIB.T6G(SCH_1):FM_GPU_HSC_EN_R

Q_RES_0402LF-33.2,1%,1/16W,CHIP,CS03322FB03  I315  R8000
   1 PRSNT_SWB_ISO_N      A @T6G_MB_LIB.T6G(SCH_1):PRSNT_SWB_ISO_N
   2 PRSNT_SWB_ISO_R_N      B @T6G_MB_LIB.T6G(SCH_1):PRSNT_SWB_ISO_R_N

Q_RES_0402LF-0,5%,1/16W,CHIP,CS00002JB13  I318  R8021
   1 FM_JTAG_BMC_OE      A @T6G_MB_LIB.T6G(SCH_1):FM_JTAG_BMC_OE
   2 FM_JTAG_BMC_R_OE      B @T6G_MB_LIB.T6G(SCH_1):FM_JTAG_BMC_R_OE

Q_RES_0402LF-0,5%,1/16W,CHIP,CS00002JB13  I319  R8032
   1 FM_ESPI_CPU0_ALERT_SEL      A @T6G_MB_LIB.T6G(SCH_1):FM_ESPI_CPU0_ALERT_SEL
   2 FM_ESPI_CPU0_ALERT_R_SEL      B @T6G_MB_LIB.T6G(SCH_1):FM_ESPI_CPU0_ALERT_R_SEL

Q_RES_0402LF-0,5%,1/16W,CHIP,CS00002JB13  I322  R6710
   1 RST_RT_CPU1_P0_PERST_R_N      A @T6G_MB_LIB.T6G(SCH_1):RST_RT_CPU1_P0_PERST_R_N
   2 RST_RT_CPU1_P0_PERST_R2_N      B @T6G_MB_LIB.T6G(SCH_1):RST_RT_CPU1_P0_PERST_R2_N

Q_RES_0402LF-0,5%,1/16W,CHIP,CS00002JB13  I324  R6711
   1 RST_RT_CPU1_P0_RESET_R_N      A @T6G_MB_LIB.T6G(SCH_1):RST_RT_CPU1_P0_RESET_R_N
   2 RST_RT_CPU1_P0_RESET_R2_N      B @T6G_MB_LIB.T6G(SCH_1):RST_RT_CPU1_P0_RESET_R2_N

Q_RES_0402LF-0,5%,1/16W,CHIP,CS00002JB13  I326  R6740
   1 RST_RT_CPU1_P1_PERST_R_N      A @T6G_MB_LIB.T6G(SCH_1):RST_RT_CPU1_P1_PERST_R_N
   2 RST_RT_CPU1_P1_PERST_R2_N      B @T6G_MB_LIB.T6G(SCH_1):RST_RT_CPU1_P1_PERST_R2_N

Q_RES_0402LF-0,5%,1/16W,CHIP,CS00002JB13  I327  R6741
   1 RST_RT_CPU1_P1_RESET_R_N      A @T6G_MB_LIB.T6G(SCH_1):RST_RT_CPU1_P1_RESET_R_N
   2 RST_RT_CPU1_P1_RESET_R2_N      B @T6G_MB_LIB.T6G(SCH_1):RST_RT_CPU1_P1_RESET_R2_N

Q_RES_0402LF-0,5%,1/16W,CHIP,CS00002JB13  I330  R6777
   1 RST_SMB_RT_R2_N      A @T6G_MB_LIB.T6G(SCH_1):RST_SMB_RT_R2_N
   2 RST_SMB_RT_R1_N      B @T6G_MB_LIB.T6G(SCH_1):RST_SMB_RT_R1_N

Q_RES_0402LF-0,5%,1/16W,CHIP,CS00002JB13  I332  R6781
   1 RST_SMB_RT_ROM_R2_N      A @T6G_MB_LIB.T6G(SCH_1):RST_SMB_RT_ROM_R2_N
   2 RST_SMB_RT_ROM_R1_N      B @T6G_MB_LIB.T6G(SCH_1):RST_SMB_RT_ROM_R1_N

Q_RES_0402LF-0,5%,1/16W,CHIP,CS00002JB13  I334  R6792
   1 RST_RT_CPU1_P2_PERST_R_N      A @T6G_MB_LIB.T6G(SCH_1):RST_RT_CPU1_P2_PERST_R_N
   2 RST_RT_CPU1_P2_PERST_R2_N      B @T6G_MB_LIB.T6G(SCH_1):RST_RT_CPU1_P2_PERST_R2_N

Q_RES_0402LF-0,5%,1/16W,CHIP,CS00002JB13  I335  R6793
   1 RST_RT_CPU1_P2_RESET_R_N      A @T6G_MB_LIB.T6G(SCH_1):RST_RT_CPU1_P2_RESET_R_N
   2 RST_RT_CPU1_P2_RESET_R2_N      B @T6G_MB_LIB.T6G(SCH_1):RST_RT_CPU1_P2_RESET_R2_N

Q_RES_0402LF-0,5%,1/16W,CHIP,CS00002JB13  I338  R6798
   1 RST_RT_CPU1_P3_PERST_R_N      A @T6G_MB_LIB.T6G(SCH_1):RST_RT_CPU1_P3_PERST_R_N
   2 RST_RT_CPU1_P3_PERST_R2_N      B @T6G_MB_LIB.T6G(SCH_1):RST_RT_CPU1_P3_PERST_R2_N

Q_RES_0402LF-0,5%,1/16W,CHIP,CS00002JB13  I339  R6799
   1 RST_RT_CPU1_P3_RESET_R_N      A @T6G_MB_LIB.T6G(SCH_1):RST_RT_CPU1_P3_RESET_R_N
   2 RST_RT_CPU1_P3_RESET_R2_N      B @T6G_MB_LIB.T6G(SCH_1):RST_RT_CPU1_P3_RESET_R2_N

Q_RES_0402LF-0,5%,1/16W,CHIP,CS00002JB13  I342  R6804
   1 RST_RT_CPU0_P0_PERST_R_N      A @T6G_MB_LIB.T6G(SCH_1):RST_RT_CPU0_P0_PERST_R_N
   2 RST_RT_CPU0_P0_PERST_R2_N      B @T6G_MB_LIB.T6G(SCH_1):RST_RT_CPU0_P0_PERST_R2_N

Q_RES_0402LF-0,5%,1/16W,CHIP,CS00002JB13  I343  R6805
   1 RST_RT_CPU0_P0_RESET_R_N      A @T6G_MB_LIB.T6G(SCH_1):RST_RT_CPU0_P0_RESET_R_N
   2 RST_RT_CPU0_P0_RESET_R2_N      B @T6G_MB_LIB.T6G(SCH_1):RST_RT_CPU0_P0_RESET_R2_N

Q_RES_0402LF-0,5%,1/16W,CHIP,CS00002JB13  I344  R6806
   1 RST_RT_CPU0_P1_PERST_R_N      A @T6G_MB_LIB.T6G(SCH_1):RST_RT_CPU0_P1_PERST_R_N
   2 RST_RT_CPU0_P1_PERST_R2_N      B @T6G_MB_LIB.T6G(SCH_1):RST_RT_CPU0_P1_PERST_R2_N

Q_RES_0402LF-0,5%,1/16W,CHIP,CS00002JB13  I345  R6807
   1 RST_RT_CPU0_P1_RESET_R_N      A @T6G_MB_LIB.T6G(SCH_1):RST_RT_CPU0_P1_RESET_R_N
   2 RST_RT_CPU0_P1_RESET_R2_N      B @T6G_MB_LIB.T6G(SCH_1):RST_RT_CPU0_P1_RESET_R2_N

Q_RES_0402LF-0,5%,1/16W,CHIP,CS00002JB13  I350  R6823
   1 RST_RT_CPU0_P2_PERST_R2_N      A @T6G_MB_LIB.T6G(SCH_1):RST_RT_CPU0_P2_PERST_R2_N
   2 RST_RT_CPU0_P2_PERST_R_N      B @T6G_MB_LIB.T6G(SCH_1):RST_RT_CPU0_P2_PERST_R_N

Q_RES_0402LF-0,5%,1/16W,CHIP,CS00002JB13  I351  R6824
   1 RST_RT_CPU0_P2_RESET_R2_N      A @T6G_MB_LIB.T6G(SCH_1):RST_RT_CPU0_P2_RESET_R2_N
   2 RST_RT_CPU0_P2_RESET_R_N      B @T6G_MB_LIB.T6G(SCH_1):RST_RT_CPU0_P2_RESET_R_N

Q_RES_0402LF-0,5%,1/16W,CHIP,CS00002JB13  I352  R6825
   1 RST_RT_CPU0_P3_PERST_R2_N      A @T6G_MB_LIB.T6G(SCH_1):RST_RT_CPU0_P3_PERST_R2_N
   2 RST_RT_CPU0_P3_PERST_R_N      B @T6G_MB_LIB.T6G(SCH_1):RST_RT_CPU0_P3_PERST_R_N

Q_RES_0402LF-0,5%,1/16W,CHIP,CS00002JB13  I353  R6826
   1 RST_RT_CPU0_P3_RESET_R2_N      A @T6G_MB_LIB.T6G(SCH_1):RST_RT_CPU0_P3_RESET_R2_N
   2 RST_RT_CPU0_P3_RESET_R_N      B @T6G_MB_LIB.T6G(SCH_1):RST_RT_CPU0_P3_RESET_R_N

Q_RES_0402LF-0,5%,1/16W,CHIP,CS00002JB13  I360  R6852
   1 PWRGD_P0V9_RETIMER_CPU0      A @T6G_MB_LIB.T6G(SCH_1):PWRGD_P0V9_RETIMER_CPU0
   2 PWRGD_P0V9_RETIMER_CPU0_R2      B @T6G_MB_LIB.T6G(SCH_1):PWRGD_P0V9_RETIMER_CPU0_R2

Q_RES_0402LF-0,5%,1/16W,CHIP,CS00002JB13  I362  R6853
   1 PWRGD_P0V9_RETIMER_CPU1      A @T6G_MB_LIB.T6G(SCH_1):PWRGD_P0V9_RETIMER_CPU1
   2 PWRGD_P0V9_RETIMER_CPU1_R2      B @T6G_MB_LIB.T6G(SCH_1):PWRGD_P0V9_RETIMER_CPU1_R2

Q_RES_0402LF-33,5%,1/16W,CHIP,CS03302JB10  I364  R6854
   1 P0V9_RETIMER_CPU0_EN      A @T6G_MB_LIB.T6G(SCH_1):P0V9_RETIMER_CPU0_EN
   2 P0V9_RETIMER_CPU0_EN_R2      B @T6G_MB_LIB.T6G(SCH_1):P0V9_RETIMER_CPU0_EN_R2

Q_RES_0402LF-33,5%,1/16W,CHIP,CS03302JB10  I366  R6855
   1 P0V9_RETIMER_CPU1_EN_R2      A @T6G_MB_LIB.T6G(SCH_1):P0V9_RETIMER_CPU1_EN_R2
   2 P0V9_RETIMER_CPU1_EN      B @T6G_MB_LIB.T6G(SCH_1):P0V9_RETIMER_CPU1_EN


DRAWING: @T6G_MB_LIB.T6G(SCH_1):PAGE248 

Q_CAP_0402-0.1UF,25V,10%,X7R,CH4104K1B00  I4  C1859
   1 P3V3_AUX      A @T6G_MB_LIB.T6G(SCH_1):P3V3_AUX
   2    GND      B @T6G_MB_LIB.T6G(SCH_1):GND

PCA9617ADP-PCA9617ADP,SMLF,IC,AL009617K02  I6  U235
   5 HP_LVC3_OCP_V3_2_R_EN     EN @T6G_MB_LIB.T6G(SCH_1):HP_LVC3_OCP_V3_2_R_EN
   1 P3V3_AUX   VCCA @T6G_MB_LIB.T6G(SCH_1):P3V3_AUX
   8 P3V3_OCP_V3_2   VCCB @T6G_MB_LIB.T6G(SCH_1):P3V3_OCP_V3_2
   2 SMB_OCP_V3_2_3V3AUX_SCL   SCLA @T6G_MB_LIB.T6G(SCH_1):SMB_OCP_V3_2_3V3AUX_SCL
   3 SMB_OCP_V3_2_3V3AUX_SDA   SDAA @T6G_MB_LIB.T6G(SCH_1):SMB_OCP_V3_2_3V3AUX_SDA
   6 SMB_OCP_V3_2_3V3AUX_BUF_SDA   SDAB @T6G_MB_LIB.T6G(SCH_1):SMB_OCP_V3_2_3V3AUX_BUF_SDA
   7 SMB_OCP_V3_2_3V3AUX_BUF_SCL   SCLB @T6G_MB_LIB.T6G(SCH_1):SMB_OCP_V3_2_3V3AUX_BUF_SCL
   4    GND    GND @T6G_MB_LIB.T6G(SCH_1):GND

Q_CAP_0402-0.1UF,25V,10%,X7R,CH4104K1B00  I9  C1861
   1 P3V3_OCP_V3_2      A @T6G_MB_LIB.T6G(SCH_1):P3V3_OCP_V3_2
   2    GND      B @T6G_MB_LIB.T6G(SCH_1):GND

PCA9617ADP-PCA9617ADP,SMLF,IC,AL009617K02  I14  U236
   5 HP_LVC3_OCP_V3_1_R_EN     EN @T6G_MB_LIB.T6G(SCH_1):HP_LVC3_OCP_V3_1_R_EN
   1 P3V3_AUX   VCCA @T6G_MB_LIB.T6G(SCH_1):P3V3_AUX
   8 P3V3_OCP_SFF   VCCB @T6G_MB_LIB.T6G(SCH_1):P3V3_OCP_SFF
   2 SMB_OCP_SFF_3V3AUX_SCL   SCLA @T6G_MB_LIB.T6G(SCH_1):SMB_OCP_SFF_3V3AUX_SCL
   3 SMB_OCP_SFF_3V3AUX_SDA   SDAA @T6G_MB_LIB.T6G(SCH_1):SMB_OCP_SFF_3V3AUX_SDA
   6 SMB_OCP_SFF_3V3AUX_BUF_SDA   SDAB @T6G_MB_LIB.T6G(SCH_1):SMB_OCP_SFF_3V3AUX_BUF_SDA
   7 SMB_OCP_SFF_3V3AUX_BUF_SCL   SCLB @T6G_MB_LIB.T6G(SCH_1):SMB_OCP_SFF_3V3AUX_BUF_SCL
   4    GND    GND @T6G_MB_LIB.T6G(SCH_1):GND

Q_CAP_0402-0.1UF,25V,10%,X7R,CH4104K1B00  I15  C1860
   1 P3V3_AUX      A @T6G_MB_LIB.T6G(SCH_1):P3V3_AUX
   2    GND      B @T6G_MB_LIB.T6G(SCH_1):GND

Q_CAP_0402-0.1UF,25V,10%,X7R,CH4104K1B00  I19  C1862
   1 P3V3_OCP_SFF      A @T6G_MB_LIB.T6G(SCH_1):P3V3_OCP_SFF
   2    GND      B @T6G_MB_LIB.T6G(SCH_1):GND

Q_RES_0402LF-4.7K,5%,1/16W,CHIP,CS24702JB10  I23  R3520
   1 P3V3_OCP_V3_2      A @T6G_MB_LIB.T6G(SCH_1):P3V3_OCP_V3_2
   2 SMB_OCP_V3_2_3V3AUX_BUF_SDA      B @T6G_MB_LIB.T6G(SCH_1):SMB_OCP_V3_2_3V3AUX_BUF_SDA

Q_RES_0402LF-4.7K,5%,1/16W,CHIP,CS24702JB10  I27  R3500
   1 P3V3_OCP_SFF      A @T6G_MB_LIB.T6G(SCH_1):P3V3_OCP_SFF
   2 SMB_OCP_SFF_3V3AUX_BUF_SCL      B @T6G_MB_LIB.T6G(SCH_1):SMB_OCP_SFF_3V3AUX_BUF_SCL

Q_RES_0402LF-4.7K,5%,1/16W,CHIP,CS24702JB10  I31  R3501
   1 P3V3_OCP_SFF      A @T6G_MB_LIB.T6G(SCH_1):P3V3_OCP_SFF
   2 SMB_OCP_SFF_3V3AUX_BUF_SDA      B @T6G_MB_LIB.T6G(SCH_1):SMB_OCP_SFF_3V3AUX_BUF_SDA

Q_RES_0402LF-4.7K,5%,1/16W,CHIP,CS24702JB10  I34  R3519
   1 P3V3_OCP_V3_2      A @T6G_MB_LIB.T6G(SCH_1):P3V3_OCP_V3_2
   2 SMB_OCP_V3_2_3V3AUX_BUF_SCL      B @T6G_MB_LIB.T6G(SCH_1):SMB_OCP_V3_2_3V3AUX_BUF_SCL

Q_RES_0402LF-0,5%,1/16W,EMPTY,CS00002JB13  I35  R3263
   1 HP_LVC3_OCP_V3_1_R_EN      A @T6G_MB_LIB.T6G(SCH_1):HP_LVC3_OCP_V3_1_R_EN
   2 P3V3_OCP_SFF_EN_R      B @T6G_MB_LIB.T6G(SCH_1):P3V3_OCP_SFF_EN_R

Q_RES_0402LF-0,5%,1/16W,EMPTY,CS00002JB13  I38  R3264
   1 HP_LVC3_OCP_V3_2_R_EN      A @T6G_MB_LIB.T6G(SCH_1):HP_LVC3_OCP_V3_2_R_EN
   2 P3V3_OCP_V3_2_EN_R      B @T6G_MB_LIB.T6G(SCH_1):P3V3_OCP_V3_2_EN_R

Q_RES_0402LF-0,5%,1/16W,EMPTY,CS00002JB13  I41  R1135
   1 HP_LVC3_OCP_V3_1_R_EN      A @T6G_MB_LIB.T6G(SCH_1):HP_LVC3_OCP_V3_1_R_EN
   2 HP_LVC3_OCP_V3_1_P12V_PWRGD      B @T6G_MB_LIB.T6G(SCH_1):HP_LVC3_OCP_V3_1_P12V_PWRGD

Q_RES_0402LF-0,5%,1/16W,CHIP,CS00002JB13  I43  R1500
   1 HP_LVC3_OCP_V3_1_R_EN      A @T6G_MB_LIB.T6G(SCH_1):HP_LVC3_OCP_V3_1_R_EN
   2 P12V_OCP_SFF_BUF_EN_R      B @T6G_MB_LIB.T6G(SCH_1):P12V_OCP_SFF_BUF_EN_R

Q_RES_0402LF-0,5%,1/16W,CHIP,CS00002JB13  I44  R1522
   1 HP_LVC3_OCP_V3_2_R_EN      A @T6G_MB_LIB.T6G(SCH_1):HP_LVC3_OCP_V3_2_R_EN
   2 P12V_OCP_V3_2_BUF_EN_R      B @T6G_MB_LIB.T6G(SCH_1):P12V_OCP_V3_2_BUF_EN_R

Q_RES_0402LF-0,5%,1/16W,EMPTY,CS00002JB13  I45  R1180
   1 HP_LVC3_OCP_V3_2_R_EN      A @T6G_MB_LIB.T6G(SCH_1):HP_LVC3_OCP_V3_2_R_EN
   2 HP_LVC3_OCP_V3_2_P12V_PWRGD      B @T6G_MB_LIB.T6G(SCH_1):HP_LVC3_OCP_V3_2_P12V_PWRGD


DRAWING: @T6G_MB_LIB.T6G(SCH_1):PAGE249 

Q_RES_0402LF-10K,1%,1/16W,CHIP,CS31002FB08  I8  R2666
   1 SMB_BMC_SWB_EN      A @T6G_MB_LIB.T6G(SCH_1):SMB_BMC_SWB_EN
   2    GND      B @T6G_MB_LIB.T6G(SCH_1):GND

Q_RES_0402LF-0,5%,1/16W,CHIP,CS00002JB13  I12  R2992
   1 SMB_BMC_GPU_EN      A @T6G_MB_LIB.T6G(SCH_1):SMB_BMC_GPU_EN
   2 SMB_BMC_GPU_EN_R3      B @T6G_MB_LIB.T6G(SCH_1):SMB_BMC_GPU_EN_R3

Q_RES_0402LF-0,5%,1/16W,CHIP,CS00002JB13  I13  R3107
   1 SMB_2_BMC_GPU_SCL      A @T6G_MB_LIB.T6G(SCH_1):SMB_2_BMC_GPU_SCL
   2 SMB_2_BMC_GPU_R_SCL      B @T6G_MB_LIB.T6G(SCH_1):SMB_2_BMC_GPU_R_SCL

Q_RES_0402LF-0,5%,1/16W,CHIP,CS00002JB13  I14  R3108
   1 SMB_2_BMC_GPU_SDA      A @T6G_MB_LIB.T6G(SCH_1):SMB_2_BMC_GPU_SDA
   2 SMB_2_BMC_GPU_R_SDA      B @T6G_MB_LIB.T6G(SCH_1):SMB_2_BMC_GPU_R_SDA

LTC4307CMS8-LTC4307CMS8,SMLF,IC,AL004307000  I15  U200
   1 SMB_BMC_GPU_EN_R3 ENABLE @T6G_MB_LIB.T6G(SCH_1):SMB_BMC_GPU_EN_R3
   3 SMB_2_BMC_GPU_R_SCL SCL_IN @T6G_MB_LIB.T6G(SCH_1):SMB_2_BMC_GPU_R_SCL
   6 SMB_2_BMC_GPU_R_SDA SDA_IN @T6G_MB_LIB.T6G(SCH_1):SMB_2_BMC_GPU_R_SDA
   2 SMB_2_BMC_GPU_BUF_R_SCL SCL_OUT @T6G_MB_LIB.T6G(SCH_1):SMB_2_BMC_GPU_BUF_R_SCL
   7 SMB_2_BMC_GPU_BUF_R_SDA SDA_OUT @T6G_MB_LIB.T6G(SCH_1):SMB_2_BMC_GPU_BUF_R_SDA
   5     NC  READY     NC
   4    GND    GND @T6G_MB_LIB.T6G(SCH_1):GND
   8 P3V3_AUX    VCC @T6G_MB_LIB.T6G(SCH_1):P3V3_AUX

Q_RES_0402LF-0,5%,1/16W,EMPTY,CS00002JB13  I17  R2987
   1 SMB_2_BMC_GPU_R_SDA      A @T6G_MB_LIB.T6G(SCH_1):SMB_2_BMC_GPU_R_SDA
   2 SMB_2_BMC_GPU_BUF_R_SDA      B @T6G_MB_LIB.T6G(SCH_1):SMB_2_BMC_GPU_BUF_R_SDA

Q_RES_0402LF-0,5%,1/16W,EMPTY,CS00002JB13  I18  R2986
   1 SMB_2_BMC_GPU_R_SCL      A @T6G_MB_LIB.T6G(SCH_1):SMB_2_BMC_GPU_R_SCL
   2 SMB_2_BMC_GPU_BUF_R_SCL      B @T6G_MB_LIB.T6G(SCH_1):SMB_2_BMC_GPU_BUF_R_SCL

Q_RES_0402LF-10K,1%,1/16W,CHIP,CS31002FB08  I23  R4603
   1 SMB_BMC_GPU_EN      A @T6G_MB_LIB.T6G(SCH_1):SMB_BMC_GPU_EN
   2    GND      B @T6G_MB_LIB.T6G(SCH_1):GND

Q_RES_0402LF-33.2,1%,1/16W,CHIP,CS03322FB03  I25  R3112
   1 I3C_BMC_SWB_SCL      A @T6G_MB_LIB.T6G(SCH_1):I3C_BMC_SWB_SCL
   2 I3C_BMC_SWB_R_SCL      B @T6G_MB_LIB.T6G(SCH_1):I3C_BMC_SWB_R_SCL

Q_RES_0402LF-0,5%,1/16W,CHIP,CS00002JB13  I26  R2676
   1 SMB_BMC_SWB_EN      A @T6G_MB_LIB.T6G(SCH_1):SMB_BMC_SWB_EN
   2 SMB_BMC_SWB_EN_R2      B @T6G_MB_LIB.T6G(SCH_1):SMB_BMC_SWB_EN_R2

Q_RES_0402LF-0,5%,1/16W,CHIP,CS00002JB13  I27  R2706
   1 I3C_BMC_SWB_R_SDA      A @T6G_MB_LIB.T6G(SCH_1):I3C_BMC_SWB_R_SDA
   2 I3C_BMC_SWB_BUF_R_SDA      B @T6G_MB_LIB.T6G(SCH_1):I3C_BMC_SWB_BUF_R_SDA

Q_RES_0402LF-0,5%,1/16W,CHIP,CS00002JB13  I28  R2725
   1 I3C_BMC_SWB_R_SCL      A @T6G_MB_LIB.T6G(SCH_1):I3C_BMC_SWB_R_SCL
   2 I3C_BMC_SWB_BUF_R_SCL      B @T6G_MB_LIB.T6G(SCH_1):I3C_BMC_SWB_BUF_R_SCL

LTC4307CMS8-LTC4307CMS8,SMLF,EMPTY,AL004307000  I30  U176
   1 SMB_BMC_SWB_EN_R2 ENABLE @T6G_MB_LIB.T6G(SCH_1):SMB_BMC_SWB_EN_R2
   3 I3C_BMC_SWB_R_SCL SCL_IN @T6G_MB_LIB.T6G(SCH_1):I3C_BMC_SWB_R_SCL
   6 I3C_BMC_SWB_R_SDA SDA_IN @T6G_MB_LIB.T6G(SCH_1):I3C_BMC_SWB_R_SDA
   2 I3C_BMC_SWB_BUF_R_SCL SCL_OUT @T6G_MB_LIB.T6G(SCH_1):I3C_BMC_SWB_BUF_R_SCL
   7 I3C_BMC_SWB_BUF_R_SDA SDA_OUT @T6G_MB_LIB.T6G(SCH_1):I3C_BMC_SWB_BUF_R_SDA
   5     NC  READY     NC
   4    GND    GND @T6G_MB_LIB.T6G(SCH_1):GND
   8 P3V3_AUX    VCC @T6G_MB_LIB.T6G(SCH_1):P3V3_AUX

Q_CAP_0402-0.1UF,25V,10%,X7R,CH4104K1B00  I32  C1796
   1 P3V3_AUX      A @T6G_MB_LIB.T6G(SCH_1):P3V3_AUX
   2    GND      B @T6G_MB_LIB.T6G(SCH_1):GND

Q_RES_0402LF-0,5%,1/16W,CHIP,CS00002JB13  I34  R3110
   1 SMB_1_BMC_GPU_SDA      A @T6G_MB_LIB.T6G(SCH_1):SMB_1_BMC_GPU_SDA
   2 SMB_1_BMC_GPU_R_SDA      B @T6G_MB_LIB.T6G(SCH_1):SMB_1_BMC_GPU_R_SDA

Q_RES_0402LF-0,5%,1/16W,CHIP,CS00002JB13  I35  R3109
   1 SMB_1_BMC_GPU_SCL      A @T6G_MB_LIB.T6G(SCH_1):SMB_1_BMC_GPU_SCL
   2 SMB_1_BMC_GPU_R_SCL      B @T6G_MB_LIB.T6G(SCH_1):SMB_1_BMC_GPU_R_SCL

Q_RES_0402LF-54.9K,1%,1/16W,CHIP,CS35492FB03  I36  R3521
   1 P3V3_AUX      A @T6G_MB_LIB.T6G(SCH_1):P3V3_AUX
   2 SMB_2_BMC_GPU_BUF_R_SCL      B @T6G_MB_LIB.T6G(SCH_1):SMB_2_BMC_GPU_BUF_R_SCL

Q_RES_0402LF-54.9K,1%,1/16W,CHIP,CS35492FB03  I37  R3522
   1 P3V3_AUX      A @T6G_MB_LIB.T6G(SCH_1):P3V3_AUX
   2 SMB_2_BMC_GPU_BUF_R_SDA      B @T6G_MB_LIB.T6G(SCH_1):SMB_2_BMC_GPU_BUF_R_SDA

Q_RES_0402LF-33.2,1%,1/16W,CHIP,CS03322FB03  I38  R2990
   1 SMB_2_BMC_GPU_BUF_R_SCL      A @T6G_MB_LIB.T6G(SCH_1):SMB_2_BMC_GPU_BUF_R_SCL
   2 SMB_2_BMC_GPU_BUF_SCL      B @T6G_MB_LIB.T6G(SCH_1):SMB_2_BMC_GPU_BUF_SCL

Q_RES_0402LF-33.2,1%,1/16W,CHIP,CS03322FB03  I39  R2991
   1 SMB_2_BMC_GPU_BUF_R_SDA      A @T6G_MB_LIB.T6G(SCH_1):SMB_2_BMC_GPU_BUF_R_SDA
   2 SMB_2_BMC_GPU_BUF_SDA      B @T6G_MB_LIB.T6G(SCH_1):SMB_2_BMC_GPU_BUF_SDA

LTC4307CMS8-LTC4307CMS8,SMLF,IC,AL004307000  I42  U194
   1 SMB_BMC_GPU_EN_R1 ENABLE @T6G_MB_LIB.T6G(SCH_1):SMB_BMC_GPU_EN_R1
   3 SMB_1_BMC_GPU_R_SCL SCL_IN @T6G_MB_LIB.T6G(SCH_1):SMB_1_BMC_GPU_R_SCL
   6 SMB_1_BMC_GPU_R_SDA SDA_IN @T6G_MB_LIB.T6G(SCH_1):SMB_1_BMC_GPU_R_SDA
   2 SMB_1_BMC_GPU_BUF_R_SCL SCL_OUT @T6G_MB_LIB.T6G(SCH_1):SMB_1_BMC_GPU_BUF_R_SCL
   7 SMB_1_BMC_GPU_BUF_R_SDA SDA_OUT @T6G_MB_LIB.T6G(SCH_1):SMB_1_BMC_GPU_BUF_R_SDA
   5     NC  READY     NC
   4    GND    GND @T6G_MB_LIB.T6G(SCH_1):GND
   8 P3V3_AUX    VCC @T6G_MB_LIB.T6G(SCH_1):P3V3_AUX

Q_RES_0402LF-0,5%,1/16W,CHIP,CS00002JB13  I43  R3106
   1 SMB_BMC_SWB_SDA      A @T6G_MB_LIB.T6G(SCH_1):SMB_BMC_SWB_SDA
   2 SMB_BMC_SWB_R_SDA      B @T6G_MB_LIB.T6G(SCH_1):SMB_BMC_SWB_R_SDA

Q_RES_0402LF-0,5%,1/16W,CHIP,CS00002JB13  I44  R3105
   1 SMB_BMC_SWB_SCL      A @T6G_MB_LIB.T6G(SCH_1):SMB_BMC_SWB_SCL
   2 SMB_BMC_SWB_R_SCL      B @T6G_MB_LIB.T6G(SCH_1):SMB_BMC_SWB_R_SCL

Q_RES_0402LF-0,5%,1/16W,CHIP,CS00002JB13  I45  R2707
   1 SMB_BMC_SWB_EN      A @T6G_MB_LIB.T6G(SCH_1):SMB_BMC_SWB_EN
   2 SMB_BMC_SWB_EN_R      B @T6G_MB_LIB.T6G(SCH_1):SMB_BMC_SWB_EN_R

Q_RES_0402LF-0,5%,1/16W,EMPTY,CS00002JB13  I47  R2705
   1 SMB_BMC_SWB_R_SCL      A @T6G_MB_LIB.T6G(SCH_1):SMB_BMC_SWB_R_SCL
   2 SMB_BMC_SWB_BUF_R_SCL      B @T6G_MB_LIB.T6G(SCH_1):SMB_BMC_SWB_BUF_R_SCL

Q_RES_0402LF-0,5%,1/16W,EMPTY,CS00002JB13  I48  R2724
   1 SMB_BMC_SWB_R_SDA      A @T6G_MB_LIB.T6G(SCH_1):SMB_BMC_SWB_R_SDA
   2 SMB_BMC_SWB_BUF_R_SDA      B @T6G_MB_LIB.T6G(SCH_1):SMB_BMC_SWB_BUF_R_SDA

LTC4307CMS8-LTC4307CMS8,SMLF,IC,AL004307000  I49  U175
   1 SMB_BMC_SWB_EN_R ENABLE @T6G_MB_LIB.T6G(SCH_1):SMB_BMC_SWB_EN_R
   3 SMB_BMC_SWB_R_SCL SCL_IN @T6G_MB_LIB.T6G(SCH_1):SMB_BMC_SWB_R_SCL
   6 SMB_BMC_SWB_R_SDA SDA_IN @T6G_MB_LIB.T6G(SCH_1):SMB_BMC_SWB_R_SDA
   2 SMB_BMC_SWB_BUF_R_SCL SCL_OUT @T6G_MB_LIB.T6G(SCH_1):SMB_BMC_SWB_BUF_R_SCL
   7 SMB_BMC_SWB_BUF_R_SDA SDA_OUT @T6G_MB_LIB.T6G(SCH_1):SMB_BMC_SWB_BUF_R_SDA
   5     NC  READY     NC
   4    GND    GND @T6G_MB_LIB.T6G(SCH_1):GND
   8 P3V3_AUX    VCC @T6G_MB_LIB.T6G(SCH_1):P3V3_AUX

Q_RES_0402LF-0,5%,1/16W,CHIP,CS00002JB13  I50  R2899
   1 SMB_BMC_GPU_EN      A @T6G_MB_LIB.T6G(SCH_1):SMB_BMC_GPU_EN
   2 SMB_BMC_GPU_EN_R1      B @T6G_MB_LIB.T6G(SCH_1):SMB_BMC_GPU_EN_R1

Q_CAP_0402-0.1UF,25V,10%,X7R,CH4104K1B00  I52  C1707
   1 P3V3_AUX      A @T6G_MB_LIB.T6G(SCH_1):P3V3_AUX
   2    GND      B @T6G_MB_LIB.T6G(SCH_1):GND

Q_RES_0402LF-2.2K,5%,1/16W,CHIP,CS22202JB07  I54  R2667
   1 P3V3_AUX      A @T6G_MB_LIB.T6G(SCH_1):P3V3_AUX
   2 SMB_BMC_SWB_BUF_R_SCL      B @T6G_MB_LIB.T6G(SCH_1):SMB_BMC_SWB_BUF_R_SCL

Q_RES_0402LF-33.2,1%,1/16W,CHIP,CS03322FB03  I56  R2672
   1 SMB_BMC_SWB_BUF_R_SDA      A @T6G_MB_LIB.T6G(SCH_1):SMB_BMC_SWB_BUF_R_SDA
   2 SMB_BMC_SWB_BUF_SDA      B @T6G_MB_LIB.T6G(SCH_1):SMB_BMC_SWB_BUF_SDA

Q_RES_0402LF-2.2K,5%,1/16W,CHIP,CS22202JB07  I57  R2669
   1 P3V3_AUX      A @T6G_MB_LIB.T6G(SCH_1):P3V3_AUX
   2 SMB_BMC_SWB_BUF_R_SDA      B @T6G_MB_LIB.T6G(SCH_1):SMB_BMC_SWB_BUF_R_SDA

Q_RES_0402LF-33.2,1%,1/16W,CHIP,CS03322FB03  I58  R2671
   1 SMB_BMC_SWB_BUF_R_SCL      A @T6G_MB_LIB.T6G(SCH_1):SMB_BMC_SWB_BUF_R_SCL
   2 SMB_BMC_SWB_BUF_SCL      B @T6G_MB_LIB.T6G(SCH_1):SMB_BMC_SWB_BUF_SCL

Q_CAP_0402-0.1UF,25V,10%,X7R,CH4104K1B00  I61  C1708
   1 P3V3_AUX      A @T6G_MB_LIB.T6G(SCH_1):P3V3_AUX
   2    GND      B @T6G_MB_LIB.T6G(SCH_1):GND

Q_RES_0402LF-4.7K,5%,1/16W,EMPTY,CS24702JB10  I62  R2668
   1 P3V3_AUX      A @T6G_MB_LIB.T6G(SCH_1):P3V3_AUX
   2 I3C_BMC_SWB_BUF_R_SDA      B @T6G_MB_LIB.T6G(SCH_1):I3C_BMC_SWB_BUF_R_SDA

Q_RES_0402LF-4.7K,5%,1/16W,EMPTY,CS24702JB10  I63  R2670
   1 P3V3_AUX      A @T6G_MB_LIB.T6G(SCH_1):P3V3_AUX
   2 I3C_BMC_SWB_BUF_R_SCL      B @T6G_MB_LIB.T6G(SCH_1):I3C_BMC_SWB_BUF_R_SCL

Q_RES_0402LF-0,5%,1/16W,EMPTY,CS00002JB13  I67  R2894
   1 SMB_1_BMC_GPU_R_SDA      A @T6G_MB_LIB.T6G(SCH_1):SMB_1_BMC_GPU_R_SDA
   2 SMB_1_BMC_GPU_BUF_R_SDA      B @T6G_MB_LIB.T6G(SCH_1):SMB_1_BMC_GPU_BUF_R_SDA

Q_RES_0402LF-0,5%,1/16W,EMPTY,CS00002JB13  I68  R2893
   1 SMB_1_BMC_GPU_R_SCL      A @T6G_MB_LIB.T6G(SCH_1):SMB_1_BMC_GPU_R_SCL
   2 SMB_1_BMC_GPU_BUF_R_SCL      B @T6G_MB_LIB.T6G(SCH_1):SMB_1_BMC_GPU_BUF_R_SCL

Q_RES_0402LF-33.2,1%,1/16W,CHIP,CS03322FB03  I69  R2675
   1 I3C_BMC_SWB_BUF_R_SCL      A @T6G_MB_LIB.T6G(SCH_1):I3C_BMC_SWB_BUF_R_SCL
   2 I3C_BMC_SWB_BUF_SCL      B @T6G_MB_LIB.T6G(SCH_1):I3C_BMC_SWB_BUF_SCL

Q_RES_0402LF-33.2,1%,1/16W,CHIP,CS03322FB03  I73  R2898
   1 SMB_1_BMC_GPU_BUF_R_SDA      A @T6G_MB_LIB.T6G(SCH_1):SMB_1_BMC_GPU_BUF_R_SDA
   2 SMB_1_BMC_GPU_BUF_SDA      B @T6G_MB_LIB.T6G(SCH_1):SMB_1_BMC_GPU_BUF_SDA

Q_RES_0402LF-33.2,1%,1/16W,CHIP,CS03322FB03  I74  R2897
   1 SMB_1_BMC_GPU_BUF_R_SCL      A @T6G_MB_LIB.T6G(SCH_1):SMB_1_BMC_GPU_BUF_R_SCL
   2 SMB_1_BMC_GPU_BUF_SCL      B @T6G_MB_LIB.T6G(SCH_1):SMB_1_BMC_GPU_BUF_SCL

Q_CAP_0402-0.1UF,25V,10%,X7R,CH4104K1B00  I78  C1766
   1 P3V3_AUX      A @T6G_MB_LIB.T6G(SCH_1):P3V3_AUX
   2    GND      B @T6G_MB_LIB.T6G(SCH_1):GND

Q_RES_0402LF-54.9K,1%,1/16W,CHIP,CS35492FB03  I80  R3523
   1 P3V3_AUX      A @T6G_MB_LIB.T6G(SCH_1):P3V3_AUX
   2 SMB_1_BMC_GPU_BUF_R_SCL      B @T6G_MB_LIB.T6G(SCH_1):SMB_1_BMC_GPU_BUF_R_SCL

Q_RES_0402LF-54.9K,1%,1/16W,CHIP,CS35492FB03  I81  R3524
   1 P3V3_AUX      A @T6G_MB_LIB.T6G(SCH_1):P3V3_AUX
   2 SMB_1_BMC_GPU_BUF_R_SDA      B @T6G_MB_LIB.T6G(SCH_1):SMB_1_BMC_GPU_BUF_R_SDA

Q_RES_0402LF-0,5%,1/16W,CHIP,CS00002JB13  I85  R3111
   1 I3C_BMC_SWB_SDA      A @T6G_MB_LIB.T6G(SCH_1):I3C_BMC_SWB_SDA
   2 I3C_BMC_SWB_R_SDA      B @T6G_MB_LIB.T6G(SCH_1):I3C_BMC_SWB_R_SDA

Q_RES_0402LF-27,5%,1/16W,CHIP,CS02702JB02  I86  R2674
   1 I3C_BMC_SWB_BUF_R_SDA      A @T6G_MB_LIB.T6G(SCH_1):I3C_BMC_SWB_BUF_R_SDA
   2 I3C_BMC_SWB_BUF_SDA      B @T6G_MB_LIB.T6G(SCH_1):I3C_BMC_SWB_BUF_SDA


DRAWING: @T6G_MB_LIB.T6G(SCH_1):PAGE137 

Q_CAP_0402-0.1UF,25V,10%,X7R,CH4104K1B00  I6  C611
   1 P3V3_AUX      A @T6G_MB_LIB.T6G(SCH_1):P3V3_AUX
   2    GND      B @T6G_MB_LIB.T6G(SCH_1):GND

Q_CAP_0402-0.1UF,25V,10%,X7R,CH4104K1B00  I8  C612
   1 PVDD18_S5_P0      A @T6G_MB_LIB.T6G(SCH_1):PVDD18_S5_P0
   2    GND      B @T6G_MB_LIB.T6G(SCH_1):GND

Q_RES_0402LF-4.7K,5%,1/16W,EMPTY,CS24702JB10  I13  R200
   1 P3V3_AUX      A @T6G_MB_LIB.T6G(SCH_1):P3V3_AUX
   2 PU_U96_EN      B @T6G_MB_LIB.T6G(SCH_1):PU_U96_EN

Q_RES_0402LF-0,5%,1/16W,CHIP,CS00002JB13  I15  R1154
   1 SMB_CPU0_CPU1_SEC_SDA_R1      A @T6G_MB_LIB.T6G(SCH_1):SMB_CPU0_CPU1_SEC_SDA_R1
   2 SMB_CPU0_CPU1_SEC_SDA_R2      B @T6G_MB_LIB.T6G(SCH_1):SMB_CPU0_CPU1_SEC_SDA_R2

Q_RES_0402LF-0,5%,1/16W,CHIP,CS00002JB13  I16  R1153
   1 SMB_CPU0_CPU1_SEC_SCL_R1      A @T6G_MB_LIB.T6G(SCH_1):SMB_CPU0_CPU1_SEC_SCL_R1
   2 SMB_CPU0_CPU1_SEC_SCL_R2      B @T6G_MB_LIB.T6G(SCH_1):SMB_CPU0_CPU1_SEC_SCL_R2

Q_CAP_0402-0.1UF,25V,10%,X7R,CH4104K1B00  I26  C23
   1 P3V3_AUX      A @T6G_MB_LIB.T6G(SCH_1):P3V3_AUX
   2    GND      B @T6G_MB_LIB.T6G(SCH_1):GND

Q_CAP_0402-0.1UF,25V,10%,X7R,CH4104K1B00  I29  C26
   1   P3V3      A @T6G_MB_LIB.T6G(SCH_1):P3V3
   2    GND      B @T6G_MB_LIB.T6G(SCH_1):GND

Q_RES_0402LF-4.7K,5%,1/16W,EMPTY,CS24702JB10  I31  R78
   1   P3V3      A @T6G_MB_LIB.T6G(SCH_1):P3V3
   2 PU_U5_EN      B @T6G_MB_LIB.T6G(SCH_1):PU_U5_EN

Q_RES_0402LF-4.7K,5%,1/16W,EMPTY,CS24702JB10  I40  R361
   1   P3V3      A @T6G_MB_LIB.T6G(SCH_1):P3V3
   2 SMB_CPU0_CPU1_APML_BUF1_SCL_R2      B @T6G_MB_LIB.T6G(SCH_1):SMB_CPU0_CPU1_APML_BUF1_SCL_R2

Q_RES_0402LF-4.7K,5%,1/16W,EMPTY,CS24702JB10  I41  R365
   1   P3V3      A @T6G_MB_LIB.T6G(SCH_1):P3V3
   2 SMB_CPU0_CPU1_APML_BUF1_SDA_R2      B @T6G_MB_LIB.T6G(SCH_1):SMB_CPU0_CPU1_APML_BUF1_SDA_R2

Q_RES_0402LF-4.7K,5%,1/16W,EMPTY,CS24702JB10  I44  R368
   1 PVDD18_S5_P0      A @T6G_MB_LIB.T6G(SCH_1):PVDD18_S5_P0
   2 SMB_CPU0_CPU1_SEC_SCL_R2      B @T6G_MB_LIB.T6G(SCH_1):SMB_CPU0_CPU1_SEC_SCL_R2

Q_RES_0402LF-4.7K,5%,1/16W,EMPTY,CS24702JB10  I46  R406
   1 PVDD18_S5_P0      A @T6G_MB_LIB.T6G(SCH_1):PVDD18_S5_P0
   2 SMB_CPU0_CPU1_SEC_SDA_R2      B @T6G_MB_LIB.T6G(SCH_1):SMB_CPU0_CPU1_SEC_SDA_R2

PCA9617ADP-PCA9617ADP,SMLF,EMPTY,AL009617K02  I48  U5
   5 PU_U5_EN     EN @T6G_MB_LIB.T6G(SCH_1):PU_U5_EN
   1 P3V3_AUX   VCCA @T6G_MB_LIB.T6G(SCH_1):P3V3_AUX
   8   P3V3   VCCB @T6G_MB_LIB.T6G(SCH_1):P3V3
   2 SMB_CPU0_CPU1_APML_BUF1_SCL   SCLA @T6G_MB_LIB.T6G(SCH_1):SMB_CPU0_CPU1_APML_BUF1_SCL
   3 SMB_CPU0_CPU1_APML_BUF1_SDA   SDAA @T6G_MB_LIB.T6G(SCH_1):SMB_CPU0_CPU1_APML_BUF1_SDA
   6 SMB_CPU0_CPU1_APML_BUF1_SDA_R1   SDAB @T6G_MB_LIB.T6G(SCH_1):SMB_CPU0_CPU1_APML_BUF1_SDA_R1
   7 SMB_CPU0_CPU1_APML_BUF1_SCL_R1   SCLB @T6G_MB_LIB.T6G(SCH_1):SMB_CPU0_CPU1_APML_BUF1_SCL_R1
   4    GND    GND @T6G_MB_LIB.T6G(SCH_1):GND

PCA9617ADP-PCA9617ADP,SMLF,IC,AL009617K02  I51  U96
   5 PU_U96_EN     EN @T6G_MB_LIB.T6G(SCH_1):PU_U96_EN
   1 PVDD18_S5_P0   VCCA @T6G_MB_LIB.T6G(SCH_1):PVDD18_S5_P0
   8 P3V3_AUX   VCCB @T6G_MB_LIB.T6G(SCH_1):P3V3_AUX
   2 SMB_CPU0_CPU1_SEC_SCL_R1   SCLA @T6G_MB_LIB.T6G(SCH_1):SMB_CPU0_CPU1_SEC_SCL_R1
   3 SMB_CPU0_CPU1_SEC_SDA_R1   SDAA @T6G_MB_LIB.T6G(SCH_1):SMB_CPU0_CPU1_SEC_SDA_R1
   6 SMB_CPU0_CPU1_SEC_SDA   SDAB @T6G_MB_LIB.T6G(SCH_1):SMB_CPU0_CPU1_SEC_SDA
   7 SMB_CPU0_CPU1_SEC_SCL   SCLB @T6G_MB_LIB.T6G(SCH_1):SMB_CPU0_CPU1_SEC_SCL
   4    GND    GND @T6G_MB_LIB.T6G(SCH_1):GND

Q_CAP_0402-0.1UF,25V,10%,X7R,CH4104K1B00  I56  C3
   1 PVDD11_S3_P0      A @T6G_MB_LIB.T6G(SCH_1):PVDD11_S3_P0
   2    GND      B @T6G_MB_LIB.T6G(SCH_1):GND

Q_CAP_0402-0.1UF,25V,10%,X7R,CH4104K1B00  I59  C2
   1 P3V3_AUX      A @T6G_MB_LIB.T6G(SCH_1):P3V3_AUX
   2    GND      B @T6G_MB_LIB.T6G(SCH_1):GND

Q_RES_0402LF-4.7K,5%,1/16W,EMPTY,CS24702JB10  I62  R201
   1 P3V3_AUX      A @T6G_MB_LIB.T6G(SCH_1):P3V3_AUX
   2 PU_U2_EN      B @T6G_MB_LIB.T6G(SCH_1):PU_U2_EN

Q_RES_0402LF-0,5%,1/16W,CHIP,CS00002JB13  I67  R202
   1 SMB_CPU0_CPU1_APML_BUF2_SCL_R1      A @T6G_MB_LIB.T6G(SCH_1):SMB_CPU0_CPU1_APML_BUF2_SCL_R1
   2 SMB_CPU0_CPU1_APML_BUF2_SCL_R2      B @T6G_MB_LIB.T6G(SCH_1):SMB_CPU0_CPU1_APML_BUF2_SCL_R2

Q_RES_0402LF-0,5%,1/16W,CHIP,CS00002JB13  I68  R206
   1 SMB_CPU0_CPU1_APML_BUF2_SDA_R1      A @T6G_MB_LIB.T6G(SCH_1):SMB_CPU0_CPU1_APML_BUF2_SDA_R1
   2 SMB_CPU0_CPU1_APML_BUF2_SDA_R2      B @T6G_MB_LIB.T6G(SCH_1):SMB_CPU0_CPU1_APML_BUF2_SDA_R2

Q_RES_0402LF-0,5%,1/16W,CHIP,CS00002JB13  I71  R274
   1 SMB_CPU0_CPU1_APML_BUF2_SCL_R2      A @T6G_MB_LIB.T6G(SCH_1):SMB_CPU0_CPU1_APML_BUF2_SCL_R2
   2 SMB_CPU0_CPU1_APML_SCL_R2      B @T6G_MB_LIB.T6G(SCH_1):SMB_CPU0_CPU1_APML_SCL_R2

Q_RES_0402LF-0,5%,1/16W,CHIP,CS00002JB13  I72  R281
   1 SMB_CPU0_CPU1_APML_BUF2_SDA_R2      A @T6G_MB_LIB.T6G(SCH_1):SMB_CPU0_CPU1_APML_BUF2_SDA_R2
   2 SMB_CPU0_CPU1_APML_SDA_R2      B @T6G_MB_LIB.T6G(SCH_1):SMB_CPU0_CPU1_APML_SDA_R2

Q_RES_0402LF-1K,1%,1/16W,EMPTY,CS21002FB06  I73  R322
   1 PVDD11_S3_P0      A @T6G_MB_LIB.T6G(SCH_1):PVDD11_S3_P0
   2 SMB_CPU0_CPU1_APML_BUF2_SCL_R2      B @T6G_MB_LIB.T6G(SCH_1):SMB_CPU0_CPU1_APML_BUF2_SCL_R2

Q_RES_0402LF-1K,1%,1/16W,EMPTY,CS21002FB06  I78  R290
   1 PVDD11_S3_P0      A @T6G_MB_LIB.T6G(SCH_1):PVDD11_S3_P0
   2 SMB_CPU0_CPU1_APML_BUF2_SDA_R2      B @T6G_MB_LIB.T6G(SCH_1):SMB_CPU0_CPU1_APML_BUF2_SDA_R2

Q_RES_0402LF-0,5%,1/16W,CHIP,CS00002JB13  I79  R151
   1 SMB_CPU0_CPU1_APML_SCL      A @T6G_MB_LIB.T6G(SCH_1):SMB_CPU0_CPU1_APML_SCL
   2 SMB_CPU0_CPU1_APML_BUF2_SCL      B @T6G_MB_LIB.T6G(SCH_1):SMB_CPU0_CPU1_APML_BUF2_SCL

Q_RES_0402LF-0,5%,1/16W,CHIP,CS00002JB13  I80  R162
   1 SMB_CPU0_CPU1_APML_SDA      A @T6G_MB_LIB.T6G(SCH_1):SMB_CPU0_CPU1_APML_SDA
   2 SMB_CPU0_CPU1_APML_BUF2_SDA      B @T6G_MB_LIB.T6G(SCH_1):SMB_CPU0_CPU1_APML_BUF2_SDA

Q_RES_0402LF-0,5%,1/16W,EMPTY,CS00002JB13  I91  R257
   1 SMB_CPU0_CPU1_APML_BUF1_SDA_R2      A @T6G_MB_LIB.T6G(SCH_1):SMB_CPU0_CPU1_APML_BUF1_SDA_R2
   2 SMB_CPU0_CPU1_APML_SDA_R2      B @T6G_MB_LIB.T6G(SCH_1):SMB_CPU0_CPU1_APML_SDA_R2

Q_RES_0402LF-0,5%,1/16W,EMPTY,CS00002JB13  I92  R256
   1 SMB_CPU0_CPU1_APML_BUF1_SCL_R2      A @T6G_MB_LIB.T6G(SCH_1):SMB_CPU0_CPU1_APML_BUF1_SCL_R2
   2 SMB_CPU0_CPU1_APML_SCL_R2      B @T6G_MB_LIB.T6G(SCH_1):SMB_CPU0_CPU1_APML_SCL_R2

Q_RES_0402LF-0,5%,1/16W,EMPTY,CS00002JB13  I93  R1151
   1 SMB_CPU0_CPU1_APML_BUF1_SCL_R1      A @T6G_MB_LIB.T6G(SCH_1):SMB_CPU0_CPU1_APML_BUF1_SCL_R1
   2 SMB_CPU0_CPU1_APML_BUF1_SCL_R2      B @T6G_MB_LIB.T6G(SCH_1):SMB_CPU0_CPU1_APML_BUF1_SCL_R2

Q_RES_0402LF-0,5%,1/16W,EMPTY,CS00002JB13  I94  R1152
   1 SMB_CPU0_CPU1_APML_BUF1_SDA_R1      A @T6G_MB_LIB.T6G(SCH_1):SMB_CPU0_CPU1_APML_BUF1_SDA_R1
   2 SMB_CPU0_CPU1_APML_BUF1_SDA_R2      B @T6G_MB_LIB.T6G(SCH_1):SMB_CPU0_CPU1_APML_BUF1_SDA_R2

Q_RES_0402LF-0,5%,1/16W,EMPTY,CS00002JB13  I95  R790
   1 SMB_CPU0_CPU1_APML_BUF1_SDA      A @T6G_MB_LIB.T6G(SCH_1):SMB_CPU0_CPU1_APML_BUF1_SDA
   2 SMB_CPU0_CPU1_APML_BUF1_SDA_R1      B @T6G_MB_LIB.T6G(SCH_1):SMB_CPU0_CPU1_APML_BUF1_SDA_R1

Q_RES_0402LF-0,5%,1/16W,EMPTY,CS00002JB13  I96  R789
   1 SMB_CPU0_CPU1_APML_BUF1_SCL      A @T6G_MB_LIB.T6G(SCH_1):SMB_CPU0_CPU1_APML_BUF1_SCL
   2 SMB_CPU0_CPU1_APML_BUF1_SCL_R1      B @T6G_MB_LIB.T6G(SCH_1):SMB_CPU0_CPU1_APML_BUF1_SCL_R1

Q_RES_0402LF-0,5%,1/16W,EMPTY,CS00002JB13  I97  R150
   1 SMB_CPU0_CPU1_APML_SDA      A @T6G_MB_LIB.T6G(SCH_1):SMB_CPU0_CPU1_APML_SDA
   2 SMB_CPU0_CPU1_APML_BUF1_SDA      B @T6G_MB_LIB.T6G(SCH_1):SMB_CPU0_CPU1_APML_BUF1_SDA

Q_RES_0402LF-0,5%,1/16W,EMPTY,CS00002JB13  I98  R140
   1 SMB_CPU0_CPU1_APML_SCL      A @T6G_MB_LIB.T6G(SCH_1):SMB_CPU0_CPU1_APML_SCL
   2 SMB_CPU0_CPU1_APML_BUF1_SCL      B @T6G_MB_LIB.T6G(SCH_1):SMB_CPU0_CPU1_APML_BUF1_SCL

PCA9617ADP-PCA9617ADP,SMLF,IC,AL009617K02  I99  U2
   5 PU_U2_EN     EN @T6G_MB_LIB.T6G(SCH_1):PU_U2_EN
   1 PVDD11_S3_P0   VCCA @T6G_MB_LIB.T6G(SCH_1):PVDD11_S3_P0
   8 P3V3_AUX   VCCB @T6G_MB_LIB.T6G(SCH_1):P3V3_AUX
   2 SMB_CPU0_CPU1_APML_BUF2_SCL_R1   SCLA @T6G_MB_LIB.T6G(SCH_1):SMB_CPU0_CPU1_APML_BUF2_SCL_R1
   3 SMB_CPU0_CPU1_APML_BUF2_SDA_R1   SDAA @T6G_MB_LIB.T6G(SCH_1):SMB_CPU0_CPU1_APML_BUF2_SDA_R1
   6 SMB_CPU0_CPU1_APML_BUF2_SDA   SDAB @T6G_MB_LIB.T6G(SCH_1):SMB_CPU0_CPU1_APML_BUF2_SDA
   7 SMB_CPU0_CPU1_APML_BUF2_SCL   SCLB @T6G_MB_LIB.T6G(SCH_1):SMB_CPU0_CPU1_APML_BUF2_SCL
   4    GND    GND @T6G_MB_LIB.T6G(SCH_1):GND


DRAWING: @T6G_MB_LIB.T6G(SCH_1):PAGE251 

Q_RES_0402LF-1K,1%,1/16W,CHIP,CS21002FB06  I1  R3704
   1 PCA9548_PCIE0_ADDR2      A @T6G_MB_LIB.T6G(SCH_1):PCA9548_PCIE0_ADDR2
   2    GND      B @T6G_MB_LIB.T6G(SCH_1):GND

Q_RES_0402LF-1K,1%,1/16W,CHIP,CS21002FB06  I4  R3707
   1 PCA9548_PCIE0_ADDR1      A @T6G_MB_LIB.T6G(SCH_1):PCA9548_PCIE0_ADDR1
   2    GND      B @T6G_MB_LIB.T6G(SCH_1):GND

Q_RES_0402LF-1K,1%,1/16W,CHIP,CS21002FB06  I6  R3709
   1 PCA9548_PCIE0_ADDR0      A @T6G_MB_LIB.T6G(SCH_1):PCA9548_PCIE0_ADDR0
   2    GND      B @T6G_MB_LIB.T6G(SCH_1):GND

Q_RES_0402LF-10K,1%,1/16W,EMPTY,CS31002FB08  I7  R3703
   1 P3V3_AUX      A @T6G_MB_LIB.T6G(SCH_1):P3V3_AUX
   2 PCA9548_PCIE0_ADDR2      B @T6G_MB_LIB.T6G(SCH_1):PCA9548_PCIE0_ADDR2

Q_RES_0402LF-10K,1%,1/16W,EMPTY,CS31002FB08  I8  R3706
   1 P3V3_AUX      A @T6G_MB_LIB.T6G(SCH_1):P3V3_AUX
   2 PCA9548_PCIE0_ADDR1      B @T6G_MB_LIB.T6G(SCH_1):PCA9548_PCIE0_ADDR1

Q_RES_0402LF-10K,1%,1/16W,EMPTY,CS31002FB08  I10  R3708
   1 P3V3_AUX      A @T6G_MB_LIB.T6G(SCH_1):P3V3_AUX
   2 PCA9548_PCIE0_ADDR0      B @T6G_MB_LIB.T6G(SCH_1):PCA9548_PCIE0_ADDR0

Q_RES_0402LF-0,5%,1/16W,CHIP,CS00002JB13  I18  R3719
   1 SMB_LM75_2_3V3AUX_SCL_R      A @T6G_MB_LIB.T6G(SCH_1):SMB_LM75_2_3V3AUX_SCL_R
   2 SMB_LM75_2_3V3AUX_SCL      B @T6G_MB_LIB.T6G(SCH_1):SMB_LM75_2_3V3AUX_SCL

Q_RES_0402LF-0,5%,1/16W,CHIP,CS00002JB13  I19  R3720
   1 SMB_LM75_2_3V3AUX_SDA_R      A @T6G_MB_LIB.T6G(SCH_1):SMB_LM75_2_3V3AUX_SDA_R
   2 SMB_LM75_2_3V3AUX_SDA      B @T6G_MB_LIB.T6G(SCH_1):SMB_LM75_2_3V3AUX_SDA

Q_RES_0402LF-0,5%,1/16W,CHIP,CS00002JB13  I20  R3717
   1 SMB_LM75_1_3V3AUX_SCL_R      A @T6G_MB_LIB.T6G(SCH_1):SMB_LM75_1_3V3AUX_SCL_R
   2 SMB_LM75_1_3V3AUX_SCL      B @T6G_MB_LIB.T6G(SCH_1):SMB_LM75_1_3V3AUX_SCL

Q_RES_0402LF-0,5%,1/16W,CHIP,CS00002JB13  I21  R3718
   1 SMB_LM75_1_3V3AUX_SDA_R      A @T6G_MB_LIB.T6G(SCH_1):SMB_LM75_1_3V3AUX_SDA_R
   2 SMB_LM75_1_3V3AUX_SDA      B @T6G_MB_LIB.T6G(SCH_1):SMB_LM75_1_3V3AUX_SDA

Q_RES_0402LF-10K,1%,1/16W,EMPTY,CS31002FB08  I27  R3705
   1 P3V3_AUX      A @T6G_MB_LIB.T6G(SCH_1):P3V3_AUX
   2 RST_SMB_SWITCH_N      B @T6G_MB_LIB.T6G(SCH_1):RST_SMB_SWITCH_N

Q_RES_0402LF-0,5%,1/16W,CHIP,CS00002JB13  I29  R3710
   1 RST_SMB_SWITCH_N      A @T6G_MB_LIB.T6G(SCH_1):RST_SMB_SWITCH_N
   2 PU_RST_SMB_PCIE2_N      B @T6G_MB_LIB.T6G(SCH_1):PU_RST_SMB_PCIE2_N

Q_RES_0402LF-0,5%,1/16W,CHIP,CS00002JB13  I30  R3716
   1 SMB_LM75_0_3V3AUX_SDA_R      A @T6G_MB_LIB.T6G(SCH_1):SMB_LM75_0_3V3AUX_SDA_R
   2 SMB_LM75_0_3V3AUX_SDA      B @T6G_MB_LIB.T6G(SCH_1):SMB_LM75_0_3V3AUX_SDA

Q_RES_0402LF-0,5%,1/16W,CHIP,CS00002JB13  I31  R3715
   1 SMB_LM75_0_3V3AUX_SCL_R      A @T6G_MB_LIB.T6G(SCH_1):SMB_LM75_0_3V3AUX_SCL_R
   2 SMB_LM75_0_3V3AUX_SCL      B @T6G_MB_LIB.T6G(SCH_1):SMB_LM75_0_3V3AUX_SCL

Q_RES_0402LF-0,5%,1/16W,CHIP,CS00002JB13  I32  R3714
   1 SMB_VR_3V3AUX_SDA_R6      A @T6G_MB_LIB.T6G(SCH_1):SMB_VR_3V3AUX_SDA_R6
   2 SMB_VR_3V3AUX_SDA      B @T6G_MB_LIB.T6G(SCH_1):SMB_VR_3V3AUX_SDA

Q_RES_0402LF-0,5%,1/16W,CHIP,CS00002JB13  I33  R3713
   1 SMB_VR_3V3AUX_SCL_R6      A @T6G_MB_LIB.T6G(SCH_1):SMB_VR_3V3AUX_SCL_R6
   2 SMB_VR_3V3AUX_SCL      B @T6G_MB_LIB.T6G(SCH_1):SMB_VR_3V3AUX_SCL

Q_CAP_0402-0.1UF,25V,10%,X7R,CH4104K1B00  I38  C2056
   1 P3V3_AUX      A @T6G_MB_LIB.T6G(SCH_1):P3V3_AUX
   2    GND      B @T6G_MB_LIB.T6G(SCH_1):GND

Q_RES_0402LF-2.2K,5%,1/16W,EMPTY,CS22202JB07  I40  R4270
   1 P3V3_AUX      A @T6G_MB_LIB.T6G(SCH_1):P3V3_AUX
   2 SMB_VR_SENSOR_3V3AUX_SDA      B @T6G_MB_LIB.T6G(SCH_1):SMB_VR_SENSOR_3V3AUX_SDA

Q_RES_0402LF-2.2K,5%,1/16W,EMPTY,CS22202JB07  I41  R4269
   1 P3V3_AUX      A @T6G_MB_LIB.T6G(SCH_1):P3V3_AUX
   2 SMB_VR_SENSOR_3V3AUX_SCL      B @T6G_MB_LIB.T6G(SCH_1):SMB_VR_SENSOR_3V3AUX_SCL

Q_RES_0402LF-2.2K,5%,1/16W,CHIP,CS22202JB07  I42  R3732
   1 P3V3_AUX      A @T6G_MB_LIB.T6G(SCH_1):P3V3_AUX
   2 SMB_LM75_3_3V3AUX_SDA      B @T6G_MB_LIB.T6G(SCH_1):SMB_LM75_3_3V3AUX_SDA

Q_RES_0402LF-2.2K,5%,1/16W,CHIP,CS22202JB07  I43  R3731
   1 P3V3_AUX      A @T6G_MB_LIB.T6G(SCH_1):P3V3_AUX
   2 SMB_LM75_3_3V3AUX_SCL      B @T6G_MB_LIB.T6G(SCH_1):SMB_LM75_3_3V3AUX_SCL

Q_RES_0402LF-2.2K,5%,1/16W,CHIP,CS22202JB07  I44  R3729
   1 P3V3_AUX      A @T6G_MB_LIB.T6G(SCH_1):P3V3_AUX
   2 SMB_LM75_2_3V3AUX_SCL      B @T6G_MB_LIB.T6G(SCH_1):SMB_LM75_2_3V3AUX_SCL

Q_RES_0402LF-2.2K,5%,1/16W,CHIP,CS22202JB07  I45  R3730
   1 P3V3_AUX      A @T6G_MB_LIB.T6G(SCH_1):P3V3_AUX
   2 SMB_LM75_2_3V3AUX_SDA      B @T6G_MB_LIB.T6G(SCH_1):SMB_LM75_2_3V3AUX_SDA

Q_RES_0402LF-2.2K,5%,1/16W,CHIP,CS22202JB07  I47  R3728
   1 P3V3_AUX      A @T6G_MB_LIB.T6G(SCH_1):P3V3_AUX
   2 SMB_LM75_1_3V3AUX_SDA      B @T6G_MB_LIB.T6G(SCH_1):SMB_LM75_1_3V3AUX_SDA

Q_RES_0402LF-2.2K,5%,1/16W,CHIP,CS22202JB07  I48  R3727
   1 P3V3_AUX      A @T6G_MB_LIB.T6G(SCH_1):P3V3_AUX
   2 SMB_LM75_1_3V3AUX_SCL      B @T6G_MB_LIB.T6G(SCH_1):SMB_LM75_1_3V3AUX_SCL

Q_RES_0402LF-2.2K,5%,1/16W,CHIP,CS22202JB07  I49  R3726
   1 P3V3_AUX      A @T6G_MB_LIB.T6G(SCH_1):P3V3_AUX
   2 SMB_LM75_0_3V3AUX_SDA      B @T6G_MB_LIB.T6G(SCH_1):SMB_LM75_0_3V3AUX_SDA

Q_RES_0402LF-2.2K,5%,1/16W,CHIP,CS22202JB07  I50  R3725
   1 P3V3_AUX      A @T6G_MB_LIB.T6G(SCH_1):P3V3_AUX
   2 SMB_LM75_0_3V3AUX_SCL      B @T6G_MB_LIB.T6G(SCH_1):SMB_LM75_0_3V3AUX_SCL

Q_RES_0402LF-2.2K,5%,1/16W,CHIP,CS22202JB07  I52  R3724
   1 P3V3_AUX      A @T6G_MB_LIB.T6G(SCH_1):P3V3_AUX
   2 SMB_VR_3V3AUX_SDA      B @T6G_MB_LIB.T6G(SCH_1):SMB_VR_3V3AUX_SDA

Q_RES_0402LF-2.2K,5%,1/16W,CHIP,CS22202JB07  I53  R3723
   1 P3V3_AUX      A @T6G_MB_LIB.T6G(SCH_1):P3V3_AUX
   2 SMB_VR_3V3AUX_SCL      B @T6G_MB_LIB.T6G(SCH_1):SMB_VR_3V3AUX_SCL

Q_RES_0402LF-0,5%,1/16W,CHIP,CS00002JB13  I66  R3722
   1 SMB_LM75_3_3V3AUX_SDA_R      A @T6G_MB_LIB.T6G(SCH_1):SMB_LM75_3_3V3AUX_SDA_R
   2 SMB_LM75_3_3V3AUX_SDA      B @T6G_MB_LIB.T6G(SCH_1):SMB_LM75_3_3V3AUX_SDA

Q_RES_0402LF-0,5%,1/16W,CHIP,CS00002JB13  I67  R3721
   1 SMB_LM75_3_3V3AUX_SCL_R      A @T6G_MB_LIB.T6G(SCH_1):SMB_LM75_3_3V3AUX_SCL_R
   2 SMB_LM75_3_3V3AUX_SCL      B @T6G_MB_LIB.T6G(SCH_1):SMB_LM75_3_3V3AUX_SCL

Q_RES_0402LF-33.2,1%,1/16W,CHIP,CS03322FB03  I68  R3712
   1 SMB_VR_SENSOR_3V3AUX_SDA      A @T6G_MB_LIB.T6G(SCH_1):SMB_VR_SENSOR_3V3AUX_SDA
   2 SMB_VR_SENSOR_3V3AUX_SDA_R      B @T6G_MB_LIB.T6G(SCH_1):SMB_VR_SENSOR_3V3AUX_SDA_R

Q_RES_0402LF-33.2,1%,1/16W,CHIP,CS03322FB03  I69  R3711
   1 SMB_VR_SENSOR_3V3AUX_SCL      A @T6G_MB_LIB.T6G(SCH_1):SMB_VR_SENSOR_3V3AUX_SCL
   2 SMB_VR_SENSOR_3V3AUX_SCL_R      B @T6G_MB_LIB.T6G(SCH_1):SMB_VR_SENSOR_3V3AUX_SCL_R

TCA9548APWR-TCA9548APWR,SMLF,IC,AL009548K02  I74  U39
   1 PCA9548_PCIE0_ADDR0     A0 @T6G_MB_LIB.T6G(SCH_1):PCA9548_PCIE0_ADDR0
   2 PCA9548_PCIE0_ADDR1     A1 @T6G_MB_LIB.T6G(SCH_1):PCA9548_PCIE0_ADDR1
   3 PU_RST_SMB_PCIE2_N RESET# @T6G_MB_LIB.T6G(SCH_1):PU_RST_SMB_PCIE2_N
   4 SMB_VR_3V3AUX_SDA_R6    SD0 @T6G_MB_LIB.T6G(SCH_1):SMB_VR_3V3AUX_SDA_R6
   5 SMB_VR_3V3AUX_SCL_R6    SC0 @T6G_MB_LIB.T6G(SCH_1):SMB_VR_3V3AUX_SCL_R6
   6 SMB_LM75_0_3V3AUX_SDA_R    SD1 @T6G_MB_LIB.T6G(SCH_1):SMB_LM75_0_3V3AUX_SDA_R
   7 SMB_LM75_0_3V3AUX_SCL_R    SC1 @T6G_MB_LIB.T6G(SCH_1):SMB_LM75_0_3V3AUX_SCL_R
   8 SMB_LM75_1_3V3AUX_SDA_R    SD2 @T6G_MB_LIB.T6G(SCH_1):SMB_LM75_1_3V3AUX_SDA_R
   9 SMB_LM75_1_3V3AUX_SCL_R    SC2 @T6G_MB_LIB.T6G(SCH_1):SMB_LM75_1_3V3AUX_SCL_R
  10 SMB_LM75_2_3V3AUX_SDA_R    SD3 @T6G_MB_LIB.T6G(SCH_1):SMB_LM75_2_3V3AUX_SDA_R
  11 SMB_LM75_2_3V3AUX_SCL_R    SC3 @T6G_MB_LIB.T6G(SCH_1):SMB_LM75_2_3V3AUX_SCL_R
  12    GND    GND @T6G_MB_LIB.T6G(SCH_1):GND
  24 P3V3_AUX    VCC @T6G_MB_LIB.T6G(SCH_1):P3V3_AUX
  23 SMB_VR_SENSOR_3V3AUX_SDA_R    SDA @T6G_MB_LIB.T6G(SCH_1):SMB_VR_SENSOR_3V3AUX_SDA_R
  22 SMB_VR_SENSOR_3V3AUX_SCL_R    SCL @T6G_MB_LIB.T6G(SCH_1):SMB_VR_SENSOR_3V3AUX_SCL_R
  21 PCA9548_PCIE0_ADDR2     A2 @T6G_MB_LIB.T6G(SCH_1):PCA9548_PCIE0_ADDR2
  20     NC    SC7     NC
  19     NC    SD7     NC
  18 SMB_ADC_SCL    SC6 @T6G_MB_LIB.T6G(SCH_1):SMB_ADC_SCL
  17 SMB_ADC_SDA    SD6 @T6G_MB_LIB.T6G(SCH_1):SMB_ADC_SDA
  16 SMB_P12V_HSC_SCL_R    SC5 @T6G_MB_LIB.T6G(SCH_1):SMB_P12V_HSC_SCL_R
  15 SMB_P12V_HSC_SDA_R    SD5 @T6G_MB_LIB.T6G(SCH_1):SMB_P12V_HSC_SDA_R
  14 SMB_LM75_3_3V3AUX_SCL_R    SC4 @T6G_MB_LIB.T6G(SCH_1):SMB_LM75_3_3V3AUX_SCL_R
  13 SMB_LM75_3_3V3AUX_SDA_R    SD4 @T6G_MB_LIB.T6G(SCH_1):SMB_LM75_3_3V3AUX_SDA_R

Q_RES_0402LF-0,5%,1/16W,CHIP,CS00002JB13  I75  R6228
   1 SMB_P12V_HSC_SDA_R      A @T6G_MB_LIB.T6G(SCH_1):SMB_P12V_HSC_SDA_R
   2 SMB_P12V_HSC_SDA      B @T6G_MB_LIB.T6G(SCH_1):SMB_P12V_HSC_SDA

Q_RES_0402LF-0,5%,1/16W,CHIP,CS00002JB13  I76  R6229
   1 SMB_P12V_HSC_SCL_R      A @T6G_MB_LIB.T6G(SCH_1):SMB_P12V_HSC_SCL_R
   2 SMB_P12V_HSC_SCL      B @T6G_MB_LIB.T6G(SCH_1):SMB_P12V_HSC_SCL

Q_RES_0402LF-0,5%,1/16W,CHIP,CS00002JB13  I79  R1312
   1 SMB_ADC_SDA      A @T6G_MB_LIB.T6G(SCH_1):SMB_ADC_SDA
   2 SMB_ADC_SDA_R      B @T6G_MB_LIB.T6G(SCH_1):SMB_ADC_SDA_R

Q_RES_0402LF-0,5%,1/16W,CHIP,CS00002JB13  I80  R1315
   1 SMB_ADC_SCL      A @T6G_MB_LIB.T6G(SCH_1):SMB_ADC_SCL
   2 SMB_ADC_SCL_R      B @T6G_MB_LIB.T6G(SCH_1):SMB_ADC_SCL_R

Q_RES_0402LF-2.2K,5%,1/16W,CHIP,CS22202JB07  I83  R1316
   1 P3V3_AUX      A @T6G_MB_LIB.T6G(SCH_1):P3V3_AUX
   2 SMB_ADC_SCL_R      B @T6G_MB_LIB.T6G(SCH_1):SMB_ADC_SCL_R

Q_RES_0402LF-2.2K,5%,1/16W,CHIP,CS22202JB07  I84  R1341
   1 P3V3_AUX      A @T6G_MB_LIB.T6G(SCH_1):P3V3_AUX
   2 SMB_ADC_SDA_R      B @T6G_MB_LIB.T6G(SCH_1):SMB_ADC_SDA_R


DRAWING: @T6G_MB_LIB.T6G(SCH_1):PAGE252 

Q_RES_0402LF-1K,1%,1/16W,CHIP,CS21002FB06  I2  R317
   1 PCA9548_PCIE3_ADDR2      A @T6G_MB_LIB.T6G(SCH_1):PCA9548_PCIE3_ADDR2
   2    GND      B @T6G_MB_LIB.T6G(SCH_1):GND

Q_RES_0402LF-1K,1%,1/16W,CHIP,CS21002FB06  I4  R319
   1 PCA9548_PCIE3_ADDR1      A @T6G_MB_LIB.T6G(SCH_1):PCA9548_PCIE3_ADDR1
   2    GND      B @T6G_MB_LIB.T6G(SCH_1):GND

Q_RES_0402LF-1K,1%,1/16W,CHIP,CS21002FB06  I6  R587
   1 PCA9548_PCIE3_ADDR0      A @T6G_MB_LIB.T6G(SCH_1):PCA9548_PCIE3_ADDR0
   2    GND      B @T6G_MB_LIB.T6G(SCH_1):GND

Q_RES_0402LF-10K,1%,1/16W,EMPTY,CS31002FB08  I7  R316
   1 P3V3_AUX      A @T6G_MB_LIB.T6G(SCH_1):P3V3_AUX
   2 PCA9548_PCIE3_ADDR2      B @T6G_MB_LIB.T6G(SCH_1):PCA9548_PCIE3_ADDR2

Q_RES_0402LF-10K,1%,1/16W,EMPTY,CS31002FB08  I8  R318
   1 P3V3_AUX      A @T6G_MB_LIB.T6G(SCH_1):P3V3_AUX
   2 PCA9548_PCIE3_ADDR1      B @T6G_MB_LIB.T6G(SCH_1):PCA9548_PCIE3_ADDR1

Q_RES_0402LF-10K,1%,1/16W,EMPTY,CS31002FB08  I10  R320
   1 P3V3_AUX      A @T6G_MB_LIB.T6G(SCH_1):P3V3_AUX
   2 PCA9548_PCIE3_ADDR0      B @T6G_MB_LIB.T6G(SCH_1):PCA9548_PCIE3_ADDR0

Q_RES_0402LF-10K,1%,1/16W,CHIP,CS31002FB08  I21  R1822
   1 P3V3_AUX      A @T6G_MB_LIB.T6G(SCH_1):P3V3_AUX
   2 RST_SMB_SWITCH_N      B @T6G_MB_LIB.T6G(SCH_1):RST_SMB_SWITCH_N

Q_RES_0402LF-0,5%,1/16W,CHIP,CS00002JB13  I23  R3526
   1 SMB_PCIE0_3V3AUX_SCL_R5      A @T6G_MB_LIB.T6G(SCH_1):SMB_PCIE0_3V3AUX_SCL_R5
   2 SMB_SENSOR_E1S_3V3AUX_SCL      B @T6G_MB_LIB.T6G(SCH_1):SMB_SENSOR_E1S_3V3AUX_SCL

Q_RES_0402LF-0,5%,1/16W,CHIP,CS00002JB13  I24  R3527
   1 SMB_PCIE0_3V3AUX_SDA_R5      A @T6G_MB_LIB.T6G(SCH_1):SMB_PCIE0_3V3AUX_SDA_R5
   2 SMB_SENSOR_E1S_3V3AUX_SDA      B @T6G_MB_LIB.T6G(SCH_1):SMB_SENSOR_E1S_3V3AUX_SDA

Q_RES_0402LF-0,5%,1/16W,CHIP,CS00002JB13  I25  R2967
   1 SMB_PCIE0_3V3AUX_SCL_R3      A @T6G_MB_LIB.T6G(SCH_1):SMB_PCIE0_3V3AUX_SCL_R3
   2 SMB_SENSOR_M2_P1_3V3AUX_SCL      B @T6G_MB_LIB.T6G(SCH_1):SMB_SENSOR_M2_P1_3V3AUX_SCL

Q_RES_0402LF-0,5%,1/16W,CHIP,CS00002JB13  I26  R2968
   1 SMB_PCIE0_3V3AUX_SDA_R3      A @T6G_MB_LIB.T6G(SCH_1):SMB_PCIE0_3V3AUX_SDA_R3
   2 SMB_SENSOR_M2_P1_3V3AUX_SDA      B @T6G_MB_LIB.T6G(SCH_1):SMB_SENSOR_M2_P1_3V3AUX_SDA

Q_RES_0402LF-0,5%,1/16W,CHIP,CS00002JB13  I27  R3393
   1 SMB_IOEXP_3V3AUX_SCL_R      A @T6G_MB_LIB.T6G(SCH_1):SMB_IOEXP_3V3AUX_SCL_R
   2 SMB_IOEXP_3V3AUX_SCL      B @T6G_MB_LIB.T6G(SCH_1):SMB_IOEXP_3V3AUX_SCL

Q_RES_0402LF-0,5%,1/16W,CHIP,CS00002JB13  I28  R2268
   1 RST_SMB_SWITCH_N      A @T6G_MB_LIB.T6G(SCH_1):RST_SMB_SWITCH_N
   2 PU_RST_SMB_PCIE0_N      B @T6G_MB_LIB.T6G(SCH_1):PU_RST_SMB_PCIE0_N

Q_RES_0402LF-0,5%,1/16W,CHIP,CS00002JB13  I29  R3394
   1 SMB_IOEXP_3V3AUX_SDA_R      A @T6G_MB_LIB.T6G(SCH_1):SMB_IOEXP_3V3AUX_SDA_R
   2 SMB_IOEXP_3V3AUX_SDA      B @T6G_MB_LIB.T6G(SCH_1):SMB_IOEXP_3V3AUX_SDA

TCA9548APWR-TCA9548APWR,SMLF,IC,AL009548K02  I33  U36
   1 PCA9548_PCIE3_ADDR0     A0 @T6G_MB_LIB.T6G(SCH_1):PCA9548_PCIE3_ADDR0
   2 PCA9548_PCIE3_ADDR1     A1 @T6G_MB_LIB.T6G(SCH_1):PCA9548_PCIE3_ADDR1
   3 PU_RST_SMB_PCIE0_N RESET# @T6G_MB_LIB.T6G(SCH_1):PU_RST_SMB_PCIE0_N
   4 SMB_USB_CPU0_HUB1_SDA_R    SD0 @T6G_MB_LIB.T6G(SCH_1):SMB_USB_CPU0_HUB1_SDA_R
   5 SMB_USB_CPU0_HUB1_SCL_R    SC0 @T6G_MB_LIB.T6G(SCH_1):SMB_USB_CPU0_HUB1_SCL_R
   6 SMB_IOEXP_3V3AUX_SDA_R    SD1 @T6G_MB_LIB.T6G(SCH_1):SMB_IOEXP_3V3AUX_SDA_R
   7 SMB_IOEXP_3V3AUX_SCL_R    SC1 @T6G_MB_LIB.T6G(SCH_1):SMB_IOEXP_3V3AUX_SCL_R
   8 SMB_PCIE0_3V3AUX_SDA_R3    SD2 @T6G_MB_LIB.T6G(SCH_1):SMB_PCIE0_3V3AUX_SDA_R3
   9 SMB_PCIE0_3V3AUX_SCL_R3    SC2 @T6G_MB_LIB.T6G(SCH_1):SMB_PCIE0_3V3AUX_SCL_R3
  10 SMB_PCIE0_3V3AUX_SDA_R5    SD3 @T6G_MB_LIB.T6G(SCH_1):SMB_PCIE0_3V3AUX_SDA_R5
  11 SMB_PCIE0_3V3AUX_SCL_R5    SC3 @T6G_MB_LIB.T6G(SCH_1):SMB_PCIE0_3V3AUX_SCL_R5
  12    GND    GND @T6G_MB_LIB.T6G(SCH_1):GND
  24 P3V3_AUX    VCC @T6G_MB_LIB.T6G(SCH_1):P3V3_AUX
  23 SMB_PCIE0_3V3AUX_SDA_R    SDA @T6G_MB_LIB.T6G(SCH_1):SMB_PCIE0_3V3AUX_SDA_R
  22 SMB_PCIE0_3V3AUX_SCL_R    SCL @T6G_MB_LIB.T6G(SCH_1):SMB_PCIE0_3V3AUX_SCL_R
  21 PCA9548_PCIE3_ADDR2     A2 @T6G_MB_LIB.T6G(SCH_1):PCA9548_PCIE3_ADDR2
  20     NC    SC7     NC
  19     NC    SD7     NC
  18 SMB_INA230_3V3AUX_SCL_R    SC6 @T6G_MB_LIB.T6G(SCH_1):SMB_INA230_3V3AUX_SCL_R
  17 SMB_INA230_3V3AUX_SDA_R    SD6 @T6G_MB_LIB.T6G(SCH_1):SMB_INA230_3V3AUX_SDA_R
  16 SMB_FRU_3V3AUX_SCL_R    SC5 @T6G_MB_LIB.T6G(SCH_1):SMB_FRU_3V3AUX_SCL_R
  15 SMB_FRU_3V3AUX_SDA_R    SD5 @T6G_MB_LIB.T6G(SCH_1):SMB_FRU_3V3AUX_SDA_R
  14 SMB_BMC_SWB_SCL_R4    SC4 @T6G_MB_LIB.T6G(SCH_1):SMB_BMC_SWB_SCL_R4
  13 SMB_BMC_SWB_SDA_R4    SD4 @T6G_MB_LIB.T6G(SCH_1):SMB_BMC_SWB_SDA_R4

Q_CAP_0402-0.1UF,25V,10%,X7R,CH4104K1B00  I34  C106
   1 P3V3_AUX      A @T6G_MB_LIB.T6G(SCH_1):P3V3_AUX
   2    GND      B @T6G_MB_LIB.T6G(SCH_1):GND

Q_RES_0402LF-2.2K,5%,1/16W,CHIP,CS22202JB07  I37  R1089
   1 P3V3_AUX      A @T6G_MB_LIB.T6G(SCH_1):P3V3_AUX
   2 SMB_SENSOR_M2_P1_3V3AUX_SCL      B @T6G_MB_LIB.T6G(SCH_1):SMB_SENSOR_M2_P1_3V3AUX_SCL

Q_RES_0402LF-2.2K,5%,1/16W,CHIP,CS22202JB07  I38  R1090
   1 P3V3_AUX      A @T6G_MB_LIB.T6G(SCH_1):P3V3_AUX
   2 SMB_SENSOR_M2_P1_3V3AUX_SDA      B @T6G_MB_LIB.T6G(SCH_1):SMB_SENSOR_M2_P1_3V3AUX_SDA

Q_RES_0402LF-2.2K,5%,1/16W,CHIP,CS22202JB07  I39  R67
   1 P3V3_AUX      A @T6G_MB_LIB.T6G(SCH_1):P3V3_AUX
   2 SMB_FRU_3V3AUX_SDA      B @T6G_MB_LIB.T6G(SCH_1):SMB_FRU_3V3AUX_SDA

Q_RES_0402LF-2.2K,5%,1/16W,CHIP,CS22202JB07  I40  R66
   1 P3V3_AUX      A @T6G_MB_LIB.T6G(SCH_1):P3V3_AUX
   2 SMB_FRU_3V3AUX_SCL      B @T6G_MB_LIB.T6G(SCH_1):SMB_FRU_3V3AUX_SCL

Q_RES_0402LF-2.2K,5%,1/16W,CHIP,CS22202JB07  I41  R2984
   1 P3V3_AUX      A @T6G_MB_LIB.T6G(SCH_1):P3V3_AUX
   2 SMB_BMC_SWB_SCL      B @T6G_MB_LIB.T6G(SCH_1):SMB_BMC_SWB_SCL

Q_RES_0402LF-2.2K,5%,1/16W,CHIP,CS22202JB07  I42  R2985
   1 P3V3_AUX      A @T6G_MB_LIB.T6G(SCH_1):P3V3_AUX
   2 SMB_BMC_SWB_SDA      B @T6G_MB_LIB.T6G(SCH_1):SMB_BMC_SWB_SDA

Q_RES_0402LF-2.2K,5%,1/16W,CHIP,CS22202JB07  I43  R3536
   1 P3V3_AUX      A @T6G_MB_LIB.T6G(SCH_1):P3V3_AUX
   2 SMB_SENSOR_E1S_3V3AUX_SDA      B @T6G_MB_LIB.T6G(SCH_1):SMB_SENSOR_E1S_3V3AUX_SDA

Q_RES_0402LF-2.2K,5%,1/16W,CHIP,CS22202JB07  I44  R3535
   1 P3V3_AUX      A @T6G_MB_LIB.T6G(SCH_1):P3V3_AUX
   2 SMB_SENSOR_E1S_3V3AUX_SCL      B @T6G_MB_LIB.T6G(SCH_1):SMB_SENSOR_E1S_3V3AUX_SCL

Q_RES_0402LF-2.2K,5%,1/16W,CHIP,CS22202JB07  I45  R3583
   1 P3V3_AUX      A @T6G_MB_LIB.T6G(SCH_1):P3V3_AUX
   2 SMB_IOEXP_3V3AUX_SDA      B @T6G_MB_LIB.T6G(SCH_1):SMB_IOEXP_3V3AUX_SDA

Q_RES_0402LF-2.2K,5%,1/16W,CHIP,CS22202JB07  I46  R3582
   1 P3V3_AUX      A @T6G_MB_LIB.T6G(SCH_1):P3V3_AUX
   2 SMB_IOEXP_3V3AUX_SCL      B @T6G_MB_LIB.T6G(SCH_1):SMB_IOEXP_3V3AUX_SCL

Q_RES_0402LF-2.2K,5%,1/16W,CHIP,CS22202JB07  I47  R3395
   1 P3V3_AUX      A @T6G_MB_LIB.T6G(SCH_1):P3V3_AUX
   2 SMB_INA230_3V3AUX_SCL      B @T6G_MB_LIB.T6G(SCH_1):SMB_INA230_3V3AUX_SCL

Q_RES_0402LF-2.2K,5%,1/16W,CHIP,CS22202JB07  I48  R3396
   1 P3V3_AUX      A @T6G_MB_LIB.T6G(SCH_1):P3V3_AUX
   2 SMB_INA230_3V3AUX_SDA      B @T6G_MB_LIB.T6G(SCH_1):SMB_INA230_3V3AUX_SDA

Q_RES_0402LF-2.2K,5%,1/16W,EMPTY,CS22202JB07  I49  R2205
   1 P3V3_AUX      A @T6G_MB_LIB.T6G(SCH_1):P3V3_AUX
   2 SMB_PCIE0_3V3AUX_SDA      B @T6G_MB_LIB.T6G(SCH_1):SMB_PCIE0_3V3AUX_SDA

Q_RES_0402LF-2.2K,5%,1/16W,EMPTY,CS22202JB07  I50  R2204
   1 P3V3_AUX      A @T6G_MB_LIB.T6G(SCH_1):P3V3_AUX
   2 SMB_PCIE0_3V3AUX_SCL      B @T6G_MB_LIB.T6G(SCH_1):SMB_PCIE0_3V3AUX_SCL

Q_RES_0402LF-0,5%,1/16W,CHIP,CS00002JB13  I67  R2565
   1 SMB_FRU_3V3AUX_SCL_R      A @T6G_MB_LIB.T6G(SCH_1):SMB_FRU_3V3AUX_SCL_R
   2 SMB_FRU_3V3AUX_SCL      B @T6G_MB_LIB.T6G(SCH_1):SMB_FRU_3V3AUX_SCL

Q_RES_0402LF-0,5%,1/16W,CHIP,CS00002JB13  I68  R3581
   1 SMB_INA230_3V3AUX_SDA_R      A @T6G_MB_LIB.T6G(SCH_1):SMB_INA230_3V3AUX_SDA_R
   2 SMB_INA230_3V3AUX_SDA      B @T6G_MB_LIB.T6G(SCH_1):SMB_INA230_3V3AUX_SDA

Q_RES_0402LF-0,5%,1/16W,CHIP,CS00002JB13  I69  R3580
   1 SMB_INA230_3V3AUX_SCL_R      A @T6G_MB_LIB.T6G(SCH_1):SMB_INA230_3V3AUX_SCL_R
   2 SMB_INA230_3V3AUX_SCL      B @T6G_MB_LIB.T6G(SCH_1):SMB_INA230_3V3AUX_SCL

Q_RES_0402LF-0,5%,1/16W,CHIP,CS00002JB13  I70  R2704
   1 SMB_BMC_SWB_SDA_R4      A @T6G_MB_LIB.T6G(SCH_1):SMB_BMC_SWB_SDA_R4
   2 SMB_BMC_SWB_SDA      B @T6G_MB_LIB.T6G(SCH_1):SMB_BMC_SWB_SDA

Q_RES_0402LF-0,5%,1/16W,CHIP,CS00002JB13  I71  R2703
   1 SMB_BMC_SWB_SCL_R4      A @T6G_MB_LIB.T6G(SCH_1):SMB_BMC_SWB_SCL_R4
   2 SMB_BMC_SWB_SCL      B @T6G_MB_LIB.T6G(SCH_1):SMB_BMC_SWB_SCL

Q_RES_0402LF-0,5%,1/16W,CHIP,CS00002JB13  I72  R2566
   1 SMB_FRU_3V3AUX_SDA_R      A @T6G_MB_LIB.T6G(SCH_1):SMB_FRU_3V3AUX_SDA_R
   2 SMB_FRU_3V3AUX_SDA      B @T6G_MB_LIB.T6G(SCH_1):SMB_FRU_3V3AUX_SDA

Q_RES_0402LF-33.2,1%,1/16W,CHIP,CS03322FB03  I73  R55
   1 SMB_PCIE0_3V3AUX_SDA      A @T6G_MB_LIB.T6G(SCH_1):SMB_PCIE0_3V3AUX_SDA
   2 SMB_PCIE0_3V3AUX_SDA_R      B @T6G_MB_LIB.T6G(SCH_1):SMB_PCIE0_3V3AUX_SDA_R

Q_RES_0402LF-33.2,1%,1/16W,CHIP,CS03322FB03  I74  R65
   1 SMB_PCIE0_3V3AUX_SCL      A @T6G_MB_LIB.T6G(SCH_1):SMB_PCIE0_3V3AUX_SCL
   2 SMB_PCIE0_3V3AUX_SCL_R      B @T6G_MB_LIB.T6G(SCH_1):SMB_PCIE0_3V3AUX_SCL_R

Q_RES_0402LF-0,5%,1/16W,CHIP,CS00002JB13  I83  R6200
   1 SMB_USB_CPU0_HUB1_SDA_R      A @T6G_MB_LIB.T6G(SCH_1):SMB_USB_CPU0_HUB1_SDA_R
   2 SMB_USB_CPU0_HUB1_SDA      B @T6G_MB_LIB.T6G(SCH_1):SMB_USB_CPU0_HUB1_SDA

Q_RES_0402LF-0,5%,1/16W,CHIP,CS00002JB13  I84  R6201
   1 SMB_USB_CPU0_HUB1_SCL_R      A @T6G_MB_LIB.T6G(SCH_1):SMB_USB_CPU0_HUB1_SCL_R
   2 SMB_USB_CPU0_HUB1_SCL      B @T6G_MB_LIB.T6G(SCH_1):SMB_USB_CPU0_HUB1_SCL

Q_RES_0402LF-2.2K,5%,1/16W,CHIP,CS22202JB07  I89  R6211
   1 P3V3_AUX      A @T6G_MB_LIB.T6G(SCH_1):P3V3_AUX
   2 SMB_USB_CPU0_HUB1_SCL      B @T6G_MB_LIB.T6G(SCH_1):SMB_USB_CPU0_HUB1_SCL

Q_RES_0402LF-2.2K,5%,1/16W,CHIP,CS22202JB07  I90  R6212
   1 P3V3_AUX      A @T6G_MB_LIB.T6G(SCH_1):P3V3_AUX
   2 SMB_USB_CPU0_HUB1_SDA      B @T6G_MB_LIB.T6G(SCH_1):SMB_USB_CPU0_HUB1_SDA


DRAWING: @T6G_MB_LIB.T6G(SCH_1):PAGE253 

Q_RES_0402LF-33.2,1%,1/16W,CHIP,CS03322FB03  I3  R3593
   1 SMB_INA230_3V3AUX_SDA      A @T6G_MB_LIB.T6G(SCH_1):SMB_INA230_3V3AUX_SDA
   2 SMB_INA230_5_3V3AUX_SDA_R      B @T6G_MB_LIB.T6G(SCH_1):SMB_INA230_5_3V3AUX_SDA_R

Q_RES_0402LF-33.2,1%,1/16W,CHIP,CS03322FB03  I4  R3592
   1 SMB_INA230_3V3AUX_SCL      A @T6G_MB_LIB.T6G(SCH_1):SMB_INA230_3V3AUX_SCL
   2 SMB_INA230_5_3V3AUX_SCL_R      B @T6G_MB_LIB.T6G(SCH_1):SMB_INA230_5_3V3AUX_SCL_R

Q_RES_0402LF-33.2,1%,1/16W,CHIP,CS03322FB03  I5  R3595
   1 SMB_INA230_3V3AUX_SDA      A @T6G_MB_LIB.T6G(SCH_1):SMB_INA230_3V3AUX_SDA
   2 SMB_INA230_4_3V3AUX_SDA_R      B @T6G_MB_LIB.T6G(SCH_1):SMB_INA230_4_3V3AUX_SDA_R

Q_RES_0402LF-33.2,1%,1/16W,CHIP,CS03322FB03  I6  R3594
   1 SMB_INA230_3V3AUX_SCL      A @T6G_MB_LIB.T6G(SCH_1):SMB_INA230_3V3AUX_SCL
   2 SMB_INA230_4_3V3AUX_SCL_R      B @T6G_MB_LIB.T6G(SCH_1):SMB_INA230_4_3V3AUX_SCL_R

Q_RES_0402LF-33.2,1%,1/16W,CHIP,CS03322FB03  I7  R3591
   1 SMB_INA230_3V3AUX_SDA      A @T6G_MB_LIB.T6G(SCH_1):SMB_INA230_3V3AUX_SDA
   2 SMB_INA230_3_3V3AUX_SDA_R      B @T6G_MB_LIB.T6G(SCH_1):SMB_INA230_3_3V3AUX_SDA_R

Q_RES_0402LF-33.2,1%,1/16W,CHIP,CS03322FB03  I8  R3590
   1 SMB_INA230_3V3AUX_SCL      A @T6G_MB_LIB.T6G(SCH_1):SMB_INA230_3V3AUX_SCL
   2 SMB_INA230_3_3V3AUX_SCL_R      B @T6G_MB_LIB.T6G(SCH_1):SMB_INA230_3_3V3AUX_SCL_R

Q_RES_0402LF-33.2,1%,1/16W,CHIP,CS03322FB03  I9  R3589
   1 SMB_INA230_3V3AUX_SDA      A @T6G_MB_LIB.T6G(SCH_1):SMB_INA230_3V3AUX_SDA
   2 SMB_INA230_2_3V3AUX_SDA_R      B @T6G_MB_LIB.T6G(SCH_1):SMB_INA230_2_3V3AUX_SDA_R

Q_RES_0402LF-33.2,1%,1/16W,CHIP,CS03322FB03  I10  R3588
   1 SMB_INA230_3V3AUX_SCL      A @T6G_MB_LIB.T6G(SCH_1):SMB_INA230_3V3AUX_SCL
   2 SMB_INA230_2_3V3AUX_SCL_R      B @T6G_MB_LIB.T6G(SCH_1):SMB_INA230_2_3V3AUX_SCL_R

Q_RES_0402LF-33.2,1%,1/16W,CHIP,CS03322FB03  I11  R3587
   1 SMB_INA230_3V3AUX_SDA      A @T6G_MB_LIB.T6G(SCH_1):SMB_INA230_3V3AUX_SDA
   2 SMB_INA230_1_3V3AUX_SDA_R      B @T6G_MB_LIB.T6G(SCH_1):SMB_INA230_1_3V3AUX_SDA_R

Q_RES_0402LF-33.2,1%,1/16W,CHIP,CS03322FB03  I12  R3586
   1 SMB_INA230_3V3AUX_SCL      A @T6G_MB_LIB.T6G(SCH_1):SMB_INA230_3V3AUX_SCL
   2 SMB_INA230_1_3V3AUX_SCL_R      B @T6G_MB_LIB.T6G(SCH_1):SMB_INA230_1_3V3AUX_SCL_R

Q_RES_0402LF-33.2,1%,1/16W,CHIP,CS03322FB03  I23  R1344
   1 SMB_INA230_3V3AUX_SCL      A @T6G_MB_LIB.T6G(SCH_1):SMB_INA230_3V3AUX_SCL
   2 SMB_INA230_6_3V3AUX_SCL_R      B @T6G_MB_LIB.T6G(SCH_1):SMB_INA230_6_3V3AUX_SCL_R

Q_RES_0402LF-33.2,1%,1/16W,CHIP,CS03322FB03  I24  R1345
   1 SMB_INA230_3V3AUX_SDA      A @T6G_MB_LIB.T6G(SCH_1):SMB_INA230_3V3AUX_SDA
   2 SMB_INA230_6_3V3AUX_SDA_R      B @T6G_MB_LIB.T6G(SCH_1):SMB_INA230_6_3V3AUX_SDA_R

Q_RES_0402LF-33.2,1%,1/16W,CHIP,CS03322FB03  I25  R1346
   1 SMB_INA230_3V3AUX_SCL      A @T6G_MB_LIB.T6G(SCH_1):SMB_INA230_3V3AUX_SCL
   2 SMB_INA230_7_3V3AUX_SCL_R      B @T6G_MB_LIB.T6G(SCH_1):SMB_INA230_7_3V3AUX_SCL_R

Q_RES_0402LF-33.2,1%,1/16W,CHIP,CS03322FB03  I26  R1347
   1 SMB_INA230_3V3AUX_SDA      A @T6G_MB_LIB.T6G(SCH_1):SMB_INA230_3V3AUX_SDA
   2 SMB_INA230_7_3V3AUX_SDA_R      B @T6G_MB_LIB.T6G(SCH_1):SMB_INA230_7_3V3AUX_SDA_R

Q_RES_0402LF-33.2,1%,1/16W,CHIP,CS03322FB03  I27  R1348
   1 SMB_INA230_3V3AUX_SCL      A @T6G_MB_LIB.T6G(SCH_1):SMB_INA230_3V3AUX_SCL
   2 SMB_INA230_8_3V3AUX_SCL_R      B @T6G_MB_LIB.T6G(SCH_1):SMB_INA230_8_3V3AUX_SCL_R

Q_RES_0402LF-33.2,1%,1/16W,CHIP,CS03322FB03  I28  R1349
   1 SMB_INA230_3V3AUX_SDA      A @T6G_MB_LIB.T6G(SCH_1):SMB_INA230_3V3AUX_SDA
   2 SMB_INA230_8_3V3AUX_SDA_R      B @T6G_MB_LIB.T6G(SCH_1):SMB_INA230_8_3V3AUX_SDA_R


DRAWING: @T6G_MB_LIB.T6G(SCH_1):PAGE355 

Q_CAP_DIFFBUS_C0201-DIFF BUS_0.22UF,6.3V,20%,X6S,SA  I7  C1990
   1 P3E_CPU0_P4_TX_C_DN<3>      1 @T6G_MB_LIB.T6G(SCH_1):P3E_CPU0_P4_TX_C_DN(3)
   2 P3E_CPU0_P4_TX_DN<3>      2 @T6G_MB_LIB.T6G(SCH_1):P3E_CPU0_P4_TX_DN(3)

Q_CAP_DIFFBUS_C0201-DIFF BUS_0.22UF,6.3V,20%,X6S,SA  I8  C1989
   1 P3E_CPU0_P4_TX_C_DP<3>      1 @T6G_MB_LIB.T6G(SCH_1):P3E_CPU0_P4_TX_C_DP(3)
   2 P3E_CPU0_P4_TX_DP<3>      2 @T6G_MB_LIB.T6G(SCH_1):P3E_CPU0_P4_TX_DP(3)

Q_CAP_DIFFBUS_C0201-DIFF BUS_0.22UF,6.3V,20%,X6S,SA  I9  C1992
   1 P3E_CPU0_P4_TX_C_DN<2>      1 @T6G_MB_LIB.T6G(SCH_1):P3E_CPU0_P4_TX_C_DN(2)
   2 P3E_CPU0_P4_TX_DN<2>      2 @T6G_MB_LIB.T6G(SCH_1):P3E_CPU0_P4_TX_DN(2)

Q_CAP_DIFFBUS_C0201-DIFF BUS_0.22UF,6.3V,20%,X6S,SA  I10  C1991
   1 P3E_CPU0_P4_TX_C_DP<2>      1 @T6G_MB_LIB.T6G(SCH_1):P3E_CPU0_P4_TX_C_DP(2)
   2 P3E_CPU0_P4_TX_DP<2>      2 @T6G_MB_LIB.T6G(SCH_1):P3E_CPU0_P4_TX_DP(2)

Q_CAP_DIFFBUS_C0201-DIFF BUS_0.22UF,6.3V,20%,X6S,SA  I11  C1994
   1 P3E_CPU0_P4_TX_C_DN<1>      1 @T6G_MB_LIB.T6G(SCH_1):P3E_CPU0_P4_TX_C_DN(1)
   2 P3E_CPU0_P4_TX_DN<1>      2 @T6G_MB_LIB.T6G(SCH_1):P3E_CPU0_P4_TX_DN(1)

Q_CAP_DIFFBUS_C0201-DIFF BUS_0.22UF,6.3V,20%,X6S,SA  I12  C1993
   1 P3E_CPU0_P4_TX_C_DP<1>      1 @T6G_MB_LIB.T6G(SCH_1):P3E_CPU0_P4_TX_C_DP(1)
   2 P3E_CPU0_P4_TX_DP<1>      2 @T6G_MB_LIB.T6G(SCH_1):P3E_CPU0_P4_TX_DP(1)

Q_CAP_DIFFBUS_C0201-DIFF BUS_0.22UF,6.3V,20%,X6S,SA  I51  C1996
   1 P3E_CPU0_P4_TX_C_DN<0>      1 @T6G_MB_LIB.T6G(SCH_1):P3E_CPU0_P4_TX_C_DN(0)
   2 P3E_CPU0_P4_TX_DN<0>      2 @T6G_MB_LIB.T6G(SCH_1):P3E_CPU0_P4_TX_DN(0)

Q_CAP_DIFFBUS_C0201-DIFF BUS_0.22UF,6.3V,20%,X6S,SA  I52  C1995
   1 P3E_CPU0_P4_TX_C_DP<0>      1 @T6G_MB_LIB.T6G(SCH_1):P3E_CPU0_P4_TX_C_DP(0)
   2 P3E_CPU0_P4_TX_DP<0>      2 @T6G_MB_LIB.T6G(SCH_1):P3E_CPU0_P4_TX_DP(0)

Q_CAP_DIFFBUS_C0201-DIFF BUS_0.22UF,6.3V,20%,X6S,SA  I53  C1547
   1 P5E_CPU1_P3_TX_C_DP<0>      1 @T6G_MB_LIB.T6G(SCH_1):P5E_CPU1_P3_TX_C_DP(0)
   2 P5E_CPU1_P3_TX_DP<0>      2 @T6G_MB_LIB.T6G(SCH_1):P5E_CPU1_P3_TX_DP(0)

Q_CAP_DIFFBUS_C0201-DIFF BUS_0.22UF,6.3V,20%,X6S,SA  I54  C1546
   1 P5E_CPU1_P3_TX_C_DN<0>      1 @T6G_MB_LIB.T6G(SCH_1):P5E_CPU1_P3_TX_C_DN(0)
   2 P5E_CPU1_P3_TX_DN<0>      2 @T6G_MB_LIB.T6G(SCH_1):P5E_CPU1_P3_TX_DN(0)

Q_CAP_DIFFBUS_C0201-DIFF BUS_0.22UF,6.3V,20%,X6S,SA  I55  C1544
   1 P5E_CPU1_P3_TX_C_DN<1>      1 @T6G_MB_LIB.T6G(SCH_1):P5E_CPU1_P3_TX_C_DN(1)
   2 P5E_CPU1_P3_TX_DN<1>      2 @T6G_MB_LIB.T6G(SCH_1):P5E_CPU1_P3_TX_DN(1)

Q_CAP_DIFFBUS_C0201-DIFF BUS_0.22UF,6.3V,20%,X6S,SA  I56  C1545
   1 P5E_CPU1_P3_TX_C_DP<1>      1 @T6G_MB_LIB.T6G(SCH_1):P5E_CPU1_P3_TX_C_DP(1)
   2 P5E_CPU1_P3_TX_DP<1>      2 @T6G_MB_LIB.T6G(SCH_1):P5E_CPU1_P3_TX_DP(1)

Q_CAP_DIFFBUS_C0201-DIFF BUS_0.22UF,6.3V,20%,X6S,SA  I57  C1543
   1 P5E_CPU1_P3_TX_C_DP<2>      1 @T6G_MB_LIB.T6G(SCH_1):P5E_CPU1_P3_TX_C_DP(2)
   2 P5E_CPU1_P3_TX_DP<2>      2 @T6G_MB_LIB.T6G(SCH_1):P5E_CPU1_P3_TX_DP(2)

Q_CAP_DIFFBUS_C0201-DIFF BUS_0.22UF,6.3V,20%,X6S,SA  I58  C1542
   1 P5E_CPU1_P3_TX_C_DN<2>      1 @T6G_MB_LIB.T6G(SCH_1):P5E_CPU1_P3_TX_C_DN(2)
   2 P5E_CPU1_P3_TX_DN<2>      2 @T6G_MB_LIB.T6G(SCH_1):P5E_CPU1_P3_TX_DN(2)

Q_CAP_DIFFBUS_C0201-DIFF BUS_0.22UF,6.3V,20%,X6S,SA  I67  C1541
   1 P5E_CPU1_P3_TX_C_DP<3>      1 @T6G_MB_LIB.T6G(SCH_1):P5E_CPU1_P3_TX_C_DP(3)
   2 P5E_CPU1_P3_TX_DP<3>      2 @T6G_MB_LIB.T6G(SCH_1):P5E_CPU1_P3_TX_DP(3)

Q_CAP_DIFFBUS_C0201-DIFF BUS_0.22UF,6.3V,20%,X6S,SA  I68  C1540
   1 P5E_CPU1_P3_TX_C_DN<3>      1 @T6G_MB_LIB.T6G(SCH_1):P5E_CPU1_P3_TX_C_DN(3)
   2 P5E_CPU1_P3_TX_DN<3>      2 @T6G_MB_LIB.T6G(SCH_1):P5E_CPU1_P3_TX_DN(3)

Q_CAP_DIFFBUS_C0201-DIFF BUS_0.22UF,6.3V,20%,X6S,SA  I69  C1539
   1 P5E_CPU1_P3_TX_C_DP<4>      1 @T6G_MB_LIB.T6G(SCH_1):P5E_CPU1_P3_TX_C_DP(4)
   2 P5E_CPU1_P3_TX_DP<4>      2 @T6G_MB_LIB.T6G(SCH_1):P5E_CPU1_P3_TX_DP(4)

Q_CAP_DIFFBUS_C0201-DIFF BUS_0.22UF,6.3V,20%,X6S,SA  I70  C1538
   1 P5E_CPU1_P3_TX_C_DN<4>      1 @T6G_MB_LIB.T6G(SCH_1):P5E_CPU1_P3_TX_C_DN(4)
   2 P5E_CPU1_P3_TX_DN<4>      2 @T6G_MB_LIB.T6G(SCH_1):P5E_CPU1_P3_TX_DN(4)

Q_CAP_DIFFBUS_C0201-DIFF BUS_0.22UF,6.3V,20%,X6S,SA  I71  C1537
   1 P5E_CPU1_P3_TX_C_DP<5>      1 @T6G_MB_LIB.T6G(SCH_1):P5E_CPU1_P3_TX_C_DP(5)
   2 P5E_CPU1_P3_TX_DP<5>      2 @T6G_MB_LIB.T6G(SCH_1):P5E_CPU1_P3_TX_DP(5)

Q_CAP_DIFFBUS_C0201-DIFF BUS_0.22UF,6.3V,20%,X6S,SA  I72  C1536
   1 P5E_CPU1_P3_TX_C_DN<5>      1 @T6G_MB_LIB.T6G(SCH_1):P5E_CPU1_P3_TX_C_DN(5)
   2 P5E_CPU1_P3_TX_DN<5>      2 @T6G_MB_LIB.T6G(SCH_1):P5E_CPU1_P3_TX_DN(5)

Q_CAP_DIFFBUS_C0201-DIFF BUS_0.22UF,6.3V,20%,X6S,SA  I73  C1535
   1 P5E_CPU1_P3_TX_C_DP<6>      1 @T6G_MB_LIB.T6G(SCH_1):P5E_CPU1_P3_TX_C_DP(6)
   2 P5E_CPU1_P3_TX_DP<6>      2 @T6G_MB_LIB.T6G(SCH_1):P5E_CPU1_P3_TX_DP(6)

Q_CAP_DIFFBUS_C0201-DIFF BUS_0.22UF,6.3V,20%,X6S,SA  I74  C1534
   1 P5E_CPU1_P3_TX_C_DN<6>      1 @T6G_MB_LIB.T6G(SCH_1):P5E_CPU1_P3_TX_C_DN(6)
   2 P5E_CPU1_P3_TX_DN<6>      2 @T6G_MB_LIB.T6G(SCH_1):P5E_CPU1_P3_TX_DN(6)

Q_CAP_DIFFBUS_C0201-DIFF BUS_0.22UF,6.3V,20%,X6S,SA  I75  C1533
   1 P5E_CPU1_P3_TX_C_DP<7>      1 @T6G_MB_LIB.T6G(SCH_1):P5E_CPU1_P3_TX_C_DP(7)
   2 P5E_CPU1_P3_TX_DP<7>      2 @T6G_MB_LIB.T6G(SCH_1):P5E_CPU1_P3_TX_DP(7)

Q_CAP_DIFFBUS_C0201-DIFF BUS_0.22UF,6.3V,20%,X6S,SA  I76  C1532
   1 P5E_CPU1_P3_TX_C_DN<7>      1 @T6G_MB_LIB.T6G(SCH_1):P5E_CPU1_P3_TX_C_DN(7)
   2 P5E_CPU1_P3_TX_DN<7>      2 @T6G_MB_LIB.T6G(SCH_1):P5E_CPU1_P3_TX_DN(7)

Q_CAP_DIFFBUS_C0201-DIFF BUS_0.22UF,6.3V,20%,X6S,SA  I77  C1531
   1 P5E_CPU1_P3_TX_C_DP<8>      1 @T6G_MB_LIB.T6G(SCH_1):P5E_CPU1_P3_TX_C_DP(8)
   2 P5E_CPU1_P3_TX_DP<8>      2 @T6G_MB_LIB.T6G(SCH_1):P5E_CPU1_P3_TX_DP(8)

Q_CAP_DIFFBUS_C0201-DIFF BUS_0.22UF,6.3V,20%,X6S,SA  I78  C1530
   1 P5E_CPU1_P3_TX_C_DN<8>      1 @T6G_MB_LIB.T6G(SCH_1):P5E_CPU1_P3_TX_C_DN(8)
   2 P5E_CPU1_P3_TX_DN<8>      2 @T6G_MB_LIB.T6G(SCH_1):P5E_CPU1_P3_TX_DN(8)

Q_CAP_DIFFBUS_C0201-DIFF BUS_0.22UF,6.3V,20%,X6S,SA  I79  C1529
   1 P5E_CPU1_P3_TX_C_DP<9>      1 @T6G_MB_LIB.T6G(SCH_1):P5E_CPU1_P3_TX_C_DP(9)
   2 P5E_CPU1_P3_TX_DP<9>      2 @T6G_MB_LIB.T6G(SCH_1):P5E_CPU1_P3_TX_DP(9)

Q_CAP_DIFFBUS_C0201-DIFF BUS_0.22UF,6.3V,20%,X6S,SA  I80  C1528
   1 P5E_CPU1_P3_TX_C_DN<9>      1 @T6G_MB_LIB.T6G(SCH_1):P5E_CPU1_P3_TX_C_DN(9)
   2 P5E_CPU1_P3_TX_DN<9>      2 @T6G_MB_LIB.T6G(SCH_1):P5E_CPU1_P3_TX_DN(9)

Q_CAP_DIFFBUS_C0201-DIFF BUS_0.22UF,6.3V,20%,X6S,SA  I81  C1526
   1 P5E_CPU1_P3_TX_C_DN<10>      1 @T6G_MB_LIB.T6G(SCH_1):P5E_CPU1_P3_TX_C_DN(10)
   2 P5E_CPU1_P3_TX_DN<10>      2 @T6G_MB_LIB.T6G(SCH_1):P5E_CPU1_P3_TX_DN(10)

Q_CAP_DIFFBUS_C0201-DIFF BUS_0.22UF,6.3V,20%,X6S,SA  I82  C1527
   1 P5E_CPU1_P3_TX_C_DP<10>      1 @T6G_MB_LIB.T6G(SCH_1):P5E_CPU1_P3_TX_C_DP(10)
   2 P5E_CPU1_P3_TX_DP<10>      2 @T6G_MB_LIB.T6G(SCH_1):P5E_CPU1_P3_TX_DP(10)

Q_CAP_DIFFBUS_C0201-DIFF BUS_0.22UF,6.3V,20%,X6S,SA  I83  C1525
   1 P5E_CPU1_P3_TX_C_DP<11>      1 @T6G_MB_LIB.T6G(SCH_1):P5E_CPU1_P3_TX_C_DP(11)
   2 P5E_CPU1_P3_TX_DP<11>      2 @T6G_MB_LIB.T6G(SCH_1):P5E_CPU1_P3_TX_DP(11)

Q_CAP_DIFFBUS_C0201-DIFF BUS_0.22UF,6.3V,20%,X6S,SA  I84  C1524
   1 P5E_CPU1_P3_TX_C_DN<11>      1 @T6G_MB_LIB.T6G(SCH_1):P5E_CPU1_P3_TX_C_DN(11)
   2 P5E_CPU1_P3_TX_DN<11>      2 @T6G_MB_LIB.T6G(SCH_1):P5E_CPU1_P3_TX_DN(11)

Q_CAP_DIFFBUS_C0201-DIFF BUS_0.22UF,6.3V,20%,X6S,SA  I85  C55
   1 P5E_CPU1_P3_TX_C_DP<12>      1 @T6G_MB_LIB.T6G(SCH_1):P5E_CPU1_P3_TX_C_DP(12)
   2 P5E_CPU1_P3_TX_DP<12>      2 @T6G_MB_LIB.T6G(SCH_1):P5E_CPU1_P3_TX_DP(12)

Q_CAP_DIFFBUS_C0201-DIFF BUS_0.22UF,6.3V,20%,X6S,SA  I86  C54
   1 P5E_CPU1_P3_TX_C_DN<12>      1 @T6G_MB_LIB.T6G(SCH_1):P5E_CPU1_P3_TX_C_DN(12)
   2 P5E_CPU1_P3_TX_DN<12>      2 @T6G_MB_LIB.T6G(SCH_1):P5E_CPU1_P3_TX_DN(12)

Q_CAP_DIFFBUS_C0201-DIFF BUS_0.22UF,6.3V,20%,X6S,SA  I107  C53
   1 P5E_CPU1_P3_TX_C_DP<13>      1 @T6G_MB_LIB.T6G(SCH_1):P5E_CPU1_P3_TX_C_DP(13)
   2 P5E_CPU1_P3_TX_DP<13>      2 @T6G_MB_LIB.T6G(SCH_1):P5E_CPU1_P3_TX_DP(13)

Q_CAP_DIFFBUS_C0201-DIFF BUS_0.22UF,6.3V,20%,X6S,SA  I116  C52
   1 P5E_CPU1_P3_TX_C_DN<13>      1 @T6G_MB_LIB.T6G(SCH_1):P5E_CPU1_P3_TX_C_DN(13)
   2 P5E_CPU1_P3_TX_DN<13>      2 @T6G_MB_LIB.T6G(SCH_1):P5E_CPU1_P3_TX_DN(13)

Q_CAP_DIFFBUS_C0201-DIFF BUS_0.22UF,6.3V,20%,X6S,SA  I117  C51
   1 P5E_CPU1_P3_TX_C_DP<14>      1 @T6G_MB_LIB.T6G(SCH_1):P5E_CPU1_P3_TX_C_DP(14)
   2 P5E_CPU1_P3_TX_DP<14>      2 @T6G_MB_LIB.T6G(SCH_1):P5E_CPU1_P3_TX_DP(14)

Q_CAP_DIFFBUS_C0201-DIFF BUS_0.22UF,6.3V,20%,X6S,SA  I118  C50
   1 P5E_CPU1_P3_TX_C_DN<14>      1 @T6G_MB_LIB.T6G(SCH_1):P5E_CPU1_P3_TX_C_DN(14)
   2 P5E_CPU1_P3_TX_DN<14>      2 @T6G_MB_LIB.T6G(SCH_1):P5E_CPU1_P3_TX_DN(14)

Q_CAP_DIFFBUS_C0201-DIFF BUS_0.22UF,6.3V,20%,X6S,SA  I119  C48
   1 P5E_CPU1_P3_TX_C_DN<15>      1 @T6G_MB_LIB.T6G(SCH_1):P5E_CPU1_P3_TX_C_DN(15)
   2 P5E_CPU1_P3_TX_DN<15>      2 @T6G_MB_LIB.T6G(SCH_1):P5E_CPU1_P3_TX_DN(15)

Q_CAP_DIFFBUS_C0201-DIFF BUS_0.22UF,6.3V,20%,X6S,SA  I120  C49
   1 P5E_CPU1_P3_TX_C_DP<15>      1 @T6G_MB_LIB.T6G(SCH_1):P5E_CPU1_P3_TX_C_DP(15)
   2 P5E_CPU1_P3_TX_DP<15>      2 @T6G_MB_LIB.T6G(SCH_1):P5E_CPU1_P3_TX_DP(15)

Q_CAP_DIFFBUS_C0201-DIFF BUS_0.22UF,6.3V,20%,X6S,SA  I133  C1099
   1 P3E_CPU1_P4_TX_C_DN<3>      1 @T6G_MB_LIB.T6G(SCH_1):P3E_CPU1_P4_TX_C_DN(3)
   2 P3E_CPU1_P4_TX_DN<3>      2 @T6G_MB_LIB.T6G(SCH_1):P3E_CPU1_P4_TX_DN(3)

Q_CAP_DIFFBUS_C0201-DIFF BUS_0.22UF,6.3V,20%,X6S,SA  I134  C1098
   1 P3E_CPU1_P4_TX_C_DP<3>      1 @T6G_MB_LIB.T6G(SCH_1):P3E_CPU1_P4_TX_C_DP(3)
   2 P3E_CPU1_P4_TX_DP<3>      2 @T6G_MB_LIB.T6G(SCH_1):P3E_CPU1_P4_TX_DP(3)

Q_CAP_DIFFBUS_C0201-DIFF BUS_0.22UF,6.3V,20%,X6S,SA  I135  C1101
   1 P3E_CPU1_P4_TX_C_DN<2>      1 @T6G_MB_LIB.T6G(SCH_1):P3E_CPU1_P4_TX_C_DN(2)
   2 P3E_CPU1_P4_TX_DN<2>      2 @T6G_MB_LIB.T6G(SCH_1):P3E_CPU1_P4_TX_DN(2)

Q_CAP_DIFFBUS_C0201-DIFF BUS_0.22UF,6.3V,20%,X6S,SA  I136  C1100
   1 P3E_CPU1_P4_TX_C_DP<2>      1 @T6G_MB_LIB.T6G(SCH_1):P3E_CPU1_P4_TX_C_DP(2)
   2 P3E_CPU1_P4_TX_DP<2>      2 @T6G_MB_LIB.T6G(SCH_1):P3E_CPU1_P4_TX_DP(2)

Q_CAP_DIFFBUS_C0201-DIFF BUS_0.22UF,6.3V,20%,X6S,SA  I137  C9103
   1 P3E_CPU1_P4_TX_C_DN<1>      1 @T6G_MB_LIB.T6G(SCH_1):P3E_CPU1_P4_TX_C_DN(1)
   2 P3E_CPU1_P4_TX_DN<1>      2 @T6G_MB_LIB.T6G(SCH_1):P3E_CPU1_P4_TX_DN(1)

Q_CAP_DIFFBUS_C0201-DIFF BUS_0.22UF,6.3V,20%,X6S,SA  I138  C9102
   1 P3E_CPU1_P4_TX_C_DP<1>      1 @T6G_MB_LIB.T6G(SCH_1):P3E_CPU1_P4_TX_C_DP(1)
   2 P3E_CPU1_P4_TX_DP<1>      2 @T6G_MB_LIB.T6G(SCH_1):P3E_CPU1_P4_TX_DP(1)

Q_CAP_DIFFBUS_C0201-DIFF BUS_0.22UF,6.3V,20%,X6S,SA  I161  C9105
   1 P3E_CPU1_P4_TX_C_DN<0>      1 @T6G_MB_LIB.T6G(SCH_1):P3E_CPU1_P4_TX_C_DN(0)
   2 P3E_CPU1_P4_TX_DN<0>      2 @T6G_MB_LIB.T6G(SCH_1):P3E_CPU1_P4_TX_DN(0)

Q_CAP_DIFFBUS_C0201-DIFF BUS_0.22UF,6.3V,20%,X6S,SA  I162  C9104
   1 P3E_CPU1_P4_TX_C_DP<0>      1 @T6G_MB_LIB.T6G(SCH_1):P3E_CPU1_P4_TX_C_DP(0)
   2 P3E_CPU1_P4_TX_DP<0>      2 @T6G_MB_LIB.T6G(SCH_1):P3E_CPU1_P4_TX_DP(0)

Q_CAP_DIFFBUS_C0201-DIFF BUS_0.22UF,6.3V,20%,X6S,SA  I165  C709
   1 P5E_CPU1_G1_TX_C_DP<0>      1 @T6G_MB_LIB.T6G(SCH_1):P5E_CPU1_G1_TX_C_DP(0)
   2 P5E_CPU1_G1_TX_DP<0>      2 @T6G_MB_LIB.T6G(SCH_1):P5E_CPU1_G1_TX_DP(0)

Q_CAP_DIFFBUS_C0201-DIFF BUS_0.22UF,6.3V,20%,X6S,SA  I166  C708
   1 P5E_CPU1_G1_TX_C_DN<0>      1 @T6G_MB_LIB.T6G(SCH_1):P5E_CPU1_G1_TX_C_DN(0)
   2 P5E_CPU1_G1_TX_DN<0>      2 @T6G_MB_LIB.T6G(SCH_1):P5E_CPU1_G1_TX_DN(0)

Q_CAP_DIFFBUS_C0201-DIFF BUS_0.22UF,6.3V,20%,X6S,SA  I167  C706
   1 P5E_CPU1_G1_TX_C_DN<1>      1 @T6G_MB_LIB.T6G(SCH_1):P5E_CPU1_G1_TX_C_DN(1)
   2 P5E_CPU1_G1_TX_DN<1>      2 @T6G_MB_LIB.T6G(SCH_1):P5E_CPU1_G1_TX_DN(1)

Q_CAP_DIFFBUS_C0201-DIFF BUS_0.22UF,6.3V,20%,X6S,SA  I168  C707
   1 P5E_CPU1_G1_TX_C_DP<1>      1 @T6G_MB_LIB.T6G(SCH_1):P5E_CPU1_G1_TX_C_DP(1)
   2 P5E_CPU1_G1_TX_DP<1>      2 @T6G_MB_LIB.T6G(SCH_1):P5E_CPU1_G1_TX_DP(1)

Q_CAP_DIFFBUS_C0201-DIFF BUS_0.22UF,6.3V,20%,X6S,SA  I169  C705
   1 P5E_CPU1_G1_TX_C_DP<2>      1 @T6G_MB_LIB.T6G(SCH_1):P5E_CPU1_G1_TX_C_DP(2)
   2 P5E_CPU1_G1_TX_DP<2>      2 @T6G_MB_LIB.T6G(SCH_1):P5E_CPU1_G1_TX_DP(2)

Q_CAP_DIFFBUS_C0201-DIFF BUS_0.22UF,6.3V,20%,X6S,SA  I170  C704
   1 P5E_CPU1_G1_TX_C_DN<2>      1 @T6G_MB_LIB.T6G(SCH_1):P5E_CPU1_G1_TX_C_DN(2)
   2 P5E_CPU1_G1_TX_DN<2>      2 @T6G_MB_LIB.T6G(SCH_1):P5E_CPU1_G1_TX_DN(2)

Q_CAP_DIFFBUS_C0201-DIFF BUS_0.22UF,6.3V,20%,X6S,SA  I197  C702
   1 P5E_CPU1_G1_TX_C_DN<3>      1 @T6G_MB_LIB.T6G(SCH_1):P5E_CPU1_G1_TX_C_DN(3)
   2 P5E_CPU1_G1_TX_DN<3>      2 @T6G_MB_LIB.T6G(SCH_1):P5E_CPU1_G1_TX_DN(3)

Q_CAP_DIFFBUS_C0201-DIFF BUS_0.22UF,6.3V,20%,X6S,SA  I198  C703
   1 P5E_CPU1_G1_TX_C_DP<3>      1 @T6G_MB_LIB.T6G(SCH_1):P5E_CPU1_G1_TX_C_DP(3)
   2 P5E_CPU1_G1_TX_DP<3>      2 @T6G_MB_LIB.T6G(SCH_1):P5E_CPU1_G1_TX_DP(3)

Q_CAP_DIFFBUS_C0201-DIFF BUS_0.22UF,6.3V,20%,X6S,SA  I199  C701
   1 P5E_CPU1_G1_TX_C_DP<4>      1 @T6G_MB_LIB.T6G(SCH_1):P5E_CPU1_G1_TX_C_DP(4)
   2 P5E_CPU1_G1_TX_DP<4>      2 @T6G_MB_LIB.T6G(SCH_1):P5E_CPU1_G1_TX_DP(4)

Q_CAP_DIFFBUS_C0201-DIFF BUS_0.22UF,6.3V,20%,X6S,SA  I200  C700
   1 P5E_CPU1_G1_TX_C_DN<4>      1 @T6G_MB_LIB.T6G(SCH_1):P5E_CPU1_G1_TX_C_DN(4)
   2 P5E_CPU1_G1_TX_DN<4>      2 @T6G_MB_LIB.T6G(SCH_1):P5E_CPU1_G1_TX_DN(4)

Q_CAP_DIFFBUS_C0201-DIFF BUS_0.22UF,6.3V,20%,X6S,SA  I201  C698
   1 P5E_CPU1_G1_TX_C_DN<5>      1 @T6G_MB_LIB.T6G(SCH_1):P5E_CPU1_G1_TX_C_DN(5)
   2 P5E_CPU1_G1_TX_DN<5>      2 @T6G_MB_LIB.T6G(SCH_1):P5E_CPU1_G1_TX_DN(5)

Q_CAP_DIFFBUS_C0201-DIFF BUS_0.22UF,6.3V,20%,X6S,SA  I202  C699
   1 P5E_CPU1_G1_TX_C_DP<5>      1 @T6G_MB_LIB.T6G(SCH_1):P5E_CPU1_G1_TX_C_DP(5)
   2 P5E_CPU1_G1_TX_DP<5>      2 @T6G_MB_LIB.T6G(SCH_1):P5E_CPU1_G1_TX_DP(5)

Q_CAP_DIFFBUS_C0201-DIFF BUS_0.22UF,6.3V,20%,X6S,SA  I203  C697
   1 P5E_CPU1_G1_TX_C_DP<6>      1 @T6G_MB_LIB.T6G(SCH_1):P5E_CPU1_G1_TX_C_DP(6)
   2 P5E_CPU1_G1_TX_DP<6>      2 @T6G_MB_LIB.T6G(SCH_1):P5E_CPU1_G1_TX_DP(6)

Q_CAP_DIFFBUS_C0201-DIFF BUS_0.22UF,6.3V,20%,X6S,SA  I204  C696
   1 P5E_CPU1_G1_TX_C_DN<6>      1 @T6G_MB_LIB.T6G(SCH_1):P5E_CPU1_G1_TX_C_DN(6)
   2 P5E_CPU1_G1_TX_DN<6>      2 @T6G_MB_LIB.T6G(SCH_1):P5E_CPU1_G1_TX_DN(6)

Q_CAP_DIFFBUS_C0201-DIFF BUS_0.22UF,6.3V,20%,X6S,SA  I205  C695
   1 P5E_CPU1_G1_TX_C_DP<7>      1 @T6G_MB_LIB.T6G(SCH_1):P5E_CPU1_G1_TX_C_DP(7)
   2 P5E_CPU1_G1_TX_DP<7>      2 @T6G_MB_LIB.T6G(SCH_1):P5E_CPU1_G1_TX_DP(7)

Q_CAP_DIFFBUS_C0201-DIFF BUS_0.22UF,6.3V,20%,X6S,SA  I206  C694
   1 P5E_CPU1_G1_TX_C_DN<7>      1 @T6G_MB_LIB.T6G(SCH_1):P5E_CPU1_G1_TX_C_DN(7)
   2 P5E_CPU1_G1_TX_DN<7>      2 @T6G_MB_LIB.T6G(SCH_1):P5E_CPU1_G1_TX_DN(7)

Q_CAP_DIFFBUS_C0201-DIFF BUS_0.22UF,6.3V,20%,X6S,SA  I216  C56
   1 P5E_CPU1_G1_TX_C_DP<8>      1 @T6G_MB_LIB.T6G(SCH_1):P5E_CPU1_G1_TX_C_DP(8)
   2 P5E_CPU1_G1_TX_DP<8>      2 @T6G_MB_LIB.T6G(SCH_1):P5E_CPU1_G1_TX_DP(8)

Q_CAP_DIFFBUS_C0201-DIFF BUS_0.22UF,6.3V,20%,X6S,SA  I217  C692
   1 P5E_CPU1_G1_TX_C_DN<8>      1 @T6G_MB_LIB.T6G(SCH_1):P5E_CPU1_G1_TX_C_DN(8)
   2 P5E_CPU1_G1_TX_DN<8>      2 @T6G_MB_LIB.T6G(SCH_1):P5E_CPU1_G1_TX_DN(8)

Q_CAP_DIFFBUS_C0201-DIFF BUS_0.22UF,6.3V,20%,X6S,SA  I218  C691
   1 P5E_CPU1_G1_TX_C_DP<9>      1 @T6G_MB_LIB.T6G(SCH_1):P5E_CPU1_G1_TX_C_DP(9)
   2 P5E_CPU1_G1_TX_DP<9>      2 @T6G_MB_LIB.T6G(SCH_1):P5E_CPU1_G1_TX_DP(9)

Q_CAP_DIFFBUS_C0201-DIFF BUS_0.22UF,6.3V,20%,X6S,SA  I219  C690
   1 P5E_CPU1_G1_TX_C_DN<9>      1 @T6G_MB_LIB.T6G(SCH_1):P5E_CPU1_G1_TX_C_DN(9)
   2 P5E_CPU1_G1_TX_DN<9>      2 @T6G_MB_LIB.T6G(SCH_1):P5E_CPU1_G1_TX_DN(9)

Q_CAP_DIFFBUS_C0201-DIFF BUS_0.22UF,6.3V,20%,X6S,SA  I220  C688
   1 P5E_CPU1_G1_TX_C_DN<10>      1 @T6G_MB_LIB.T6G(SCH_1):P5E_CPU1_G1_TX_C_DN(10)
   2 P5E_CPU1_G1_TX_DN<10>      2 @T6G_MB_LIB.T6G(SCH_1):P5E_CPU1_G1_TX_DN(10)

Q_CAP_DIFFBUS_C0201-DIFF BUS_0.22UF,6.3V,20%,X6S,SA  I221  C689
   1 P5E_CPU1_G1_TX_C_DP<10>      1 @T6G_MB_LIB.T6G(SCH_1):P5E_CPU1_G1_TX_C_DP(10)
   2 P5E_CPU1_G1_TX_DP<10>      2 @T6G_MB_LIB.T6G(SCH_1):P5E_CPU1_G1_TX_DP(10)

Q_CAP_DIFFBUS_C0201-DIFF BUS_0.22UF,6.3V,20%,X6S,SA  I222  C687
   1 P5E_CPU1_G1_TX_C_DP<11>      1 @T6G_MB_LIB.T6G(SCH_1):P5E_CPU1_G1_TX_C_DP(11)
   2 P5E_CPU1_G1_TX_DP<11>      2 @T6G_MB_LIB.T6G(SCH_1):P5E_CPU1_G1_TX_DP(11)

Q_CAP_DIFFBUS_C0201-DIFF BUS_0.22UF,6.3V,20%,X6S,SA  I223  C686
   1 P5E_CPU1_G1_TX_C_DN<11>      1 @T6G_MB_LIB.T6G(SCH_1):P5E_CPU1_G1_TX_C_DN(11)
   2 P5E_CPU1_G1_TX_DN<11>      2 @T6G_MB_LIB.T6G(SCH_1):P5E_CPU1_G1_TX_DN(11)

Q_CAP_DIFFBUS_C0201-DIFF BUS_0.22UF,6.3V,20%,X6S,SA  I224  C685
   1 P5E_CPU1_G1_TX_C_DP<12>      1 @T6G_MB_LIB.T6G(SCH_1):P5E_CPU1_G1_TX_C_DP(12)
   2 P5E_CPU1_G1_TX_DP<12>      2 @T6G_MB_LIB.T6G(SCH_1):P5E_CPU1_G1_TX_DP(12)

Q_CAP_DIFFBUS_C0201-DIFF BUS_0.22UF,6.3V,20%,X6S,SA  I225  C684
   1 P5E_CPU1_G1_TX_C_DN<12>      1 @T6G_MB_LIB.T6G(SCH_1):P5E_CPU1_G1_TX_C_DN(12)
   2 P5E_CPU1_G1_TX_DN<12>      2 @T6G_MB_LIB.T6G(SCH_1):P5E_CPU1_G1_TX_DN(12)

Q_CAP_DIFFBUS_C0201-DIFF BUS_0.22UF,6.3V,20%,X6S,SA  I236  C683
   1 P5E_CPU1_G1_TX_C_DP<13>      1 @T6G_MB_LIB.T6G(SCH_1):P5E_CPU1_G1_TX_C_DP(13)
   2 P5E_CPU1_G1_TX_DP<13>      2 @T6G_MB_LIB.T6G(SCH_1):P5E_CPU1_G1_TX_DP(13)

Q_CAP_DIFFBUS_C0201-DIFF BUS_0.22UF,6.3V,20%,X6S,SA  I247  C682
   1 P5E_CPU1_G1_TX_C_DN<13>      1 @T6G_MB_LIB.T6G(SCH_1):P5E_CPU1_G1_TX_C_DN(13)
   2 P5E_CPU1_G1_TX_DN<13>      2 @T6G_MB_LIB.T6G(SCH_1):P5E_CPU1_G1_TX_DN(13)

Q_CAP_DIFFBUS_C0201-DIFF BUS_0.22UF,6.3V,20%,X6S,SA  I248  C681
   1 P5E_CPU1_G1_TX_C_DP<14>      1 @T6G_MB_LIB.T6G(SCH_1):P5E_CPU1_G1_TX_C_DP(14)
   2 P5E_CPU1_G1_TX_DP<14>      2 @T6G_MB_LIB.T6G(SCH_1):P5E_CPU1_G1_TX_DP(14)

Q_CAP_DIFFBUS_C0201-DIFF BUS_0.22UF,6.3V,20%,X6S,SA  I249  C680
   1 P5E_CPU1_G1_TX_C_DN<14>      1 @T6G_MB_LIB.T6G(SCH_1):P5E_CPU1_G1_TX_C_DN(14)
   2 P5E_CPU1_G1_TX_DN<14>      2 @T6G_MB_LIB.T6G(SCH_1):P5E_CPU1_G1_TX_DN(14)

Q_CAP_DIFFBUS_C0201-DIFF BUS_0.22UF,6.3V,20%,X6S,SA  I250  C679
   1 P5E_CPU1_G1_TX_C_DP<15>      1 @T6G_MB_LIB.T6G(SCH_1):P5E_CPU1_G1_TX_C_DP(15)
   2 P5E_CPU1_G1_TX_DP<15>      2 @T6G_MB_LIB.T6G(SCH_1):P5E_CPU1_G1_TX_DP(15)

Q_CAP_DIFFBUS_C0201-DIFF BUS_0.22UF,6.3V,20%,X6S,SA  I251  C678
   1 P5E_CPU1_G1_TX_C_DN<15>      1 @T6G_MB_LIB.T6G(SCH_1):P5E_CPU1_G1_TX_C_DN(15)
   2 P5E_CPU1_G1_TX_DN<15>      2 @T6G_MB_LIB.T6G(SCH_1):P5E_CPU1_G1_TX_DN(15)


DRAWING: @T6G_MB_LIB.T6G(SCH_1):PAGE297 

Q_RES_0402LF-0,5%,1/16W,CHIP,CS00002JB13  I2  R3775
   1 FM_SMB_RST_E1S_0_R_N      A @T6G_MB_LIB.T6G(SCH_1):FM_SMB_RST_E1S_0_R_N
   2 RST_SMB_E1S_N      B @T6G_MB_LIB.T6G(SCH_1):RST_SMB_E1S_N

74LVC2G07DW7-74LVC2G07DW-7,SMLF,IC,AL002G07003  I4  U134
   1 RST_SMB_E1S_N     1A @T6G_MB_LIB.T6G(SCH_1):RST_SMB_E1S_N
   3 RST_SMB_E1S_N     2A @T6G_MB_LIB.T6G(SCH_1):RST_SMB_E1S_N
   6 RST_SMB_BUF_E1S_0_N     1Y @T6G_MB_LIB.T6G(SCH_1):RST_SMB_BUF_E1S_0_N
   4 SMB_PCIE_E1S_ISO_EN_R2     2Y @T6G_MB_LIB.T6G(SCH_1):SMB_PCIE_E1S_ISO_EN_R2
   2    GND    GND @T6G_MB_LIB.T6G(SCH_1):GND
   5 P3V3_AUX    VCC @T6G_MB_LIB.T6G(SCH_1):P3V3_AUX

Q_RES_0402LF-1K,1%,1/16W,CHIP,CS21002FB06  I6  R10296
   1 E1S_0_PWRDIS      A @T6G_MB_LIB.T6G(SCH_1):E1S_0_PWRDIS
   2    GND      B @T6G_MB_LIB.T6G(SCH_1):GND

Q_RES_0402LF-10K,1%,1/16W,CHIP,CS31002FB08  I7  R3771
   1 P3V3_AUX      A @T6G_MB_LIB.T6G(SCH_1):P3V3_AUX
   2 E1S_0_PWRDIS      B @T6G_MB_LIB.T6G(SCH_1):E1S_0_PWRDIS

Q_RES_0402LF-0,5%,1/16W,CHIP,CS00002JB13  I30  R3779
   1 RST_PERST_E1S_0_N      A @T6G_MB_LIB.T6G(SCH_1):RST_PERST_E1S_0_N
   2 RST_PCIE_E1S_PERST_N      B @T6G_MB_LIB.T6G(SCH_1):RST_PCIE_E1S_PERST_N

Q_RES_0402LF-10K,1%,1/16W,CHIP,CS31002FB08  I31  R2317
   1 P3V3_E1S_0      A @T6G_MB_LIB.T6G(SCH_1):P3V3_E1S_0
   2 PU_E1S_0_DUALPORT_EN_N      B @T6G_MB_LIB.T6G(SCH_1):PU_E1S_0_DUALPORT_EN_N

Q_CAP_0402-0.1UF,25V,10%,X7R,CH4104K1B00  I36  C1592
   1 P3V3_AUX      A @T6G_MB_LIB.T6G(SCH_1):P3V3_AUX
   2    GND      B @T6G_MB_LIB.T6G(SCH_1):GND

Q_RES_0402LF-0,5%,1/16W,CHIP,CS00002JB13  I37  R2114
   1 SMB_PCIE_E1S_ISO_EN_R2      A @T6G_MB_LIB.T6G(SCH_1):SMB_PCIE_E1S_ISO_EN_R2
   2 SMB_PCIE_E1S_ISO_EN      B @T6G_MB_LIB.T6G(SCH_1):SMB_PCIE_E1S_ISO_EN

Q_RES_0402LF-0,5%,1/16W,CHIP,CS00002JB13  I38  R3772
   1 RST_SMB_BUF_E1S_0_N      A @T6G_MB_LIB.T6G(SCH_1):RST_SMB_BUF_E1S_0_N
   2 RST_SMB_E1S_0_N      B @T6G_MB_LIB.T6G(SCH_1):RST_SMB_E1S_0_N

Q_RES_0402LF-4.7K,5%,1/16W,CHIP,CS24702JB10  I40  R2125
   1 P3V3_AUX      A @T6G_MB_LIB.T6G(SCH_1):P3V3_AUX
   2 SMB_PCIE_E1S_ISO_EN      B @T6G_MB_LIB.T6G(SCH_1):SMB_PCIE_E1S_ISO_EN

Q_CAP_C0805-22UF,16V,20%,X6S,CH6223MEA01  I66  C1276
   1 P12V_E1S_0_R      A @T6G_MB_LIB.T6G(SCH_1):P12V_E1S_0_R
   2    GND      B @T6G_MB_LIB.T6G(SCH_1):GND

Q_CAP_C0805-22UF,16V,20%,X6S,CH6223MEA01  I67  C1277
   1 P12V_E1S_0_R      A @T6G_MB_LIB.T6G(SCH_1):P12V_E1S_0_R
   2    GND      B @T6G_MB_LIB.T6G(SCH_1):GND

Q_CAP_0402-0.1UF,25V,10%,X7R,CH4104K1B00  I68  C1278
   1 P12V_E1S_0_R      A @T6G_MB_LIB.T6G(SCH_1):P12V_E1S_0_R
   2    GND      B @T6G_MB_LIB.T6G(SCH_1):GND

Q_CAP_0402-0.1UF,25V,10%,X7R,CH4104K1B00  I74  C1279
   1 P12V_E1S_0_R      A @T6G_MB_LIB.T6G(SCH_1):P12V_E1S_0_R
   2    GND      B @T6G_MB_LIB.T6G(SCH_1):GND

Q_RES_0402LF-100,1%,1/16W,EMPTY,CS11002FB07  I75  R2426
   1 E1S_0_PERST1_CLKREQ_N      A @T6G_MB_LIB.T6G(SCH_1):E1S_0_PERST1_CLKREQ_N
   2    GND      B @T6G_MB_LIB.T6G(SCH_1):GND

Q_RES_0402LF-10K,1%,1/16W,CHIP,CS31002FB08  I79  R10287
   1 P3V3_E1S_0      A @T6G_MB_LIB.T6G(SCH_1):P3V3_E1S_0
   2 E1S_0_PERST1_CLKREQ_N      B @T6G_MB_LIB.T6G(SCH_1):E1S_0_PERST1_CLKREQ_N

Q_CAP_0402-0.1UF,25V,10%,X7R,CH4104K1B00  I87  C1282
   1 P3V3_E1S_0      A @T6G_MB_LIB.T6G(SCH_1):P3V3_E1S_0
   2    GND      B @T6G_MB_LIB.T6G(SCH_1):GND

Q_CAP_0402-0.1UF,25V,10%,X7R,CH4104K1B00  I88  C1283
   1 P3V3_E1S_0      A @T6G_MB_LIB.T6G(SCH_1):P3V3_E1S_0
   2    GND      B @T6G_MB_LIB.T6G(SCH_1):GND

SCONN56_123276793-SCONN56_1-2327679-3,SMLF,IO,DFHSA  I90  J90
  B1 P12V_E1S_0_R P12V_B1 @T6G_MB_LIB.T6G(SCH_1):P12V_E1S_0_R
  B2 P12V_E1S_0_R P12V_B2 @T6G_MB_LIB.T6G(SCH_1):P12V_E1S_0_R
  B3 P12V_E1S_0_R P12V_B3 @T6G_MB_LIB.T6G(SCH_1):P12V_E1S_0_R
  B4 P12V_E1S_0_R P12V_B4 @T6G_MB_LIB.T6G(SCH_1):P12V_E1S_0_R
  B5 P12V_E1S_0_R P12V_B5 @T6G_MB_LIB.T6G(SCH_1):P12V_E1S_0_R
  B6 P12V_E1S_0_R P12V_B6 @T6G_MB_LIB.T6G(SCH_1):P12V_E1S_0_R
  A1    GND GND_A1 @T6G_MB_LIB.T6G(SCH_1):GND
  A2    GND GND_A2 @T6G_MB_LIB.T6G(SCH_1):GND
  A3    GND GND_A3 @T6G_MB_LIB.T6G(SCH_1):GND
  A4    GND GND_A4 @T6G_MB_LIB.T6G(SCH_1):GND
  A5    GND GND_A5 @T6G_MB_LIB.T6G(SCH_1):GND
  A6    GND GND_A6 @T6G_MB_LIB.T6G(SCH_1):GND
  B7 TP_E1S_0_MFG    MFG @T6G_MB_LIB.T6G(SCH_1):TP_E1S_0_MFG
  B8 TP_E1S_0_RFU    RFU @T6G_MB_LIB.T6G(SCH_1):TP_E1S_0_RFU
  B9 PU_E1S_0_DUALPORT_EN_N DUALPORTEN# @T6G_MB_LIB.T6G(SCH_1):PU_E1S_0_DUALPORT_EN_N
 B11 P3V3_E1S_0 P3V3_AUX @T6G_MB_LIB.T6G(SCH_1):P3V3_E1S_0
 B12 E1S_0_PWRDIS PWRDIS @T6G_MB_LIB.T6G(SCH_1):E1S_0_PWRDIS
 B13    GND GND_B13 @T6G_MB_LIB.T6G(SCH_1):GND
 B16    GND GND_B16 @T6G_MB_LIB.T6G(SCH_1):GND
 B19    GND GND_B19 @T6G_MB_LIB.T6G(SCH_1):GND
 B22    GND GND_B22 @T6G_MB_LIB.T6G(SCH_1):GND
 B25    GND GND_B25 @T6G_MB_LIB.T6G(SCH_1):GND
 B28    GND GND_B28 @T6G_MB_LIB.T6G(SCH_1):GND
 B14 CLK_100M_CPU0_CLK12_DN REFCLK_N0 @T6G_MB_LIB.T6G(SCH_1):CLK_100M_CPU0_CLK12_DN
 B15 CLK_100M_CPU0_CLK12_DP REFCLK_P0 @T6G_MB_LIB.T6G(SCH_1):CLK_100M_CPU0_CLK12_DP
 B17 P3E_CPU0_P4_TX_C_DP<0> PET_N0 @T6G_MB_LIB.T6G(SCH_1):P3E_CPU0_P4_TX_C_DP(0)
 B18 P3E_CPU0_P4_TX_C_DN<0> PET_P0 @T6G_MB_LIB.T6G(SCH_1):P3E_CPU0_P4_TX_C_DN(0)
 B20 P3E_CPU0_P4_TX_C_DP<1> PET_N1 @T6G_MB_LIB.T6G(SCH_1):P3E_CPU0_P4_TX_C_DP(1)
 B21 P3E_CPU0_P4_TX_C_DN<1> PET_P1 @T6G_MB_LIB.T6G(SCH_1):P3E_CPU0_P4_TX_C_DN(1)
 B23 P3E_CPU0_P4_TX_C_DP<2> PET_N2 @T6G_MB_LIB.T6G(SCH_1):P3E_CPU0_P4_TX_C_DP(2)
 B24 P3E_CPU0_P4_TX_C_DN<2> PET_P2 @T6G_MB_LIB.T6G(SCH_1):P3E_CPU0_P4_TX_C_DN(2)
 B26 P3E_CPU0_P4_TX_C_DN<3> PET_N3 @T6G_MB_LIB.T6G(SCH_1):P3E_CPU0_P4_TX_C_DN(3)
 B27 P3E_CPU0_P4_TX_C_DP<3> PET_P3 @T6G_MB_LIB.T6G(SCH_1):P3E_CPU0_P4_TX_C_DP(3)
  A7 SMB_E1S_3V3AUX_ISO_SCL SMBCLK @T6G_MB_LIB.T6G(SCH_1):SMB_E1S_3V3AUX_ISO_SCL
  A8 SMB_E1S_3V3AUX_ISO_SDA SMBDAT @T6G_MB_LIB.T6G(SCH_1):SMB_E1S_3V3AUX_ISO_SDA
  A9 RST_SMB_E1S_0_N SMBRST# @T6G_MB_LIB.T6G(SCH_1):RST_SMB_E1S_0_N
 A10 FM_LED_ACTIVE_E1S_0_BUF LED#_ACTIVITY @T6G_MB_LIB.T6G(SCH_1):FM_LED_ACTIVE_E1S_0_BUF
 B10 RST_PCIE_E1S_PERST_N PERST0# @T6G_MB_LIB.T6G(SCH_1):RST_PCIE_E1S_PERST_N
 A11 E1S_0_PERST1_CLKREQ_N PERST1#_CLKREQ# @T6G_MB_LIB.T6G(SCH_1):E1S_0_PERST1_CLKREQ_N
 A12 E1S_0_PRSNT_N PRSNT0# @T6G_MB_LIB.T6G(SCH_1):E1S_0_PRSNT_N
 A13    GND GND_A13 @T6G_MB_LIB.T6G(SCH_1):GND
 A16    GND GND_A16 @T6G_MB_LIB.T6G(SCH_1):GND
 A19    GND GND_A19 @T6G_MB_LIB.T6G(SCH_1):GND
 A22    GND GND_A22 @T6G_MB_LIB.T6G(SCH_1):GND
 A25    GND GND_A25 @T6G_MB_LIB.T6G(SCH_1):GND
 A28    GND GND_A28 @T6G_MB_LIB.T6G(SCH_1):GND
 A14 TP_CLK_100M_E1S_0_DN REFCLK_N1 @T6G_MB_LIB.T6G(SCH_1):TP_CLK_100M_E1S_0_DN
 A15 TP_CLK_100M_E1S_0_DP REFCLK_P1 @T6G_MB_LIB.T6G(SCH_1):TP_CLK_100M_E1S_0_DP
 A17 P3E_CPU0_P4_RX_DP<0> PER_N0 @T6G_MB_LIB.T6G(SCH_1):P3E_CPU0_P4_RX_DP(0)
 A18 P3E_CPU0_P4_RX_DN<0> PER_P0 @T6G_MB_LIB.T6G(SCH_1):P3E_CPU0_P4_RX_DN(0)
 A20 P3E_CPU0_P4_RX_DP<1> PER_N1 @T6G_MB_LIB.T6G(SCH_1):P3E_CPU0_P4_RX_DP(1)
 A21 P3E_CPU0_P4_RX_DN<1> PER_P1 @T6G_MB_LIB.T6G(SCH_1):P3E_CPU0_P4_RX_DN(1)
 A23 P3E_CPU0_P4_RX_DP<2> PER_N2 @T6G_MB_LIB.T6G(SCH_1):P3E_CPU0_P4_RX_DP(2)
 A24 P3E_CPU0_P4_RX_DN<2> PER_P2 @T6G_MB_LIB.T6G(SCH_1):P3E_CPU0_P4_RX_DN(2)
 A26 P3E_CPU0_P4_RX_DP<3> PER_N3 @T6G_MB_LIB.T6G(SCH_1):P3E_CPU0_P4_RX_DP(3)
 A27 P3E_CPU0_P4_RX_DN<3> PER_P3 @T6G_MB_LIB.T6G(SCH_1):P3E_CPU0_P4_RX_DN(3)
  G2    GND     G2 @T6G_MB_LIB.T6G(SCH_1):GND
  G1    GND     G1 @T6G_MB_LIB.T6G(SCH_1):GND

Q_RES_0402LF-0,5%,1/16W,CHIP,CS00002JB13  I94  R955
   1 FM_LED_ACTIVE_E1S_0      A @T6G_MB_LIB.T6G(SCH_1):FM_LED_ACTIVE_E1S_0
   2 FM_LED_ACTIVE_E1S_0_R      B @T6G_MB_LIB.T6G(SCH_1):FM_LED_ACTIVE_E1S_0_R

Q_RES_0402LF-4.7K,5%,1/16W,CHIP,CS24702JB10  I95  R999
   1 FM_LED_ACTIVE_E1S_0_R      A @T6G_MB_LIB.T6G(SCH_1):FM_LED_ACTIVE_E1S_0_R
   2    GND      B @T6G_MB_LIB.T6G(SCH_1):GND

74LVC1G17GW-74LVC1G17GW,SMLF,IC,AL1G0017K01  I97  U44
   5 P3V3_E1S_0    VCC @T6G_MB_LIB.T6G(SCH_1):P3V3_E1S_0
   2 FM_LED_ACTIVE_E1S_0_R      A @T6G_MB_LIB.T6G(SCH_1):FM_LED_ACTIVE_E1S_0_R
   3    GND    GND @T6G_MB_LIB.T6G(SCH_1):GND
   4 FM_LED_ACTIVE_E1S_0_R_BUF      Y @T6G_MB_LIB.T6G(SCH_1):FM_LED_ACTIVE_E1S_0_R_BUF
   1     NC     NC     NC

Q_CAP_0402-0.1UF,25V,10%,X7R,CH4104K1B00  I99  C508
   1 P3V3_E1S_0      A @T6G_MB_LIB.T6G(SCH_1):P3V3_E1S_0
   2    GND      B @T6G_MB_LIB.T6G(SCH_1):GND

Q_RES_0402LF-0,5%,1/16W,CHIP,CS00002JB13  I101  R1038
   1 FM_LED_ACTIVE_E1S_0_R_BUF      A @T6G_MB_LIB.T6G(SCH_1):FM_LED_ACTIVE_E1S_0_R_BUF
   2 FM_LED_ACTIVE_E1S_0_BUF      B @T6G_MB_LIB.T6G(SCH_1):FM_LED_ACTIVE_E1S_0_BUF

Q_RES_0402LF-4.7K,5%,1/16W,CHIP,CS24702JB10  I102  R1000
   1 FM_LED_ACTIVE_E1S_0_BUF      A @T6G_MB_LIB.T6G(SCH_1):FM_LED_ACTIVE_E1S_0_BUF
   2    GND      B @T6G_MB_LIB.T6G(SCH_1):GND

Q_RES_0402LF-10K,1%,1/16W,CHIP,CS31002FB08  I105  R1673
   1 P3V3_E1S_0      A @T6G_MB_LIB.T6G(SCH_1):P3V3_E1S_0
   2 RST_SMB_E1S_0_N      B @T6G_MB_LIB.T6G(SCH_1):RST_SMB_E1S_0_N

Q_RES_0402LF-4.7K,5%,1/16W,EMPTY,CS24702JB10  I106  R3773
   1 P3V3_AUX      A @T6G_MB_LIB.T6G(SCH_1):P3V3_AUX
   2 RST_SMB_E1S_0_N      B @T6G_MB_LIB.T6G(SCH_1):RST_SMB_E1S_0_N


DRAWING: @T6G_MB_LIB.T6G(SCH_1):PAGE110 

Q_RES_0402LF-68K,1%,1/16W,EMPTY,CS36802FB04  I2  R3268
   1 FM_P2E_EQA1      A @T6G_MB_LIB.T6G(SCH_1):FM_P2E_EQA1
   2    GND      B @T6G_MB_LIB.T6G(SCH_1):GND

Q_RES_0402LF-1K,1%,1/16W,EMPTY,CS21002FB06  I4  R3272
   1 FM_P2E_EQA1      A @T6G_MB_LIB.T6G(SCH_1):FM_P2E_EQA1
   2    GND      B @T6G_MB_LIB.T6G(SCH_1):GND

Q_RES_0402LF-1K,1%,1/16W,EMPTY,CS21002FB06  I5  R3271
   1 P3V3_AUX      A @T6G_MB_LIB.T6G(SCH_1):P3V3_AUX
   2 FM_P2E_EQA1      B @T6G_MB_LIB.T6G(SCH_1):FM_P2E_EQA1

Q_RES_0402LF-68K,1%,1/16W,EMPTY,CS36802FB04  I8  R3267
   1 FM_P2E_FGB      A @T6G_MB_LIB.T6G(SCH_1):FM_P2E_FGB
   2    GND      B @T6G_MB_LIB.T6G(SCH_1):GND

Q_RES_0402LF-1K,1%,1/16W,EMPTY,CS21002FB06  I9  R3270
   1 FM_P2E_FGB      A @T6G_MB_LIB.T6G(SCH_1):FM_P2E_FGB
   2    GND      B @T6G_MB_LIB.T6G(SCH_1):GND

Q_RES_0402LF-68K,1%,1/16W,EMPTY,CS36802FB04  I12  R3273
   1 FM_P2E_FGA      A @T6G_MB_LIB.T6G(SCH_1):FM_P2E_FGA
   2    GND      B @T6G_MB_LIB.T6G(SCH_1):GND

Q_RES_0402LF-1K,1%,1/16W,EMPTY,CS21002FB06  I14  R3269
   1 P3V3_AUX      A @T6G_MB_LIB.T6G(SCH_1):P3V3_AUX
   2 FM_P2E_FGB      B @T6G_MB_LIB.T6G(SCH_1):FM_P2E_FGB

Q_RES_0402LF-68K,1%,1/16W,EMPTY,CS36802FB04  I16  R3274
   1 FM_P2E_EQA0      A @T6G_MB_LIB.T6G(SCH_1):FM_P2E_EQA0
   2    GND      B @T6G_MB_LIB.T6G(SCH_1):GND

Q_RES_0402LF-1K,1%,1/16W,CHIP,CS21002FB06  I18  R3278
   1 FM_P2E_EQA0      A @T6G_MB_LIB.T6G(SCH_1):FM_P2E_EQA0
   2    GND      B @T6G_MB_LIB.T6G(SCH_1):GND

Q_RES_0402LF-1K,1%,1/16W,EMPTY,CS21002FB06  I19  R3277
   1 P3V3_AUX      A @T6G_MB_LIB.T6G(SCH_1):P3V3_AUX
   2 FM_P2E_EQA0      B @T6G_MB_LIB.T6G(SCH_1):FM_P2E_EQA0

Q_RES_0402LF-68K,1%,1/16W,EMPTY,CS36802FB04  I22  R3279
   1 FM_P2E_EQB1      A @T6G_MB_LIB.T6G(SCH_1):FM_P2E_EQB1
   2    GND      B @T6G_MB_LIB.T6G(SCH_1):GND

Q_RES_0402LF-1K,1%,1/16W,EMPTY,CS21002FB06  I25  R3281
   1 FM_P2E_EQB1      A @T6G_MB_LIB.T6G(SCH_1):FM_P2E_EQB1
   2    GND      B @T6G_MB_LIB.T6G(SCH_1):GND

Q_RES_0402LF-1K,1%,1/16W,EMPTY,CS21002FB06  I26  R3280
   1 P3V3_AUX      A @T6G_MB_LIB.T6G(SCH_1):P3V3_AUX
   2 FM_P2E_EQB1      B @T6G_MB_LIB.T6G(SCH_1):FM_P2E_EQB1

Q_RES_0402LF-1K,1%,1/16W,EMPTY,CS21002FB06  I29  R3276
   1 FM_P2E_FGA      A @T6G_MB_LIB.T6G(SCH_1):FM_P2E_FGA
   2    GND      B @T6G_MB_LIB.T6G(SCH_1):GND

Q_RES_0402LF-1K,1%,1/16W,EMPTY,CS21002FB06  I32  R3275
   1 P3V3_AUX      A @T6G_MB_LIB.T6G(SCH_1):P3V3_AUX
   2 FM_P2E_FGA      B @T6G_MB_LIB.T6G(SCH_1):FM_P2E_FGA

Q_RES_0402LF-68K,1%,1/16W,EMPTY,CS36802FB04  I34  R3282
   1 FM_P2E_EQB0      A @T6G_MB_LIB.T6G(SCH_1):FM_P2E_EQB0
   2    GND      B @T6G_MB_LIB.T6G(SCH_1):GND

Q_RES_0402LF-1K,1%,1/16W,CHIP,CS21002FB06  I36  R3284
   1 FM_P2E_EQB0      A @T6G_MB_LIB.T6G(SCH_1):FM_P2E_EQB0
   2    GND      B @T6G_MB_LIB.T6G(SCH_1):GND

Q_RES_0402LF-1K,1%,1/16W,EMPTY,CS21002FB06  I37  R3283
   1 P3V3_AUX      A @T6G_MB_LIB.T6G(SCH_1):P3V3_AUX
   2 FM_P2E_EQB0      B @T6G_MB_LIB.T6G(SCH_1):FM_P2E_EQB0

Q_RES_0402LF-68K,1%,1/16W,EMPTY,CS36802FB04  I42  R3285
   1 FM_P2E_SWB      A @T6G_MB_LIB.T6G(SCH_1):FM_P2E_SWB
   2    GND      B @T6G_MB_LIB.T6G(SCH_1):GND

Q_RES_0402LF-1K,1%,1/16W,EMPTY,CS21002FB06  I44  R3287
   1 FM_P2E_SWB      A @T6G_MB_LIB.T6G(SCH_1):FM_P2E_SWB
   2    GND      B @T6G_MB_LIB.T6G(SCH_1):GND

Q_RES_0402LF-1K,1%,1/16W,EMPTY,CS21002FB06  I45  R3286
   1 P3V3_AUX      A @T6G_MB_LIB.T6G(SCH_1):P3V3_AUX
   2 FM_P2E_SWB      B @T6G_MB_LIB.T6G(SCH_1):FM_P2E_SWB

Q_CAP_C0805-10UF,25V,10%,X6S,CH6104KEA00  I60  C1867
   1 P3V3_AUX      A @T6G_MB_LIB.T6G(SCH_1):P3V3_AUX
   2    GND      B @T6G_MB_LIB.T6G(SCH_1):GND

Q_CAP_0402-0.1UF,25V,10%,X7R,CH4104K1B00  I61  C1863
   1 P3V3_AUX      A @T6G_MB_LIB.T6G(SCH_1):P3V3_AUX
   2    GND      B @T6G_MB_LIB.T6G(SCH_1):GND

Q_CAP_0402-0.1UF,25V,10%,X7R,CH4104K1B00  I62  C1864
   1 P3V3_AUX      A @T6G_MB_LIB.T6G(SCH_1):P3V3_AUX
   2    GND      B @T6G_MB_LIB.T6G(SCH_1):GND

PI3EQX12902AZLEX-PI3EQX12902AZLEX,SMLF,IC,AL012902A  I63  U237
   1 P3V3_AUX   VDD1 @T6G_MB_LIB.T6G(SCH_1):P3V3_AUX
   2 P2E_MB_BMC_TX_C_R1_DP<0>    AIP @T6G_MB_LIB.T6G(SCH_1):P2E_MB_BMC_TX_C_R1_DP(0)
   3 P2E_MB_BMC_TX_C_R1_DN<0>    AIN @T6G_MB_LIB.T6G(SCH_1):P2E_MB_BMC_TX_C_R1_DN(0)
   4    GND   GND1 @T6G_MB_LIB.T6G(SCH_1):GND
   5 PU_TEST  TEST# @T6G_MB_LIB.T6G(SCH_1):PU_TEST
   6    GND   GND2 @T6G_MB_LIB.T6G(SCH_1):GND
   7    GND   GND3 @T6G_MB_LIB.T6G(SCH_1):GND
   8 P2E_MB_BMC_RX_BUF_C_DN<0>    BON @T6G_MB_LIB.T6G(SCH_1):P2E_MB_BMC_RX_BUF_C_DN(0)
   9 P2E_MB_BMC_RX_BUF_C_DP<0>    BOP @T6G_MB_LIB.T6G(SCH_1):P2E_MB_BMC_RX_BUF_C_DP(0)
  10 P3V3_AUX   VDD2 @T6G_MB_LIB.T6G(SCH_1):P3V3_AUX
  11 FM_P2E_EN_N    EN# @T6G_MB_LIB.T6G(SCH_1):FM_P2E_EN_N
  12 FM_P2E_SWB    SWB @T6G_MB_LIB.T6G(SCH_1):FM_P2E_SWB
  13    GND   GND4 @T6G_MB_LIB.T6G(SCH_1):GND
  14 FM_P2E_FGB    FGB @T6G_MB_LIB.T6G(SCH_1):FM_P2E_FGB
  15 FM_P2E_EQB1   EQB1 @T6G_MB_LIB.T6G(SCH_1):FM_P2E_EQB1
  16 P3V3_AUX   VDD3 @T6G_MB_LIB.T6G(SCH_1):P3V3_AUX
  17 P2E_MB_BMC_RX_R1_DP<0>    BIP @T6G_MB_LIB.T6G(SCH_1):P2E_MB_BMC_RX_R1_DP(0)
  18 P2E_MB_BMC_RX_R1_DN<0>    BIN @T6G_MB_LIB.T6G(SCH_1):P2E_MB_BMC_RX_R1_DN(0)
  19    GND   GND5 @T6G_MB_LIB.T6G(SCH_1):GND
  20 FM_P2E_EQB0   EQB0 @T6G_MB_LIB.T6G(SCH_1):FM_P2E_EQB0
  21 FM_P2E_EQA0   EQA0 @T6G_MB_LIB.T6G(SCH_1):FM_P2E_EQA0
  22    GND   GND6 @T6G_MB_LIB.T6G(SCH_1):GND
  23 P2E_MB_BMC_TX_BUF_DN<0>    AON @T6G_MB_LIB.T6G(SCH_1):P2E_MB_BMC_TX_BUF_DN(0)
  24 P2E_MB_BMC_TX_BUF_DP<0>    AOP @T6G_MB_LIB.T6G(SCH_1):P2E_MB_BMC_TX_BUF_DP(0)
  25 P3V3_AUX   VDD4 @T6G_MB_LIB.T6G(SCH_1):P3V3_AUX
  26 FM_P2E_EQA1   EQA1 @T6G_MB_LIB.T6G(SCH_1):FM_P2E_EQA1
  27 FM_P2E_FGA    FGA @T6G_MB_LIB.T6G(SCH_1):FM_P2E_FGA
  28    GND   GND7 @T6G_MB_LIB.T6G(SCH_1):GND
  29 FM_P2E_SWA    SWA @T6G_MB_LIB.T6G(SCH_1):FM_P2E_SWA
  30 FM_P2E_MODE   MODE @T6G_MB_LIB.T6G(SCH_1):FM_P2E_MODE
  TH    GND GND_TH @T6G_MB_LIB.T6G(SCH_1):GND

Q_CAP_0402-0.1UF,25V,10%,X7R,CH4104K1B00  I64  C1865
   1 P3V3_AUX      A @T6G_MB_LIB.T6G(SCH_1):P3V3_AUX
   2    GND      B @T6G_MB_LIB.T6G(SCH_1):GND

Q_CAP_0402-0.1UF,25V,10%,X7R,CH4104K1B00  I65  C1866
   1 P3V3_AUX      A @T6G_MB_LIB.T6G(SCH_1):P3V3_AUX
   2    GND      B @T6G_MB_LIB.T6G(SCH_1):GND

Q_RES_0402LF-0,5%,1/16W,CHIP,CS00002JB13  I67  R4537
   1 FM_P2E_EN_N      A @T6G_MB_LIB.T6G(SCH_1):FM_P2E_EN_N
   2 CLK_GEN2_GPU_FPGA_OE_OR_N      B @T6G_MB_LIB.T6G(SCH_1):CLK_GEN2_GPU_FPGA_OE_OR_N

Q_RES_0402LF-68K,1%,1/16W,EMPTY,CS36802FB04  I74  R3288
   1 FM_P2E_SWA      A @T6G_MB_LIB.T6G(SCH_1):FM_P2E_SWA
   2    GND      B @T6G_MB_LIB.T6G(SCH_1):GND

Q_RES_0402LF-1K,1%,1/16W,EMPTY,CS21002FB06  I76  R3290
   1 FM_P2E_SWA      A @T6G_MB_LIB.T6G(SCH_1):FM_P2E_SWA
   2    GND      B @T6G_MB_LIB.T6G(SCH_1):GND

Q_RES_0402LF-1K,1%,1/16W,EMPTY,CS21002FB06  I77  R3289
   1 P3V3_AUX      A @T6G_MB_LIB.T6G(SCH_1):P3V3_AUX
   2 FM_P2E_SWA      B @T6G_MB_LIB.T6G(SCH_1):FM_P2E_SWA

Q_RES_0402LF-4.7K,1%,1/16W,EMPTY,CS24702FB06  I81  R3265
   1 CLK_GEN2_GPU_FPGA_OE_OR_N      A @T6G_MB_LIB.T6G(SCH_1):CLK_GEN2_GPU_FPGA_OE_OR_N
   2    GND      B @T6G_MB_LIB.T6G(SCH_1):GND

Q_RES_0402LF-4.7K,1%,1/16W,EMPTY,CS24702FB06  I88  R3291
   1 PU_TEST      A @T6G_MB_LIB.T6G(SCH_1):PU_TEST
   2    GND      B @T6G_MB_LIB.T6G(SCH_1):GND

Q_RES_0402LF-4.7K,1%,1/16W,CHIP,CS24702FB06  I89  R3292
   1 P3V3_AUX      A @T6G_MB_LIB.T6G(SCH_1):P3V3_AUX
   2 CLK_GEN2_GPU_FPGA_OE_OR_N      B @T6G_MB_LIB.T6G(SCH_1):CLK_GEN2_GPU_FPGA_OE_OR_N

Q_RES_0402LF-4.7K,1%,1/16W,EMPTY,CS24702FB06  I92  R3293
   1 FM_P2E_MODE      A @T6G_MB_LIB.T6G(SCH_1):FM_P2E_MODE
   2    GND      B @T6G_MB_LIB.T6G(SCH_1):GND

Q_RES_0402LF-4.7K,1%,1/16W,CHIP,CS24702FB06  I93  R3266
   1 P3V3_AUX      A @T6G_MB_LIB.T6G(SCH_1):P3V3_AUX
   2 FM_P2E_MODE      B @T6G_MB_LIB.T6G(SCH_1):FM_P2E_MODE


DRAWING: @T6G_MB_LIB.T6G(SCH_1):PAGE53 

Q_CAP_DIFFBUS_C0201-DIFF BUS_0.22UF,6.3V,20%,X6S,SA  I132  C2073
   1 P3E_CPU1_P5_TX_C_DP<1>      1 @T6G_MB_LIB.T6G(SCH_1):P3E_CPU1_P5_TX_C_DP(1)
   2 P3E_CPU1_P5_TX_DP<1>      2 @T6G_MB_LIB.T6G(SCH_1):P3E_CPU1_P5_TX_DP(1)

Q_CAP_DIFFBUS_C0201-DIFF BUS_0.22UF,6.3V,20%,X6S,SA  I133  C2074
   1 P3E_CPU1_P5_TX_C_DN<1>      1 @T6G_MB_LIB.T6G(SCH_1):P3E_CPU1_P5_TX_C_DN(1)
   2 P3E_CPU1_P5_TX_DN<1>      2 @T6G_MB_LIB.T6G(SCH_1):P3E_CPU1_P5_TX_DN(1)

Q_CAP_DIFFBUS_C0201-DIFF BUS_0.22UF,6.3V,20%,X6S,SA  I134  C2076
   1 P3E_CPU1_P5_TX_C_DN<0>      1 @T6G_MB_LIB.T6G(SCH_1):P3E_CPU1_P5_TX_C_DN(0)
   2 P3E_CPU1_P5_TX_DN<0>      2 @T6G_MB_LIB.T6G(SCH_1):P3E_CPU1_P5_TX_DN(0)

Q_CAP_DIFFBUS_C0201-DIFF BUS_0.22UF,6.3V,20%,X6S,SA  I135  C2075
   1 P3E_CPU1_P5_TX_C_DP<0>      1 @T6G_MB_LIB.T6G(SCH_1):P3E_CPU1_P5_TX_C_DP(0)
   2 P3E_CPU1_P5_TX_DP<0>      2 @T6G_MB_LIB.T6G(SCH_1):P3E_CPU1_P5_TX_DP(0)

GENOA_SP5-SOCKET6096_13568-001,SMLF,IO,DGA^6000030  I145  U26
DG47 P3E_CPU1_P4_RX_DN<2> P4_RXN2 @T6G_MB_LIB.T6G(SCH_1):P3E_CPU1_P4_RX_DN(2)
DG44 P3E_CPU1_P4_RX_DN<3> P4_RXN3 @T6G_MB_LIB.T6G(SCH_1):P3E_CPU1_P4_RX_DN(3)
DG48 P3E_CPU1_P4_RX_DP<2> P4_RXP2 @T6G_MB_LIB.T6G(SCH_1):P3E_CPU1_P4_RX_DP(2)
DG45 P3E_CPU1_P4_RX_DP<3> P4_RXP3 @T6G_MB_LIB.T6G(SCH_1):P3E_CPU1_P4_RX_DP(3)
DE46 P3E_CPU1_P4_TX_DN<2> P4_TXN2 @T6G_MB_LIB.T6G(SCH_1):P3E_CPU1_P4_TX_DN(2)
DE43 P3E_CPU1_P4_TX_DN<3> P4_TXN3 @T6G_MB_LIB.T6G(SCH_1):P3E_CPU1_P4_TX_DN(3)
DE47 P3E_CPU1_P4_TX_DP<2> P4_TXP2 @T6G_MB_LIB.T6G(SCH_1):P3E_CPU1_P4_TX_DP(2)
DE44 P3E_CPU1_P4_TX_DP<3> P4_TXP3 @T6G_MB_LIB.T6G(SCH_1):P3E_CPU1_P4_TX_DP(3)
 E44 P3E_CPU1_P5_RX_DP<0> P5_RXN2 @T6G_MB_LIB.T6G(SCH_1):P3E_CPU1_P5_RX_DP(0)
 E41 P3E_CPU1_P5_RX_DP<1> P5_RXN3 @T6G_MB_LIB.T6G(SCH_1):P3E_CPU1_P5_RX_DP(1)
 E43 P3E_CPU1_P5_RX_DN<0> P5_RXP2 @T6G_MB_LIB.T6G(SCH_1):P3E_CPU1_P5_RX_DN(0)
 E40 P3E_CPU1_P5_RX_DN<1> P5_RXP3 @T6G_MB_LIB.T6G(SCH_1):P3E_CPU1_P5_RX_DN(1)
 C45 P3E_CPU1_P5_TX_DN<0> P5_TXN2 @T6G_MB_LIB.T6G(SCH_1):P3E_CPU1_P5_TX_DN(0)
 C42 P3E_CPU1_P5_TX_DN<1> P5_TXN3 @T6G_MB_LIB.T6G(SCH_1):P3E_CPU1_P5_TX_DN(1)
 C44 P3E_CPU1_P5_TX_DP<0> P5_TXP2 @T6G_MB_LIB.T6G(SCH_1):P3E_CPU1_P5_TX_DP(0)
 C41 P3E_CPU1_P5_TX_DP<1> P5_TXP3 @T6G_MB_LIB.T6G(SCH_1):P3E_CPU1_P5_TX_DP(1)
DE53 P3E_CPU1_P4_TX_DP<0> P4_TXP0 @T6G_MB_LIB.T6G(SCH_1):P3E_CPU1_P4_TX_DP(0)
DE50 P3E_CPU1_P4_TX_DP<1> P4_TXP1 @T6G_MB_LIB.T6G(SCH_1):P3E_CPU1_P4_TX_DP(1)
DE52 P3E_CPU1_P4_TX_DN<0> P4_TXN0 @T6G_MB_LIB.T6G(SCH_1):P3E_CPU1_P4_TX_DN(0)
DG54 P3E_CPU1_P4_RX_DP<0> P4_RXP0 @T6G_MB_LIB.T6G(SCH_1):P3E_CPU1_P4_RX_DP(0)
DE49 P3E_CPU1_P4_TX_DN<1> P4_TXN1 @T6G_MB_LIB.T6G(SCH_1):P3E_CPU1_P4_TX_DN(1)
DG51 P3E_CPU1_P4_RX_DP<1> P4_RXP1 @T6G_MB_LIB.T6G(SCH_1):P3E_CPU1_P4_RX_DP(1)
DG53 P3E_CPU1_P4_RX_DN<0> P4_RXN0 @T6G_MB_LIB.T6G(SCH_1):P3E_CPU1_P4_RX_DN(0)
DG50 P3E_CPU1_P4_RX_DN<1> P4_RXN1 @T6G_MB_LIB.T6G(SCH_1):P3E_CPU1_P4_RX_DN(1)
 E50     NC WAFL_RXN0||P5_RXN0     NC
 E49     NC WAFL_RXP0||P5_RXP0     NC
 E47 WAFL_CPU0_TX0_CPU1_RX1_DN WAFL_RXN1||P5_RXN1 @T6G_MB_LIB.T6G(SCH_1):WAFL_CPU0_TX0_CPU1_RX1_DN
 E46 WAFL_CPU0_TX0_CPU1_RX1_DP WAFL_RXP1||P5_RXP1 @T6G_MB_LIB.T6G(SCH_1):WAFL_CPU0_TX0_CPU1_RX1_DP
 C51     NC WAFL_TXN0||P5_TXN0     NC
 C50     NC WAFL_TXP0||P5_TXP0     NC
 C48 WAFL_CPU1_TX1_CPU0_RX0_DN WAFL_TXN1||P5_TXN1 @T6G_MB_LIB.T6G(SCH_1):WAFL_CPU1_TX1_CPU0_RX0_DN
 C47 WAFL_CPU1_TX1_CPU0_RX0_DP WAFL_TXP1||P5_TXP1 @T6G_MB_LIB.T6G(SCH_1):WAFL_CPU1_TX1_CPU0_RX0_DP


DRAWING: @T6G_MB_LIB.T6G(SCH_1):PAGE28 

Q_RES_0402LF-1K,1%,1/16W,EMPTY,CS21002FB06  I22  R420
   1 PVDD11_S3_P0      A @T6G_MB_LIB.T6G(SCH_1):PVDD11_S3_P0
   2 I3C_1_SPD_DDRGL_CPU0_R_SDA      B @T6G_MB_LIB.T6G(SCH_1):I3C_1_SPD_DDRGL_CPU0_R_SDA

Q_RES_0402LF-1K,1%,1/16W,EMPTY,CS21002FB06  I25  R425
   1 PVDD11_S3_P0      A @T6G_MB_LIB.T6G(SCH_1):PVDD11_S3_P0
   2 I3C_0_SPD_DDRAF_CPU0_R_SCL      B @T6G_MB_LIB.T6G(SCH_1):I3C_0_SPD_DDRAF_CPU0_R_SCL

Q_RES_0402LF-1K,1%,1/16W,CHIP,CS21002FB06  I53  R443
   1 PWRGD_CPU0_PWROK      A @T6G_MB_LIB.T6G(SCH_1):PWRGD_CPU0_PWROK
   2 PVDD18_S5_P0      B @T6G_MB_LIB.T6G(SCH_1):PVDD18_S5_P0

Q_RES_0402LF-33,5%,1/16W,CHIP,CS03302JB10  I96  R212
   1 SMB_CPU_5_R_SCL      A @T6G_MB_LIB.T6G(SCH_1):SMB_CPU_5_R_SCL
   2 SMB_CPU_5_SCL      B @T6G_MB_LIB.T6G(SCH_1):SMB_CPU_5_SCL

Q_RES_0402LF-33,5%,1/16W,CHIP,CS03302JB10  I136  R248
   1 FM_CPU0_SLP_S5_N      A @T6G_MB_LIB.T6G(SCH_1):FM_CPU0_SLP_S5_N
   2 CPU0_SLP_S5_N      B @T6G_MB_LIB.T6G(SCH_1):CPU0_SLP_S5_N

Q_CRYSTAL_SMLF-32.768KHZ,IC,BG632768012  I140  Y3
   1 XTAL_CPU0_X32K_X1      1 @T6G_MB_LIB.T6G(SCH_1):XTAL_CPU0_X32K_X1
   2 XTAL_CPU0_X32K_X2      2 @T6G_MB_LIB.T6G(SCH_1):XTAL_CPU0_X32K_X2

Q_RES_0402LF-0,5%,1/16W,CHIP,CS00002JB13  I151  R2660
   1 CLK_100M_CPU0_CLK11_R_DN      A @T6G_MB_LIB.T6G(SCH_1):CLK_100M_CPU0_CLK11_R_DN
   2 CLK_100M_CPU0_CLK11_DN      B @T6G_MB_LIB.T6G(SCH_1):CLK_100M_CPU0_CLK11_DN

Q_RES_0402LF-0,5%,1/16W,CHIP,CS00002JB13  I155  R8566
   1 CLK_100M_CPU0_CLK03_R_DN      A @T6G_MB_LIB.T6G(SCH_1):CLK_100M_CPU0_CLK03_R_DN
   2 CLK_100M_CPU0_CLK03_DN      B @T6G_MB_LIB.T6G(SCH_1):CLK_100M_CPU0_CLK03_DN

Q_RES_0402LF-0,5%,1/16W,CHIP,CS00002JB13  I156  R8564
   1 CLK_100M_CPU0_CLK02_R_DN      A @T6G_MB_LIB.T6G(SCH_1):CLK_100M_CPU0_CLK02_R_DN
   2 CLK_100M_CPU0_CLK02_DN      B @T6G_MB_LIB.T6G(SCH_1):CLK_100M_CPU0_CLK02_DN

Q_RES_0402LF-0,5%,1/16W,CHIP,CS00002JB13  I171  R435
   1 CLK_100M_REF_OUT_DP      A @T6G_MB_LIB.T6G(SCH_1):CLK_100M_REF_OUT_DP
   2 CLK_100M_REF_IN_DP      B @T6G_MB_LIB.T6G(SCH_1):CLK_100M_REF_IN_DP

Q_RES_0402LF-0,5%,1/16W,CHIP,CS00002JB13  I172  R436
   1 CLK_100M_REF_OUT_DN      A @T6G_MB_LIB.T6G(SCH_1):CLK_100M_REF_OUT_DN
   2 CLK_100M_REF_IN_DN      B @T6G_MB_LIB.T6G(SCH_1):CLK_100M_REF_IN_DN

Q_RES_0402LF-1K,1%,1/16W,EMPTY,CS21002FB06  I23  R421
   1 PVDD11_S3_P0      A @T6G_MB_LIB.T6G(SCH_1):PVDD11_S3_P0
   2 I3C_1_SPD_DDRGL_CPU0_R_SCL      B @T6G_MB_LIB.T6G(SCH_1):I3C_1_SPD_DDRGL_CPU0_R_SCL

Q_RES_0402LF-1K,1%,1/16W,EMPTY,CS21002FB06  I24  R423
   1 PVDD11_S3_P0      A @T6G_MB_LIB.T6G(SCH_1):PVDD11_S3_P0
   2 I3C_0_SPD_DDRAF_CPU0_R_SDA      B @T6G_MB_LIB.T6G(SCH_1):I3C_0_SPD_DDRAF_CPU0_R_SDA

CONN6_HBC1031L200D8H-CONN6_HBC1031-L200D-8H,THLF,IA  I28  J6
   1 CPU0_PWR_BTN_N      1 @T6G_MB_LIB.T6G(SCH_1):CPU0_PWR_BTN_N
   2    GND      2 @T6G_MB_LIB.T6G(SCH_1):GND
   3 RST_CPU0_SYS_N      3 @T6G_MB_LIB.T6G(SCH_1):RST_CPU0_SYS_N
   4    GND      4 @T6G_MB_LIB.T6G(SCH_1):GND
   5     NC      5     NC
   6    GND      6 @T6G_MB_LIB.T6G(SCH_1):GND

Q_RES_0402LF-2.2K,5%,1/16W,CHIP,CS22202JB07  I29  R422
   1 PVDD18_S5_P0      A @T6G_MB_LIB.T6G(SCH_1):PVDD18_S5_P0
   2 RST_CPU0_SYS_N      B @T6G_MB_LIB.T6G(SCH_1):RST_CPU0_SYS_N

Q_RES_0402LF-2.2K,5%,1/16W,CHIP,CS22202JB07  I30  R424
   1 PVDD18_S5_P0      A @T6G_MB_LIB.T6G(SCH_1):PVDD18_S5_P0
   2 CPU0_PWR_BTN_N      B @T6G_MB_LIB.T6G(SCH_1):CPU0_PWR_BTN_N

Q_RES_0402LF-4.7K,5%,1/16W,EMPTY,CS24702JB10  I33  R582
   1    GND      A @T6G_MB_LIB.T6G(SCH_1):GND
   2 RST_CPU0_RSMRST_N      B @T6G_MB_LIB.T6G(SCH_1):RST_CPU0_RSMRST_N

Q_RES_0402LF-4.7K,5%,1/16W,EMPTY,CS24702JB10  I34  R581
   1 RST_CPU0_RSMRST_N      A @T6G_MB_LIB.T6G(SCH_1):RST_CPU0_RSMRST_N
   2 PVDD18_S5_P0      B @T6G_MB_LIB.T6G(SCH_1):PVDD18_S5_P0

Q_RES_0402LF-4.7K,5%,1/16W,EMPTY,CS24702JB10  I36  R287
   1    GND      A @T6G_MB_LIB.T6G(SCH_1):GND
   2 CPU0_PWR_GOOD      B @T6G_MB_LIB.T6G(SCH_1):CPU0_PWR_GOOD

Q_RES_0402LF-4.7K,5%,1/16W,EMPTY,CS24702JB10  I37  R440
   1    GND      A @T6G_MB_LIB.T6G(SCH_1):GND
   2 CPU0_PWR_GD_OUT      B @T6G_MB_LIB.T6G(SCH_1):CPU0_PWR_GD_OUT

Q_RES_0402LF-4.7K,5%,1/16W,EMPTY,CS24702JB10  I40  R5026
   1    GND      A @T6G_MB_LIB.T6G(SCH_1):GND
   2 FM_SMM_CRASHDUMP      B @T6G_MB_LIB.T6G(SCH_1):FM_SMM_CRASHDUMP

Q_RES_0402LF-4.7K,5%,1/16W,CHIP,CS24702JB10  I41  R276
   1 CPU0_PWR_GOOD      A @T6G_MB_LIB.T6G(SCH_1):CPU0_PWR_GOOD
   2 PVDD18_S5_P0      B @T6G_MB_LIB.T6G(SCH_1):PVDD18_S5_P0

Q_RES_0402LF-4.7K,5%,1/16W,EMPTY,CS24702JB10  I42  R288
   1 CPU0_PWR_GD_OUT      A @T6G_MB_LIB.T6G(SCH_1):CPU0_PWR_GD_OUT
   2 PVDD18_S5_P0      B @T6G_MB_LIB.T6G(SCH_1):PVDD18_S5_P0

Q_RES_0402LF-4.7K,5%,1/16W,CHIP,CS24702JB10  I43  R444
   1 FM_SMM_CRASHDUMP      A @T6G_MB_LIB.T6G(SCH_1):FM_SMM_CRASHDUMP
   2 PVDD18_S5_P0      B @T6G_MB_LIB.T6G(SCH_1):PVDD18_S5_P0

Q_RES_0402LF-2.2K,5%,1/16W,CHIP,CS22202JB07  I44  R207
   1 FM_INT_CPU0_HP_UBM_N      A @T6G_MB_LIB.T6G(SCH_1):FM_INT_CPU0_HP_UBM_N
   2 PVDD18_S5_P0      B @T6G_MB_LIB.T6G(SCH_1):PVDD18_S5_P0

Q_RES_0402LF-4.7K,5%,1/16W,CHIP,CS24702JB10  I45  R452
   1 CPU0_NV_SAVE_N      A @T6G_MB_LIB.T6G(SCH_1):CPU0_NV_SAVE_N
   2 PVDD18_S5_P0      B @T6G_MB_LIB.T6G(SCH_1):PVDD18_S5_P0

Q_RES_0402LF-4.7K,5%,1/16W,CHIP,CS24702JB10  I46  R451
   1 CPU0_SPD_HOST_CTRL_N      A @T6G_MB_LIB.T6G(SCH_1):CPU0_SPD_HOST_CTRL_N
   2 PVDD18_S5_P0      B @T6G_MB_LIB.T6G(SCH_1):PVDD18_S5_P0

Q_RES_0402LF-4.7K,5%,1/16W,CHIP,CS24702JB10  I47  R450
   1 CPU0_SMERR_N      A @T6G_MB_LIB.T6G(SCH_1):CPU0_SMERR_N
   2 PVDD18_S5_P0      B @T6G_MB_LIB.T6G(SCH_1):PVDD18_S5_P0

Q_RES_0402LF-4.7K,5%,1/16W,EMPTY,CS24702JB10  I48  R449
   1 CPU0_SLP_S3_N      A @T6G_MB_LIB.T6G(SCH_1):CPU0_SLP_S3_N
   2 PVDD18_S5_P0      B @T6G_MB_LIB.T6G(SCH_1):PVDD18_S5_P0

Q_RES_0402LF-4.7K,5%,1/16W,EMPTY,CS24702JB10  I49  R448
   1 CPU0_SLP_S5_N      A @T6G_MB_LIB.T6G(SCH_1):CPU0_SLP_S5_N
   2 PVDD18_S5_P0      B @T6G_MB_LIB.T6G(SCH_1):PVDD18_S5_P0

Q_RES_0402LF-2.2K,5%,1/16W,CHIP,CS22202JB07  I55  R441
   1 CPU0_NMI_SYNC_FLOOD_N      A @T6G_MB_LIB.T6G(SCH_1):CPU0_NMI_SYNC_FLOOD_N
   2 PVDD18_S5_P0      B @T6G_MB_LIB.T6G(SCH_1):PVDD18_S5_P0

Q_RES_0402LF-1K,1%,1/16W,CHIP,CS21002FB06  I56  R442
   1 RST_CPU0_RESETL_N      A @T6G_MB_LIB.T6G(SCH_1):RST_CPU0_RESETL_N
   2 PVDD18_S5_P0      B @T6G_MB_LIB.T6G(SCH_1):PVDD18_S5_P0

Q_RES_0402LF-4.7K,5%,1/16W,EMPTY,CS24702JB10  I59  R5027
   1    GND      A @T6G_MB_LIB.T6G(SCH_1):GND
   2 IRQ_SMI_ACTIVE_N      B @T6G_MB_LIB.T6G(SCH_1):IRQ_SMI_ACTIVE_N

Q_RES_0402LF-4.7K,5%,1/16W,EMPTY,CS24702JB10  I60  R5028
   1    GND      A @T6G_MB_LIB.T6G(SCH_1):GND
   2 IRQ_BMC_SMI_N      B @T6G_MB_LIB.T6G(SCH_1):IRQ_BMC_SMI_N

Q_RES_0402LF-4.7K,5%,1/16W,EMPTY,CS24702JB10  I62  R5029
   1    GND      A @T6G_MB_LIB.T6G(SCH_1):GND
   2 IRQ_TPM_SPI_R_N      B @T6G_MB_LIB.T6G(SCH_1):IRQ_TPM_SPI_R_N

Q_RES_0402LF-4.7K,5%,1/16W,CHIP,CS24702JB10  I64  R446
   1 IRQ_SMI_ACTIVE_N      A @T6G_MB_LIB.T6G(SCH_1):IRQ_SMI_ACTIVE_N
   2 PVDD18_S5_P0      B @T6G_MB_LIB.T6G(SCH_1):PVDD18_S5_P0

Q_RES_0402LF-4.7K,5%,1/16W,CHIP,CS24702JB10  I65  R447
   1 IRQ_TPM_SPI_R_N      A @T6G_MB_LIB.T6G(SCH_1):IRQ_TPM_SPI_R_N
   2 PVDD18_S5_P0      B @T6G_MB_LIB.T6G(SCH_1):PVDD18_S5_P0

Q_RES_0402LF-4.7K,5%,1/16W,CHIP,CS24702JB10  I66  R445
   1 IRQ_BMC_SMI_N      A @T6G_MB_LIB.T6G(SCH_1):IRQ_BMC_SMI_N
   2 PVDD18_S5_P0      B @T6G_MB_LIB.T6G(SCH_1):PVDD18_S5_P0

Q_RES_0402LF-4.7K,5%,1/16W,CHIP,CS24702JB10  I69  R938
   1 BOOT_RDY_H      A @T6G_MB_LIB.T6G(SCH_1):BOOT_RDY_H
   2 PVDD18_S5_P0      B @T6G_MB_LIB.T6G(SCH_1):PVDD18_S5_P0

Q_RES_0402LF-0,5%,1/16W,CHIP,CS00002JB13  I93  R939
   1 FM_BIOS_POST_CMPLT_R_N      A @T6G_MB_LIB.T6G(SCH_1):FM_BIOS_POST_CMPLT_R_N
   2 FM_BIOS_POST_CMPLT_N      B @T6G_MB_LIB.T6G(SCH_1):FM_BIOS_POST_CMPLT_N

Q_RES_0402LF-0,5%,1/16W,CHIP,CS00002JB13  I94  R940
   1 BOOT_RDY_R_H      A @T6G_MB_LIB.T6G(SCH_1):BOOT_RDY_R_H
   2 BOOT_RDY_H      B @T6G_MB_LIB.T6G(SCH_1):BOOT_RDY_H

Q_RES_0402LF-0,5%,1/16W,CHIP,CS00002JB13  I95  R213
   1 SMB_CPU_5_R_SDA      A @T6G_MB_LIB.T6G(SCH_1):SMB_CPU_5_R_SDA
   2 SMB_CPU_5_SDA      B @T6G_MB_LIB.T6G(SCH_1):SMB_CPU_5_SDA

Q_RES_0402LF-0,5%,1/16W,CHIP,CS00002JB13  I97  R431
   1 SMB_CPU0_4_R_SDA      A @T6G_MB_LIB.T6G(SCH_1):SMB_CPU0_4_R_SDA
   2 SMB_CPU0_4_SDA      B @T6G_MB_LIB.T6G(SCH_1):SMB_CPU0_4_SDA

Q_RES_0402LF-0,5%,1/16W,CHIP,CS00002JB13  I98  R430
   1 SMB_CPU0_4_R_SCL      A @T6G_MB_LIB.T6G(SCH_1):SMB_CPU0_4_R_SCL
   2 SMB_CPU0_4_SCL      B @T6G_MB_LIB.T6G(SCH_1):SMB_CPU0_4_SCL

Q_RES_0402LF-0,5%,1/16W,CHIP,CS00002JB13  I100  R1205
   1 FM_PASSWORD_CLEAR_R_N      A @T6G_MB_LIB.T6G(SCH_1):FM_PASSWORD_CLEAR_R_N
   2 FM_PASSWORD_CLEAR_N      B @T6G_MB_LIB.T6G(SCH_1):FM_PASSWORD_CLEAR_N

Q_XTAL_4P_13BI_24GND-48MHZ,SMLF,MISC,BG648000076  I103  Y2
   1 XTAL_CPU0_X48M_X1     X1 @T6G_MB_LIB.T6G(SCH_1):XTAL_CPU0_X48M_X1
   2    GND     G1 @T6G_MB_LIB.T6G(SCH_1):GND
   4    GND     G2 @T6G_MB_LIB.T6G(SCH_1):GND
   3 XTAL_CPU0_X48M_X2_R     X2 @T6G_MB_LIB.T6G(SCH_1):XTAL_CPU0_X48M_X2_R

Q_RES_0402LF-10M,1%,1/16W,CHIP,CS61002FB02  I104  R432
   1 XTAL_CPU0_X48M_X1      A @T6G_MB_LIB.T6G(SCH_1):XTAL_CPU0_X48M_X1
   2 XTAL_CPU0_X48M_X2_R      B @T6G_MB_LIB.T6G(SCH_1):XTAL_CPU0_X48M_X2_R

Q_RES_0402LF-33,5%,1/16W,CHIP,CS03302JB10  I135  R249
   1 FM_CPU0_SLP_S3_N      A @T6G_MB_LIB.T6G(SCH_1):FM_CPU0_SLP_S3_N
   2 CPU0_SLP_S3_N      B @T6G_MB_LIB.T6G(SCH_1):CPU0_SLP_S3_N

Q_RES_0402LF-0,5%,1/16W,CHIP,CS00002JB13  I152  R2659
   1 CLK_100M_CPU0_CLK11_R_DP      A @T6G_MB_LIB.T6G(SCH_1):CLK_100M_CPU0_CLK11_R_DP
   2 CLK_100M_CPU0_CLK11_DP      B @T6G_MB_LIB.T6G(SCH_1):CLK_100M_CPU0_CLK11_DP

Q_RES_0402LF-0,5%,1/16W,CHIP,CS00002JB13  I153  R9273
   1 CLK_100M_CPU0_CLK04_R_DP      A @T6G_MB_LIB.T6G(SCH_1):CLK_100M_CPU0_CLK04_R_DP
   2 CLK_100M_CPU0_CLK04_DP      B @T6G_MB_LIB.T6G(SCH_1):CLK_100M_CPU0_CLK04_DP

Q_RES_0402LF-0,5%,1/16W,CHIP,CS00002JB13  I154  R9274
   1 CLK_100M_CPU0_CLK04_R_DN      A @T6G_MB_LIB.T6G(SCH_1):CLK_100M_CPU0_CLK04_R_DN
   2 CLK_100M_CPU0_CLK04_DN      B @T6G_MB_LIB.T6G(SCH_1):CLK_100M_CPU0_CLK04_DN

Q_RES_0402LF-0,5%,1/16W,CHIP,CS00002JB13  I157  R8563
   1 CLK_100M_CPU0_CLK02_R_DP      A @T6G_MB_LIB.T6G(SCH_1):CLK_100M_CPU0_CLK02_R_DP
   2 CLK_100M_CPU0_CLK02_DP      B @T6G_MB_LIB.T6G(SCH_1):CLK_100M_CPU0_CLK02_DP

Q_RES_0402LF-0,5%,1/16W,CHIP,CS00002JB13  I158  R8565
   1 CLK_100M_CPU0_CLK03_R_DP      A @T6G_MB_LIB.T6G(SCH_1):CLK_100M_CPU0_CLK03_R_DP
   2 CLK_100M_CPU0_CLK03_DP      B @T6G_MB_LIB.T6G(SCH_1):CLK_100M_CPU0_CLK03_DP

Q_RES_0402LF-0,5%,1/16W,CHIP,CS00002JB13  I160  R4535
   1 CLK_100M_CPU0_CLK01_R_DP      A @T6G_MB_LIB.T6G(SCH_1):CLK_100M_CPU0_CLK01_R_DP
   2 CLK_100M_CPU0_CLK01_DP      B @T6G_MB_LIB.T6G(SCH_1):CLK_100M_CPU0_CLK01_DP

Q_RES_0402LF-0,5%,1/16W,CHIP,CS00002JB13  I161  R4536
   1 CLK_100M_CPU0_CLK01_R_DN      A @T6G_MB_LIB.T6G(SCH_1):CLK_100M_CPU0_CLK01_R_DN
   2 CLK_100M_CPU0_CLK01_DN      B @T6G_MB_LIB.T6G(SCH_1):CLK_100M_CPU0_CLK01_DN

Q_RES_0402LF-33,5%,1/16W,CHIP,CS03302JB10  I165  R434
   1 CPU0_PWR_GD_OUT      A @T6G_MB_LIB.T6G(SCH_1):CPU0_PWR_GD_OUT
   2 CPU1_PWR_GD_IN      B @T6G_MB_LIB.T6G(SCH_1):CPU1_PWR_GD_IN

Q_RES_0402LF-0,5%,1/16W,CHIP,CS00002JB13  I167  R9275
   1 CLK_100M_CPU0_CLK05_R_DP      A @T6G_MB_LIB.T6G(SCH_1):CLK_100M_CPU0_CLK05_R_DP
   2 CLK_100M_CPU0_CLK05_DP      B @T6G_MB_LIB.T6G(SCH_1):CLK_100M_CPU0_CLK05_DP

Q_RES_0402LF-0,5%,1/16W,CHIP,CS00002JB13  I168  R9276
   1 CLK_100M_CPU0_CLK05_R_DN      A @T6G_MB_LIB.T6G(SCH_1):CLK_100M_CPU0_CLK05_R_DN
   2 CLK_100M_CPU0_CLK05_DN      B @T6G_MB_LIB.T6G(SCH_1):CLK_100M_CPU0_CLK05_DN

GENOA_SP5-SOCKET6096_13568-001,SMLF,IO,DGA^6000030  I188  U25
 DJ8 CPU0_PWR_GOOD PWR_GOOD @T6G_MB_LIB.T6G(SCH_1):CPU0_PWR_GOOD
DG10 RST_CPU0_RSMRST_N RSMRST_L @T6G_MB_LIB.T6G(SCH_1):RST_CPU0_RSMRST_N
 DJ5 CPU0_SLP_S3_N SLP_S3_L @T6G_MB_LIB.T6G(SCH_1):CPU0_SLP_S3_N
 DG4 CPU0_SLP_S5_N SLP_S5_L @T6G_MB_LIB.T6G(SCH_1):CPU0_SLP_S5_N
 DH6 RST_CPU0_SYS_N SYS_RESET_L||AGPIO1 @T6G_MB_LIB.T6G(SCH_1):RST_CPU0_SYS_N
DJ10 IRQ_WAKE_N WAKE_L||AGPIO2 @T6G_MB_LIB.T6G(SCH_1):IRQ_WAKE_N
DJ14 XTAL_CPU0_X32K_X1 X32K_X1 @T6G_MB_LIB.T6G(SCH_1):XTAL_CPU0_X32K_X1
DJ13 XTAL_CPU0_X32K_X2 X32K_X2 @T6G_MB_LIB.T6G(SCH_1):XTAL_CPU0_X32K_X2
DJ17 XTAL_CPU0_X48M_X1 X48M_X1 @T6G_MB_LIB.T6G(SCH_1):XTAL_CPU0_X48M_X1
DJ16 XTAL_CPU0_X48M_X2 X48M_X2 @T6G_MB_LIB.T6G(SCH_1):XTAL_CPU0_X48M_X2
 DH7 CPU0_PWR_BTN_N PWR_BTN_L||AGPIO0 @T6G_MB_LIB.T6G(SCH_1):CPU0_PWR_BTN_N
 B64 CPU0_NV_SAVE_N NV_SAVE_L @T6G_MB_LIB.T6G(SCH_1):CPU0_NV_SAVE_N
 B63 CPU0_FORCE_SELFREFRESH FORCE_SELFREFRESH @T6G_MB_LIB.T6G(SCH_1):CPU0_FORCE_SELFREFRESH
 DH9 CLK_CPU0_RTCCLK RTCCLK @T6G_MB_LIB.T6G(SCH_1):CLK_CPU0_RTCCLK
  C9 CLK_100M_CPU0_CLK05_R_DN GPP_CLK05N @T6G_MB_LIB.T6G(SCH_1):CLK_100M_CPU0_CLK05_R_DN
DJ50     NC GPP_CLK15N     NC
 C12 CLK_100M_CPU0_CLK04_R_DN GPP_CLK04N @T6G_MB_LIB.T6G(SCH_1):CLK_100M_CPU0_CLK04_R_DN
DJ47     NC GPP_CLK14N     NC
  B9 CLK_100M_CPU0_CLK05_R_DP GPP_CLK05P @T6G_MB_LIB.T6G(SCH_1):CLK_100M_CPU0_CLK05_R_DP
 A11 CLK_100M_CPU0_CLK03_R_DN GPP_CLK03N @T6G_MB_LIB.T6G(SCH_1):CLK_100M_CPU0_CLK03_R_DN
DJ51     NC GPP_CLK15P     NC
DJ54 CLK_100M_CPU0_CLK13_R_DN GPP_CLK13N @T6G_MB_LIB.T6G(SCH_1):CLK_100M_CPU0_CLK13_R_DN
 B12 CLK_100M_CPU0_CLK04_R_DP GPP_CLK04P @T6G_MB_LIB.T6G(SCH_1):CLK_100M_CPU0_CLK04_R_DP
  C6 CLK_100M_CPU0_CLK02_R_DN GPP_CLK02N @T6G_MB_LIB.T6G(SCH_1):CLK_100M_CPU0_CLK02_R_DN
DJ48     NC GPP_CLK14P     NC
DJ44 CLK_100M_CPU0_CLK12_R_DN GPP_CLK12N @T6G_MB_LIB.T6G(SCH_1):CLK_100M_CPU0_CLK12_R_DN
 A10 CLK_100M_CPU0_CLK03_R_DP GPP_CLK03P @T6G_MB_LIB.T6G(SCH_1):CLK_100M_CPU0_CLK03_R_DP
  A7 CLK_100M_CPU0_CLK01_R_DN GPP_CLK01N @T6G_MB_LIB.T6G(SCH_1):CLK_100M_CPU0_CLK01_R_DN
DJ53 CLK_100M_CPU0_CLK13_R_DP GPP_CLK13P @T6G_MB_LIB.T6G(SCH_1):CLK_100M_CPU0_CLK13_R_DP
DJ42 CLK_100M_CPU0_CLK11_R_DN GPP_CLK11N @T6G_MB_LIB.T6G(SCH_1):CLK_100M_CPU0_CLK11_R_DN
  B6 CLK_100M_CPU0_CLK02_R_DP GPP_CLK02P @T6G_MB_LIB.T6G(SCH_1):CLK_100M_CPU0_CLK02_R_DP
DJ45 CLK_100M_CPU0_CLK12_R_DP GPP_CLK12P @T6G_MB_LIB.T6G(SCH_1):CLK_100M_CPU0_CLK12_R_DP
  A8 CLK_100M_CPU0_CLK01_R_DP GPP_CLK01P @T6G_MB_LIB.T6G(SCH_1):CLK_100M_CPU0_CLK01_R_DP
DJ41 CLK_100M_CPU0_CLK11_R_DP GPP_CLK11P @T6G_MB_LIB.T6G(SCH_1):CLK_100M_CPU0_CLK11_R_DP
DF36 FM_PASSWORD_CLEAR_R_N AGPIO4||SATA_ACT_L @T6G_MB_LIB.T6G(SCH_1):FM_PASSWORD_CLEAR_R_N
DE36 CPU0_SPD_HOST_CTRL_N AGPIO3||SPD_HOST_CTRL_L @T6G_MB_LIB.T6G(SCH_1):CPU0_SPD_HOST_CTRL_N
DG36 RST_CPU0_PERST1_N PCIE_RST1_L||AGPIO26 @T6G_MB_LIB.T6G(SCH_1):RST_CPU0_PERST1_N
 B15     NC SGPIO_LOAD||AGPIO261     NC
 B72 SMB_CPU0_2_R_SDA I3C2_SDA||I2C2_SDA||SPD2_SDA||AGPIO150 @T6G_MB_LIB.T6G(SCH_1):SMB_CPU0_2_R_SDA
 D15     NC SGPIO_DATAOUT||AGPIO260     NC
  B4 SMB_CPU0_3_R_SDA I3C3_SDA||I2C3_SDA||SPD3_SDA||AGPIO152 @T6G_MB_LIB.T6G(SCH_1):SMB_CPU0_3_R_SDA
 A13 FAB_REV_ID2 AGPIO258||SGPIO2_CLK||CLK_REQ02_L @T6G_MB_LIB.T6G(SCH_1):FAB_REV_ID2
 A14 FAB_REV_ID0 AGPIO256||SGPIO0_CLK @T6G_MB_LIB.T6G(SCH_1):FAB_REV_ID0
 D18 RST_CPU0_PERST0_N PCIE_RST0_L||AGPIO266 @T6G_MB_LIB.T6G(SCH_1):RST_CPU0_PERST0_N
DH16 IRQ_SMI_ACTIVE_N AGPIO115||CLK_REQ11_L @T6G_MB_LIB.T6G(SCH_1):IRQ_SMI_ACTIVE_N
 B71 I3C_0_SPD_DDRAF_CPU0_R_SDA I3C0_SDA||I2C0_SDA||SPD0_SDA||SMBUS0_SDA||AGPIO146 @T6G_MB_LIB.T6G(SCH_1):I3C_0_SPD_DDRAF_CPU0_R_SDA
  C7 I3C_1_SPD_DDRGL_CPU0_R_SCL I3C1_SCL||I2C1_SCL||SPD1_SCL||AGPIO147 @T6G_MB_LIB.T6G(SCH_1):I3C_1_SPD_DDRGL_CPU0_R_SCL
 C72 SMB_CPU0_2_R_SCL I3C2_SCL||I2C2_SCL||SPD2_SCL||AGPIO149 @T6G_MB_LIB.T6G(SCH_1):SMB_CPU0_2_R_SCL
 A71 I3C_0_SPD_DDRAF_CPU0_R_SCL I3C0_SCL||I2C0_SCL||SPD0_SCL||SMBUS0_SCL||AGPIO145 @T6G_MB_LIB.T6G(SCH_1):I3C_0_SPD_DDRAF_CPU0_R_SCL
 B16     NC AGPIO259||SGPIO3_CLK     NC
DH36 CPU0_PWR_GD_OUT PWRGD_OUT||AGPIO12 @T6G_MB_LIB.T6G(SCH_1):CPU0_PWR_GD_OUT
DH15 IRQ_TPM_SPI_R_N AGPIO116||CLK_REQ12_L @T6G_MB_LIB.T6G(SCH_1):IRQ_TPM_SPI_R_N
  A5 I3C_1_SPD_DDRGL_CPU0_R_SDA I3C1_SDA||I2C1_SDA||SPD1_SDA||AGPIO148 @T6G_MB_LIB.T6G(SCH_1):I3C_1_SPD_DDRGL_CPU0_R_SDA
  A4 SMB_CPU0_3_R_SCL I3C3_SCL||I2C3_SCL||SPD3_SCL||AGPIO151 @T6G_MB_LIB.T6G(SCH_1):SMB_CPU0_3_R_SCL
DG12 SMB_CPU0_4_R_SCL I2C4_SCL||HP_SCL||UBM_SCL||AGPIO13 @T6G_MB_LIB.T6G(SCH_1):SMB_CPU0_4_R_SCL
DH12 SMB_CPU0_4_R_SDA I2C4_SDA||HP_SDA||UBM_SDA||AGPIO14 @T6G_MB_LIB.T6G(SCH_1):SMB_CPU0_4_R_SDA
DJ21 SMB_CPU_5_R_SCL I2C5_SCL||BMC_SCL||SMBUS1_SCL||AGPIO19 @T6G_MB_LIB.T6G(SCH_1):SMB_CPU_5_R_SCL
DJ20 SMB_CPU_5_R_SDA I2C5_SDA||BMC_SDA||SMBUS1_SDA||AGPIO20 @T6G_MB_LIB.T6G(SCH_1):SMB_CPU_5_R_SDA
DJ11 CPU0_SMERR_N SMERR_L||AGPIO24 @T6G_MB_LIB.T6G(SCH_1):CPU0_SMERR_N
 A19 CLK_100M_REF_OUT_DP REFCLK100SSC_P||GPP_CLK10P @T6G_MB_LIB.T6G(SCH_1):CLK_100M_REF_OUT_DP
 A20 CLK_100M_REF_OUT_DN REFCLK100SSC_N||GPP_CLK10N @T6G_MB_LIB.T6G(SCH_1):CLK_100M_REF_OUT_DN
 B67 RST_CPU0_RESETL_N RESET_L @T6G_MB_LIB.T6G(SCH_1):RST_CPU0_RESETL_N
DH30 BOOT_RDY_R_H AGPIO104 @T6G_MB_LIB.T6G(SCH_1):BOOT_RDY_R_H
DE30 BIOS_DEBUG_MODE AGPIO105 @T6G_MB_LIB.T6G(SCH_1):BIOS_DEBUG_MODE
DF31 FM_BOARD_SKU_ID2 AGPIO106 @T6G_MB_LIB.T6G(SCH_1):FM_BOARD_SKU_ID2
DG31 FM_BOARD_SKU_ID3 AGPIO107 @T6G_MB_LIB.T6G(SCH_1):FM_BOARD_SKU_ID3
DG32 CPU0_ROM_TYPE_SELECT AGPIO109 @T6G_MB_LIB.T6G(SCH_1):CPU0_ROM_TYPE_SELECT
DG11     NC AGPIO87     NC
DF33 FM_BOARD_SKU_ID0 AGPIO21 @T6G_MB_LIB.T6G(SCH_1):FM_BOARD_SKU_ID0
DJ29 FM_BIOS_POST_CMPLT_R_N AGPIO88 @T6G_MB_LIB.T6G(SCH_1):FM_BIOS_POST_CMPLT_R_N
DE32 FM_BOARD_SKU_ID1 AGPIO22 @T6G_MB_LIB.T6G(SCH_1):FM_BOARD_SKU_ID1
DJ35 FM_INT_CPU0_HP_UBM_N GENINT_L||PM_INTR_L||UBM_CPRSNT_CHANGE_DET_L||AGPIO89 @T6G_MB_LIB.T6G(SCH_1):FM_INT_CPU0_HP_UBM_N
DF40 FM_SMM_CRASHDUMP AGPIO5||DEVSLP0||SATA_ZP0_L @T6G_MB_LIB.T6G(SCH_1):FM_SMM_CRASHDUMP
DE40 IRQ_BMC_SMI_N AGPIO6||DEVSLP1||SATA_ZP1_L @T6G_MB_LIB.T6G(SCH_1):IRQ_BMC_SMI_N
 D69 PWRGD_CPU0_PWROK PWROK||SVI_RST_L @T6G_MB_LIB.T6G(SCH_1):PWRGD_CPU0_PWROK
 C14 FAB_REV_ID1 AGPIO257||SGPIO1_CLK||CLK_REQ01_L @T6G_MB_LIB.T6G(SCH_1):FAB_REV_ID1
 D14 SMB_CPU0_SEC_SDA SEC_SDA||AGPIO263 @T6G_MB_LIB.T6G(SCH_1):SMB_CPU0_SEC_SDA
 B14 SMB_CPU0_SEC_SCL SEC_SCL||AGPIO262 @T6G_MB_LIB.T6G(SCH_1):SMB_CPU0_SEC_SCL
DJ31 CPU0_NMI_SYNC_FLOOD_N NMI_SYNC_FLOOD_L @T6G_MB_LIB.T6G(SCH_1):CPU0_NMI_SYNC_FLOOD_N
 DH4 FM_BOARD_SKU_ID4 AGPIO7 @T6G_MB_LIB.T6G(SCH_1):FM_BOARD_SKU_ID4

Q_RES_0402LF-0,5%,1/16W,CHIP,CS00002JB13  I191  R4303
   1 CLK_100M_CPU0_CLK12_R_DP      A @T6G_MB_LIB.T6G(SCH_1):CLK_100M_CPU0_CLK12_R_DP
   2 CLK_100M_CPU0_CLK12_DP      B @T6G_MB_LIB.T6G(SCH_1):CLK_100M_CPU0_CLK12_DP

Q_RES_0402LF-0,5%,1/16W,CHIP,CS00002JB13  I192  R4304
   1 CLK_100M_CPU0_CLK12_R_DN      A @T6G_MB_LIB.T6G(SCH_1):CLK_100M_CPU0_CLK12_R_DN
   2 CLK_100M_CPU0_CLK12_DN      B @T6G_MB_LIB.T6G(SCH_1):CLK_100M_CPU0_CLK12_DN

Q_CAP_0402-1000PF,50V,5%,X7R,TMP_QCH21006JB10  I194  C5023
   1 RST_CPU0_RSMRST_N      A @T6G_MB_LIB.T6G(SCH_1):RST_CPU0_RSMRST_N
   2    GND      B @T6G_MB_LIB.T6G(SCH_1):GND

Q_RES_0402LF-49.9,1%,1/16W,CHIP,CS04992FB07  I195  R5102
   1 XTAL_CPU0_X48M_X2      A @T6G_MB_LIB.T6G(SCH_1):XTAL_CPU0_X48M_X2
   2 XTAL_CPU0_X48M_X2_R      B @T6G_MB_LIB.T6G(SCH_1):XTAL_CPU0_X48M_X2_R

Q_RES_0402LF-0,5%,1/16W,CHIP,CS00002JB13  I206  R27
   1 SMB_CPU0_2_R_SCL      A @T6G_MB_LIB.T6G(SCH_1):SMB_CPU0_2_R_SCL
   2 SMB_CPU0_2_SCL      B @T6G_MB_LIB.T6G(SCH_1):SMB_CPU0_2_SCL

Q_RES_0402LF-0,5%,1/16W,CHIP,CS00002JB13  I207  R28
   1 SMB_CPU0_2_R_SDA      A @T6G_MB_LIB.T6G(SCH_1):SMB_CPU0_2_R_SDA
   2 SMB_CPU0_2_SDA      B @T6G_MB_LIB.T6G(SCH_1):SMB_CPU0_2_SDA

Q_RES_0402LF-0,5%,1/16W,CHIP,CS00002JB13  I208  R29
   1 SMB_CPU0_3_R_SCL      A @T6G_MB_LIB.T6G(SCH_1):SMB_CPU0_3_R_SCL
   2 SMB_CPU0_3_SCL      B @T6G_MB_LIB.T6G(SCH_1):SMB_CPU0_3_SCL

Q_RES_0402LF-0,5%,1/16W,CHIP,CS00002JB13  I209  R30
   1 SMB_CPU0_3_R_SDA      A @T6G_MB_LIB.T6G(SCH_1):SMB_CPU0_3_R_SDA
   2 SMB_CPU0_3_SDA      B @T6G_MB_LIB.T6G(SCH_1):SMB_CPU0_3_SDA

Q_RES_0402LF-4.7K,5%,1/16W,CHIP,CS24702JB10  I210  R6081
   1 PVDD11_S3_P0      A @T6G_MB_LIB.T6G(SCH_1):PVDD11_S3_P0
   2 SMB_CPU0_2_SCL      B @T6G_MB_LIB.T6G(SCH_1):SMB_CPU0_2_SCL

Q_RES_0402LF-4.7K,5%,1/16W,CHIP,CS24702JB10  I212  R6082
   1 PVDD11_S3_P0      A @T6G_MB_LIB.T6G(SCH_1):PVDD11_S3_P0
   2 SMB_CPU0_2_SDA      B @T6G_MB_LIB.T6G(SCH_1):SMB_CPU0_2_SDA

Q_RES_0402LF-4.7K,5%,1/16W,CHIP,CS24702JB10  I213  R6083
   1 PVDD11_S3_P0      A @T6G_MB_LIB.T6G(SCH_1):PVDD11_S3_P0
   2 SMB_CPU0_3_SCL      B @T6G_MB_LIB.T6G(SCH_1):SMB_CPU0_3_SCL

Q_RES_0402LF-4.7K,5%,1/16W,CHIP,CS24702JB10  I214  R6084
   1 PVDD11_S3_P0      A @T6G_MB_LIB.T6G(SCH_1):PVDD11_S3_P0
   2 SMB_CPU0_3_SDA      B @T6G_MB_LIB.T6G(SCH_1):SMB_CPU0_3_SDA

Q_RES_0402LF-20M,1%,1/16W,CHIP,CS62002FB01  I221  R433
   1 XTAL_CPU0_X32K_X1      A @T6G_MB_LIB.T6G(SCH_1):XTAL_CPU0_X32K_X1
   2 XTAL_CPU0_X32K_X2      B @T6G_MB_LIB.T6G(SCH_1):XTAL_CPU0_X32K_X2

Q_RES_0402LF-4.7K,5%,1/16W,EMPTY,CS24702JB10  I222  R438
   1 CPU0_FORCE_SELFREFRESH      A @T6G_MB_LIB.T6G(SCH_1):CPU0_FORCE_SELFREFRESH
   2 PVDD18_S5_P0      B @T6G_MB_LIB.T6G(SCH_1):PVDD18_S5_P0

Q_RES_0402LF-2.2K,5%,1/16W,CHIP,CS22202JB07  I224  R6502
   1 CPU0_FORCE_SELFREFRESH      A @T6G_MB_LIB.T6G(SCH_1):CPU0_FORCE_SELFREFRESH
   2    GND      B @T6G_MB_LIB.T6G(SCH_1):GND

Q_RES_0402LF-0,5%,1/16W,CHIP,CS00002JB13  I228  R8306
   1 CLK_100M_CPU0_CLK13_R_DN      A @T6G_MB_LIB.T6G(SCH_1):CLK_100M_CPU0_CLK13_R_DN
   2 CLK_100M_CPU0_CLK13_DN      B @T6G_MB_LIB.T6G(SCH_1):CLK_100M_CPU0_CLK13_DN

Q_RES_0402LF-0,5%,1/16W,CHIP,CS00002JB13  I229  R8305
   1 CLK_100M_CPU0_CLK13_R_DP      A @T6G_MB_LIB.T6G(SCH_1):CLK_100M_CPU0_CLK13_R_DP
   2 CLK_100M_CPU0_CLK13_DP      B @T6G_MB_LIB.T6G(SCH_1):CLK_100M_CPU0_CLK13_DP

Q_CAP_C0402-8.2PF,50V,0.1P,NP0,CH-8216TB09  I230  C215
   1 XTAL_CPU0_X32K_X1      A @T6G_MB_LIB.T6G(SCH_1):XTAL_CPU0_X32K_X1
   2    GND      B @T6G_MB_LIB.T6G(SCH_1):GND

Q_CAP_C0402-8.2PF,50V,0.1P,NP0,CH-8216TB09  I231  C216
   1 XTAL_CPU0_X32K_X2      A @T6G_MB_LIB.T6G(SCH_1):XTAL_CPU0_X32K_X2
   2    GND      B @T6G_MB_LIB.T6G(SCH_1):GND

Q_CAP_C0402-3.9P,50V,0.1P,NPO,CH-3916TB01  I232  C213
   1 XTAL_CPU0_X48M_X1      A @T6G_MB_LIB.T6G(SCH_1):XTAL_CPU0_X48M_X1
   2    GND      B @T6G_MB_LIB.T6G(SCH_1):GND

Q_CAP_C0402-3.9P,50V,0.1P,NPO,CH-3916TB01  I233  C214
   1 XTAL_CPU0_X48M_X2_R      A @T6G_MB_LIB.T6G(SCH_1):XTAL_CPU0_X48M_X2_R
   2    GND      B @T6G_MB_LIB.T6G(SCH_1):GND


DRAWING: @T6G_MB_LIB.T6G(SCH_1):PAGE368 

MOSFET_NCH_DUAL-PJT138K,SMLF,IC,BAM138K0003  I3  Q144
   1    GND     S1 @T6G_MB_LIB.T6G(SCH_1):GND
   2 PWRGD_PS_PWROK_PLD     G1 @T6G_MB_LIB.T6G(SCH_1):PWRGD_PS_PWROK_PLD
   6 PWRGD_PS_PWROK_PLD_N     D1 @T6G_MB_LIB.T6G(SCH_1):PWRGD_PS_PWROK_PLD_N

Q_RES_0402LF-4.7K,5%,1/16W,CHIP,CS24702JB10  I5  R4604
   1 P3V3_AUX      A @T6G_MB_LIB.T6G(SCH_1):P3V3_AUX
   2 PWRGD_PS_PWROK_PLD_N      B @T6G_MB_LIB.T6G(SCH_1):PWRGD_PS_PWROK_PLD_N

Q_RES_0402LF-0,5%,1/16W,CHIP,CS00002JB13  I7  R3048
   1 MB0_P12V_STBY_PWRGD      A @T6G_MB_LIB.T6G(SCH_1):MB0_P12V_STBY_PWRGD
   2 PWRGD_PS_PWROK      B @T6G_MB_LIB.T6G(SCH_1):PWRGD_PS_PWROK

Q_RES_0402LF-0,5%,1/16W,CHIP,CS00002JB13  I8  R3047
   1 MB0_P12V_STBY_PWRGD      A @T6G_MB_LIB.T6G(SCH_1):MB0_P12V_STBY_PWRGD
   2 PWRGD_PS_PWROK_PLD      B @T6G_MB_LIB.T6G(SCH_1):PWRGD_PS_PWROK_PLD

MOSFET_NCH_DUAL-PJT138K,SMLF,IC,BAM138K0003  I10  Q144
   3 PWRGD_PS_PWROK_PLD_ISO     D2 @T6G_MB_LIB.T6G(SCH_1):PWRGD_PS_PWROK_PLD_ISO
   5 PWRGD_PS_PWROK_PLD_N     G2 @T6G_MB_LIB.T6G(SCH_1):PWRGD_PS_PWROK_PLD_N
   4    GND     S2 @T6G_MB_LIB.T6G(SCH_1):GND

Q_RES_0402LF-1K,1%,1/16W,CHIP,CS21002FB06  I11  R4605
   1 P3V3_AUX      A @T6G_MB_LIB.T6G(SCH_1):P3V3_AUX
   2 PWRGD_PS_PWROK_PLD_ISO      B @T6G_MB_LIB.T6G(SCH_1):PWRGD_PS_PWROK_PLD_ISO

Q_RES_0402LF-33.2,1%,1/16W,CHIP,CS03322FB03  I13  R9446
   1 PWRGD_PS_PWROK_PLD_ISO      A @T6G_MB_LIB.T6G(SCH_1):PWRGD_PS_PWROK_PLD_ISO
   2 PWRGD_PS_PWROK_PLD_ISO_R      B @T6G_MB_LIB.T6G(SCH_1):PWRGD_PS_PWROK_PLD_ISO_R


DRAWING: @T6G_MB_LIB.T6G(SCH_1):PAGE254 

Q_LED_SMLF-LED_BLUE,LTST-C281TBKT-5A,IC,BEBL0172Z00  I3  D99
   A LED_P3V3      A @T6G_MB_LIB.T6G(SCH_1):LED_P3V3
   C    GND      C @T6G_MB_LIB.T6G(SCH_1):GND

Q_RES_0402LF-130,1%,1/16W,CHIP,CS11302FB03  I8  R3100
   1 LED_P3V3      A @T6G_MB_LIB.T6G(SCH_1):LED_P3V3
   2   P3V3      B @T6G_MB_LIB.T6G(SCH_1):P3V3

Q_RES_0402LF-470,1%,1/16W,CHIP,CS14702FB04  I9  R3102
   1 LED_P5V      A @T6G_MB_LIB.T6G(SCH_1):LED_P5V
   2    P5V      B @T6G_MB_LIB.T6G(SCH_1):P5V

Q_LED_SMLF-LED_BLUE,LTST-C281TBKT-5A,IC,BEBL0172Z00  I14  D96
   A LED_PWRGD_PS_PWROK_PLD      A @T6G_MB_LIB.T6G(SCH_1):LED_PWRGD_PS_PWROK_PLD
   C LED_PWRGD_PS_PWROK_PLD_D      C @T6G_MB_LIB.T6G(SCH_1):LED_PWRGD_PS_PWROK_PLD_D

Q_RES_0402LF-130,1%,1/16W,CHIP,CS11302FB03  I15  R3075
   1 LED_PWRGD_PS_PWROK_PLD      A @T6G_MB_LIB.T6G(SCH_1):LED_PWRGD_PS_PWROK_PLD
   2 P3V3_AUX      B @T6G_MB_LIB.T6G(SCH_1):P3V3_AUX

Q_LED_SMLF-LED_BLUE,LTST-C281TBKT-5A,IC,BEBL0172Z00  I17  D98
   A LED_P5V      A @T6G_MB_LIB.T6G(SCH_1):LED_P5V
   C    GND      C @T6G_MB_LIB.T6G(SCH_1):GND

MOSFET_NCH_DUAL-PJT138K,SMLF,IC,BAM138K0003  I18  Q78
   3 LED_PWRGD_PS_PWROK_PLD_D     D2 @T6G_MB_LIB.T6G(SCH_1):LED_PWRGD_PS_PWROK_PLD_D
   5 PWRGD_PS_PWROK_PLD     G2 @T6G_MB_LIB.T6G(SCH_1):PWRGD_PS_PWROK_PLD
   4    GND     S2 @T6G_MB_LIB.T6G(SCH_1):GND

Q_RES_0402LF-130,1%,1/16W,CHIP,CS11302FB03  I21  R3071
   1 LED_PWRGD_P1V8_AUX      A @T6G_MB_LIB.T6G(SCH_1):LED_PWRGD_P1V8_AUX
   2 P3V3_AUX      B @T6G_MB_LIB.T6G(SCH_1):P3V3_AUX

Q_LED_SMLF-LED_BLUE,LTST-C281TBKT-5A,IC,BEBL0172Z00  I23  D91
   A LED_PWRGD_P1V8_AUX      A @T6G_MB_LIB.T6G(SCH_1):LED_PWRGD_P1V8_AUX
   C LED_PWRGD_P1V8_AUX_D      C @T6G_MB_LIB.T6G(SCH_1):LED_PWRGD_P1V8_AUX_D

MOSFET_NCH_DUAL-PJT138K,SMLF,IC,BAM138K0003  I24  Q78
   1    GND     S1 @T6G_MB_LIB.T6G(SCH_1):GND
   2 PWRGD_P1V8_AUX_R     G1 @T6G_MB_LIB.T6G(SCH_1):PWRGD_P1V8_AUX_R
   6 LED_PWRGD_P1V8_AUX_D     D1 @T6G_MB_LIB.T6G(SCH_1):LED_PWRGD_P1V8_AUX_D

Q_RES_0402LF-130,1%,1/16W,CHIP,CS11302FB03  I32  R3069
   1 LED_PWRGD_SYS_PWROK_R      A @T6G_MB_LIB.T6G(SCH_1):LED_PWRGD_SYS_PWROK_R
   2 P3V3_AUX      B @T6G_MB_LIB.T6G(SCH_1):P3V3_AUX

Q_LED_SMLF-LED_BLUE,LTST-C281TBKT-5A,IC,BEBL0172Z00  I33  D88
   A LED_PWRGD_SYS_PWROK_R      A @T6G_MB_LIB.T6G(SCH_1):LED_PWRGD_SYS_PWROK_R
   C LED_PWRGD_SYS_PWROK_R_D      C @T6G_MB_LIB.T6G(SCH_1):LED_PWRGD_SYS_PWROK_R_D

MOSFET_NCH_DUAL-PJT138K,SMLF,IC,BAM138K0003  I35  Q87
   3 LED_PWRGD_SYS_PWROK_R_D     D2 @T6G_MB_LIB.T6G(SCH_1):LED_PWRGD_SYS_PWROK_R_D
   5 SCM_SYS_PWROK_R2     G2 @T6G_MB_LIB.T6G(SCH_1):SCM_SYS_PWROK_R2
   4    GND     S2 @T6G_MB_LIB.T6G(SCH_1):GND

MOSFET_NCH_DUAL-PJT138K,SMLF,IC,BAM138K0003  I38  Q87
   1    GND     S1 @T6G_MB_LIB.T6G(SCH_1):GND
   2 RST_CPU0_RSMRST_N     G1 @T6G_MB_LIB.T6G(SCH_1):RST_CPU0_RSMRST_N
   6 LED_RST_RSMRST_PLD_R_N_D     D1 @T6G_MB_LIB.T6G(SCH_1):LED_RST_RSMRST_PLD_R_N_D

Q_LED_SMLF-LED_BLUE,LTST-C281TBKT-5A,IC,BEBL0172Z00  I40  D93
   A LED_RST_RSMRST_PLD_R_N      A @T6G_MB_LIB.T6G(SCH_1):LED_RST_RSMRST_PLD_R_N
   C LED_RST_RSMRST_PLD_R_N_D      C @T6G_MB_LIB.T6G(SCH_1):LED_RST_RSMRST_PLD_R_N_D

Q_RES_0402LF-130,1%,1/16W,CHIP,CS11302FB03  I41  R3074
   1 LED_RST_RSMRST_PLD_R_N      A @T6G_MB_LIB.T6G(SCH_1):LED_RST_RSMRST_PLD_R_N
   2 P3V3_AUX      B @T6G_MB_LIB.T6G(SCH_1):P3V3_AUX

Q_LED_SMLF-LED_BLUE,LTST-C281TBKT-5A,IC,BEBL0172Z00  I43  D6000
   A LED_PWRGD_P1V2_AUX      A @T6G_MB_LIB.T6G(SCH_1):LED_PWRGD_P1V2_AUX
   C LED_PWRGD_P1V2_AUX_D      C @T6G_MB_LIB.T6G(SCH_1):LED_PWRGD_P1V2_AUX_D

Q_RES_0402LF-130,1%,1/16W,CHIP,CS11302FB03  I45  R6246
   1 LED_PWRGD_P1V2_AUX      A @T6G_MB_LIB.T6G(SCH_1):LED_PWRGD_P1V2_AUX
   2 P3V3_AUX      B @T6G_MB_LIB.T6G(SCH_1):P3V3_AUX

MOSFET_NCH_DUAL-PJT138K,SMLF,IC,BAM138K0003  I47  Q6000
   1    GND     S1 @T6G_MB_LIB.T6G(SCH_1):GND
   2 PWRGD_P1V2_AUX_R     G1 @T6G_MB_LIB.T6G(SCH_1):PWRGD_P1V2_AUX_R
   6 LED_PWRGD_P1V2_AUX_D     D1 @T6G_MB_LIB.T6G(SCH_1):LED_PWRGD_P1V2_AUX_D


DRAWING: @T6G_MB_LIB.T6G(SCH_1):PAGE79 

Q_RES_0402LF-33,5%,1/16W,CHIP,CS03302JB10  I16  R160
   1 JTAG_SCM_TRST_R_N      A @T6G_MB_LIB.T6G(SCH_1):JTAG_SCM_TRST_R_N
   2 JTAG_SCM_TRST_N      B @T6G_MB_LIB.T6G(SCH_1):JTAG_SCM_TRST_N

Q_RES_0402LF-33,5%,1/16W,CHIP,CS03302JB10  I17  R992
   1 FM_SYS_THROTTLE_R_N      A @T6G_MB_LIB.T6G(SCH_1):FM_SYS_THROTTLE_R_N
   2 FM_SYS_THROTTLE_N      B @T6G_MB_LIB.T6G(SCH_1):FM_SYS_THROTTLE_N

Q_RES_0402LF-0,5%,1/16W,CHIP,CS00002JB13  I18  R493
   1 SMB_CPU0_4_XLTR_R_SDA      A @T6G_MB_LIB.T6G(SCH_1):SMB_CPU0_4_XLTR_R_SDA
   2 SMB_CPU0_4_XLTR_SDA      B @T6G_MB_LIB.T6G(SCH_1):SMB_CPU0_4_XLTR_SDA

Q_RES_0402LF-0,5%,1/16W,CHIP,CS00002JB13  I19  R70
   1 SMB_CPU0_4_XLTR_R_SCL      A @T6G_MB_LIB.T6G(SCH_1):SMB_CPU0_4_XLTR_R_SCL
   2 SMB_CPU0_4_XLTR_SCL      B @T6G_MB_LIB.T6G(SCH_1):SMB_CPU0_4_XLTR_SCL

Q_RES_0402LF-0,5%,1/16W,CHIP,CS00002JB13  I20  R6039
   1 OC_ALERT_N      A @T6G_MB_LIB.T6G(SCH_1):OC_ALERT_N
   2 HSC_D_OC      B @T6G_MB_LIB.T6G(SCH_1):HSC_D_OC

Q_RES_0402LF-0,5%,1/16W,CHIP,CS00002JB13  I21  R6038
   1 UV_ALERT_N      A @T6G_MB_LIB.T6G(SCH_1):UV_ALERT_N
   2 IRQ_UV_DETECT_N      B @T6G_MB_LIB.T6G(SCH_1):IRQ_UV_DETECT_N

Q_RES_0402LF-33,5%,1/16W,CHIP,CS03302JB10  I23  R23
   1 P3V3_OCP_SFF_EN      A @T6G_MB_LIB.T6G(SCH_1):P3V3_OCP_SFF_EN
   2 P3V3_OCP_SFF_EN_R      B @T6G_MB_LIB.T6G(SCH_1):P3V3_OCP_SFF_EN_R

Q_RES_0402LF-0,5%,1/16W,CHIP,CS00002JB13  I24  R168
   1 SGPIO_SCM_DI_R<1>      A @T6G_MB_LIB.T6G(SCH_1):SGPIO_SCM_DI_R(1)
   2 SGPIO_SCM_DI_<1>      B @T6G_MB_LIB.T6G(SCH_1):SGPIO_SCM_DI_(1)

Q_RES_0402LF-33,5%,1/16W,CHIP,CS03302JB10  I43  R172
   1 FM_I3C_CPU1_MUX1_R_SEL      A @T6G_MB_LIB.T6G(SCH_1):FM_I3C_CPU1_MUX1_R_SEL
   2 FM_I3C_CPU1_MUX1_SEL      B @T6G_MB_LIB.T6G(SCH_1):FM_I3C_CPU1_MUX1_SEL

Q_RES_0402LF-33,5%,1/16W,CHIP,CS03302JB10  I44  R58
   1 SGPIO_SCM_INTR_R_N      A @T6G_MB_LIB.T6G(SCH_1):SGPIO_SCM_INTR_R_N
   2 SGPIO_SCM_INTR_N      B @T6G_MB_LIB.T6G(SCH_1):SGPIO_SCM_INTR_N

Q_RES_0402LF-0,5%,1/16W,CHIP,CS00002JB13  I45  R167
   1 SGPIO_SCM_DI_R<0>      A @T6G_MB_LIB.T6G(SCH_1):SGPIO_SCM_DI_R(0)
   2 SGPIO_SCM_DI_<0>      B @T6G_MB_LIB.T6G(SCH_1):SGPIO_SCM_DI_(0)

Q_RES_0402LF-33,5%,1/16W,CHIP,CS03302JB10  I46  R49
   1 SCM_JTAG_MUX_R_S0      A @T6G_MB_LIB.T6G(SCH_1):SCM_JTAG_MUX_R_S0
   2 SCM_JTAG_MUX_S0      B @T6G_MB_LIB.T6G(SCH_1):SCM_JTAG_MUX_S0

Q_RES_0402LF-33,5%,1/16W,CHIP,CS03302JB10  I47  R165
   1 FM_I3C_CPU0_MUX1_OE_R_N      A @T6G_MB_LIB.T6G(SCH_1):FM_I3C_CPU0_MUX1_OE_R_N
   2 FM_I3C_CPU0_MUX1_OE_N      B @T6G_MB_LIB.T6G(SCH_1):FM_I3C_CPU0_MUX1_OE_N

Q_RES_0402LF-33,5%,1/16W,CHIP,CS03302JB10  I48  R169
   1 FM_I3C_CPU1_MUX0_OE_R_N      A @T6G_MB_LIB.T6G(SCH_1):FM_I3C_CPU1_MUX0_OE_R_N
   2 FM_I3C_CPU1_MUX0_OE_N      B @T6G_MB_LIB.T6G(SCH_1):FM_I3C_CPU1_MUX0_OE_N

Q_RES_0402LF-33,5%,1/16W,CHIP,CS03302JB10  I49  R50
   1 SCM_JTAG_MUX_R_S1      A @T6G_MB_LIB.T6G(SCH_1):SCM_JTAG_MUX_R_S1
   2 SCM_JTAG_MUX_S1      B @T6G_MB_LIB.T6G(SCH_1):SCM_JTAG_MUX_S1

Q_RES_0402LF-33,5%,1/16W,CHIP,CS03302JB10  I50  R164
   1 FM_I3C_CPU0_MUX0_R_SEL      A @T6G_MB_LIB.T6G(SCH_1):FM_I3C_CPU0_MUX0_R_SEL
   2 FM_I3C_CPU0_MUX0_SEL      B @T6G_MB_LIB.T6G(SCH_1):FM_I3C_CPU0_MUX0_SEL

Q_RES_0402LF-33,5%,1/16W,CHIP,CS03302JB10  I51  R166
   1 FM_I3C_CPU0_MUX1_R_SEL      A @T6G_MB_LIB.T6G(SCH_1):FM_I3C_CPU0_MUX1_R_SEL
   2 FM_I3C_CPU0_MUX1_SEL      B @T6G_MB_LIB.T6G(SCH_1):FM_I3C_CPU0_MUX1_SEL

Q_RES_0402LF-33,5%,1/16W,CHIP,CS03302JB10  I52  R171
   1 FM_I3C_CPU1_MUX1_OE_R_N      A @T6G_MB_LIB.T6G(SCH_1):FM_I3C_CPU1_MUX1_OE_R_N
   2 FM_I3C_CPU1_MUX1_OE_N      B @T6G_MB_LIB.T6G(SCH_1):FM_I3C_CPU1_MUX1_OE_N

Q_RES_0402LF-33,5%,1/16W,CHIP,CS03302JB10  I53  R170
   1 FM_I3C_CPU1_MUX0_R_SEL      A @T6G_MB_LIB.T6G(SCH_1):FM_I3C_CPU1_MUX0_R_SEL
   2 FM_I3C_CPU1_MUX0_SEL      B @T6G_MB_LIB.T6G(SCH_1):FM_I3C_CPU1_MUX0_SEL

Q_RES_0402LF-33,5%,1/16W,CHIP,CS03302JB10  I54  R163
   1 FM_I3C_CPU0_MUX0_OE_R_N      A @T6G_MB_LIB.T6G(SCH_1):FM_I3C_CPU0_MUX0_OE_R_N
   2 FM_I3C_CPU0_MUX0_OE_N      B @T6G_MB_LIB.T6G(SCH_1):FM_I3C_CPU0_MUX0_OE_N

Q_RES_0402LF-33,5%,1/16W,CHIP,CS03302JB10  I64  R6030
   1 CLK_GEN2_GPU_FPGA_OE_N      A @T6G_MB_LIB.T6G(SCH_1):CLK_GEN2_GPU_FPGA_OE_N
   2 CLK_GEN2_GPU_FPGA_OE_R_N      B @T6G_MB_LIB.T6G(SCH_1):CLK_GEN2_GPU_FPGA_OE_R_N

Q_RES_0402LF-33,5%,1/16W,CHIP,CS03302JB10  I79  R63
   1 SCM_SYS_PWROK_R      A @T6G_MB_LIB.T6G(SCH_1):SCM_SYS_PWROK_R
   2 SCM_SYS_PWROK      B @T6G_MB_LIB.T6G(SCH_1):SCM_SYS_PWROK

Q_RES_0402LF-0,5%,1/16W,CHIP,CS00002JB13  I80  R211
   1 SMB_2_PLD_3V3AUX_SDA_R1      A @T6G_MB_LIB.T6G(SCH_1):SMB_2_PLD_3V3AUX_SDA_R1
   2 SMB_2_PLD_3V3AUX_SDA_R2      B @T6G_MB_LIB.T6G(SCH_1):SMB_2_PLD_3V3AUX_SDA_R2

Q_RES_0402LF-0,5%,1/16W,CHIP,CS00002JB13  I81  R210
   1 SMB_2_PLD_3V3AUX_SCL_R1      A @T6G_MB_LIB.T6G(SCH_1):SMB_2_PLD_3V3AUX_SCL_R1
   2 SMB_2_PLD_3V3AUX_SCL_R2      B @T6G_MB_LIB.T6G(SCH_1):SMB_2_PLD_3V3AUX_SCL_R2

Q_RES_0402LF-0,5%,1/16W,CHIP,CS00002JB13  I82  R56
   1 SMB_1_PLD_3V3AUX_SDA_R1      A @T6G_MB_LIB.T6G(SCH_1):SMB_1_PLD_3V3AUX_SDA_R1
   2 SMB_1_PLD_3V3AUX_SDA_R2      B @T6G_MB_LIB.T6G(SCH_1):SMB_1_PLD_3V3AUX_SDA_R2

LCMXO3LF9400C5BG484C-LCMXO3LF-9400C-5BG484C,SMLF,IA  I25  U18
  E8 JTAG_SCM_PLD_TDI PT15C||TDO @T6G_MB_LIB.T6G(SCH_1):JTAG_SCM_PLD_TDI
  E9 JTAG_SCM_PLD_TDO PT15D||TDI @T6G_MB_LIB.T6G(SCH_1):JTAG_SCM_PLD_TDO
 D10 JTAG_SCM_PLD_TCK PT22C||TCK @T6G_MB_LIB.T6G(SCH_1):JTAG_SCM_PLD_TCK
 C10 JTAG_SCM_PLD_TMS PT22D||TMS @T6G_MB_LIB.T6G(SCH_1):JTAG_SCM_PLD_TMS
 E15 CPLD_PROGRAMN PT31D||PROGRAMN @T6G_MB_LIB.T6G(SCH_1):CPLD_PROGRAMN
 F16 VIRTUAL_RESEAT PT44C||INITN @T6G_MB_LIB.T6G(SCH_1):VIRTUAL_RESEAT
 E17 VIRTUAL_RESEAT_FPGA_R_N PT44D||DONE @T6G_MB_LIB.T6G(SCH_1):VIRTUAL_RESEAT_FPGA_R_N
 E14 CPLD_JTAG_EN PT31C||JTAGENB @T6G_MB_LIB.T6G(SCH_1):CPLD_JTAG_EN

Q_RES_0402LF-33,5%,1/16W,CHIP,CS03302JB10  I55  R6031
   1 VIRTUAL_RESEAT_FPGA_N      A @T6G_MB_LIB.T6G(SCH_1):VIRTUAL_RESEAT_FPGA_N
   2 VIRTUAL_RESEAT_FPGA_R_N      B @T6G_MB_LIB.T6G(SCH_1):VIRTUAL_RESEAT_FPGA_R_N

Q_RES_0402LF-33,5%,1/16W,CHIP,CS03302JB10  I65  R6029
   1 CLK_GEN2_BMC_RC_OE_N      A @T6G_MB_LIB.T6G(SCH_1):CLK_GEN2_BMC_RC_OE_N
   2 CLK_GEN2_BMC_RC_OE_R_N      B @T6G_MB_LIB.T6G(SCH_1):CLK_GEN2_BMC_RC_OE_R_N

Q_RES_0402LF-0,5%,1/16W,CHIP,CS00002JB13  I83  R51
   1 SMB_1_PLD_3V3AUX_SCL_R1      A @T6G_MB_LIB.T6G(SCH_1):SMB_1_PLD_3V3AUX_SCL_R1
   2 SMB_1_PLD_3V3AUX_SCL_R2      B @T6G_MB_LIB.T6G(SCH_1):SMB_1_PLD_3V3AUX_SCL_R2

LCMXO3LF9400C5BG484C-LCMXO3LF-9400C-5BG484C,SMLF,IA  I94  U18
 B21 IRQ_SML1_PMBUS_ALERT_N PT43B||R_GPLLC @T6G_MB_LIB.T6G(SCH_1):IRQ_SML1_PMBUS_ALERT_N
 A20 P1V8_RETIMER_CPU1_R_EN PT43A||R_GPLLT @T6G_MB_LIB.T6G(SCH_1):P1V8_RETIMER_CPU1_R_EN
 B19 FM_LED_PWRGD_PVDD11_S3_P1  PT41B @T6G_MB_LIB.T6G(SCH_1):FM_LED_PWRGD_PVDD11_S3_P1
 A18 FM_LED_PWRGD_PVDDIO_P1  PT41A @T6G_MB_LIB.T6G(SCH_1):FM_LED_PWRGD_PVDDIO_P1
 F14 SCM_SPARE_1  PT31B @T6G_MB_LIB.T6G(SCH_1):SCM_SPARE_1
 G14 SCM_SPARE_0  PT31A @T6G_MB_LIB.T6G(SCH_1):SCM_SPARE_0
 F12 GPU_3V3IO_RSVD3_FFU_ISO_R  PT28B @T6G_MB_LIB.T6G(SCH_1):GPU_3V3IO_RSVD3_FFU_ISO_R
 G12 PRSNT_CABLE_GPU_B3_ISO_R_N  PT28A @T6G_MB_LIB.T6G(SCH_1):PRSNT_CABLE_GPU_B3_ISO_R_N
 A12 SMB_1_PLD_3V3AUX_SDA_R2 PT27D||SDA||PCLKC0_0 @T6G_MB_LIB.T6G(SCH_1):SMB_1_PLD_3V3AUX_SDA_R2
 B12 SMB_1_PLD_3V3AUX_SCL_R2 PT27C||SCL||PCLKT0_0 @T6G_MB_LIB.T6G(SCH_1):SMB_1_PLD_3V3AUX_SCL_R2
 B22 FM_OCP_V3_2_PWR_GOOD PT44B||R_GPLLC @T6G_MB_LIB.T6G(SCH_1):FM_OCP_V3_2_PWR_GOOD
 A21 SMB_BMC_SWB_EN PT44A||R_GPLLT @T6G_MB_LIB.T6G(SCH_1):SMB_BMC_SWB_EN
 A10 OC_ALERT_N PT23B||PCLKC0_1 @T6G_MB_LIB.T6G(SCH_1):OC_ALERT_N
 B10 UV_ALERT_N PT23A||PCLKT0_1 @T6G_MB_LIB.T6G(SCH_1):UV_ALERT_N
  D8 SGPIO_OCP_SFF_LD_N  PT15B @T6G_MB_LIB.T6G(SCH_1):SGPIO_OCP_SFF_LD_N
  F7 FM_I3C_CPU0_MUX1_R_SEL   PT9D @T6G_MB_LIB.T6G(SCH_1):FM_I3C_CPU0_MUX1_R_SEL
  A2 FM_I3C_CPU1_MUX0_R_SEL PT9B||L_GPLLC @T6G_MB_LIB.T6G(SCH_1):FM_I3C_CPU1_MUX0_R_SEL
  E6 FM_I3C_CPU1_MUX1_OE_R_N   PT9C @T6G_MB_LIB.T6G(SCH_1):FM_I3C_CPU1_MUX1_OE_R_N
  B1 FM_I3C_CPU0_MUX0_OE_R_N PT9A||L_GPLLT @T6G_MB_LIB.T6G(SCH_1):FM_I3C_CPU0_MUX0_OE_R_N
  C8 PCIE_M2_SSD0_PRSNT_N  PT15A @T6G_MB_LIB.T6G(SCH_1):PCIE_M2_SSD0_PRSNT_N
  B3 SCM_JTAG_MUX_R_S0  PT11A @T6G_MB_LIB.T6G(SCH_1):SCM_JTAG_MUX_R_S0
  A4 SGPIO_SCM_DI_R<0>  PT11B @T6G_MB_LIB.T6G(SCH_1):SGPIO_SCM_DI_R(0)
 F10 FM_BOARD_BMC_SKU_ID2  PT22A @T6G_MB_LIB.T6G(SCH_1):FM_BOARD_BMC_SKU_ID2
 E10 FM_LED_ACTIVE_E1S_0  PT22B @T6G_MB_LIB.T6G(SCH_1):FM_LED_ACTIVE_E1S_0
  F8 PWRGD_PS_PWROK_PLD_ISO_R  PT11C @T6G_MB_LIB.T6G(SCH_1):PWRGD_PS_PWROK_PLD_ISO_R
  G8 SGPIO_SCM_INTR_R_N  PT11D @T6G_MB_LIB.T6G(SCH_1):SGPIO_SCM_INTR_R_N
  B2 FM_I3C_CPU1_MUX0_OE_R_N  PT10A @T6G_MB_LIB.T6G(SCH_1):FM_I3C_CPU1_MUX0_OE_R_N
  A3 SCM_JTAG_MUX_R_S1  PT10B @T6G_MB_LIB.T6G(SCH_1):SCM_JTAG_MUX_R_S1
  C3 FM_I3C_CPU0_MUX0_R_SEL  PT10C @T6G_MB_LIB.T6G(SCH_1):FM_I3C_CPU0_MUX0_R_SEL
  C4 FM_I3C_CPU0_MUX1_OE_R_N  PT10D @T6G_MB_LIB.T6G(SCH_1):FM_I3C_CPU0_MUX1_OE_R_N
  B4 SGPIO_SCM_DO_<1>  PT12A @T6G_MB_LIB.T6G(SCH_1):SGPIO_SCM_DO_(1)
  A5 SGPIO_SCM_RESET_N  PT12B @T6G_MB_LIB.T6G(SCH_1):SGPIO_SCM_RESET_N
  D5 FM_I3C_CPU1_MUX1_R_SEL  PT12C @T6G_MB_LIB.T6G(SCH_1):FM_I3C_CPU1_MUX1_R_SEL
  C5 FM_BOARD_BMC_SKU_ID0  PT12D @T6G_MB_LIB.T6G(SCH_1):FM_BOARD_BMC_SKU_ID0
  B5 SGPIO_SCM_LD_<1>  PT13A @T6G_MB_LIB.T6G(SCH_1):SGPIO_SCM_LD_(1)
  A6 E1S_0_PERST1_CLKREQ_R_N  PT13B @T6G_MB_LIB.T6G(SCH_1):E1S_0_PERST1_CLKREQ_R_N
  D6 SGPIO_SCM_CLK_<0>  PT13C @T6G_MB_LIB.T6G(SCH_1):SGPIO_SCM_CLK_(0)
  E7 SGPIO_SCM_DO_<0>  PT13D @T6G_MB_LIB.T6G(SCH_1):SGPIO_SCM_DO_(0)
  B6 IRQ_HSC_FAULT_BUF_R_N  PT14A @T6G_MB_LIB.T6G(SCH_1):IRQ_HSC_FAULT_BUF_R_N
  A7 FM_UV_ADR_TRIGGER_R_N  PT14B @T6G_MB_LIB.T6G(SCH_1):FM_UV_ADR_TRIGGER_R_N
  C6 SGPIO_SCM_DI_R<1>  PT14C @T6G_MB_LIB.T6G(SCH_1):SGPIO_SCM_DI_R(1)
  D7 SGPIO_SCM_LD_<0>  PT14D @T6G_MB_LIB.T6G(SCH_1):SGPIO_SCM_LD_(0)
  B8 SGPIO_OCP_SFF_DATAIN  PT20A @T6G_MB_LIB.T6G(SCH_1):SGPIO_OCP_SFF_DATAIN
  A8 SGPIO_OCP_SFF_DATAOUT  PT20B @T6G_MB_LIB.T6G(SCH_1):SGPIO_OCP_SFF_DATAOUT
  C9 SGPIO_OCP_SFF_CLK  PT20C @T6G_MB_LIB.T6G(SCH_1):SGPIO_OCP_SFF_CLK
  D9 OCP_V3_2_MAIN_PWR_EN  PT20D @T6G_MB_LIB.T6G(SCH_1):OCP_V3_2_MAIN_PWR_EN
  B9 P3V3_OCP_SFF_EN  PT21A @T6G_MB_LIB.T6G(SCH_1):P3V3_OCP_SFF_EN
  A9 OCP_V3_1_P3V3_PLD_R_PWRGD  PT21B @T6G_MB_LIB.T6G(SCH_1):OCP_V3_1_P3V3_PLD_R_PWRGD
  F9 P12V_OCP_SFF_EN  PT21C @T6G_MB_LIB.T6G(SCH_1):P12V_OCP_SFF_EN
  G9 FM_BOARD_BMC_SKU_ID1  PT21D @T6G_MB_LIB.T6G(SCH_1):FM_BOARD_BMC_SKU_ID1
 G11 SMB_CPU0_4_XLTR_R_SCL  PT23C @T6G_MB_LIB.T6G(SCH_1):SMB_CPU0_4_XLTR_R_SCL
 F11 SMB_CPU0_4_XLTR_R_SDA  PT23D @T6G_MB_LIB.T6G(SCH_1):SMB_CPU0_4_XLTR_R_SDA
 B11 FM_BOARD_BMC_SKU_ID3  PT24A @T6G_MB_LIB.T6G(SCH_1):FM_BOARD_BMC_SKU_ID3
 A11 FM_BOARD_BMC_SKU_ID4  PT24B @T6G_MB_LIB.T6G(SCH_1):FM_BOARD_BMC_SKU_ID4
 E11 FM_SYS_THROTTLE_R_N  PT24C @T6G_MB_LIB.T6G(SCH_1):FM_SYS_THROTTLE_R_N
 D11 JTAG_SCM_TRST_R_N  PT24D @T6G_MB_LIB.T6G(SCH_1):JTAG_SCM_TRST_R_N
 D12 FM_FAN_PWR_EN  PT27A @T6G_MB_LIB.T6G(SCH_1):FM_FAN_PWR_EN
 E12 SCM_SYS_PWRBTN_N  PT27B @T6G_MB_LIB.T6G(SCH_1):SCM_SYS_PWRBTN_N
 E13 HP_LVC3_OCP_V3_2_P12V_PWRGD_R  PT28C @T6G_MB_LIB.T6G(SCH_1):HP_LVC3_OCP_V3_2_P12V_PWRGD_R
 F13 FM_UARTSW_MSB_N  PT28D @T6G_MB_LIB.T6G(SCH_1):FM_UARTSW_MSB_N
 A13 SMB_2_PLD_3V3AUX_SCL_R2  PT29A @T6G_MB_LIB.T6G(SCH_1):SMB_2_PLD_3V3AUX_SCL_R2
 B13 SMB_2_PLD_3V3AUX_SDA_R2  PT29B @T6G_MB_LIB.T6G(SCH_1):SMB_2_PLD_3V3AUX_SDA_R2
 C13 SCM_ROT_CPU_RST_R_N  PT29C @T6G_MB_LIB.T6G(SCH_1):SCM_ROT_CPU_RST_R_N
 D13 RST_MB_STBY_N  PT29D @T6G_MB_LIB.T6G(SCH_1):RST_MB_STBY_N
 A14 SGPIO_OCP_V3_2_LD_N  PT30A @T6G_MB_LIB.T6G(SCH_1):SGPIO_OCP_V3_2_LD_N
 B14 SGPIO_OCP_V3_2_DATAIN  PT30B @T6G_MB_LIB.T6G(SCH_1):SGPIO_OCP_V3_2_DATAIN
 C14 SGPIO_OCP_V3_2_DATAOUT  PT30C @T6G_MB_LIB.T6G(SCH_1):SGPIO_OCP_V3_2_DATAOUT
 D14 SGPIO_OCP_V3_2_CLK  PT30D @T6G_MB_LIB.T6G(SCH_1):SGPIO_OCP_V3_2_CLK
 A15 SCM_SYS_PWROK  PT38A @T6G_MB_LIB.T6G(SCH_1):SCM_SYS_PWROK
 B15 P1V8_RETIMER_CPU0_R_EN  PT38B @T6G_MB_LIB.T6G(SCH_1):P1V8_RETIMER_CPU0_R_EN
 C15 PVDDCR_SOC_P1_EN  PT38C @T6G_MB_LIB.T6G(SCH_1):PVDDCR_SOC_P1_EN
 D15 PRSNT_OCP_V3_2_N  PT38D @T6G_MB_LIB.T6G(SCH_1):PRSNT_OCP_V3_2_N
 A16 PWRGD_P5V  PT39A @T6G_MB_LIB.T6G(SCH_1):PWRGD_P5V
 B17 PVDDCR_CPU0_P0_EN  PT39B @T6G_MB_LIB.T6G(SCH_1):PVDDCR_CPU0_P0_EN
 C17 RST_SRST_PLD_BMC_R_N  PT39C @T6G_MB_LIB.T6G(SCH_1):RST_SRST_PLD_BMC_R_N
 D16 FPGA_IO3V3_RSVD_1  PT39D @T6G_MB_LIB.T6G(SCH_1):FPGA_IO3V3_RSVD_1
 A17 PWRGD_PVDDCR_SOC_P1  PT40A @T6G_MB_LIB.T6G(SCH_1):PWRGD_PVDDCR_SOC_P1
 B18 FM_LED_PWRGD_PVDDCR_SOC_P1  PT40B @T6G_MB_LIB.T6G(SCH_1):FM_LED_PWRGD_PVDDCR_SOC_P1
 E16 FM_LED_PWRGD_PVDDCR_CPU1_P1  PT40C @T6G_MB_LIB.T6G(SCH_1):FM_LED_PWRGD_PVDDCR_CPU1_P1
 D17 RST_SMB_SWITCH_N  PT40D @T6G_MB_LIB.T6G(SCH_1):RST_SMB_SWITCH_N
 C18 FM_OCP_V3_2_AUX_PWR_EN  PT41C @T6G_MB_LIB.T6G(SCH_1):FM_OCP_V3_2_AUX_PWR_EN
 D18 SGPIO_SCM_CLK_<1>  PT41D @T6G_MB_LIB.T6G(SCH_1):SGPIO_SCM_CLK_(1)
 A19 FM_LED_PWRGD_PVDD18_S5_P1  PT42A @T6G_MB_LIB.T6G(SCH_1):FM_LED_PWRGD_PVDD18_S5_P1
 B20 FM_SOL_UART_CH_SEL  PT42B @T6G_MB_LIB.T6G(SCH_1):FM_SOL_UART_CH_SEL
 F15 OCP_V3_2_P3V3_PLD_R_PWRGD  PT42C @T6G_MB_LIB.T6G(SCH_1):OCP_V3_2_P3V3_PLD_R_PWRGD
 G15 FM_UARTSW_LSB_N  PT42D @T6G_MB_LIB.T6G(SCH_1):FM_UARTSW_LSB_N
 C19 CLK_GEN2_BMC_RC_OE_R_N  PT43C @T6G_MB_LIB.T6G(SCH_1):CLK_GEN2_BMC_RC_OE_R_N
 C20 CLK_GEN2_GPU_FPGA_OE_R_N  PT43D @T6G_MB_LIB.T6G(SCH_1):CLK_GEN2_GPU_FPGA_OE_R_N

Q_RES_0402LF-0,5%,1/16W,CHIP,CS00002JB13  I112  R6095
   1 IRQ_HSC_FAULT_BUF_R_N      A @T6G_MB_LIB.T6G(SCH_1):IRQ_HSC_FAULT_BUF_R_N
   2 IRQ_HSC_FAULT_BUF_N      B @T6G_MB_LIB.T6G(SCH_1):IRQ_HSC_FAULT_BUF_N

Q_RES_0402LF-0,5%,1/16W,CHIP,CS00002JB13  I115  R6096
   1 FM_UV_ADR_TRIGGER_R_N      A @T6G_MB_LIB.T6G(SCH_1):FM_UV_ADR_TRIGGER_R_N
   2 FM_UV_ADR_TRIGGER_N      B @T6G_MB_LIB.T6G(SCH_1):FM_UV_ADR_TRIGGER_N

Q_RES_0402LF-33.2,1%,1/16W,CHIP,CS03322FB03  I121  R4145
   1 PRSNT_CABLE_GPU_B3_ISO_R_N      A @T6G_MB_LIB.T6G(SCH_1):PRSNT_CABLE_GPU_B3_ISO_R_N
   2 PRSNT_CABLE_GPU_B3_ISO_N      B @T6G_MB_LIB.T6G(SCH_1):PRSNT_CABLE_GPU_B3_ISO_N

Q_RES_0402LF-33.2,1%,1/16W,CHIP,CS03322FB03  I122  R4146
   1 GPU_3V3IO_RSVD3_FFU_ISO_R      A @T6G_MB_LIB.T6G(SCH_1):GPU_3V3IO_RSVD3_FFU_ISO_R
   2 GPU_3V3IO_RSVD3_FFU_ISO      B @T6G_MB_LIB.T6G(SCH_1):GPU_3V3IO_RSVD3_FFU_ISO

Q_RES_0402LF-0,5%,1/16W,EMPTY,CS00002JB13  I128  R6094
   1 E1S_0_PERST1_CLKREQ_R_N      A @T6G_MB_LIB.T6G(SCH_1):E1S_0_PERST1_CLKREQ_R_N
   2 E1S_0_PERST1_CLKREQ_N      B @T6G_MB_LIB.T6G(SCH_1):E1S_0_PERST1_CLKREQ_N

Q_RES_0402LF-0,5%,1/16W,CHIP,CS00002JB13  I129  R6116
   1 E1S_0_PERST1_CLKREQ_R_N      A @T6G_MB_LIB.T6G(SCH_1):E1S_0_PERST1_CLKREQ_R_N
   2 E1S_0_PRSNT_N      B @T6G_MB_LIB.T6G(SCH_1):E1S_0_PRSNT_N

Q_RES_0402LF-100,1%,1/16W,CHIP,CS11002FB07  I131  R6117
   1 HP_LVC3_OCP_V3_2_PRSNT2_PLD_N      A @T6G_MB_LIB.T6G(SCH_1):HP_LVC3_OCP_V3_2_PRSNT2_PLD_N
   2 PRSNT_OCP_V3_2_N      B @T6G_MB_LIB.T6G(SCH_1):PRSNT_OCP_V3_2_N

Q_RES_0402LF-0,5%,1/16W,CHIP,CS00002JB13  I139  R407
   1 P12V_OCP_V3_2_PLD_PWRGD      A @T6G_MB_LIB.T6G(SCH_1):P12V_OCP_V3_2_PLD_PWRGD
   2 HP_LVC3_OCP_V3_2_P12V_PWRGD_R      B @T6G_MB_LIB.T6G(SCH_1):HP_LVC3_OCP_V3_2_P12V_PWRGD_R

Q_RES_0402LF-0,5%,1/16W,CHIP,CS00002JB13  I141  R419
   1 RST_SRST_PLD_BMC_N      A @T6G_MB_LIB.T6G(SCH_1):RST_SRST_PLD_BMC_N
   2 RST_SRST_PLD_BMC_R_N      B @T6G_MB_LIB.T6G(SCH_1):RST_SRST_PLD_BMC_R_N

Q_RES_0402LF-0,5%,1/16W,CHIP,CS00002JB13  I144  R439
   1 PWRGD_P5V      A @T6G_MB_LIB.T6G(SCH_1):PWRGD_P5V
   2 PWRGD_P5V_R2      B @T6G_MB_LIB.T6G(SCH_1):PWRGD_P5V_R2

Q_RES_0402LF-33,5%,1/16W,CHIP,CS03302JB10  I146  R6850
   1 P1V8_RETIMER_CPU0_EN      A @T6G_MB_LIB.T6G(SCH_1):P1V8_RETIMER_CPU0_EN
   2 P1V8_RETIMER_CPU0_R_EN      B @T6G_MB_LIB.T6G(SCH_1):P1V8_RETIMER_CPU0_R_EN

Q_RES_0402LF-33,5%,1/16W,CHIP,CS03302JB10  I147  R6851
   1 P1V8_RETIMER_CPU1_EN      A @T6G_MB_LIB.T6G(SCH_1):P1V8_RETIMER_CPU1_EN
   2 P1V8_RETIMER_CPU1_R_EN      B @T6G_MB_LIB.T6G(SCH_1):P1V8_RETIMER_CPU1_R_EN

Q_RES_0402LF-33,5%,1/16W,CHIP,CS03302JB10  I153  R152
   1 P12V_OCP_SFF_EN      A @T6G_MB_LIB.T6G(SCH_1):P12V_OCP_SFF_EN
   2 P12V_OCP_SFF_EN_R      B @T6G_MB_LIB.T6G(SCH_1):P12V_OCP_SFF_EN_R

Q_RES_0402LF-0,5%,1/16W,CHIP,CS00002JB13  I155  R1179
   1 FM_OCP_V3_2_AUX_PWR_R_EN      A @T6G_MB_LIB.T6G(SCH_1):FM_OCP_V3_2_AUX_PWR_R_EN
   2 FM_OCP_V3_2_AUX_PWR_EN      B @T6G_MB_LIB.T6G(SCH_1):FM_OCP_V3_2_AUX_PWR_EN


DRAWING: @T6G_MB_LIB.T6G(SCH_1):PAGE82 

Q_RES_0402LF-1K,1%,1/16W,CHIP,CS21002FB06  I35  R638
   1 CPLD_JTAG_EN      A @T6G_MB_LIB.T6G(SCH_1):CPLD_JTAG_EN
   2 P3V3_AUX      B @T6G_MB_LIB.T6G(SCH_1):P3V3_AUX

Q_RES_0402LF-4.7K,5%,1/16W,EMPTY,CS24702JB10  I36  R1195
   1 P12V_OCP_SFF_EN_R      A @T6G_MB_LIB.T6G(SCH_1):P12V_OCP_SFF_EN_R
   2 P3V3_AUX      B @T6G_MB_LIB.T6G(SCH_1):P3V3_AUX

Q_RES_0402LF-4.7K,5%,1/16W,EMPTY,CS24702JB10  I39  R6061
   1 P12V_OCP_V3_2_EN_R      A @T6G_MB_LIB.T6G(SCH_1):P12V_OCP_V3_2_EN_R
   2 P3V3_AUX      B @T6G_MB_LIB.T6G(SCH_1):P3V3_AUX

Q_RES_0402LF-4.7K,5%,1/16W,EMPTY,CS24702JB10  I40  R6062
   1 P3V3_OCP_V3_2_EN_R      A @T6G_MB_LIB.T6G(SCH_1):P3V3_OCP_V3_2_EN_R
   2 P3V3_AUX      B @T6G_MB_LIB.T6G(SCH_1):P3V3_AUX

Q_RES_0402LF-1K,1%,1/16W,CHIP,CS21002FB06  I53  R993
   1 FM_SYS_THROTTLE_N      A @T6G_MB_LIB.T6G(SCH_1):FM_SYS_THROTTLE_N
   2 P3V3_AUX      B @T6G_MB_LIB.T6G(SCH_1):P3V3_AUX

Q_RES_0402LF-4.7K,5%,1/16W,EMPTY,CS24702JB10  I54  R1314
   1 E1S_0_P12V_EN      A @T6G_MB_LIB.T6G(SCH_1):E1S_0_P12V_EN
   2 P3V3_AUX      B @T6G_MB_LIB.T6G(SCH_1):P3V3_AUX

Q_RES_0402LF-1K,1%,1/16W,CHIP,CS21002FB06  I56  R1527
   1 PRSNT_HDT_N      A @T6G_MB_LIB.T6G(SCH_1):PRSNT_HDT_N
   2 P3V3_AUX      B @T6G_MB_LIB.T6G(SCH_1):P3V3_AUX

Q_RES_0402LF-1K,1%,1/16W,CHIP,CS21002FB06  I57  R1189
   1 PVDD11_S3_P0_PMALERT      A @T6G_MB_LIB.T6G(SCH_1):PVDD11_S3_P0_PMALERT
   2 P3V3_AUX      B @T6G_MB_LIB.T6G(SCH_1):P3V3_AUX

Q_RES_0402LF-1K,1%,1/16W,CHIP,CS21002FB06  I58  R1190
   1 PVDD11_S3_P1_PMALERT      A @T6G_MB_LIB.T6G(SCH_1):PVDD11_S3_P1_PMALERT
   2 P3V3_AUX      B @T6G_MB_LIB.T6G(SCH_1):P3V3_AUX

Q_RES_0402LF-1K,1%,1/16W,CHIP,CS21002FB06  I59  R1187
   1 PVDDCR_CPU0_P1_PMALERT      A @T6G_MB_LIB.T6G(SCH_1):PVDDCR_CPU0_P1_PMALERT
   2 P3V3_AUX      B @T6G_MB_LIB.T6G(SCH_1):P3V3_AUX

Q_RES_0402LF-1K,1%,1/16W,CHIP,CS21002FB06  I60  R1186
   1 PVDDCR_CPU1_P0_SMB_ALERT      A @T6G_MB_LIB.T6G(SCH_1):PVDDCR_CPU1_P0_SMB_ALERT
   2 P3V3_AUX      B @T6G_MB_LIB.T6G(SCH_1):P3V3_AUX

Q_RES_0402LF-1K,1%,1/16W,CHIP,CS21002FB06  I61  R1188
   1 PVDDCR_CPU1_P1_SMB_ALERT      A @T6G_MB_LIB.T6G(SCH_1):PVDDCR_CPU1_P1_SMB_ALERT
   2 P3V3_AUX      B @T6G_MB_LIB.T6G(SCH_1):P3V3_AUX

Q_RES_0402LF-1K,1%,1/16W,CHIP,CS21002FB06  I62  R1185
   1 PVDDCR_CPU0_P0_PMALERT      A @T6G_MB_LIB.T6G(SCH_1):PVDDCR_CPU0_P0_PMALERT
   2 P3V3_AUX      B @T6G_MB_LIB.T6G(SCH_1):P3V3_AUX

Q_RES_0402LF-4.7K,5%,1/16W,CHIP,CS24702JB10  I76  R1286
   1 FM_P1_PCC1_N      A @T6G_MB_LIB.T6G(SCH_1):FM_P1_PCC1_N
   2 PVDD18_S5_P1      B @T6G_MB_LIB.T6G(SCH_1):PVDD18_S5_P1

Q_RES_0402LF-4.7K,5%,1/16W,CHIP,CS24702JB10  I77  R1285
   1 FM_P1_PCC0_N      A @T6G_MB_LIB.T6G(SCH_1):FM_P1_PCC0_N
   2 PVDD18_S5_P1      B @T6G_MB_LIB.T6G(SCH_1):PVDD18_S5_P1

Q_CAP_C0402-0.1UF,16V,10%,X7R,CH4103K1B08  I79  C1134
   1 P1V8_AUX      A @T6G_MB_LIB.T6G(SCH_1):P1V8_AUX
   2    GND      B @T6G_MB_LIB.T6G(SCH_1):GND

Q_CAP_C0402-0.1UF,16V,10%,X7R,CH4103K1B08  I80  C1132
   1 P1V8_AUX      A @T6G_MB_LIB.T6G(SCH_1):P1V8_AUX
   2    GND      B @T6G_MB_LIB.T6G(SCH_1):GND

Q_CAP_C0402-0.1UF,16V,10%,X7R,CH4103K1B08  I82  C1131
   1 P1V8_AUX      A @T6G_MB_LIB.T6G(SCH_1):P1V8_AUX
   2    GND      B @T6G_MB_LIB.T6G(SCH_1):GND

Q_CAP_C0402-0.1UF,16V,10%,X7R,CH4103K1B08  I83  C352
   1 P1V8_AUX      A @T6G_MB_LIB.T6G(SCH_1):P1V8_AUX
   2    GND      B @T6G_MB_LIB.T6G(SCH_1):GND

Q_CAP_C0402-0.1UF,16V,10%,X7R,CH4103K1B08  I84  C1128
   1 P1V8_AUX      A @T6G_MB_LIB.T6G(SCH_1):P1V8_AUX
   2    GND      B @T6G_MB_LIB.T6G(SCH_1):GND

Q_CAP_C0402-0.1UF,16V,10%,X7R,CH4103K1B08  I85  C1129
   1 P1V8_AUX      A @T6G_MB_LIB.T6G(SCH_1):P1V8_AUX
   2    GND      B @T6G_MB_LIB.T6G(SCH_1):GND

Q_CAP_C0402-0.1UF,16V,10%,X7R,CH4103K1B08  I86  C1126
   1 P1V8_AUX      A @T6G_MB_LIB.T6G(SCH_1):P1V8_AUX
   2    GND      B @T6G_MB_LIB.T6G(SCH_1):GND

Q_CAP_C0402-0.1UF,16V,10%,X7R,CH4103K1B08  I87  C1127
   1 P1V8_AUX      A @T6G_MB_LIB.T6G(SCH_1):P1V8_AUX
   2    GND      B @T6G_MB_LIB.T6G(SCH_1):GND

Q_RES_0402LF-10K,1%,1/16W,CHIP,CS31002FB08  I97  R25
   1 FM_I3C_CPU1_MUX1_OE_N      A @T6G_MB_LIB.T6G(SCH_1):FM_I3C_CPU1_MUX1_OE_N
   2    GND      B @T6G_MB_LIB.T6G(SCH_1):GND

Q_CAP_C0402-0.1UF,16V,10%,X7R,CH4103K1B08  I105  C358
   1 P3V3_AUX      A @T6G_MB_LIB.T6G(SCH_1):P3V3_AUX
   2    GND      B @T6G_MB_LIB.T6G(SCH_1):GND

Q_CAP_C0402-0.1UF,16V,10%,X7R,CH4103K1B08  I106  C357
   1 P3V3_AUX      A @T6G_MB_LIB.T6G(SCH_1):P3V3_AUX
   2    GND      B @T6G_MB_LIB.T6G(SCH_1):GND

Q_CAP_C0402-0.1UF,16V,10%,X7R,CH4103K1B08  I107  C356
   1 P3V3_AUX      A @T6G_MB_LIB.T6G(SCH_1):P3V3_AUX
   2    GND      B @T6G_MB_LIB.T6G(SCH_1):GND

Q_CAP_C0402-0.1UF,16V,10%,X7R,CH4103K1B08  I108  C355
   1 P3V3_AUX      A @T6G_MB_LIB.T6G(SCH_1):P3V3_AUX
   2    GND      B @T6G_MB_LIB.T6G(SCH_1):GND

Q_CAP_C0402-0.1UF,16V,10%,X7R,CH4103K1B08  I109  C1176
   1 P3V3_AUX      A @T6G_MB_LIB.T6G(SCH_1):P3V3_AUX
   2    GND      B @T6G_MB_LIB.T6G(SCH_1):GND

Q_CAP_C0402-0.1UF,16V,10%,X7R,CH4103K1B08  I110  C1175
   1 P3V3_AUX      A @T6G_MB_LIB.T6G(SCH_1):P3V3_AUX
   2    GND      B @T6G_MB_LIB.T6G(SCH_1):GND

Q_CAP_C0402-0.1UF,16V,10%,X7R,CH4103K1B08  I111  C1174
   1 P3V3_AUX      A @T6G_MB_LIB.T6G(SCH_1):P3V3_AUX
   2    GND      B @T6G_MB_LIB.T6G(SCH_1):GND

Q_CAP_C0402-0.1UF,16V,10%,X7R,CH4103K1B08  I112  C1172
   1 P3V3_AUX      A @T6G_MB_LIB.T6G(SCH_1):P3V3_AUX
   2    GND      B @T6G_MB_LIB.T6G(SCH_1):GND

Q_CAP_C0402-0.1UF,16V,10%,X7R,CH4103K1B08  I113  C1173
   1 P3V3_AUX      A @T6G_MB_LIB.T6G(SCH_1):P3V3_AUX
   2    GND      B @T6G_MB_LIB.T6G(SCH_1):GND

Q_CAP_C0402-0.1UF,16V,10%,X7R,CH4103K1B08  I114  C1171
   1 P3V3_AUX      A @T6G_MB_LIB.T6G(SCH_1):P3V3_AUX
   2    GND      B @T6G_MB_LIB.T6G(SCH_1):GND

Q_RES_0402LF-10K,1%,1/16W,CHIP,CS31002FB08  I120  R804
   1 RST_PERST_M2_0_N      A @T6G_MB_LIB.T6G(SCH_1):RST_PERST_M2_0_N
   2    GND      B @T6G_MB_LIB.T6G(SCH_1):GND

Q_RES_0402LF-10K,1%,1/16W,CHIP,CS31002FB08  I126  R18
   1 RST_CPU1_PERST0_N      A @T6G_MB_LIB.T6G(SCH_1):RST_CPU1_PERST0_N
   2    GND      B @T6G_MB_LIB.T6G(SCH_1):GND

Q_RES_0402LF-10K,1%,1/16W,CHIP,CS31002FB08  I128  R19
   1 RST_CPU1_PERST1_N      A @T6G_MB_LIB.T6G(SCH_1):RST_CPU1_PERST1_N
   2    GND      B @T6G_MB_LIB.T6G(SCH_1):GND

Q_RES_0402LF-1K,1%,1/16W,CHIP,CS21002FB06  I33  R639
   1 CPLD_PROGRAMN      A @T6G_MB_LIB.T6G(SCH_1):CPLD_PROGRAMN
   2 P3V3_AUX      B @T6G_MB_LIB.T6G(SCH_1):P3V3_AUX

Q_RES_0402LF-4.7K,5%,1/16W,EMPTY,CS24702JB10  I38  R1071
   1 P3V3_OCP_SFF_EN_R      A @T6G_MB_LIB.T6G(SCH_1):P3V3_OCP_SFF_EN_R
   2 P3V3_AUX      B @T6G_MB_LIB.T6G(SCH_1):P3V3_AUX

Q_RES_0402LF-4.7K,5%,1/16W,EMPTY,CS24702JB10  I41  R757
   1 E1S_0_P3V3_EN      A @T6G_MB_LIB.T6G(SCH_1):E1S_0_P3V3_EN
   2 P3V3_AUX      B @T6G_MB_LIB.T6G(SCH_1):P3V3_AUX

Q_RES_0402LF-4.7K,5%,1/16W,CHIP,CS24702JB10  I64  R654
   1 SCM_USB_OC_N      A @T6G_MB_LIB.T6G(SCH_1):SCM_USB_OC_N
   2 P1V8_AUX      B @T6G_MB_LIB.T6G(SCH_1):P1V8_AUX

Q_RES_0402LF-2.2K,5%,1/16W,CHIP,CS22202JB07  I72  R1351
   1 RST_CPU0_KBRST_R_N      A @T6G_MB_LIB.T6G(SCH_1):RST_CPU0_KBRST_R_N
   2 PVDD18_S5_P0      B @T6G_MB_LIB.T6G(SCH_1):PVDD18_S5_P0

Q_RES_0402LF-4.7K,5%,1/16W,CHIP,CS24702JB10  I73  R1288
   1 FM_P0_PCC1_N      A @T6G_MB_LIB.T6G(SCH_1):FM_P0_PCC1_N
   2 PVDD18_S5_P0      B @T6G_MB_LIB.T6G(SCH_1):PVDD18_S5_P0

Q_RES_0402LF-4.7K,5%,1/16W,CHIP,CS24702JB10  I74  R1287
   1 FM_P0_PCC0_N      A @T6G_MB_LIB.T6G(SCH_1):FM_P0_PCC0_N
   2 PVDD18_S5_P0      B @T6G_MB_LIB.T6G(SCH_1):PVDD18_S5_P0

Q_CAP_C0402-0.1UF,16V,10%,X7R,CH4103K1B08  I81  C1133
   1 P1V8_AUX      A @T6G_MB_LIB.T6G(SCH_1):P1V8_AUX
   2    GND      B @T6G_MB_LIB.T6G(SCH_1):GND

Q_RES_0402LF-10K,1%,1/16W,CHIP,CS31002FB08  I93  R10
   1 FM_I3C_CPU0_MUX0_OE_N      A @T6G_MB_LIB.T6G(SCH_1):FM_I3C_CPU0_MUX0_OE_N
   2    GND      B @T6G_MB_LIB.T6G(SCH_1):GND

Q_RES_0402LF-10K,1%,1/16W,CHIP,CS31002FB08  I94  R11
   1 FM_I3C_CPU0_MUX1_OE_N      A @T6G_MB_LIB.T6G(SCH_1):FM_I3C_CPU0_MUX1_OE_N
   2    GND      B @T6G_MB_LIB.T6G(SCH_1):GND

Q_RES_0402LF-10K,1%,1/16W,CHIP,CS31002FB08  I95  R12
   1 FM_I3C_CPU1_MUX0_OE_N      A @T6G_MB_LIB.T6G(SCH_1):FM_I3C_CPU1_MUX0_OE_N
   2    GND      B @T6G_MB_LIB.T6G(SCH_1):GND

Q_CAP_C0402-0.1UF,16V,10%,X7R,CH4103K1B08  I102  C362
   1 P3V3_AUX      A @T6G_MB_LIB.T6G(SCH_1):P3V3_AUX
   2    GND      B @T6G_MB_LIB.T6G(SCH_1):GND

Q_CAP_C0402-0.1UF,16V,10%,X7R,CH4103K1B08  I103  C360
   1 P3V3_AUX      A @T6G_MB_LIB.T6G(SCH_1):P3V3_AUX
   2    GND      B @T6G_MB_LIB.T6G(SCH_1):GND

Q_CAP_C0402-0.1UF,16V,10%,X7R,CH4103K1B08  I104  C361
   1 P3V3_AUX      A @T6G_MB_LIB.T6G(SCH_1):P3V3_AUX
   2    GND      B @T6G_MB_LIB.T6G(SCH_1):GND

Q_RES_0402LF-10K,1%,1/16W,CHIP,CS31002FB08  I118  R800
   1 RST_PERST_E1S_0_N      A @T6G_MB_LIB.T6G(SCH_1):RST_PERST_E1S_0_N
   2    GND      B @T6G_MB_LIB.T6G(SCH_1):GND

Q_RES_0402LF-10K,1%,1/16W,CHIP,CS31002FB08  I124  R16
   1 RST_CPU0_PERST0_N      A @T6G_MB_LIB.T6G(SCH_1):RST_CPU0_PERST0_N
   2    GND      B @T6G_MB_LIB.T6G(SCH_1):GND

Q_RES_0402LF-10K,1%,1/16W,CHIP,CS31002FB08  I125  R17
   1 RST_CPU0_PERST1_N      A @T6G_MB_LIB.T6G(SCH_1):RST_CPU0_PERST1_N
   2    GND      B @T6G_MB_LIB.T6G(SCH_1):GND

Q_CAP_C0402-0.1UF,16V,10%,X7R,CH4103K1B08  I135  C359
   1 P3V3_AUX      A @T6G_MB_LIB.T6G(SCH_1):P3V3_AUX
   2    GND      B @T6G_MB_LIB.T6G(SCH_1):GND

Q_RES_0402LF-2K,1%,1/16W,CHIP,CS22002FB07  I137  R6114
   1 RST_PERST_CPU0_SWB_N      A @T6G_MB_LIB.T6G(SCH_1):RST_PERST_CPU0_SWB_N
   2    GND      B @T6G_MB_LIB.T6G(SCH_1):GND

Q_RES_0402LF-2K,1%,1/16W,CHIP,CS22002FB07  I141  R6115
   1 RST_PERST_CPU1_SWB_N      A @T6G_MB_LIB.T6G(SCH_1):RST_PERST_CPU1_SWB_N
   2    GND      B @T6G_MB_LIB.T6G(SCH_1):GND

Q_RES_0402LF-10K,1%,1/16W,CHIP,CS31002FB08  I143  R6185
   1 FM_SEC_MUX_OE_N      A @T6G_MB_LIB.T6G(SCH_1):FM_SEC_MUX_OE_N
   2    GND      B @T6G_MB_LIB.T6G(SCH_1):GND

Q_RES_0402LF-4.7K,5%,1/16W,EMPTY,CS24702JB10  I146  R6186
   1 FM_SEC_MUX_OE_N      A @T6G_MB_LIB.T6G(SCH_1):FM_SEC_MUX_OE_N
   2 P3V3_AUX      B @T6G_MB_LIB.T6G(SCH_1):P3V3_AUX

Q_RES_0402LF-10K,1%,1/16W,EMPTY,CS31002FB08  I151  R6187
   1 FM_SEC_MUX_SEL      A @T6G_MB_LIB.T6G(SCH_1):FM_SEC_MUX_SEL
   2    GND      B @T6G_MB_LIB.T6G(SCH_1):GND

Q_RES_0402LF-4.7K,5%,1/16W,EMPTY,CS24702JB10  I152  R6188
   1 FM_SEC_MUX_SEL      A @T6G_MB_LIB.T6G(SCH_1):FM_SEC_MUX_SEL
   2 P3V3_AUX      B @T6G_MB_LIB.T6G(SCH_1):P3V3_AUX

Q_RES_0402LF-2K,1%,1/16W,CHIP,CS22002FB07  I154  R3
   1 RST_PERST_CPU1_SWB_1_N      A @T6G_MB_LIB.T6G(SCH_1):RST_PERST_CPU1_SWB_1_N
   2    GND      B @T6G_MB_LIB.T6G(SCH_1):GND

Q_RES_0402LF-4.7K,5%,1/16W,EMPTY,CS24702JB10  I156  R134
   1 FM_APML_MUX2_OE_N      A @T6G_MB_LIB.T6G(SCH_1):FM_APML_MUX2_OE_N
   2 P3V3_AUX      B @T6G_MB_LIB.T6G(SCH_1):P3V3_AUX

Q_RES_0402LF-4.7K,5%,1/16W,EMPTY,CS24702JB10  I157  R135
   1 FM_APML_MUX2_SEL      A @T6G_MB_LIB.T6G(SCH_1):FM_APML_MUX2_SEL
   2 P3V3_AUX      B @T6G_MB_LIB.T6G(SCH_1):P3V3_AUX

Q_RES_0402LF-10K,1%,1/16W,EMPTY,CS31002FB08  I162  R136
   1 FM_APML_MUX2_SEL      A @T6G_MB_LIB.T6G(SCH_1):FM_APML_MUX2_SEL
   2    GND      B @T6G_MB_LIB.T6G(SCH_1):GND

Q_RES_0402LF-10K,1%,1/16W,CHIP,CS31002FB08  I163  R126
   1 FM_APML_MUX2_OE_N      A @T6G_MB_LIB.T6G(SCH_1):FM_APML_MUX2_OE_N
   2    GND      B @T6G_MB_LIB.T6G(SCH_1):GND

Q_RES_0402LF-1K,1%,1/16W,EMPTY,CS21002FB06  I166  R64
   1 SCM_SYS_PWRBTN_N      A @T6G_MB_LIB.T6G(SCH_1):SCM_SYS_PWRBTN_N
   2 P3V3_AUX      B @T6G_MB_LIB.T6G(SCH_1):P3V3_AUX

Q_RES_0402LF-1K,1%,1/16W,CHIP,CS21002FB06  I170  R8033
   1 FM_ESPI_CPU0_ALERT_R_SEL      A @T6G_MB_LIB.T6G(SCH_1):FM_ESPI_CPU0_ALERT_R_SEL
   2    GND      B @T6G_MB_LIB.T6G(SCH_1):GND

Q_RES_0402LF-10K,1%,1/16W,CHIP,CS31002FB08  I171  R1304
   1 E1S_0_PRSNT_N      A @T6G_MB_LIB.T6G(SCH_1):E1S_0_PRSNT_N
   2 P3V3_AUX      B @T6G_MB_LIB.T6G(SCH_1):P3V3_AUX


DRAWING: @T6G_MB_LIB.T6G(SCH_1):PAGE338 

Q_RES_0402LF-1K,1%,1/16W,CHIP,CS21002FB06  I9  R1906
   1 P3V3_AUX      A @T6G_MB_LIB.T6G(SCH_1):P3V3_AUX
   2 OCP_SFF_PRSNT2_R_N      B @T6G_MB_LIB.T6G(SCH_1):OCP_SFF_PRSNT2_R_N

MOSFET_NCH_DUAL-PJT138K,SMLF,IC,BAM138K0003  I11  Q123
   1    GND     S1 @T6G_MB_LIB.T6G(SCH_1):GND
   2 P12V_OCP_EN_1_R     G1 @T6G_MB_LIB.T6G(SCH_1):P12V_OCP_EN_1_R
   6 P12V_OCP_1_EN_G     D1 @T6G_MB_LIB.T6G(SCH_1):P12V_OCP_1_EN_G

Q_RES_0402LF-1K,1%,1/16W,CHIP,CS21002FB06  I15  R1905
   1 P3V3_AUX      A @T6G_MB_LIB.T6G(SCH_1):P3V3_AUX
   2 OCP_SFF_PRSNT0_R_N      B @T6G_MB_LIB.T6G(SCH_1):OCP_SFF_PRSNT0_R_N

Q_RES_0402LF-10K,1%,1/16W,CHIP,CS31002FB08  I17  R4068
   1 P12V_AUX      A @T6G_MB_LIB.T6G(SCH_1):P12V_AUX
   2 P12V_OCP_1_EN_G      B @T6G_MB_LIB.T6G(SCH_1):P12V_OCP_1_EN_G

MOSFET_NCH_DUAL-PJT138K,SMLF,IC,BAM138K0003  I19  Q123
   3 P12V_OCP_UV_1_R     D2 @T6G_MB_LIB.T6G(SCH_1):P12V_OCP_UV_1_R
   5 P12V_OCP_1_EN_G     G2 @T6G_MB_LIB.T6G(SCH_1):P12V_OCP_1_EN_G
   4    GND     S2 @T6G_MB_LIB.T6G(SCH_1):GND

MOSFET_NCH_DUAL-PJT138K,SMLF,IC,BAM138K0003  I23  Q124
   1    GND     S1 @T6G_MB_LIB.T6G(SCH_1):GND
   2 P3V3_OCP_EN_1_R     G1 @T6G_MB_LIB.T6G(SCH_1):P3V3_OCP_EN_1_R
   6 P3V3_OCP_1_EN_G     D1 @T6G_MB_LIB.T6G(SCH_1):P3V3_OCP_1_EN_G

Q_RES_0402LF-1K,1%,1/16W,CHIP,CS21002FB06  I24  R1908
   1 P3V3_AUX      A @T6G_MB_LIB.T6G(SCH_1):P3V3_AUX
   2 OCP_SFF_PRSNT3_R_N      B @T6G_MB_LIB.T6G(SCH_1):OCP_SFF_PRSNT3_R_N

74LVC2G07DW7-74LVC2G07DW-7,SMLF,IC,AL002G07003  I26  U8
   1 OCP_SFF_PRSNT2_R_N     1A @T6G_MB_LIB.T6G(SCH_1):OCP_SFF_PRSNT2_R_N
   3 OCP_SFF_PRSNT3_R_N     2A @T6G_MB_LIB.T6G(SCH_1):OCP_SFF_PRSNT3_R_N
   6 HP_LVC3_OCP_V3_1_PRSNT2_N_R     1Y @T6G_MB_LIB.T6G(SCH_1):HP_LVC3_OCP_V3_1_PRSNT2_N_R
   4 HP_LVC3_OCP_V3_1_PRSNT2_N_R     2Y @T6G_MB_LIB.T6G(SCH_1):HP_LVC3_OCP_V3_1_PRSNT2_N_R
   2    GND    GND @T6G_MB_LIB.T6G(SCH_1):GND
   5 P3V3_AUX    VCC @T6G_MB_LIB.T6G(SCH_1):P3V3_AUX

Q_RES_0402LF-1K,1%,1/16W,CHIP,CS21002FB06  I28  R1907
   1 P3V3_AUX      A @T6G_MB_LIB.T6G(SCH_1):P3V3_AUX
   2 OCP_SFF_PRSNT1_R_N      B @T6G_MB_LIB.T6G(SCH_1):OCP_SFF_PRSNT1_R_N

74LVC2G07DW7-74LVC2G07DW-7,SMLF,IC,AL002G07003  I29  U211
   1 OCP_SFF_PRSNT0_R_N     1A @T6G_MB_LIB.T6G(SCH_1):OCP_SFF_PRSNT0_R_N
   3 OCP_SFF_PRSNT1_R_N     2A @T6G_MB_LIB.T6G(SCH_1):OCP_SFF_PRSNT1_R_N
   6 HP_LVC3_OCP_V3_1_PRSNT2_N_R     1Y @T6G_MB_LIB.T6G(SCH_1):HP_LVC3_OCP_V3_1_PRSNT2_N_R
   4 HP_LVC3_OCP_V3_1_PRSNT2_N_R     2Y @T6G_MB_LIB.T6G(SCH_1):HP_LVC3_OCP_V3_1_PRSNT2_N_R
   2    GND    GND @T6G_MB_LIB.T6G(SCH_1):GND
   5 P3V3_AUX    VCC @T6G_MB_LIB.T6G(SCH_1):P3V3_AUX

Q_CAP_0402-0.1UF,25V,10%,X7R,CH4104K1B00  I30  C593
   1 P3V3_AUX      A @T6G_MB_LIB.T6G(SCH_1):P3V3_AUX
   2    GND      B @T6G_MB_LIB.T6G(SCH_1):GND

Q_CAP_0402-0.1UF,25V,10%,X7R,CH4104K1B00  I33  C592
   1 P3V3_AUX      A @T6G_MB_LIB.T6G(SCH_1):P3V3_AUX
   2    GND      B @T6G_MB_LIB.T6G(SCH_1):GND

Q_RES_0402LF-15K,1%,1/16W,CHIP,CS31502FB05  I36  PR3788
   1 P12V_OCP_OV_1      A @T6G_MB_LIB.T6G(SCH_1):P12V_OCP_OV_1
   2    GND      B @T6G_MB_LIB.T6G(SCH_1):GND

Q_RES_0402LF-0,5%,1/16W,CHIP,CS00002JB13  I40  R3784
   1 P12V_OCP_UV_1_R      A @T6G_MB_LIB.T6G(SCH_1):P12V_OCP_UV_1_R
   2 P12V_OCP_UV_1      B @T6G_MB_LIB.T6G(SCH_1):P12V_OCP_UV_1

Q_RES_0402LF-6.8K,1%,1/16W,CHIP,CS26802FB02  I42  PR3787
   1 P12V_OCP_UV_1      A @T6G_MB_LIB.T6G(SCH_1):P12V_OCP_UV_1
   2 P12V_OCP_OV_1      B @T6G_MB_LIB.T6G(SCH_1):P12V_OCP_OV_1

Q_RES_0402LF-160K,1%,1/16W,CHIP,CS41602FB05  I43  PR3786
   1 P12V_AUX      A @T6G_MB_LIB.T6G(SCH_1):P12V_AUX
   2 P12V_OCP_UV_1      B @T6G_MB_LIB.T6G(SCH_1):P12V_OCP_UV_1

Q_CAP_C0402-1UF,25V,10%,X6S,CH5104KEB02  I45  PC2079
   1 P12V_AUX      A @T6G_MB_LIB.T6G(SCH_1):P12V_AUX
   2    GND      B @T6G_MB_LIB.T6G(SCH_1):GND

Q_RES_0402LF-0,5%,1/16W,CHIP,CS00002JB13  I46  R1148
   1 HP_LVC3_OCP_V3_1_PRSNT2_N_R      A @T6G_MB_LIB.T6G(SCH_1):HP_LVC3_OCP_V3_1_PRSNT2_N_R
   2 HP_LVC3_OCP_SFF_PRSNT2_PLD_N      B @T6G_MB_LIB.T6G(SCH_1):HP_LVC3_OCP_SFF_PRSNT2_PLD_N

Q_RES_0402LF-30.1K,1%,1/16W,CHIP,CS33012FB03  I48  PR5484
   1 P12V_OCP_CB_1      A @T6G_MB_LIB.T6G(SCH_1):P12V_OCP_CB_1
   2    GND      B @T6G_MB_LIB.T6G(SCH_1):GND

MAX15090BEWIT-MAX15090BEWI+T,SMLF,IC,AL015080B00  I50  PU203
  A2 P12V_OCP_VCC_1    VCC @T6G_MB_LIB.T6G(SCH_1):P12V_OCP_VCC_1
  A3 P12V_AUX  IN_A3 @T6G_MB_LIB.T6G(SCH_1):P12V_AUX
  A5 P12V_AUX  IN_A5 @T6G_MB_LIB.T6G(SCH_1):P12V_AUX
  B3 P12V_AUX  IN_B3 @T6G_MB_LIB.T6G(SCH_1):P12V_AUX
  B5 P12V_AUX  IN_B5 @T6G_MB_LIB.T6G(SCH_1):P12V_AUX
  C3 P12V_AUX  IN_C3 @T6G_MB_LIB.T6G(SCH_1):P12V_AUX
  C5 P12V_AUX  IN_C5 @T6G_MB_LIB.T6G(SCH_1):P12V_AUX
  D5 P12V_AUX  IN_D5 @T6G_MB_LIB.T6G(SCH_1):P12V_AUX
  B1 P12V_OCP_CB_1     CB @T6G_MB_LIB.T6G(SCH_1):P12V_OCP_CB_1
  B7    GND    EN# @T6G_MB_LIB.T6G(SCH_1):GND
  D1 P12V_OCP_REG_1    REG @T6G_MB_LIB.T6G(SCH_1):P12V_OCP_REG_1
  D2 P12V_OCP_UV_1     UV @T6G_MB_LIB.T6G(SCH_1):P12V_OCP_UV_1
  D3 P12V_OCP_OV_1     OV @T6G_MB_LIB.T6G(SCH_1):P12V_OCP_OV_1
  A1 P12V_OCP_SENSE_1 ISENSE @T6G_MB_LIB.T6G(SCH_1):P12V_OCP_SENSE_1
  A4 P12V_OCP_SFF OUT_A4 @T6G_MB_LIB.T6G(SCH_1):P12V_OCP_SFF
  B4 P12V_OCP_SFF OUT_B4 @T6G_MB_LIB.T6G(SCH_1):P12V_OCP_SFF
  B6 P12V_OCP_SFF OUT_B6 @T6G_MB_LIB.T6G(SCH_1):P12V_OCP_SFF
  C4 P12V_OCP_SFF OUT_C4 @T6G_MB_LIB.T6G(SCH_1):P12V_OCP_SFF
  C6 P12V_OCP_SFF OUT_C6 @T6G_MB_LIB.T6G(SCH_1):P12V_OCP_SFF
  D4 P12V_OCP_SFF OUT_D4 @T6G_MB_LIB.T6G(SCH_1):P12V_OCP_SFF
  D6 P12V_OCP_SFF OUT_D6 @T6G_MB_LIB.T6G(SCH_1):P12V_OCP_SFF
  A6 P12V_OCP_GATE_1   GATE @T6G_MB_LIB.T6G(SCH_1):P12V_OCP_GATE_1
  A7    GND   CDLY @T6G_MB_LIB.T6G(SCH_1):GND
  B2    GND GND_B2 @T6G_MB_LIB.T6G(SCH_1):GND
  C1    GND GND_C1 @T6G_MB_LIB.T6G(SCH_1):GND
  C2    GND GND_C2 @T6G_MB_LIB.T6G(SCH_1):GND
  C7 P12V_OCP_FAULT_1 FAULT# @T6G_MB_LIB.T6G(SCH_1):P12V_OCP_FAULT_1
  D7 P12V_OCP_PWRGD_1     PG @T6G_MB_LIB.T6G(SCH_1):P12V_OCP_PWRGD_1

Q_CAP_C0402-1UF,25V,10%,X6S,CH5104KEB02  I54  PC2087
   1    GND      A @T6G_MB_LIB.T6G(SCH_1):GND
   2 P12V_OCP_REG_1      B @T6G_MB_LIB.T6G(SCH_1):P12V_OCP_REG_1

Q_CAP_C0402-1UF,25V,10%,X6S,CH5104KEB02  I55  PC2085
   1 P12V_OCP_VCC_1      A @T6G_MB_LIB.T6G(SCH_1):P12V_OCP_VCC_1
   2    GND      B @T6G_MB_LIB.T6G(SCH_1):GND

Q_RES_0402LF-10,1%,1/16W,CHIP,CS01002FB07  I56  PR3792
   1 P12V_AUX      A @T6G_MB_LIB.T6G(SCH_1):P12V_AUX
   2 P12V_OCP_VCC_1      B @T6G_MB_LIB.T6G(SCH_1):P12V_OCP_VCC_1

Q_RES_0402LF-10K,1%,1/16W,CHIP,CS31002FB08  I59  R4070
   1 P12V_AUX      A @T6G_MB_LIB.T6G(SCH_1):P12V_AUX
   2 P3V3_OCP_1_EN_G      B @T6G_MB_LIB.T6G(SCH_1):P3V3_OCP_1_EN_G

Q_RES_0402LF-0,5%,1/16W,CHIP,CS00002JB13  I61  R3785
   1 P3V3_OCP_UV_1_R1      A @T6G_MB_LIB.T6G(SCH_1):P3V3_OCP_UV_1_R1
   2 P3V3_OCP_UV_1      B @T6G_MB_LIB.T6G(SCH_1):P3V3_OCP_UV_1

Q_CAP_C0402-1UF,25V,10%,X6S,CH5104KEB02  I62  PC5328
   1 P3V3_AUX      A @T6G_MB_LIB.T6G(SCH_1):P3V3_AUX
   2    GND      B @T6G_MB_LIB.T6G(SCH_1):GND

Q_RES_0402LF-7.15K,1%,1/16W,CHIP,CS27152FB03  I64  PR3790
   1 P3V3_OCP_UV_1      A @T6G_MB_LIB.T6G(SCH_1):P3V3_OCP_UV_1
   2 P3V3_OCP_OV_1      B @T6G_MB_LIB.T6G(SCH_1):P3V3_OCP_OV_1

Q_RES_0402LF-25.5K,1%,1/16W,CHIP,CS32552FB06  I66  PR3789
   1 P3V3_AUX      A @T6G_MB_LIB.T6G(SCH_1):P3V3_AUX
   2 P3V3_OCP_UV_1      B @T6G_MB_LIB.T6G(SCH_1):P3V3_OCP_UV_1

Q_CAP_C0402-1UF,25V,10%,X6S,CH5104KEB02  I67  PC2093
   1    GND      A @T6G_MB_LIB.T6G(SCH_1):GND
   2 P3V3_OCP_REG_1      B @T6G_MB_LIB.T6G(SCH_1):P3V3_OCP_REG_1

Q_RES_0402LF-10,1%,1/16W,CHIP,CS01002FB07  I68  PR3798
   1 P3V3_AUX      A @T6G_MB_LIB.T6G(SCH_1):P3V3_AUX
   2 P3V3_OCP_VCC_1      B @T6G_MB_LIB.T6G(SCH_1):P3V3_OCP_VCC_1

Q_RES_0402LF-10K,1%,1/16W,CHIP,CS31002FB08  I71  R1150
   1 P3V3_AUX      A @T6G_MB_LIB.T6G(SCH_1):P3V3_AUX
   2 HP_LVC3_OCP_SFF_PRSNT2_PLD_N      B @T6G_MB_LIB.T6G(SCH_1):HP_LVC3_OCP_SFF_PRSNT2_PLD_N

Q_RES_0402LF-845,1%,1/16W,CHIP,CS18452FB01  I73  PR3781
   1 P12V_OCP_SENSE_1      A @T6G_MB_LIB.T6G(SCH_1):P12V_OCP_SENSE_1
   2    GND      B @T6G_MB_LIB.T6G(SCH_1):GND

Q_CAP_C0402-0.01UF,50V,10%,EMPTY,CH31006KB18  I74  PC2088
   1 P12V_OCP_SFF      A @T6G_MB_LIB.T6G(SCH_1):P12V_OCP_SFF
   2 P12V_OCP_GATE_1      B @T6G_MB_LIB.T6G(SCH_1):P12V_OCP_GATE_1

Q_RES_0402LF-0,5%,1/16W,CHIP,CS00002JB13  I75  R3144
   1 P12V_OCP_PWRGD_1      A @T6G_MB_LIB.T6G(SCH_1):P12V_OCP_PWRGD_1
   2 HP_LVC3_OCP_V3_1_P12V_PWRGD      B @T6G_MB_LIB.T6G(SCH_1):HP_LVC3_OCP_V3_1_P12V_PWRGD

Q_RES_0402LF-10M,1%,1/16W,CHIP,CS61002FB02  I76  PR4524
   1 P12V_OCP_SFF      A @T6G_MB_LIB.T6G(SCH_1):P12V_OCP_SFF
   2 P12V_OCP_GATE_1      B @T6G_MB_LIB.T6G(SCH_1):P12V_OCP_GATE_1

Q_CAP_C0402-3900PF,50V,10%,X7R,CH23906KB14  I77  PC4056
   1 P12V_OCP_GATE_1      A @T6G_MB_LIB.T6G(SCH_1):P12V_OCP_GATE_1
   2    GND      B @T6G_MB_LIB.T6G(SCH_1):GND

SCHOTTKY_AC-B340A-13-F,SMLF,IC,BC000340Z30  I79  PD102
   A    GND      A @T6G_MB_LIB.T6G(SCH_1):GND
   C P12V_OCP_SFF      C @T6G_MB_LIB.T6G(SCH_1):P12V_OCP_SFF

Q_RES_0402LF-0,5%,1/16W,CHIP,CS00002JB13  I80  R3870
   1 P12V_OCP_SENSE_1      A @T6G_MB_LIB.T6G(SCH_1):P12V_OCP_SENSE_1
   2 P12V_OCP_SFF_ISENSE_MAM_TIC      B @T6G_MB_LIB.T6G(SCH_1):P12V_OCP_SFF_ISENSE_MAM_TIC

Q_RES_0402LF-0,5%,1/16W,EMPTY,CS00002JB13  I82  R3869
   1 P12V_OCP_SENSE_1      A @T6G_MB_LIB.T6G(SCH_1):P12V_OCP_SENSE_1
   2 P12V_OCP_SFF_ISENSE_MAM_MAM      B @T6G_MB_LIB.T6G(SCH_1):P12V_OCP_SFF_ISENSE_MAM_MAM

Q_RES_0402LF-100K,1%,1/16W,CHIP,CS41002FB09  I83  R3799
   1 P3V3_AUX      A @T6G_MB_LIB.T6G(SCH_1):P3V3_AUX
   2 P12V_OCP_FAULT_1      B @T6G_MB_LIB.T6G(SCH_1):P12V_OCP_FAULT_1

Q_RES_0402LF-100K,1%,1/16W,CHIP,CS41002FB09  I85  R3797
   1 P3V3_AUX      A @T6G_MB_LIB.T6G(SCH_1):P3V3_AUX
   2 HP_LVC3_OCP_V3_1_P12V_PWRGD      B @T6G_MB_LIB.T6G(SCH_1):HP_LVC3_OCP_V3_1_P12V_PWRGD

Q_CAP_0402-0.1UF,25V,10%,X7R,CH4104K1B00  I86  PC2092
   1 P12V_OCP_SFF      A @T6G_MB_LIB.T6G(SCH_1):P12V_OCP_SFF
   2    GND      B @T6G_MB_LIB.T6G(SCH_1):GND

Q_CAP_C0805-22UF,16V,20%,X6S,CH6223MEA01  I87  PC2080
   1 P12V_OCP_SFF      A @T6G_MB_LIB.T6G(SCH_1):P12V_OCP_SFF
   2    GND      B @T6G_MB_LIB.T6G(SCH_1):GND

Q_CAP_C0805-10UF,16V,10%,X6S,CH6103KEA01  I89  PC2082
   1 P12V_OCP_SFF      A @T6G_MB_LIB.T6G(SCH_1):P12V_OCP_SFF
   2    GND      B @T6G_MB_LIB.T6G(SCH_1):GND

Q_CAP_C0402-0.01UF,50V,10%,EMPTY,CH31006KB18  I94  PC2144
   1 P3V3_OCP_SFF_R      A @T6G_MB_LIB.T6G(SCH_1):P3V3_OCP_SFF_R
   2 P3V3_OCP_GATE_PU202_1      B @T6G_MB_LIB.T6G(SCH_1):P3V3_OCP_GATE_PU202_1

Q_RES_0402LF-4.53K,1%,1/16W,CHIP,CS24532FB03  I95  PR5481
   1 P3V3_OCP_SENSE_1      A @T6G_MB_LIB.T6G(SCH_1):P3V3_OCP_SENSE_1
   2    GND      B @T6G_MB_LIB.T6G(SCH_1):GND

Q_RES_0402LF-10M,1%,1/16W,CHIP,CS61002FB02  I96  PR4525
   1 P3V3_OCP_SFF_R      A @T6G_MB_LIB.T6G(SCH_1):P3V3_OCP_SFF_R
   2 P3V3_OCP_GATE_PU202_1      B @T6G_MB_LIB.T6G(SCH_1):P3V3_OCP_GATE_PU202_1

SCHOTTKY_AC-B340A-13-F,SMLF,IC,BC000340Z30  I97  PD103
   A    GND      A @T6G_MB_LIB.T6G(SCH_1):GND
   C P3V3_OCP_SFF_R      C @T6G_MB_LIB.T6G(SCH_1):P3V3_OCP_SFF_R

Q_CAP_C0402-6800PF,50V,10%,X7R,CH2686K1B01  I100  PC2089
   1 P3V3_OCP_GATE_PU202_1      A @T6G_MB_LIB.T6G(SCH_1):P3V3_OCP_GATE_PU202_1
   2    GND      B @T6G_MB_LIB.T6G(SCH_1):GND

Q_RES_0402LF-100K,1%,1/16W,CHIP,CS41002FB09  I101  R3796
   1 P3V3_AUX      A @T6G_MB_LIB.T6G(SCH_1):P3V3_AUX
   2 P3V3_OCP_FAULT_1      B @T6G_MB_LIB.T6G(SCH_1):P3V3_OCP_FAULT_1

Q_CAP_0402-0.1UF,25V,10%,X7R,CH4104K1B00  I104  PC2091
   1 P3V3_OCP_SFF_R      A @T6G_MB_LIB.T6G(SCH_1):P3V3_OCP_SFF_R
   2    GND      B @T6G_MB_LIB.T6G(SCH_1):GND

Q_CAP_C0805-10UF,16V,10%,X6S,CH6103KEA01  I106  PC2081
   1 P3V3_OCP_SFF_R      A @T6G_MB_LIB.T6G(SCH_1):P3V3_OCP_SFF_R
   2    GND      B @T6G_MB_LIB.T6G(SCH_1):GND

Q_CAP_C0402-1UF,25V,10%,X6S,CH5104KEB02  I110  PC2086
   1 P3V3_OCP_VCC_1      A @T6G_MB_LIB.T6G(SCH_1):P3V3_OCP_VCC_1
   2    GND      B @T6G_MB_LIB.T6G(SCH_1):GND

Q_RES_0402LF-5.36K,1%,1/16W,CHIP,CS25362FB02  I111  PR3780
   1 P3V3_OCP_CB_1      A @T6G_MB_LIB.T6G(SCH_1):P3V3_OCP_CB_1
   2    GND      B @T6G_MB_LIB.T6G(SCH_1):GND

MOSFET_NCH_DUAL-PJT138K,SMLF,IC,BAM138K0003  I112  Q124
   3 P3V3_OCP_UV_1_R1     D2 @T6G_MB_LIB.T6G(SCH_1):P3V3_OCP_UV_1_R1
   5 P3V3_OCP_1_EN_G     G2 @T6G_MB_LIB.T6G(SCH_1):P3V3_OCP_1_EN_G
   4    GND     S2 @T6G_MB_LIB.T6G(SCH_1):GND

MAX15090BEWIT-MAX15090BEWI+T,SMLF,IC,AL015080B00  I113  PU202
  A2 P3V3_OCP_VCC_1    VCC @T6G_MB_LIB.T6G(SCH_1):P3V3_OCP_VCC_1
  A3 P3V3_AUX  IN_A3 @T6G_MB_LIB.T6G(SCH_1):P3V3_AUX
  A5 P3V3_AUX  IN_A5 @T6G_MB_LIB.T6G(SCH_1):P3V3_AUX
  B3 P3V3_AUX  IN_B3 @T6G_MB_LIB.T6G(SCH_1):P3V3_AUX
  B5 P3V3_AUX  IN_B5 @T6G_MB_LIB.T6G(SCH_1):P3V3_AUX
  C3 P3V3_AUX  IN_C3 @T6G_MB_LIB.T6G(SCH_1):P3V3_AUX
  C5 P3V3_AUX  IN_C5 @T6G_MB_LIB.T6G(SCH_1):P3V3_AUX
  D5 P3V3_AUX  IN_D5 @T6G_MB_LIB.T6G(SCH_1):P3V3_AUX
  B1 P3V3_OCP_CB_1     CB @T6G_MB_LIB.T6G(SCH_1):P3V3_OCP_CB_1
  B7    GND    EN# @T6G_MB_LIB.T6G(SCH_1):GND
  D1 P3V3_OCP_REG_1    REG @T6G_MB_LIB.T6G(SCH_1):P3V3_OCP_REG_1
  D2 P3V3_OCP_UV_1     UV @T6G_MB_LIB.T6G(SCH_1):P3V3_OCP_UV_1
  D3 P3V3_OCP_OV_1     OV @T6G_MB_LIB.T6G(SCH_1):P3V3_OCP_OV_1
  A1 P3V3_OCP_SENSE_1 ISENSE @T6G_MB_LIB.T6G(SCH_1):P3V3_OCP_SENSE_1
  A4 P3V3_OCP_SFF_R OUT_A4 @T6G_MB_LIB.T6G(SCH_1):P3V3_OCP_SFF_R
  B4 P3V3_OCP_SFF_R OUT_B4 @T6G_MB_LIB.T6G(SCH_1):P3V3_OCP_SFF_R
  B6 P3V3_OCP_SFF_R OUT_B6 @T6G_MB_LIB.T6G(SCH_1):P3V3_OCP_SFF_R
  C4 P3V3_OCP_SFF_R OUT_C4 @T6G_MB_LIB.T6G(SCH_1):P3V3_OCP_SFF_R
  C6 P3V3_OCP_SFF_R OUT_C6 @T6G_MB_LIB.T6G(SCH_1):P3V3_OCP_SFF_R
  D4 P3V3_OCP_SFF_R OUT_D4 @T6G_MB_LIB.T6G(SCH_1):P3V3_OCP_SFF_R
  D6 P3V3_OCP_SFF_R OUT_D6 @T6G_MB_LIB.T6G(SCH_1):P3V3_OCP_SFF_R
  A6 P3V3_OCP_GATE_PU202_1   GATE @T6G_MB_LIB.T6G(SCH_1):P3V3_OCP_GATE_PU202_1
  A7    GND   CDLY @T6G_MB_LIB.T6G(SCH_1):GND
  B2    GND GND_B2 @T6G_MB_LIB.T6G(SCH_1):GND
  C1    GND GND_C1 @T6G_MB_LIB.T6G(SCH_1):GND
  C2    GND GND_C2 @T6G_MB_LIB.T6G(SCH_1):GND
  C7 P3V3_OCP_FAULT_1 FAULT# @T6G_MB_LIB.T6G(SCH_1):P3V3_OCP_FAULT_1
  D7 P3V3_OCP_PWRGD_1     PG @T6G_MB_LIB.T6G(SCH_1):P3V3_OCP_PWRGD_1

Q_RES_0402LF-15K,1%,1/16W,CHIP,CS31502FB05  I114  PR3791
   1 P3V3_OCP_OV_1      A @T6G_MB_LIB.T6G(SCH_1):P3V3_OCP_OV_1
   2    GND      B @T6G_MB_LIB.T6G(SCH_1):GND

DIODE_TVS-SMF14A,SMLF,IC,BCSMF14AZ01  I115  PD101
   A    GND      A @T6G_MB_LIB.T6G(SCH_1):GND
   C P12V_AUX      C @T6G_MB_LIB.T6G(SCH_1):P12V_AUX

Q_RES_0402LF-0,5%,1/16W,CHIP,CS00002JB13  I116  R576
   1 HP_LVC3_OCP_V3_1_PRSNT2_N_R      A @T6G_MB_LIB.T6G(SCH_1):HP_LVC3_OCP_V3_1_PRSNT2_N_R
   2 HP_LVC3_OCP_SFF_PRSNT2_N      B @T6G_MB_LIB.T6G(SCH_1):HP_LVC3_OCP_SFF_PRSNT2_N

Q_RES_0402LF-10K,1%,1/16W,CHIP,CS31002FB08  I118  R577
   1 P3V3_AUX      A @T6G_MB_LIB.T6G(SCH_1):P3V3_AUX
   2 HP_LVC3_OCP_SFF_PRSNT2_N      B @T6G_MB_LIB.T6G(SCH_1):HP_LVC3_OCP_SFF_PRSNT2_N

Q_RES_0402LF-0,5%,1/16W,EMPTY,CS00002JB13  I123  R4061
   1 P12V_OCP_SFF_EN_R      A @T6G_MB_LIB.T6G(SCH_1):P12V_OCP_SFF_EN_R
   2 P12V_OCP_EN_1_R      B @T6G_MB_LIB.T6G(SCH_1):P12V_OCP_EN_1_R

Q_RES_0402LF-0,5%,1/16W,CHIP,CS00002JB13  I125  R561
   1 P12V_OCP_SFF_BUF_EN_R      A @T6G_MB_LIB.T6G(SCH_1):P12V_OCP_SFF_BUF_EN_R
   2 P12V_OCP_EN_1_R      B @T6G_MB_LIB.T6G(SCH_1):P12V_OCP_EN_1_R

Q_RES_0402LF-0,5%,1/16W,EMPTY,CS00002JB13  I126  R5487
   1 P3V3_OCP_SFF_EN_R      A @T6G_MB_LIB.T6G(SCH_1):P3V3_OCP_SFF_EN_R
   2 P3V3_OCP_EN_1_R      B @T6G_MB_LIB.T6G(SCH_1):P3V3_OCP_EN_1_R

Q_RES_0402LF-4.7K,5%,1/16W,EMPTY,CS24702JB10  I127  R4069
   1 P3V3_OCP_EN_1_R      A @T6G_MB_LIB.T6G(SCH_1):P3V3_OCP_EN_1_R
   2    GND      B @T6G_MB_LIB.T6G(SCH_1):GND

Q_RES_0402LF-4.7K,5%,1/16W,EMPTY,CS24702JB10  I130  R6045
   1 P12V_OCP_EN_1_R      A @T6G_MB_LIB.T6G(SCH_1):P12V_OCP_EN_1_R
   2    GND      B @T6G_MB_LIB.T6G(SCH_1):GND

Q_RES_0402LF-100K,1%,1/16W,EMPTY,CS41002FB09  I131  R3783
   1 P3V3_AUX      A @T6G_MB_LIB.T6G(SCH_1):P3V3_AUX
   2 OCP_V3_1_P3V3_PWRGD      B @T6G_MB_LIB.T6G(SCH_1):OCP_V3_1_P3V3_PWRGD

Q_RES_0402LF-0,5%,1/16W,EMPTY,CS00002JB13  I132  R3794
   1 P3V3_OCP_PWRGD_1      A @T6G_MB_LIB.T6G(SCH_1):P3V3_OCP_PWRGD_1
   2 OCP_V3_1_P3V3_PWRGD      B @T6G_MB_LIB.T6G(SCH_1):OCP_V3_1_P3V3_PWRGD

Q_RES_0402LF-0,5%,1/16W,EMPTY,CS00002JB13  I133  R1136
   1 HP_LVC3_OCP_V3_1_P12V_PWRGD      A @T6G_MB_LIB.T6G(SCH_1):HP_LVC3_OCP_V3_1_P12V_PWRGD
   2 P3V3_OCP_EN_1_R      B @T6G_MB_LIB.T6G(SCH_1):P3V3_OCP_EN_1_R

Q_RES_0402LF-0,5%,1/16W,CHIP,CS00002JB13  I135  R1486
   1 P12V_OCP_SFF_BUF_EN_R      A @T6G_MB_LIB.T6G(SCH_1):P12V_OCP_SFF_BUF_EN_R
   2 P3V3_OCP_EN_1_R      B @T6G_MB_LIB.T6G(SCH_1):P3V3_OCP_EN_1_R


DRAWING: @T6G_MB_LIB.T6G(SCH_1):PAGE83 

Q_RES_0402LF-4.7K,5%,1/16W,CHIP,CS24702JB10  I22  R996
   1 P1V8_AUX      A @T6G_MB_LIB.T6G(SCH_1):P1V8_AUX
   2 SCM_IRQ_1V8_N      B @T6G_MB_LIB.T6G(SCH_1):SCM_IRQ_1V8_N

Q_CAP_0402-0.1UF,25V,10%,X7R,CH4104K1B00  I24  C552
   1 P1V8_AUX      A @T6G_MB_LIB.T6G(SCH_1):P1V8_AUX
   2    GND      B @T6G_MB_LIB.T6G(SCH_1):GND

SN74LVC1G07DBVR_SMLF-SN74LVC1G07DBVR,IC,AL1G0007024  I26  U92
   2 SCM_IRQ_1V8_N      A @T6G_MB_LIB.T6G(SCH_1):SCM_IRQ_1V8_N
   4 SCM_IRQ_R_N      Y @T6G_MB_LIB.T6G(SCH_1):SCM_IRQ_R_N
   1     NC     NC     NC
   5 P1V8_AUX    VCC @T6G_MB_LIB.T6G(SCH_1):P1V8_AUX
   3    GND    GND @T6G_MB_LIB.T6G(SCH_1):GND

Q_RES_0402LF-33,5%,1/16W,CHIP,CS03302JB10  I27  R71
   1 SCM_IRQ_R_N      A @T6G_MB_LIB.T6G(SCH_1):SCM_IRQ_R_N
   2 SCM_IRQ_N      B @T6G_MB_LIB.T6G(SCH_1):SCM_IRQ_N

Q_RES_0402LF-4.7K,5%,1/16W,CHIP,CS24702JB10  I29  R1338
   1 P3V3_AUX      A @T6G_MB_LIB.T6G(SCH_1):P3V3_AUX
   2 SCM_IRQ_N      B @T6G_MB_LIB.T6G(SCH_1):SCM_IRQ_N

Q_RES_0402LF-1K,1%,1/16W,CHIP,CS21002FB06  I54  R6145
   1 FM_BOARD_BMC_SKU_ID0      A @T6G_MB_LIB.T6G(SCH_1):FM_BOARD_BMC_SKU_ID0
   2    GND      B @T6G_MB_LIB.T6G(SCH_1):GND

Q_RES_0402LF-1K,1%,1/16W,EMPTY,CS21002FB06  I50  R6122
   1 PVDD18_S5_P0      A @T6G_MB_LIB.T6G(SCH_1):PVDD18_S5_P0
   2 FM_BOARD_SKU_ID2      B @T6G_MB_LIB.T6G(SCH_1):FM_BOARD_SKU_ID2

Q_RES_0402LF-1K,1%,1/16W,CHIP,CS21002FB06  I52  R6144
   1 FM_BOARD_BMC_SKU_ID1      A @T6G_MB_LIB.T6G(SCH_1):FM_BOARD_BMC_SKU_ID1
   2    GND      B @T6G_MB_LIB.T6G(SCH_1):GND

Q_RES_0402LF-1K,1%,1/16W,CHIP,CS21002FB06  I36  R6143
   1 FM_BOARD_BMC_SKU_ID2      A @T6G_MB_LIB.T6G(SCH_1):FM_BOARD_BMC_SKU_ID2
   2    GND      B @T6G_MB_LIB.T6G(SCH_1):GND

Q_RES_0402LF-1K,1%,1/16W,EMPTY,CS21002FB06  I39  R6138
   1 P3V3_AUX      A @T6G_MB_LIB.T6G(SCH_1):P3V3_AUX
   2 FM_BOARD_BMC_SKU_ID2      B @T6G_MB_LIB.T6G(SCH_1):FM_BOARD_BMC_SKU_ID2

Q_RES_0402LF-1K,1%,1/16W,CHIP,CS21002FB06  I46  R6127
   1 FM_BOARD_SKU_ID2      A @T6G_MB_LIB.T6G(SCH_1):FM_BOARD_SKU_ID2
   2    GND      B @T6G_MB_LIB.T6G(SCH_1):GND

Q_RES_0402LF-1K,1%,1/16W,EMPTY,CS21002FB06  I55  R6139
   1 P3V3_AUX      A @T6G_MB_LIB.T6G(SCH_1):P3V3_AUX
   2 FM_BOARD_BMC_SKU_ID1      B @T6G_MB_LIB.T6G(SCH_1):FM_BOARD_BMC_SKU_ID1

Q_RES_0402LF-1K,1%,1/16W,EMPTY,CS21002FB06  I56  R6140
   1 P3V3_AUX      A @T6G_MB_LIB.T6G(SCH_1):P3V3_AUX
   2 FM_BOARD_BMC_SKU_ID0      B @T6G_MB_LIB.T6G(SCH_1):FM_BOARD_BMC_SKU_ID0

Q_RES_0402LF-1K,1%,1/16W,CHIP,CS21002FB06  I64  R6128
   1 FM_BOARD_SKU_ID1      A @T6G_MB_LIB.T6G(SCH_1):FM_BOARD_SKU_ID1
   2    GND      B @T6G_MB_LIB.T6G(SCH_1):GND

Q_RES_0402LF-1K,1%,1/16W,CHIP,CS21002FB06  I65  R6129
   1 FM_BOARD_SKU_ID0      A @T6G_MB_LIB.T6G(SCH_1):FM_BOARD_SKU_ID0
   2    GND      B @T6G_MB_LIB.T6G(SCH_1):GND

Q_RES_0402LF-1K,1%,1/16W,EMPTY,CS21002FB06  I71  R6123
   1 PVDD18_S5_P0      A @T6G_MB_LIB.T6G(SCH_1):PVDD18_S5_P0
   2 FM_BOARD_SKU_ID1      B @T6G_MB_LIB.T6G(SCH_1):FM_BOARD_SKU_ID1

Q_RES_0402LF-1K,1%,1/16W,EMPTY,CS21002FB06  I72  R6124
   1 PVDD18_S5_P0      A @T6G_MB_LIB.T6G(SCH_1):PVDD18_S5_P0
   2 FM_BOARD_SKU_ID0      B @T6G_MB_LIB.T6G(SCH_1):FM_BOARD_SKU_ID0

Q_RES_0402LF-1K,1%,1/16W,CHIP,CS21002FB06  I115  R6120
   1 PVDD18_S5_P0      A @T6G_MB_LIB.T6G(SCH_1):PVDD18_S5_P0
   2 FM_BOARD_SKU_ID4      B @T6G_MB_LIB.T6G(SCH_1):FM_BOARD_SKU_ID4

Q_RES_0402LF-1K,1%,1/16W,EMPTY,CS21002FB06  I116  R6125
   1 FM_BOARD_SKU_ID4      A @T6G_MB_LIB.T6G(SCH_1):FM_BOARD_SKU_ID4
   2    GND      B @T6G_MB_LIB.T6G(SCH_1):GND

Q_RES_0402LF-1K,1%,1/16W,CHIP,CS21002FB06  I117  R6136
   1 P3V3_AUX      A @T6G_MB_LIB.T6G(SCH_1):P3V3_AUX
   2 FM_BOARD_BMC_SKU_ID4      B @T6G_MB_LIB.T6G(SCH_1):FM_BOARD_BMC_SKU_ID4

Q_RES_0402LF-1K,1%,1/16W,EMPTY,CS21002FB06  I118  R6141
   1 FM_BOARD_BMC_SKU_ID4      A @T6G_MB_LIB.T6G(SCH_1):FM_BOARD_BMC_SKU_ID4
   2    GND      B @T6G_MB_LIB.T6G(SCH_1):GND

Q_RES_0402LF-1K,1%,1/16W,CHIP,CS21002FB06  I119  R6126
   1 FM_BOARD_SKU_ID3      A @T6G_MB_LIB.T6G(SCH_1):FM_BOARD_SKU_ID3
   2    GND      B @T6G_MB_LIB.T6G(SCH_1):GND

Q_RES_0402LF-1K,1%,1/16W,EMPTY,CS21002FB06  I120  R6121
   1 PVDD18_S5_P0      A @T6G_MB_LIB.T6G(SCH_1):PVDD18_S5_P0
   2 FM_BOARD_SKU_ID3      B @T6G_MB_LIB.T6G(SCH_1):FM_BOARD_SKU_ID3

Q_RES_0402LF-1K,1%,1/16W,EMPTY,CS21002FB06  I121  R6137
   1 P3V3_AUX      A @T6G_MB_LIB.T6G(SCH_1):P3V3_AUX
   2 FM_BOARD_BMC_SKU_ID3      B @T6G_MB_LIB.T6G(SCH_1):FM_BOARD_BMC_SKU_ID3

Q_RES_0402LF-1K,1%,1/16W,CHIP,CS21002FB06  I122  R6142
   1 FM_BOARD_BMC_SKU_ID3      A @T6G_MB_LIB.T6G(SCH_1):FM_BOARD_BMC_SKU_ID3
   2    GND      B @T6G_MB_LIB.T6G(SCH_1):GND

Q_RES_0402LF-1K,1%,1/16W,CHIP,CS21002FB06  I131  R6130
   1 PVDD18_S5_P0      A @T6G_MB_LIB.T6G(SCH_1):PVDD18_S5_P0
   2 FAB_REV_ID2      B @T6G_MB_LIB.T6G(SCH_1):FAB_REV_ID2

Q_RES_0402LF-1K,1%,1/16W,EMPTY,CS21002FB06  I132  R6133
   1 FAB_REV_ID2      A @T6G_MB_LIB.T6G(SCH_1):FAB_REV_ID2
   2    GND      B @T6G_MB_LIB.T6G(SCH_1):GND

Q_RES_0402LF-1K,1%,1/16W,CHIP,CS21002FB06  I133  R6134
   1 FAB_REV_ID1      A @T6G_MB_LIB.T6G(SCH_1):FAB_REV_ID1
   2    GND      B @T6G_MB_LIB.T6G(SCH_1):GND

Q_RES_0402LF-1K,1%,1/16W,EMPTY,CS21002FB06  I134  R6131
   1 PVDD18_S5_P0      A @T6G_MB_LIB.T6G(SCH_1):PVDD18_S5_P0
   2 FAB_REV_ID1      B @T6G_MB_LIB.T6G(SCH_1):FAB_REV_ID1

Q_RES_0402LF-1K,1%,1/16W,EMPTY,CS21002FB06  I135  R6132
   1 PVDD18_S5_P0      A @T6G_MB_LIB.T6G(SCH_1):PVDD18_S5_P0
   2 FAB_REV_ID0      B @T6G_MB_LIB.T6G(SCH_1):FAB_REV_ID0

Q_RES_0402LF-1K,1%,1/16W,CHIP,CS21002FB06  I136  R6135
   1 FAB_REV_ID0      A @T6G_MB_LIB.T6G(SCH_1):FAB_REV_ID0
   2    GND      B @T6G_MB_LIB.T6G(SCH_1):GND

Q_RES_0402LF-1K,1%,1/16W,EMPTY,CS21002FB06  I137  R6149
   1 FAB_BMC_REV_ID2      A @T6G_MB_LIB.T6G(SCH_1):FAB_BMC_REV_ID2
   2    GND      B @T6G_MB_LIB.T6G(SCH_1):GND

Q_RES_0402LF-1K,1%,1/16W,CHIP,CS21002FB06  I138  R6146
   1 P1V8_AUX      A @T6G_MB_LIB.T6G(SCH_1):P1V8_AUX
   2 FAB_BMC_REV_ID2      B @T6G_MB_LIB.T6G(SCH_1):FAB_BMC_REV_ID2

Q_RES_0402LF-1K,1%,1/16W,CHIP,CS21002FB06  I139  R6150
   1 FAB_BMC_REV_ID1      A @T6G_MB_LIB.T6G(SCH_1):FAB_BMC_REV_ID1
   2    GND      B @T6G_MB_LIB.T6G(SCH_1):GND

Q_RES_0402LF-1K,1%,1/16W,EMPTY,CS21002FB06  I140  R6147
   1 P1V8_AUX      A @T6G_MB_LIB.T6G(SCH_1):P1V8_AUX
   2 FAB_BMC_REV_ID1      B @T6G_MB_LIB.T6G(SCH_1):FAB_BMC_REV_ID1

Q_RES_0402LF-1K,1%,1/16W,CHIP,CS21002FB06  I141  R6151
   1 FAB_BMC_REV_ID0      A @T6G_MB_LIB.T6G(SCH_1):FAB_BMC_REV_ID0
   2    GND      B @T6G_MB_LIB.T6G(SCH_1):GND

Q_RES_0402LF-1K,1%,1/16W,EMPTY,CS21002FB06  I142  R6148
   1 P1V8_AUX      A @T6G_MB_LIB.T6G(SCH_1):P1V8_AUX
   2 FAB_BMC_REV_ID0      B @T6G_MB_LIB.T6G(SCH_1):FAB_BMC_REV_ID0


DRAWING: @T6G_MB_LIB.T6G(SCH_1):PAGE81 

Q_RES_0402LF-0,5%,1/16W,CHIP,CS00002JB13  I44  R262
   1 CPU1_CORETYPE0      A @T6G_MB_LIB.T6G(SCH_1):CPU1_CORETYPE0
   2 FM_CPU1_CORETYPE0      B @T6G_MB_LIB.T6G(SCH_1):FM_CPU1_CORETYPE0

Q_RES_0402LF-0,5%,1/16W,CHIP,CS00002JB13  I45  R180
   1 CPU0_SP5R1      A @T6G_MB_LIB.T6G(SCH_1):CPU0_SP5R1
   2 FM_CPU0_SP5R1      B @T6G_MB_LIB.T6G(SCH_1):FM_CPU0_SP5R1

Q_RES_0402LF-0,5%,1/16W,CHIP,CS00002JB13  I46  R181
   1 CPU0_SP5R2      A @T6G_MB_LIB.T6G(SCH_1):CPU0_SP5R2
   2 FM_CPU0_SP5R2      B @T6G_MB_LIB.T6G(SCH_1):FM_CPU0_SP5R2

Q_RES_0402LF-0,5%,1/16W,CHIP,CS00002JB13  I47  R263
   1 CPU1_CORETYPE1      A @T6G_MB_LIB.T6G(SCH_1):CPU1_CORETYPE1
   2 FM_CPU1_CORETYPE1      B @T6G_MB_LIB.T6G(SCH_1):FM_CPU1_CORETYPE1

Q_RES_0402LF-0,5%,1/16W,CHIP,CS00002JB13  I48  R184
   1 CPU0_CORETYPE1      A @T6G_MB_LIB.T6G(SCH_1):CPU0_CORETYPE1
   2 FM_CPU0_CORETYPE1      B @T6G_MB_LIB.T6G(SCH_1):FM_CPU0_CORETYPE1

Q_RES_0402LF-0,5%,1/16W,CHIP,CS00002JB13  I49  R260
   1 CPU1_SP5R1      A @T6G_MB_LIB.T6G(SCH_1):CPU1_SP5R1
   2 FM_CPU1_SP5R1      B @T6G_MB_LIB.T6G(SCH_1):FM_CPU1_SP5R1

Q_RES_0402LF-0,5%,1/16W,CHIP,CS00002JB13  I50  R261
   1 CPU1_SP5R2      A @T6G_MB_LIB.T6G(SCH_1):CPU1_SP5R2
   2 FM_CPU1_SP5R2      B @T6G_MB_LIB.T6G(SCH_1):FM_CPU1_SP5R2

Q_RES_0402LF-33,5%,1/16W,CHIP,CS03302JB10  I51  R232
   1 FM_PVDDCR_CPU1_P0_EN      A @T6G_MB_LIB.T6G(SCH_1):FM_PVDDCR_CPU1_P0_EN
   2 FM_PVDDCR_CPU1_P0_R_EN      B @T6G_MB_LIB.T6G(SCH_1):FM_PVDDCR_CPU1_P0_R_EN

Q_RES_0402LF-0,5%,1/16W,CHIP,CS00002JB13  I52  R222
   1 CPU0_SP5R3      A @T6G_MB_LIB.T6G(SCH_1):CPU0_SP5R3
   2 FM_CPU0_SP5R3      B @T6G_MB_LIB.T6G(SCH_1):FM_CPU0_SP5R3

Q_RES_0402LF-0,5%,1/16W,CHIP,CS00002JB13  I53  R264
   1 CPU1_CORETYPE2      A @T6G_MB_LIB.T6G(SCH_1):CPU1_CORETYPE2
   2 FM_CPU1_CORETYPE2      B @T6G_MB_LIB.T6G(SCH_1):FM_CPU1_CORETYPE2

Q_RES_0402LF-0,5%,1/16W,CHIP,CS00002JB13  I54  R233
   1 PWRGD_PVDDCR_CPU1_P0      A @T6G_MB_LIB.T6G(SCH_1):PWRGD_PVDDCR_CPU1_P0
   2 FM_PWRGD_PVDDCR_CPU1_P0      B @T6G_MB_LIB.T6G(SCH_1):FM_PWRGD_PVDDCR_CPU1_P0

Q_RES_0402LF-0,5%,1/16W,CHIP,CS00002JB13  I55  R268
   1 CPU1_SP5R3      A @T6G_MB_LIB.T6G(SCH_1):CPU1_SP5R3
   2 FM_CPU1_SP5R3      B @T6G_MB_LIB.T6G(SCH_1):FM_CPU1_SP5R3

Q_RES_0402LF-0,5%,1/16W,CHIP,CS00002JB13  I56  R269
   1 CPU1_SP5R4      A @T6G_MB_LIB.T6G(SCH_1):CPU1_SP5R4
   2 FM_CPU1_SP5R4      B @T6G_MB_LIB.T6G(SCH_1):FM_CPU1_SP5R4

Q_RES_0402LF-0,5%,1/16W,CHIP,CS00002JB13  I57  R141
   1 PVDDCR_CPU1_P1_OCP_N      A @T6G_MB_LIB.T6G(SCH_1):PVDDCR_CPU1_P1_OCP_N
   2 FM_PVDDCR_CPU1_P1_OCP_N      B @T6G_MB_LIB.T6G(SCH_1):FM_PVDDCR_CPU1_P1_OCP_N

Q_RES_0402LF-0,5%,1/16W,CHIP,CS00002JB13  I58  R189
   1 FM_BMC_TPM_PRES_N      A @T6G_MB_LIB.T6G(SCH_1):FM_BMC_TPM_PRES_N
   2 FM_BMC_TPM_PRES_N_R      B @T6G_MB_LIB.T6G(SCH_1):FM_BMC_TPM_PRES_N_R

Q_RES_0402LF-0,5%,1/16W,CHIP,CS00002JB13  I59  R137
   1 PVDDCR_CPU1_P0_OCP_N      A @T6G_MB_LIB.T6G(SCH_1):PVDDCR_CPU1_P0_OCP_N
   2 FM_PVDDCR_CPU1_P0_OCP_N      B @T6G_MB_LIB.T6G(SCH_1):FM_PVDDCR_CPU1_P0_OCP_N

Q_RES_0402LF-0,5%,1/16W,CHIP,CS00002JB13  I60  R231
   1 PVDDCR_CPU0_P0_OCP_N      A @T6G_MB_LIB.T6G(SCH_1):PVDDCR_CPU0_P0_OCP_N
   2 FM_PVDDCR_CPU0_P0_OCP_N      B @T6G_MB_LIB.T6G(SCH_1):FM_PVDDCR_CPU0_P0_OCP_N

Q_RES_0402LF-0,5%,1/16W,CHIP,CS00002JB13  I61  R188
   1 FM_BMC_READY_N      A @T6G_MB_LIB.T6G(SCH_1):FM_BMC_READY_N
   2 FM_BMC_READY_R_N      B @T6G_MB_LIB.T6G(SCH_1):FM_BMC_READY_R_N

Q_RES_0402LF-0,5%,1/16W,CHIP,CS00002JB13  I62  R239
   1 CPU0_XTRIG_L7      A @T6G_MB_LIB.T6G(SCH_1):CPU0_XTRIG_L7
   2 FM_CPU0_XTRIG_L7      B @T6G_MB_LIB.T6G(SCH_1):FM_CPU0_XTRIG_L7

Q_RES_0402LF-0,5%,1/16W,CHIP,CS00002JB13  I63  R243
   1 FM_SMM_CRASHDUMP      A @T6G_MB_LIB.T6G(SCH_1):FM_SMM_CRASHDUMP
   2 FM_SMM_CRASHDUMP_R      B @T6G_MB_LIB.T6G(SCH_1):FM_SMM_CRASHDUMP_R

Q_RES_0402LF-0,5%,1/16W,CHIP,CS00002JB13  I64  R190
   1 FM_CPU1_BMC_RST_N      A @T6G_MB_LIB.T6G(SCH_1):FM_CPU1_BMC_RST_N
   2 FM_CPU1_BMC_RST_R_N      B @T6G_MB_LIB.T6G(SCH_1):FM_CPU1_BMC_RST_R_N

Q_RES_0402LF-0,5%,1/16W,CHIP,CS00002JB13  I65  R246
   1 IRQ_TPM_SPI_R_N      A @T6G_MB_LIB.T6G(SCH_1):IRQ_TPM_SPI_R_N
   2 IRQ_TPM_SPI_R1_N      B @T6G_MB_LIB.T6G(SCH_1):IRQ_TPM_SPI_R1_N

Q_RES_0402LF-0,5%,1/16W,CHIP,CS00002JB13  I66  R236
   1 CPU0_XTRIG_L4      A @T6G_MB_LIB.T6G(SCH_1):CPU0_XTRIG_L4
   2 FM_CPU0_XTRIG_L4      B @T6G_MB_LIB.T6G(SCH_1):FM_CPU0_XTRIG_L4

Q_RES_0402LF-0,5%,1/16W,CHIP,CS00002JB13  I67  R245
   1 IRQ_SMI_ACTIVE_N      A @T6G_MB_LIB.T6G(SCH_1):IRQ_SMI_ACTIVE_N
   2 IRQ_SMI_ACTIVE_N_R      B @T6G_MB_LIB.T6G(SCH_1):IRQ_SMI_ACTIVE_N_R

Q_RES_0402LF-0,5%,1/16W,CHIP,CS00002JB13  I68  R187
   1 IRQ_CPU_BMC_NMI_N      A @T6G_MB_LIB.T6G(SCH_1):IRQ_CPU_BMC_NMI_N
   2 IRQ_CPU_BMC_NMI_R_N      B @T6G_MB_LIB.T6G(SCH_1):IRQ_CPU_BMC_NMI_R_N

Q_RES_0402LF-0,5%,1/16W,CHIP,CS00002JB13  I69  R237
   1 CPU0_XTRIG_L5      A @T6G_MB_LIB.T6G(SCH_1):CPU0_XTRIG_L5
   2 FM_CPU0_XTRIG_L5      B @T6G_MB_LIB.T6G(SCH_1):FM_CPU0_XTRIG_L5

Q_RES_0402LF-0,5%,1/16W,CHIP,CS00002JB13  I70  R235
   1 CPU1_XTRIG_L7      A @T6G_MB_LIB.T6G(SCH_1):CPU1_XTRIG_L7
   2 FM_CPU1_XTRIG_L7      B @T6G_MB_LIB.T6G(SCH_1):FM_CPU1_XTRIG_L7

Q_RES_0402LF-0,5%,1/16W,CHIP,CS00002JB13  I71  R238
   1 CPU0_XTRIG_L6      A @T6G_MB_LIB.T6G(SCH_1):CPU0_XTRIG_L6
   2 FM_CPU0_XTRIG_L6      B @T6G_MB_LIB.T6G(SCH_1):FM_CPU0_XTRIG_L6

Q_RES_0402LF-0,5%,1/16W,CHIP,CS00002JB13  I72  R244
   1 IRQ_BMC_SMI_N      A @T6G_MB_LIB.T6G(SCH_1):IRQ_BMC_SMI_N
   2 IRQ_BMC_SMI_R_N      B @T6G_MB_LIB.T6G(SCH_1):IRQ_BMC_SMI_R_N

Q_RES_0402LF-33,5%,1/16W,CHIP,CS03302JB10  I73  R267
   1 CPU1_SA1      A @T6G_MB_LIB.T6G(SCH_1):CPU1_SA1
   2 FM_CPU1_SA1      B @T6G_MB_LIB.T6G(SCH_1):FM_CPU1_SA1

Q_RES_0402LF-0,5%,1/16W,CHIP,CS00002JB13  I75  R234
   1 CPU1_XTRIG_L6      A @T6G_MB_LIB.T6G(SCH_1):CPU1_XTRIG_L6
   2 FM_CPU1_XTRIG_L6      B @T6G_MB_LIB.T6G(SCH_1):FM_CPU1_XTRIG_L6

Q_RES_0402LF-0,5%,1/16W,CHIP,CS00002JB13  I77  R204
   1 CPU1_XTRIG_L4      A @T6G_MB_LIB.T6G(SCH_1):CPU1_XTRIG_L4
   2 FM_CPU1_XTRIG_L4      B @T6G_MB_LIB.T6G(SCH_1):FM_CPU1_XTRIG_L4

Q_RES_0402LF-0,5%,1/16W,CHIP,CS00002JB13  I80  R185
   1 CPU0_CORETYPE2      A @T6G_MB_LIB.T6G(SCH_1):CPU0_CORETYPE2
   2 FM_CPU0_CORETYPE2      B @T6G_MB_LIB.T6G(SCH_1):FM_CPU0_CORETYPE2

Q_RES_0402LF-33,5%,1/16W,CHIP,CS03302JB10  I81  R959
   1 OCP_SFF_MAIN_PWR_EN      A @T6G_MB_LIB.T6G(SCH_1):OCP_SFF_MAIN_PWR_EN
   2 FM_PLD_OCP_SFF_MAIN_PWR_EN_R      B @T6G_MB_LIB.T6G(SCH_1):FM_PLD_OCP_SFF_MAIN_PWR_EN_R

Q_RES_0402LF-0,5%,1/16W,CHIP,CS00002JB13  I82  R183
   1 CPU0_CORETYPE0      A @T6G_MB_LIB.T6G(SCH_1):CPU0_CORETYPE0
   2 FM_CPU0_CORETYPE0      B @T6G_MB_LIB.T6G(SCH_1):FM_CPU0_CORETYPE0

Q_RES_0402LF-0,5%,1/16W,CHIP,CS00002JB13  I99  R6052
   1 E1S_0_PRSNT_R_N      A @T6G_MB_LIB.T6G(SCH_1):E1S_0_PRSNT_R_N
   2 E1S_0_PRSNT_N      B @T6G_MB_LIB.T6G(SCH_1):E1S_0_PRSNT_N

Q_RES_0402LF-0,5%,1/16W,CHIP,CS00002JB13  I100  R223
   1 FM_CPU0_SP5R4      A @T6G_MB_LIB.T6G(SCH_1):FM_CPU0_SP5R4
   2 CPU0_SP5R4      B @T6G_MB_LIB.T6G(SCH_1):CPU0_SP5R4

Q_RES_0402LF-0,5%,1/16W,CHIP,CS00002JB13  I101  R182
   1 FM_PRSNT_CPU0_R_N      A @T6G_MB_LIB.T6G(SCH_1):FM_PRSNT_CPU0_R_N
   2 FM_PRSNT_CPU0_N      B @T6G_MB_LIB.T6G(SCH_1):FM_PRSNT_CPU0_N

Q_RES_0402LF-0,5%,1/16W,CHIP,CS00002JB13  I102  R6051
   1 P12V_OCP_V3_1_PWRGD      A @T6G_MB_LIB.T6G(SCH_1):P12V_OCP_V3_1_PWRGD
   2 P12V_OCP_V3_1_PLD_PWRGD      B @T6G_MB_LIB.T6G(SCH_1):P12V_OCP_V3_1_PLD_PWRGD

Q_RES_0402LF-33,5%,1/16W,CHIP,CS03302JB10  I103  R227
   1 FM_PVDD11_S3_P0_EN      A @T6G_MB_LIB.T6G(SCH_1):FM_PVDD11_S3_P0_EN
   2 PVDD11_S3_P0_EN      B @T6G_MB_LIB.T6G(SCH_1):PVDD11_S3_P0_EN

LCMXO3LF9400C5BG484C-LCMXO3LF-9400C-5BG484C,SMLF,IA  I143  U18
  D3 FM_CPU1_XTRIG_L4   PL2A @T6G_MB_LIB.T6G(SCH_1):FM_CPU1_XTRIG_L4
  D4 FM_CPU1_XTRIG_L5   PL2B @T6G_MB_LIB.T6G(SCH_1):FM_CPU1_XTRIG_L5
  F6 FM_CPU1_XTRIG_L6   PL2C @T6G_MB_LIB.T6G(SCH_1):FM_CPU1_XTRIG_L6
  G7 FM_CPU1_SA1   PL2D @T6G_MB_LIB.T6G(SCH_1):FM_CPU1_SA1
  E4 FM_CPU0_XTRIG_L6 PL3A||L_GPLLT_FB @T6G_MB_LIB.T6G(SCH_1):FM_CPU0_XTRIG_L6
  F5 IRQ_BMC_SMI_R_N PL3B||L_GPLLC_FB @T6G_MB_LIB.T6G(SCH_1):IRQ_BMC_SMI_R_N
  G6 FM_CPU1_XTRIG_L7   PL3C @T6G_MB_LIB.T6G(SCH_1):FM_CPU1_XTRIG_L7
  H7 IRQ_CPU_BMC_NMI_R_N   PL3D @T6G_MB_LIB.T6G(SCH_1):IRQ_CPU_BMC_NMI_R_N
  C1 FM_CPU0_XTRIG_L5 PL4A||L_GPLLT_IN @T6G_MB_LIB.T6G(SCH_1):FM_CPU0_XTRIG_L5
  D2 FM_CPU0_XTRIG_L4 PL4B||L_GPLLC_IN @T6G_MB_LIB.T6G(SCH_1):FM_CPU0_XTRIG_L4
  G5 IRQ_SMI_ACTIVE_N_R   PL4C @T6G_MB_LIB.T6G(SCH_1):IRQ_SMI_ACTIVE_N_R
  H6 IRQ_TPM_SPI_R1_N   PL4D @T6G_MB_LIB.T6G(SCH_1):IRQ_TPM_SPI_R1_N
  D1 FM_SMM_CRASHDUMP_R   PL5A @T6G_MB_LIB.T6G(SCH_1):FM_SMM_CRASHDUMP_R
  E2 FM_CPU1_BMC_RST_R_N   PL5B @T6G_MB_LIB.T6G(SCH_1):FM_CPU1_BMC_RST_R_N
  E3 FM_CPU0_XTRIG_L7   PL5C @T6G_MB_LIB.T6G(SCH_1):FM_CPU0_XTRIG_L7
  F4 FM_BMC_READY_R_N   PL5D @T6G_MB_LIB.T6G(SCH_1):FM_BMC_READY_R_N
  L7 PVDD11_S3_P0_PMALERT  PL13A @T6G_MB_LIB.T6G(SCH_1):PVDD11_S3_P0_PMALERT
  K5 P12V_SCM_ADC_ALERT  PL13B @T6G_MB_LIB.T6G(SCH_1):P12V_SCM_ADC_ALERT
  K4 P12V_HSC_T_CRIT_R_N  PL13C @T6G_MB_LIB.T6G(SCH_1):P12V_HSC_T_CRIT_R_N
  K3 E1S_0_P3V3_P12V_ADC_ALERT  PL13D @T6G_MB_LIB.T6G(SCH_1):E1S_0_P3V3_P12V_ADC_ALERT
  K2 FM_SEC_MUX_OE_R_N  PL14A @T6G_MB_LIB.T6G(SCH_1):FM_SEC_MUX_OE_R_N
  K1 FM_SEC_MUX_R_SEL  PL14B @T6G_MB_LIB.T6G(SCH_1):FM_SEC_MUX_R_SEL
  L1 LED_HDD_ACTIVITY_B_PLD_N PL16A||PCLKT4_0 @T6G_MB_LIB.T6G(SCH_1):LED_HDD_ACTIVITY_B_PLD_N
  M2 FM_SCM_PRSNT1_N PL16B||PCLKC4_0 @T6G_MB_LIB.T6G(SCH_1):FM_SCM_PRSNT1_N
  P4 FM_CPU1_CORETYPE0  PL20A @T6G_MB_LIB.T6G(SCH_1):FM_CPU1_CORETYPE0
  N5 FM_CPU0_SP5R1  PL20B @T6G_MB_LIB.T6G(SCH_1):FM_CPU0_SP5R1
  N6 FM_CPU0_SP5R2  PL20C @T6G_MB_LIB.T6G(SCH_1):FM_CPU0_SP5R2
  N7 P12V_HSC_TEMP_ALERT_R_N  PL20D @T6G_MB_LIB.T6G(SCH_1):P12V_HSC_TEMP_ALERT_R_N
  R2 FM_CPU0_CORETYPE1  PL21A @T6G_MB_LIB.T6G(SCH_1):FM_CPU0_CORETYPE1
  T1 FM_CPU1_CORETYPE1  PL21B @T6G_MB_LIB.T6G(SCH_1):FM_CPU1_CORETYPE1
  P5 FM_APML_MUX2_SEL_R  PL21C @T6G_MB_LIB.T6G(SCH_1):FM_APML_MUX2_SEL_R
  P6 FM_APML_MUX2_OE_R_N  PL21D @T6G_MB_LIB.T6G(SCH_1):FM_APML_MUX2_OE_R_N
  T5 FM_PDB_BUF_EN_N  PL26C @T6G_MB_LIB.T6G(SCH_1):FM_PDB_BUF_EN_N
  T6 PWRGD_CHGL_CPU1_R2  PL26D @T6G_MB_LIB.T6G(SCH_1):PWRGD_CHGL_CPU1_R2
  L6 PVDDCR_CPU1_P1_SMB_ALERT  PL14C @T6G_MB_LIB.T6G(SCH_1):PVDDCR_CPU1_P1_SMB_ALERT
  L5 PVDDCR_CPU1_P0_SMB_ALERT  PL14D @T6G_MB_LIB.T6G(SCH_1):PVDDCR_CPU1_P0_SMB_ALERT
  L3 FM_THERMAL_ALERT_R_N  PL16C @T6G_MB_LIB.T6G(SCH_1):FM_THERMAL_ALERT_R_N
  L4 SMB_BMC_GPU_EN  PL16D @T6G_MB_LIB.T6G(SCH_1):SMB_BMC_GPU_EN
  G3 FM_PVDDCR_CPU1_P0_OCP_N   PL6C @T6G_MB_LIB.T6G(SCH_1):FM_PVDDCR_CPU1_P0_OCP_N
  G4 FM_PVDDCR_CPU1_P1_OCP_N   PL6D @T6G_MB_LIB.T6G(SCH_1):FM_PVDDCR_CPU1_P1_OCP_N
  E1 FM_BMC_TPM_PRES_N_R   PL6A @T6G_MB_LIB.T6G(SCH_1):FM_BMC_TPM_PRES_N_R
  F1 FM_PVDDCR_CPU0_P0_OCP_N   PL6B @T6G_MB_LIB.T6G(SCH_1):FM_PVDDCR_CPU0_P0_OCP_N
  T2 FM_CPU1_CORETYPE2  PL25A @T6G_MB_LIB.T6G(SCH_1):FM_CPU1_CORETYPE2
  U1 FM_CPU0_SP5R3  PL25B @T6G_MB_LIB.T6G(SCH_1):FM_CPU0_SP5R3
  R3 FM_CPU1_SP5R1  PL24A @T6G_MB_LIB.T6G(SCH_1):FM_CPU1_SP5R1
  R4 FM_CPU1_SP5R2  PL24B @T6G_MB_LIB.T6G(SCH_1):FM_CPU1_SP5R2
  R5 FM_LED_PWRGD_PVDDCR_CPU1_P0  PL24C @T6G_MB_LIB.T6G(SCH_1):FM_LED_PWRGD_PVDDCR_CPU1_P0
  P7 FM_PVDDCR_CPU1_P0_R_EN  PL24D @T6G_MB_LIB.T6G(SCH_1):FM_PVDDCR_CPU1_P0_R_EN
  R6 PWRGD_CHAF_CPU1_R2  PL25C @T6G_MB_LIB.T6G(SCH_1):PWRGD_CHAF_CPU1_R2
  R7 FM_PWRGD_PVDDCR_CPU1_P0  PL25D @T6G_MB_LIB.T6G(SCH_1):FM_PWRGD_PVDDCR_CPU1_P0
  T3 FM_CPU1_SP5R3  PL26A @T6G_MB_LIB.T6G(SCH_1):FM_CPU1_SP5R3
  T4 FM_CPU1_SP5R4  PL26B @T6G_MB_LIB.T6G(SCH_1):FM_CPU1_SP5R4
  M1 M2_0_P3V3_ADC_ALERT  PL17A @T6G_MB_LIB.T6G(SCH_1):M2_0_P3V3_ADC_ALERT
  N1 PVDD11_S3_P1_PMALERT  PL17B @T6G_MB_LIB.T6G(SCH_1):PVDD11_S3_P1_PMALERT
  M6 FM_PLD_OCP_SFF_AUX_PWR_R_EN  PL17C @T6G_MB_LIB.T6G(SCH_1):FM_PLD_OCP_SFF_AUX_PWR_R_EN
  M5 PVDDCR_CPU0_P1_PMALERT  PL17D @T6G_MB_LIB.T6G(SCH_1):PVDDCR_CPU0_P1_PMALERT
  N2 FM_CLKREQ_M2_1_N  PL18A @T6G_MB_LIB.T6G(SCH_1):FM_CLKREQ_M2_1_N
  P1 OCP_V3_2_P3V3_P12V_ADC_ALERT  PL18B @T6G_MB_LIB.T6G(SCH_1):OCP_V3_2_P3V3_P12V_ADC_ALERT
  N3 FM_CLR_CMOS  PL18C @T6G_MB_LIB.T6G(SCH_1):FM_CLR_CMOS
  N4 PWRGD_OCP_SFF_PWR_GOOD  PL18D @T6G_MB_LIB.T6G(SCH_1):PWRGD_OCP_SFF_PWR_GOOD
  P2 FM_SMB_RST_E1S_0_N  PL19A @T6G_MB_LIB.T6G(SCH_1):FM_SMB_RST_E1S_0_N
  R1 FM_CPU0_CORETYPE0  PL19B @T6G_MB_LIB.T6G(SCH_1):FM_CPU0_CORETYPE0
  P3 FM_CPU0_CORETYPE2  PL19C @T6G_MB_LIB.T6G(SCH_1):FM_CPU0_CORETYPE2
  M7 FM_PLD_OCP_SFF_MAIN_PWR_EN_R  PL19D @T6G_MB_LIB.T6G(SCH_1):FM_PLD_OCP_SFF_MAIN_PWR_EN_R
  U2 FM_CPU0_SP5R4 PL27A||PCLKT3_0 @T6G_MB_LIB.T6G(SCH_1):FM_CPU0_SP5R4
  V1 FM_PRSNT_CPU0_R_N PL27B||PCLKC3_0 @T6G_MB_LIB.T6G(SCH_1):FM_PRSNT_CPU0_R_N
  U3 E1S_0_PRSNT_R_N  PL27C @T6G_MB_LIB.T6G(SCH_1):E1S_0_PRSNT_R_N
  U4 PWRGD_P5V_AUX_R3  PL27D @T6G_MB_LIB.T6G(SCH_1):PWRGD_P5V_AUX_R3
  W1 PWRGD_CHAF_CPU0_R2  PL28A @T6G_MB_LIB.T6G(SCH_1):PWRGD_CHAF_CPU0_R2
  W2 P12V_OCP_V3_1_PWRGD  PL28B @T6G_MB_LIB.T6G(SCH_1):P12V_OCP_V3_1_PWRGD
  V4 FM_LED_PWRGD_PVDDCR_SOC_P0  PL28C @T6G_MB_LIB.T6G(SCH_1):FM_LED_PWRGD_PVDDCR_SOC_P0
  U5 FM_LED_PWRGD_PVDDCR_CPU0_P0  PL28D @T6G_MB_LIB.T6G(SCH_1):FM_LED_PWRGD_PVDDCR_CPU0_P0
  Y1 PWRGD_CHGL_CPU0_R2  PL29A @T6G_MB_LIB.T6G(SCH_1):PWRGD_CHGL_CPU0_R2
 AA1 OCP_SFF_P3V3_P12V_ADC_ALERT  PL29B @T6G_MB_LIB.T6G(SCH_1):OCP_SFF_P3V3_P12V_ADC_ALERT
  W3 PVDDCR_SOC_P0_EN  PL29C @T6G_MB_LIB.T6G(SCH_1):PVDDCR_SOC_P0_EN
  Y2 PWRGD_PVDDCR_SOC_P0  PL29D @T6G_MB_LIB.T6G(SCH_1):PWRGD_PVDDCR_SOC_P0
  Y3 PWRGD_PVDDCR_CPU0_P0  PL30A @T6G_MB_LIB.T6G(SCH_1):PWRGD_PVDDCR_CPU0_P0
  W4 FM_PVDD11_S3_P0_EN  PL30B @T6G_MB_LIB.T6G(SCH_1):FM_PVDD11_S3_P0_EN
  V5 FM_PRSNT_CPU1_R_N  PL30C @T6G_MB_LIB.T6G(SCH_1):FM_PRSNT_CPU1_R_N
  T7 FM_PVDDCR_CPU1_P1_R_EN  PL30D @T6G_MB_LIB.T6G(SCH_1):FM_PVDDCR_CPU1_P1_R_EN
  G2 FM_PVDDCR_CPU0_P1_OCP_N PL7A||PCLKT5_0 @T6G_MB_LIB.T6G(SCH_1):FM_PVDDCR_CPU0_P1_OCP_N
  G1 FM_CPU1_PROCHOT_R_N PL7B||PCLKC5_0 @T6G_MB_LIB.T6G(SCH_1):FM_CPU1_PROCHOT_R_N
  H4 FM_PVDD11_S3_P1_OCP_N   PL7C @T6G_MB_LIB.T6G(SCH_1):FM_PVDD11_S3_P1_OCP_N
  H3 FM_PVDD11_S3_P0_OCP_N   PL7D @T6G_MB_LIB.T6G(SCH_1):FM_PVDD11_S3_P0_OCP_N
  H2 CPU0_THERMTRIP_R_N  PL10A @T6G_MB_LIB.T6G(SCH_1):CPU0_THERMTRIP_R_N
  H1 RT_BOARD_ID_ID1  PL10B @T6G_MB_LIB.T6G(SCH_1):RT_BOARD_ID_ID1
  J7 FM_CPU1_SA0  PL10C @T6G_MB_LIB.T6G(SCH_1):FM_CPU1_SA0
  J6 FM_CPU0_PROCHOT_R_N  PL10D @T6G_MB_LIB.T6G(SCH_1):FM_CPU0_PROCHOT_R_N
  H5 FM_CPU0_SA0  PL11A @T6G_MB_LIB.T6G(SCH_1):FM_CPU0_SA0
  J5 CPU1_THERMTRIP_R_N  PL11B @T6G_MB_LIB.T6G(SCH_1):CPU1_THERMTRIP_R_N
  J4 RT_BOARD_ID_ID0  PL11C @T6G_MB_LIB.T6G(SCH_1):RT_BOARD_ID_ID0
  J3 FM_INT_CPU0_HP_UBM_R_N  PL11D @T6G_MB_LIB.T6G(SCH_1):FM_INT_CPU0_HP_UBM_R_N
  J2 FM_CPU0_SA1  PL12A @T6G_MB_LIB.T6G(SCH_1):FM_CPU0_SA1
  J1 FAB_BMC_REV_ID0  PL12B @T6G_MB_LIB.T6G(SCH_1):FAB_BMC_REV_ID0
  K7 FAB_BMC_REV_ID1  PL12C @T6G_MB_LIB.T6G(SCH_1):FAB_BMC_REV_ID1
  K6 FAB_BMC_REV_ID2  PL12D @T6G_MB_LIB.T6G(SCH_1):FAB_BMC_REV_ID2

LCMXO3LF9400C5BG484C-LCMXO3LF-9400C-5BG484C,SMLF,IA  I1  U18
  A1    GND   GND1 @T6G_MB_LIB.T6G(SCH_1):GND
 A22    GND   GND2 @T6G_MB_LIB.T6G(SCH_1):GND
  B7    GND   GND3 @T6G_MB_LIB.T6G(SCH_1):GND
 B16    GND   GND4 @T6G_MB_LIB.T6G(SCH_1):GND
  C2    GND   GND5 @T6G_MB_LIB.T6G(SCH_1):GND
 C11    GND   GND6 @T6G_MB_LIB.T6G(SCH_1):GND
  E5    GND   GND7 @T6G_MB_LIB.T6G(SCH_1):GND
 E18    GND   GND8 @T6G_MB_LIB.T6G(SCH_1):GND
  F2    GND   GND9 @T6G_MB_LIB.T6G(SCH_1):GND
 F21    GND  GND10 @T6G_MB_LIB.T6G(SCH_1):GND
  H8    GND  GND11 @T6G_MB_LIB.T6G(SCH_1):GND
 H10    GND  GND12 @T6G_MB_LIB.T6G(SCH_1):GND
 H13    GND  GND13 @T6G_MB_LIB.T6G(SCH_1):GND
 H15    GND  GND14 @T6G_MB_LIB.T6G(SCH_1):GND
  J9    GND  GND15 @T6G_MB_LIB.T6G(SCH_1):GND
 J10    GND  GND16 @T6G_MB_LIB.T6G(SCH_1):GND
 J11    GND  GND17 @T6G_MB_LIB.T6G(SCH_1):GND
 J12    GND  GND18 @T6G_MB_LIB.T6G(SCH_1):GND
 J13    GND  GND19 @T6G_MB_LIB.T6G(SCH_1):GND
 J14    GND  GND20 @T6G_MB_LIB.T6G(SCH_1):GND
  K9    GND  GND21 @T6G_MB_LIB.T6G(SCH_1):GND
 K14    GND  GND22 @T6G_MB_LIB.T6G(SCH_1):GND
 K21    GND  GND23 @T6G_MB_LIB.T6G(SCH_1):GND
  L2    GND  GND24 @T6G_MB_LIB.T6G(SCH_1):GND
  L9    GND  GND25 @T6G_MB_LIB.T6G(SCH_1):GND
 L10    GND  GND26 @T6G_MB_LIB.T6G(SCH_1):GND
 L13    GND  GND27 @T6G_MB_LIB.T6G(SCH_1):GND
 L14    GND  GND28 @T6G_MB_LIB.T6G(SCH_1):GND
 L18    GND  GND29 @T6G_MB_LIB.T6G(SCH_1):GND
  M4    GND  GND30 @T6G_MB_LIB.T6G(SCH_1):GND
  M9    GND  GND31 @T6G_MB_LIB.T6G(SCH_1):GND
 M10    GND  GND32 @T6G_MB_LIB.T6G(SCH_1):GND
 M13    GND  GND33 @T6G_MB_LIB.T6G(SCH_1):GND
 M14    GND  GND34 @T6G_MB_LIB.T6G(SCH_1):GND
  N9    GND  GND35 @T6G_MB_LIB.T6G(SCH_1):GND
 N14    GND  GND36 @T6G_MB_LIB.T6G(SCH_1):GND
 N21    GND  GND37 @T6G_MB_LIB.T6G(SCH_1):GND
  P9    GND  GND38 @T6G_MB_LIB.T6G(SCH_1):GND
 P10    GND  GND39 @T6G_MB_LIB.T6G(SCH_1):GND
 P11    GND  GND40 @T6G_MB_LIB.T6G(SCH_1):GND
 P12    GND  GND41 @T6G_MB_LIB.T6G(SCH_1):GND
 P13    GND  GND42 @T6G_MB_LIB.T6G(SCH_1):GND
 P14    GND  GND43 @T6G_MB_LIB.T6G(SCH_1):GND
  R8    GND  GND44 @T6G_MB_LIB.T6G(SCH_1):GND
 R15    GND  GND45 @T6G_MB_LIB.T6G(SCH_1):GND
  V2    GND  GND46 @T6G_MB_LIB.T6G(SCH_1):GND
 V21    GND  GND47 @T6G_MB_LIB.T6G(SCH_1):GND
 W12    GND  GND48 @T6G_MB_LIB.T6G(SCH_1):GND
 Y16    GND  GND50 @T6G_MB_LIB.T6G(SCH_1):GND
  Y7    GND  GND49 @T6G_MB_LIB.T6G(SCH_1):GND
 AB1    GND  GND51 @T6G_MB_LIB.T6G(SCH_1):GND
AB22    GND  GND52 @T6G_MB_LIB.T6G(SCH_1):GND

Q_RES_0402LF-0,5%,1/16W,CHIP,CS00002JB13  I74  R205
   1 CPU1_XTRIG_L5      A @T6G_MB_LIB.T6G(SCH_1):CPU1_XTRIG_L5
   2 FM_CPU1_XTRIG_L5      B @T6G_MB_LIB.T6G(SCH_1):FM_CPU1_XTRIG_L5

Q_RES_0402LF-0,5%,1/16W,CHIP,CS00002JB13  I83  R6054
   1 FM_OCP_SFF_PWR_GOOD      A @T6G_MB_LIB.T6G(SCH_1):FM_OCP_SFF_PWR_GOOD
   2 PWRGD_OCP_SFF_PWR_GOOD      B @T6G_MB_LIB.T6G(SCH_1):PWRGD_OCP_SFF_PWR_GOOD

Q_RES_0402LF-33,5%,1/16W,CHIP,CS03302JB10  I84  R275
   1 CLR_CMOS      A @T6G_MB_LIB.T6G(SCH_1):CLR_CMOS
   2 FM_CLR_CMOS      B @T6G_MB_LIB.T6G(SCH_1):FM_CLR_CMOS

Q_RES_0402LF-0,5%,1/16W,CHIP,CS00002JB13  I85  R6053
   1 M2_SSD0_CLKREQ_EN_N      A @T6G_MB_LIB.T6G(SCH_1):M2_SSD0_CLKREQ_EN_N
   2 FM_CLKREQ_M2_1_N      B @T6G_MB_LIB.T6G(SCH_1):FM_CLKREQ_M2_1_N

Q_RES_0402LF-33,5%,1/16W,CHIP,CS03302JB10  I86  R958
   1 FM_PLD_OCP_SFF_AUX_PWR_EN      A @T6G_MB_LIB.T6G(SCH_1):FM_PLD_OCP_SFF_AUX_PWR_EN
   2 FM_PLD_OCP_SFF_AUX_PWR_R_EN      B @T6G_MB_LIB.T6G(SCH_1):FM_PLD_OCP_SFF_AUX_PWR_R_EN

Q_RES_0402LF-0,5%,1/16W,CHIP,CS00002JB13  I104  R271
   1 FM_PRSNT_CPU1_R_N      A @T6G_MB_LIB.T6G(SCH_1):FM_PRSNT_CPU1_R_N
   2 FM_PRSNT_CPU1_N      B @T6G_MB_LIB.T6G(SCH_1):FM_PRSNT_CPU1_N

Q_RES_0402LF-33,5%,1/16W,CHIP,CS03302JB10  I105  R285
   1 FM_PVDDCR_CPU1_P1_R_EN      A @T6G_MB_LIB.T6G(SCH_1):FM_PVDDCR_CPU1_P1_R_EN
   2 FM_PVDDCR_CPU1_P1_EN      B @T6G_MB_LIB.T6G(SCH_1):FM_PVDDCR_CPU1_P1_EN

Q_RES_0402LF-33,5%,1/16W,CHIP,CS03302JB10  I106  R81
   1 FM_INT_CPU0_HP_UBM_R_N      A @T6G_MB_LIB.T6G(SCH_1):FM_INT_CPU0_HP_UBM_R_N
   2 FM_INT_CPU0_HP_UBM_N      B @T6G_MB_LIB.T6G(SCH_1):FM_INT_CPU0_HP_UBM_N

Q_RES_0402LF-33,5%,1/16W,CHIP,CS03302JB10  I107  R221
   1 FM_CPU0_SA1      A @T6G_MB_LIB.T6G(SCH_1):FM_CPU0_SA1
   2 CPU0_SA1      B @T6G_MB_LIB.T6G(SCH_1):CPU0_SA1

Q_RES_0402LF-33,5%,1/16W,CHIP,CS03302JB10  I108  R266
   1 FM_CPU1_SA0      A @T6G_MB_LIB.T6G(SCH_1):FM_CPU1_SA0
   2 CPU1_SA0      B @T6G_MB_LIB.T6G(SCH_1):CPU1_SA0

Q_RES_0402LF-33,5%,1/16W,CHIP,CS03302JB10  I109  R220
   1 FM_CPU0_SA0      A @T6G_MB_LIB.T6G(SCH_1):FM_CPU0_SA0
   2 CPU0_SA0      B @T6G_MB_LIB.T6G(SCH_1):CPU0_SA0

Q_RES_0402LF-33,5%,1/16W,CHIP,CS03302JB10  I110  R179
   1 FM_CPU0_PROCHOT_R_N      A @T6G_MB_LIB.T6G(SCH_1):FM_CPU0_PROCHOT_R_N
   2 CPU0_PROCHOT_N      B @T6G_MB_LIB.T6G(SCH_1):CPU0_PROCHOT_N

Q_RES_0402LF-0,5%,1/16W,CHIP,CS00002JB13  I111  R226
   1 FM_PVDD11_S3_P0_OCP_N      A @T6G_MB_LIB.T6G(SCH_1):FM_PVDD11_S3_P0_OCP_N
   2 PVDD11_S3_P0_OCP_N      B @T6G_MB_LIB.T6G(SCH_1):PVDD11_S3_P0_OCP_N

Q_RES_0402LF-33,5%,1/16W,CHIP,CS03302JB10  I112  R270
   1 FM_CPU1_PROCHOT_R_N      A @T6G_MB_LIB.T6G(SCH_1):FM_CPU1_PROCHOT_R_N
   2 CPU1_PROCHOT_N      B @T6G_MB_LIB.T6G(SCH_1):CPU1_PROCHOT_N

Q_RES_0402LF-0,5%,1/16W,CHIP,CS00002JB13  I113  R278
   1 FM_PVDD11_S3_P1_OCP_N      A @T6G_MB_LIB.T6G(SCH_1):FM_PVDD11_S3_P1_OCP_N
   2 PVDD11_S3_P1_OCP_N      B @T6G_MB_LIB.T6G(SCH_1):PVDD11_S3_P1_OCP_N

Q_RES_0402LF-0,5%,1/16W,CHIP,CS00002JB13  I140  R284
   1 FM_PVDDCR_CPU0_P1_OCP_N      A @T6G_MB_LIB.T6G(SCH_1):FM_PVDDCR_CPU0_P1_OCP_N
   2 PVDDCR_CPU0_P1_OCP_N      B @T6G_MB_LIB.T6G(SCH_1):PVDDCR_CPU0_P1_OCP_N

LCMXO3LF9400C5BG484C-LCMXO3LF-9400C-5BG484C,SMLF,IA  I141  U18
 K10 P3V3_AUX   VCC1 @T6G_MB_LIB.T6G(SCH_1):P3V3_AUX
 K11 P3V3_AUX   VCC2 @T6G_MB_LIB.T6G(SCH_1):P3V3_AUX
 K12 P3V3_AUX   VCC3 @T6G_MB_LIB.T6G(SCH_1):P3V3_AUX
 K13 P3V3_AUX   VCC4 @T6G_MB_LIB.T6G(SCH_1):P3V3_AUX
 L11 P3V3_AUX   VCC5 @T6G_MB_LIB.T6G(SCH_1):P3V3_AUX
 L12 P3V3_AUX   VCC6 @T6G_MB_LIB.T6G(SCH_1):P3V3_AUX
 M11 P3V3_AUX   VCC7 @T6G_MB_LIB.T6G(SCH_1):P3V3_AUX
 M12 P3V3_AUX   VCC8 @T6G_MB_LIB.T6G(SCH_1):P3V3_AUX
 N10 P3V3_AUX   VCC9 @T6G_MB_LIB.T6G(SCH_1):P3V3_AUX
 N11 P3V3_AUX  VCC10 @T6G_MB_LIB.T6G(SCH_1):P3V3_AUX
 N12 P3V3_AUX  VCC11 @T6G_MB_LIB.T6G(SCH_1):P3V3_AUX
 N13 P3V3_AUX  VCC12 @T6G_MB_LIB.T6G(SCH_1):P3V3_AUX
  F3 P1V8_AUX VCCIO5_1 @T6G_MB_LIB.T6G(SCH_1):P1V8_AUX
  J8 P1V8_AUX VCCIO5_2 @T6G_MB_LIB.T6G(SCH_1):P1V8_AUX
  K8 P1V8_AUX VCCIO5_3 @T6G_MB_LIB.T6G(SCH_1):P1V8_AUX
  L8 P3V3_AUX VCCIO4_1 @T6G_MB_LIB.T6G(SCH_1):P3V3_AUX
  M8 P3V3_AUX VCCIO4_2 @T6G_MB_LIB.T6G(SCH_1):P3V3_AUX
  M3 P3V3_AUX VCCIO4_3 @T6G_MB_LIB.T6G(SCH_1):P3V3_AUX
  N8 P3V3_AUX VCCIO3_1 @T6G_MB_LIB.T6G(SCH_1):P3V3_AUX
  P8 P3V3_AUX VCCIO3_2 @T6G_MB_LIB.T6G(SCH_1):P3V3_AUX
  V3 P3V3_AUX VCCIO3_3 @T6G_MB_LIB.T6G(SCH_1):P3V3_AUX
  R9 P3V3_AUX VCCIO2_1 @T6G_MB_LIB.T6G(SCH_1):P3V3_AUX
 R10 P3V3_AUX VCCIO2_2 @T6G_MB_LIB.T6G(SCH_1):P3V3_AUX
 R11 P3V3_AUX VCCIO2_3 @T6G_MB_LIB.T6G(SCH_1):P3V3_AUX
 R12 P3V3_AUX VCCIO2_4 @T6G_MB_LIB.T6G(SCH_1):P3V3_AUX
 R13 P3V3_AUX VCCIO2_5 @T6G_MB_LIB.T6G(SCH_1):P3V3_AUX
 R14 P3V3_AUX VCCIO2_6 @T6G_MB_LIB.T6G(SCH_1):P3V3_AUX
  W7 P3V3_AUX VCCIO2_7 @T6G_MB_LIB.T6G(SCH_1):P3V3_AUX
 W11 P3V3_AUX VCCIO2_8 @T6G_MB_LIB.T6G(SCH_1):P3V3_AUX
 W16 P3V3_AUX VCCIO2_9 @T6G_MB_LIB.T6G(SCH_1):P3V3_AUX
 F20 P1V8_AUX VCCIO1_1 @T6G_MB_LIB.T6G(SCH_1):P1V8_AUX
 J15 P1V8_AUX VCCIO1_2 @T6G_MB_LIB.T6G(SCH_1):P1V8_AUX
 K15 P1V8_AUX VCCIO1_3 @T6G_MB_LIB.T6G(SCH_1):P1V8_AUX
 L15 P1V8_AUX VCCIO1_4 @T6G_MB_LIB.T6G(SCH_1):P1V8_AUX
 M15 P1V8_AUX VCCIO1_5 @T6G_MB_LIB.T6G(SCH_1):P1V8_AUX
 M18 P1V8_AUX VCCIO1_6 @T6G_MB_LIB.T6G(SCH_1):P1V8_AUX
 N15 P1V8_AUX VCCIO1_7 @T6G_MB_LIB.T6G(SCH_1):P1V8_AUX
 P15 P1V8_AUX VCCIO1_8 @T6G_MB_LIB.T6G(SCH_1):P1V8_AUX
 V20 P1V8_AUX VCCIO1_9 @T6G_MB_LIB.T6G(SCH_1):P1V8_AUX
  C7 P3V3_AUX VCCIO0_1 @T6G_MB_LIB.T6G(SCH_1):P3V3_AUX
 C12 P3V3_AUX VCCIO0_2 @T6G_MB_LIB.T6G(SCH_1):P3V3_AUX
 C16 P3V3_AUX VCCIO0_3 @T6G_MB_LIB.T6G(SCH_1):P3V3_AUX
 G10 P3V3_AUX VCCIO0_4 @T6G_MB_LIB.T6G(SCH_1):P3V3_AUX
 H11 P3V3_AUX VCCIO0_7 @T6G_MB_LIB.T6G(SCH_1):P3V3_AUX
 H12 P3V3_AUX VCCIO0_8 @T6G_MB_LIB.T6G(SCH_1):P3V3_AUX
 H14 P3V3_AUX VCCIO0_9 @T6G_MB_LIB.T6G(SCH_1):P3V3_AUX
  H9 P3V3_AUX VCCIO0_6 @T6G_MB_LIB.T6G(SCH_1):P3V3_AUX
 G13 P3V3_AUX VCCIO0_5 @T6G_MB_LIB.T6G(SCH_1):P3V3_AUX

Q_RES_0402LF-0,5%,1/16W,CHIP,CS00002JB13  I146  R6073
   1 FM_PDB_BUF_EN_R_N      A @T6G_MB_LIB.T6G(SCH_1):FM_PDB_BUF_EN_R_N
   2 FM_PDB_BUF_EN_N      B @T6G_MB_LIB.T6G(SCH_1):FM_PDB_BUF_EN_N

Q_RES_0402LF-0,5%,1/16W,CHIP,CS00002JB13  I164  R6183
   1 FM_SEC_MUX_OE_N      A @T6G_MB_LIB.T6G(SCH_1):FM_SEC_MUX_OE_N
   2 FM_SEC_MUX_OE_R_N      B @T6G_MB_LIB.T6G(SCH_1):FM_SEC_MUX_OE_R_N

Q_RES_0402LF-0,5%,1/16W,CHIP,CS00002JB13  I165  R6184
   1 FM_SEC_MUX_SEL      A @T6G_MB_LIB.T6G(SCH_1):FM_SEC_MUX_SEL
   2 FM_SEC_MUX_R_SEL      B @T6G_MB_LIB.T6G(SCH_1):FM_SEC_MUX_R_SEL

Q_RES_0402LF-0,5%,1/16W,CHIP,CS00002JB13  I168  R132
   1 FM_APML_MUX2_OE_N      A @T6G_MB_LIB.T6G(SCH_1):FM_APML_MUX2_OE_N
   2 FM_APML_MUX2_OE_R_N      B @T6G_MB_LIB.T6G(SCH_1):FM_APML_MUX2_OE_R_N

Q_RES_0402LF-0,5%,1/16W,CHIP,CS00002JB13  I169  R133
   1 FM_APML_MUX2_SEL      A @T6G_MB_LIB.T6G(SCH_1):FM_APML_MUX2_SEL
   2 FM_APML_MUX2_SEL_R      B @T6G_MB_LIB.T6G(SCH_1):FM_APML_MUX2_SEL_R

Q_RES_0402LF-0,5%,1/16W,CHIP,CS00002JB13  I176  R1340
   1 OCP_SFF_P3V3_P12V_ADC_ALERT      A @T6G_MB_LIB.T6G(SCH_1):OCP_SFF_P3V3_P12V_ADC_ALERT
   2 OCP_SFF_P3V3_P12V_ADC_R_ALERT      B @T6G_MB_LIB.T6G(SCH_1):OCP_SFF_P3V3_P12V_ADC_R_ALERT

Q_RES_0402LF-0,5%,1/16W,CHIP,CS00002JB13  I178  R1329
   1 E1S_0_P3V3_P12V_ADC_R_ALERT      A @T6G_MB_LIB.T6G(SCH_1):E1S_0_P3V3_P12V_ADC_R_ALERT
   2 E1S_0_P3V3_P12V_ADC_ALERT      B @T6G_MB_LIB.T6G(SCH_1):E1S_0_P3V3_P12V_ADC_ALERT

Q_RES_0402LF-0,5%,1/16W,CHIP,CS00002JB13  I180  R1339
   1 OCP_V3_2_P3V3_P12V_ADC_R_ALERT      A @T6G_MB_LIB.T6G(SCH_1):OCP_V3_2_P3V3_P12V_ADC_R_ALERT
   2 OCP_V3_2_P3V3_P12V_ADC_ALERT      B @T6G_MB_LIB.T6G(SCH_1):OCP_V3_2_P3V3_P12V_ADC_ALERT


DRAWING: @T6G_MB_LIB.T6G(SCH_1):PAGE339 

Q_CAP_0402-0.22UF,16V,10%,X7R,CH4223K1B00  I60  PC2153
   1 P12V_OCP_TIMER_1      A @T6G_MB_LIB.T6G(SCH_1):P12V_OCP_TIMER_1
   2    GND      B @T6G_MB_LIB.T6G(SCH_1):GND

Q_RES_0402LF-14.3K,1%,1/16W,CHIP,CS31432FB02  I63  PR3835
   1 P12V_OCP_ISET_1      A @T6G_MB_LIB.T6G(SCH_1):P12V_OCP_ISET_1
   2    GND      B @T6G_MB_LIB.T6G(SCH_1):GND

Q_CAP_C0402-0.047UF,25V,10%,X7R,CH3474K1B04  I64  PC2155
   1 P12V_OCP_SS_1      A @T6G_MB_LIB.T6G(SCH_1):P12V_OCP_SS_1
   2    GND      B @T6G_MB_LIB.T6G(SCH_1):GND

Q_CAP_C0402-1UF,25V,10%,X6S,CH5104KEB02  I68  PC2154
   1 P12V_AUX      A @T6G_MB_LIB.T6G(SCH_1):P12V_AUX
   2    GND      B @T6G_MB_LIB.T6G(SCH_1):GND

Q_RES_0402LF-17.4K,1%,1/16W,CHIP,CS31742FB04  I71  PR3837
   1 P12V_OCP_IMON_1      A @T6G_MB_LIB.T6G(SCH_1):P12V_OCP_IMON_1
   2    GND      B @T6G_MB_LIB.T6G(SCH_1):GND

Q_CAP_C0402-100NF,50V,10%,X7R,CH4106K1B01  I73  PC2156
   1 P12V_OCP_IMON_1      A @T6G_MB_LIB.T6G(SCH_1):P12V_OCP_IMON_1
   2    GND      B @T6G_MB_LIB.T6G(SCH_1):GND

Q_RES_0402LF-10K,1%,1/16W,CHIP,CS31002FB08  I74  PR3839
   1 P12V_OCP_FLTB_1      A @T6G_MB_LIB.T6G(SCH_1):P12V_OCP_FLTB_1
   2 P3V3_AUX      B @T6G_MB_LIB.T6G(SCH_1):P3V3_AUX

Q_RES_0402LF-10K,1%,1/16W,CHIP,CS31002FB08  I75  R4532
   1 P3V3_AUX      A @T6G_MB_LIB.T6G(SCH_1):P3V3_AUX
   2 HP_LVC3_OCP_V3_1_P12V_PWRGD      B @T6G_MB_LIB.T6G(SCH_1):HP_LVC3_OCP_V3_1_P12V_PWRGD

Q_RES_0402LF-100,1%,1/16W,EMPTY,CS11002FB07  I76  PR3838
   1 P12V_OCP_SFF      A @T6G_MB_LIB.T6G(SCH_1):P12V_OCP_SFF
   2 P12V_OCP_AVIN_PD_1      B @T6G_MB_LIB.T6G(SCH_1):P12V_OCP_AVIN_PD_1

Q_RES_0402LF-10K,1%,1/16W,CHIP,CS31002FB08  I80  PR3842
   1 P12V_OCP_OV_FB_1      A @T6G_MB_LIB.T6G(SCH_1):P12V_OCP_OV_FB_1
   2    GND      B @T6G_MB_LIB.T6G(SCH_1):GND

Q_RES_0402LF-71.5K,1%,1/16W,EMPTY,CS37152FB05  I81  PR3840
   1 P12V_OCP_SFF      A @T6G_MB_LIB.T6G(SCH_1):P12V_OCP_SFF
   2 P12V_OCP_OV_FB_1      B @T6G_MB_LIB.T6G(SCH_1):P12V_OCP_OV_FB_1

Q_RES_0402LF-120K,1%,1/16W,CHIP,CS41202FB05  I82  PR3841
   1 P12V_AUX      A @T6G_MB_LIB.T6G(SCH_1):P12V_AUX
   2 P12V_OCP_OV_FB_1      B @T6G_MB_LIB.T6G(SCH_1):P12V_OCP_OV_FB_1

Q_RES_0402LF-0,5%,1/16W,EMPTY,CS00002JB13  I84  R3872
   1 P12V_OCP_IMON_1      A @T6G_MB_LIB.T6G(SCH_1):P12V_OCP_IMON_1
   2 P12V_OCP_SFF_ISENSE_MPS_TIC      B @T6G_MB_LIB.T6G(SCH_1):P12V_OCP_SFF_ISENSE_MPS_TIC

Q_RES_0402LF-0,5%,1/16W,CHIP,CS00002JB13  I85  R3871
   1 P12V_OCP_IMON_1      A @T6G_MB_LIB.T6G(SCH_1):P12V_OCP_IMON_1
   2 P12V_OCP_SFF_ISENSE_MPS_MAM      B @T6G_MB_LIB.T6G(SCH_1):P12V_OCP_SFF_ISENSE_MPS_MAM

Q_CAP_C0603-2.2UF,16V,20%,X7R,CH5223M1900  I86  PC2158
   1 P12V_OCP_AVIN_PD_1      A @T6G_MB_LIB.T6G(SCH_1):P12V_OCP_AVIN_PD_1
   2    GND      B @T6G_MB_LIB.T6G(SCH_1):GND

Q_RES_0603LF-49.9,1%,1/10W,CHIP,CS04993F909  I88  PR3843
   1 P12V_AUX      A @T6G_MB_LIB.T6G(SCH_1):P12V_AUX
   2 P12V_OCP_AVIN_PD_1      B @T6G_MB_LIB.T6G(SCH_1):P12V_OCP_AVIN_PD_1

Q_CAP_0402-0.1UF,25V,10%,X7R,CH4104K1B00  I91  PC2160
   1 P12V_OCP_SFF      A @T6G_MB_LIB.T6G(SCH_1):P12V_OCP_SFF
   2    GND      B @T6G_MB_LIB.T6G(SCH_1):GND

Q_CAP_0402-39PF,50V,5%,NPO,CH03906JB06  I98  PC2157
   1 P3V3_OCP_MODE_1      A @T6G_MB_LIB.T6G(SCH_1):P3V3_OCP_MODE_1
   2    GND      B @T6G_MB_LIB.T6G(SCH_1):GND

Q_RES_0402LF-71.5K,1%,1/16W,CHIP,CS37152FB05  I100  PR3844
   1 P3V3_OCP_MODE_1      A @T6G_MB_LIB.T6G(SCH_1):P3V3_OCP_MODE_1
   2    GND      B @T6G_MB_LIB.T6G(SCH_1):GND

Q_RES_0402LF-1.33K,1%,1/16W,CHIP,CS21332FB05  I102  PR3846
   1    GND      A @T6G_MB_LIB.T6G(SCH_1):GND
   2 P3V3_OCP_ILIMIT_1      B @T6G_MB_LIB.T6G(SCH_1):P3V3_OCP_ILIMIT_1

Q_CAP_0402-0.068UF,16V,10%,X7R,CH3683K1B09  I104  PC2161
   1 P3V3_OCP_DVDT_1      A @T6G_MB_LIB.T6G(SCH_1):P3V3_OCP_DVDT_1
   2    GND      B @T6G_MB_LIB.T6G(SCH_1):GND

Q_CAP_0402-100PF,50V,5%,X7R,CH11006JB18  I106  PC2162
   1 P3V3_OCP_GATE_1      A @T6G_MB_LIB.T6G(SCH_1):P3V3_OCP_GATE_1
   2    GND      B @T6G_MB_LIB.T6G(SCH_1):GND

Q_CAP_C0805-10UF,16V,10%,X6S,CH6103KEA01  I108  PC2163
   1 P3V3_OCP_SFF_R      A @T6G_MB_LIB.T6G(SCH_1):P3V3_OCP_SFF_R
   2    GND      B @T6G_MB_LIB.T6G(SCH_1):GND

Q_CAP_C0402-1UF,25V,10%,X6S,CH5104KEB02  I111  PC2159
   1 P3V3_AUX      A @T6G_MB_LIB.T6G(SCH_1):P3V3_AUX
   2    GND      B @T6G_MB_LIB.T6G(SCH_1):GND

MP5016GQHLZ-MP5016GQH-L-Z,SMLF,IC,AL005016007  I113  PU205
   9 P3V3_OCP_EN_1_R2     EN @T6G_MB_LIB.T6G(SCH_1):P3V3_OCP_EN_1_R2
   5 P3V3_OCP_MODE_1   MODE @T6G_MB_LIB.T6G(SCH_1):P3V3_OCP_MODE_1
   4 P3V3_OCP_ILIMIT_1 ILIMIT @T6G_MB_LIB.T6G(SCH_1):P3V3_OCP_ILIMIT_1
   3    GND    GND @T6G_MB_LIB.T6G(SCH_1):GND
 1_2 P3V3_AUX    VCC @T6G_MB_LIB.T6G(SCH_1):P3V3_AUX
  10 P3V3_OCP_DVDT_1  DV_DT @T6G_MB_LIB.T6G(SCH_1):P3V3_OCP_DVDT_1
   8 P3V3_OCP_GATE_1   GATE @T6G_MB_LIB.T6G(SCH_1):P3V3_OCP_GATE_1
 6_7 P3V3_OCP_SFF_R SOURCE @T6G_MB_LIB.T6G(SCH_1):P3V3_OCP_SFF_R

Q_RES_0402LF-0,5%,1/16W,EMPTY,CS00002JB13  I128  R3834
   1 P12V_OCP_SFF_EN_R      A @T6G_MB_LIB.T6G(SCH_1):P12V_OCP_SFF_EN_R
   2 P12V_OCP_EN_1_R2      B @T6G_MB_LIB.T6G(SCH_1):P12V_OCP_EN_1_R2

Q_RES_0402LF-0,5%,1/16W,CHIP,CS00002JB13  I130  R591
   1 P12V_OCP_SFF_BUF_EN_R      A @T6G_MB_LIB.T6G(SCH_1):P12V_OCP_SFF_BUF_EN_R
   2 P12V_OCP_EN_1_R2      B @T6G_MB_LIB.T6G(SCH_1):P12V_OCP_EN_1_R2

Q_RES_0402LF-0,5%,1/16W,EMPTY,CS00002JB13  I131  R3845
   1 P3V3_OCP_SFF_EN_R      A @T6G_MB_LIB.T6G(SCH_1):P3V3_OCP_SFF_EN_R
   2 P3V3_OCP_EN_1_R2      B @T6G_MB_LIB.T6G(SCH_1):P3V3_OCP_EN_1_R2

Q_RES_0402LF-0,5%,1/16W,CHIP,CS00002JB13  I134  R1487
   1 P12V_OCP_SFF_BUF_EN_R      A @T6G_MB_LIB.T6G(SCH_1):P12V_OCP_SFF_BUF_EN_R
   2 P3V3_OCP_EN_1_R2      B @T6G_MB_LIB.T6G(SCH_1):P3V3_OCP_EN_1_R2

Q_RES_0402LF-0,5%,1/16W,EMPTY,CS00002JB13  I135  R1137
   1 HP_LVC3_OCP_V3_1_P12V_PWRGD      A @T6G_MB_LIB.T6G(SCH_1):HP_LVC3_OCP_V3_1_P12V_PWRGD
   2 P3V3_OCP_EN_1_R2      B @T6G_MB_LIB.T6G(SCH_1):P3V3_OCP_EN_1_R2

RS31312R-RS31312R,SMLF,IC,AL031312000  I137  PU204
  20 P12V_OCP_SFF VOUT_20 @T6G_MB_LIB.T6G(SCH_1):P12V_OCP_SFF
21_22 P12V_AUX VIN_21_22 @T6G_MB_LIB.T6G(SCH_1):P12V_AUX
  19 P12V_OCP_SFF VOUT_19 @T6G_MB_LIB.T6G(SCH_1):P12V_OCP_SFF
  18 P12V_OCP_SFF VOUT_18 @T6G_MB_LIB.T6G(SCH_1):P12V_OCP_SFF
  17 P12V_OCP_SFF VOUT_17 @T6G_MB_LIB.T6G(SCH_1):P12V_OCP_SFF
  16 P12V_OCP_SFF VOUT_16 @T6G_MB_LIB.T6G(SCH_1):P12V_OCP_SFF
  15 P12V_OCP_SFF VOUT_15 @T6G_MB_LIB.T6G(SCH_1):P12V_OCP_SFF
  14 P12V_OCP_SFF VOUT_14 @T6G_MB_LIB.T6G(SCH_1):P12V_OCP_SFF
  12 P12V_OCP_AVIN_PD_1   AVIN @T6G_MB_LIB.T6G(SCH_1):P12V_OCP_AVIN_PD_1
  13 P12V_OCP_SFF VOUT_13 @T6G_MB_LIB.T6G(SCH_1):P12V_OCP_SFF
  11 P12V_OCP_OV_FB_1     OV @T6G_MB_LIB.T6G(SCH_1):P12V_OCP_OV_FB_1
  10 HP_LVC3_OCP_V3_1_P12V_PWRGD     PG @T6G_MB_LIB.T6G(SCH_1):HP_LVC3_OCP_V3_1_P12V_PWRGD
   9 P12V_OCP_FLTB_1   FLTB @T6G_MB_LIB.T6G(SCH_1):P12V_OCP_FLTB_1
   8 P12V_OCP_IMON_1   IMON @T6G_MB_LIB.T6G(SCH_1):P12V_OCP_IMON_1
  23 P12V_AUX VIN_23 @T6G_MB_LIB.T6G(SCH_1):P12V_AUX
  24 P12V_AUX VIN_24 @T6G_MB_LIB.T6G(SCH_1):P12V_AUX
  25 P12V_AUX VIN_25 @T6G_MB_LIB.T6G(SCH_1):P12V_AUX
  26 P12V_AUX VIN_26 @T6G_MB_LIB.T6G(SCH_1):P12V_AUX
   1 P12V_OCP_EN_1_R2     EN @T6G_MB_LIB.T6G(SCH_1):P12V_OCP_EN_1_R2
   2    GND LOADEN @T6G_MB_LIB.T6G(SCH_1):GND
   3    GND   ENTM @T6G_MB_LIB.T6G(SCH_1):GND
   4 P12V_OCP_TIMER_1  TIMER @T6G_MB_LIB.T6G(SCH_1):P12V_OCP_TIMER_1
   5 P12V_OCP_ISET_1   ISET @T6G_MB_LIB.T6G(SCH_1):P12V_OCP_ISET_1
   6 P12V_OCP_SS_1     SS @T6G_MB_LIB.T6G(SCH_1):P12V_OCP_SS_1
   7    GND    GND @T6G_MB_LIB.T6G(SCH_1):GND


DRAWING: @T6G_MB_LIB.T6G(SCH_1):PAGE244 

Q_CAP_C0402-0.1UF,25V,10%,X6S,CH4104KEB00  I2  PC1648
   1 P12V_AUX      A @T6G_MB_LIB.T6G(SCH_1):P12V_AUX
   2    GND      B @T6G_MB_LIB.T6G(SCH_1):GND

Q_INDUCTOR_SMLF-BLM18SN220TN1D/8000MA,IND,CX220TN1A  I5  PL8064
   2 SW_P5V_AUX_FLT      2 @T6G_MB_LIB.T6G(SCH_1):SW_P5V_AUX_FLT
   1 P12V_AUX      1 @T6G_MB_LIB.T6G(SCH_1):P12V_AUX

Q_CAP_C0805-22UF,16V,20%,X6S,CH6223MEA01  I7  PC1849
   1 SW_P5V_AUX_FLT      A @T6G_MB_LIB.T6G(SCH_1):SW_P5V_AUX_FLT
   2    GND      B @T6G_MB_LIB.T6G(SCH_1):GND

Q_CAP_C0402-1UF,25V,10%,X6S,CH5104KEB02  I8  PC1848
   1 P5V_AUX_VCC      A @T6G_MB_LIB.T6G(SCH_1):P5V_AUX_VCC
   2    GND      B @T6G_MB_LIB.T6G(SCH_1):GND

Q_CAP_C0805-22UF,16V,20%,X6S,CH6223MEA01  I10  PC1850
   1 SW_P5V_AUX_FLT      A @T6G_MB_LIB.T6G(SCH_1):SW_P5V_AUX_FLT
   2    GND      B @T6G_MB_LIB.T6G(SCH_1):GND

Q_CAP_C0805-22UF,16V,20%,X6S,CH6223MEA01  I11  PC1898
   1 SW_P5V_AUX_FLT      A @T6G_MB_LIB.T6G(SCH_1):SW_P5V_AUX_FLT
   2    GND      B @T6G_MB_LIB.T6G(SCH_1):GND

Q_CAP_C0402-1UF,16V,10%,X6S,CH5103KEB01  I13  PC1846
   1 SW_P5V_AUX_FLT      A @T6G_MB_LIB.T6G(SCH_1):SW_P5V_AUX_FLT
   2    GND      B @T6G_MB_LIB.T6G(SCH_1):GND

Q_RES_0402LF-16.9K,1%,1/16W,CHIP,CS31692FB03  I15  PR8089
   1 P5V_AUX_CS      A @T6G_MB_LIB.T6G(SCH_1):P5V_AUX_CS
   2    GND      B @T6G_MB_LIB.T6G(SCH_1):GND

Q_CAP_0402-0.1UF,25V,10%,X7R,CH4104K1B00  I19  PC1853
   1 P5V_AUX_REF      A @T6G_MB_LIB.T6G(SCH_1):P5V_AUX_REF
   2    GND      B @T6G_MB_LIB.T6G(SCH_1):GND

Q_CAP_0402-47PF,50V,5%,NPO,TMP_QCH04706JB01  I20  PC1877
   1 P5V_AUX_FB      A @T6G_MB_LIB.T6G(SCH_1):P5V_AUX_FB
   2 P5V_AUX      B @T6G_MB_LIB.T6G(SCH_1):P5V_AUX

Q_RES_0402LF-11.8K,0.1%,1/16W,CHIP,CS31182BB06  I23  PR8091
   1 P5V_AUX_FB      A @T6G_MB_LIB.T6G(SCH_1):P5V_AUX_FB
   2    GND      B @T6G_MB_LIB.T6G(SCH_1):GND

Q_CAP_C0402-0.22UF,25V,10%,X7R,CH4224K1B01  I24  PC1847
   1 SW_P5V_AUX_BST      A @T6G_MB_LIB.T6G(SCH_1):SW_P5V_AUX_BST
   2 SW_P5V_AUX_SW      B @T6G_MB_LIB.T6G(SCH_1):SW_P5V_AUX_SW

Q_RES_0402LF-10K,1%,1/16W,CHIP,CS31002FB08  I25  R2356
   1 P5V_AUX_VCC      A @T6G_MB_LIB.T6G(SCH_1):P5V_AUX_VCC
   2 PWRGD_P5V_AUX_R      B @T6G_MB_LIB.T6G(SCH_1):PWRGD_P5V_AUX_R

Q_RES_0402LF-0,5%,1/16W,CHIP,CS00002JB13  I26  R2316
   1 PWRGD_P5V_AUX_R      A @T6G_MB_LIB.T6G(SCH_1):PWRGD_P5V_AUX_R
   2 PWRGD_P5V_AUX      B @T6G_MB_LIB.T6G(SCH_1):PWRGD_P5V_AUX

Q_RES_0402LF-86.6K,1%,1/16W,CHIP,CS38662FB05  I27  PR8092
   1 P5V_AUX_FB      A @T6G_MB_LIB.T6G(SCH_1):P5V_AUX_FB
   2 P5V_AUX      B @T6G_MB_LIB.T6G(SCH_1):P5V_AUX

Q_INDUCTOR_SMLF-4.7UH,IND,CV-47A0MZ10  I28  PL8065
   2 P5V_AUX      2 @T6G_MB_LIB.T6G(SCH_1):P5V_AUX
   1 SW_P5V_AUX_SW      1 @T6G_MB_LIB.T6G(SCH_1):SW_P5V_AUX_SW

Q_CAPP_SMLF-220UF,6.3V,20%,ALUM,CC72201MZ28  I30  PC1845
   1 P5V_AUX      A @T6G_MB_LIB.T6G(SCH_1):P5V_AUX
   2    GND      B @T6G_MB_LIB.T6G(SCH_1):GND

Q_CAP_C0805-22UF,10V,20%,X6S,CH6222MEA01  I31  PC1855
   1 P5V_AUX      A @T6G_MB_LIB.T6G(SCH_1):P5V_AUX
   2    GND      B @T6G_MB_LIB.T6G(SCH_1):GND

Q_CAP_C0805-22UF,10V,20%,X6S,CH6222MEA01  I32  PC1856
   1 P5V_AUX      A @T6G_MB_LIB.T6G(SCH_1):P5V_AUX
   2    GND      B @T6G_MB_LIB.T6G(SCH_1):GND

Q_CAP_0402-0.1UF,25V,10%,X7R,CH4104K1B00  I34  PC1852
   1 P5V_AUX      A @T6G_MB_LIB.T6G(SCH_1):P5V_AUX
   2    GND      B @T6G_MB_LIB.T6G(SCH_1):GND

Q_RES_0402LF-0,5%,1/16W,CHIP,CS00002JB13  I37  PR3337
   1 P5V_AUX_MODE      A @T6G_MB_LIB.T6G(SCH_1):P5V_AUX_MODE
   2    GND      B @T6G_MB_LIB.T6G(SCH_1):GND

MPQ8633AGLEC807Z-MPQ8633AGLE-C807-Z,SMLF,IC,AL0086A  I38  U326
  10 SW_P5V_AUX_FLT   VIN1 @T6G_MB_LIB.T6G(SCH_1):SW_P5V_AUX_FLT
   9 PWRGD_P5V_AUX_R  PGOOD @T6G_MB_LIB.T6G(SCH_1):PWRGD_P5V_AUX_R
11_18    GND   PGND @T6G_MB_LIB.T6G(SCH_1):GND
   8 P5V_AUX_EN     EN @T6G_MB_LIB.T6G(SCH_1):P5V_AUX_EN
   1 SW_P5V_AUX_BST    BST @T6G_MB_LIB.T6G(SCH_1):SW_P5V_AUX_BST
   7 P5V_AUX_FB     FB @T6G_MB_LIB.T6G(SCH_1):P5V_AUX_FB
   2    GND   AGND @T6G_MB_LIB.T6G(SCH_1):GND
  19 P5V_AUX_VCC    VCC @T6G_MB_LIB.T6G(SCH_1):P5V_AUX_VCC
   6    GND   RGND @T6G_MB_LIB.T6G(SCH_1):GND
  20 SW_P5V_AUX_SW     SW @T6G_MB_LIB.T6G(SCH_1):SW_P5V_AUX_SW
   5 P5V_AUX_REF TRK_REF @T6G_MB_LIB.T6G(SCH_1):P5V_AUX_REF
   4 P5V_AUX_MODE   MODE @T6G_MB_LIB.T6G(SCH_1):P5V_AUX_MODE
   3 P5V_AUX_CS     CS @T6G_MB_LIB.T6G(SCH_1):P5V_AUX_CS
  21 SW_P5V_AUX_FLT   VIN2 @T6G_MB_LIB.T6G(SCH_1):SW_P5V_AUX_FLT

Q_RES_0402LF-0,5%,1/16W,CHIP,CS00002JB13  I40  R6097
   1 MB0_P12V_STBY_PWRGD      A @T6G_MB_LIB.T6G(SCH_1):MB0_P12V_STBY_PWRGD
   2 P5V_AUX_EN      B @T6G_MB_LIB.T6G(SCH_1):P5V_AUX_EN


DRAWING: @T6G_MB_LIB.T6G(SCH_1):PAGE167 

Q_CAP_C0402-1UF,25V,10%,X6S,CH5104KEB02  I2  PC118
   1 PVDD_33_S5_VCC      A @T6G_MB_LIB.T6G(SCH_1):PVDD_33_S5_VCC
   2    GND      B @T6G_MB_LIB.T6G(SCH_1):GND

Q_CAP_0402-0.1UF,25V,10%,EMPTY,CH4104K1B00  I5  C348
   1 PVDD33_S5_EN      A @T6G_MB_LIB.T6G(SCH_1):PVDD33_S5_EN
   2    GND      B @T6G_MB_LIB.T6G(SCH_1):GND

Q_CAP_C0402-0.1UF,25V,10%,X6S,CH4104KEB00  I8  PC6000
   1 P12V_AUX      A @T6G_MB_LIB.T6G(SCH_1):P12V_AUX
   2    GND      B @T6G_MB_LIB.T6G(SCH_1):GND

Q_INDUCTOR_SMLF-BLM18SN220TN1D/8000MA,IND,CX220TN1A  I10  PL71
   2 SW_P12V_AUX_PVDD_33_S5_FLT      2 @T6G_MB_LIB.T6G(SCH_1):SW_P12V_AUX_PVDD_33_S5_FLT
   1 P12V_AUX      1 @T6G_MB_LIB.T6G(SCH_1):P12V_AUX

Q_CAP_C0805-22UF,16V,20%,X6S,CH6223MEA01  I12  PC119
   1 SW_P12V_AUX_PVDD_33_S5_FLT      A @T6G_MB_LIB.T6G(SCH_1):SW_P12V_AUX_PVDD_33_S5_FLT
   2    GND      B @T6G_MB_LIB.T6G(SCH_1):GND

Q_CAP_C0805-22UF,16V,20%,X6S,CH6223MEA01  I13  PC120
   1 SW_P12V_AUX_PVDD_33_S5_FLT      A @T6G_MB_LIB.T6G(SCH_1):SW_P12V_AUX_PVDD_33_S5_FLT
   2    GND      B @T6G_MB_LIB.T6G(SCH_1):GND

Q_RES_0402LF-6.98K,1%,1/16W,CHIP,CS26982FB08  I15  PR452
   1 PVDD_33_S5_CS      A @T6G_MB_LIB.T6G(SCH_1):PVDD_33_S5_CS
   2    GND      B @T6G_MB_LIB.T6G(SCH_1):GND

Q_RES_0402LF-0,5%,1/16W,CHIP,CS00002JB13  I17  PR6000
   1    GND      A @T6G_MB_LIB.T6G(SCH_1):GND
   2 PVDD_33_S5_MODE      B @T6G_MB_LIB.T6G(SCH_1):PVDD_33_S5_MODE

Q_CAP_0402-0.1UF,25V,10%,X7R,CH4104K1B00  I19  PC127
   1 PVDD_33_S5_REF      A @T6G_MB_LIB.T6G(SCH_1):PVDD_33_S5_REF
   2    GND      B @T6G_MB_LIB.T6G(SCH_1):GND

Q_RES_0402LF-12.4K,1%,1/16W,CHIP,CS31242FB02  I23  PR454
   1 PVDD_33_S5_FB      A @T6G_MB_LIB.T6G(SCH_1):PVDD_33_S5_FB
   2    GND      B @T6G_MB_LIB.T6G(SCH_1):GND

Q_CAP_0402-100PF,50V,5%,NPO,CH11006JB00  I24  PC132
   1 PVDD_33_S5_FB      A @T6G_MB_LIB.T6G(SCH_1):PVDD_33_S5_FB
   2 PVDD_33_S5      B @T6G_MB_LIB.T6G(SCH_1):PVDD_33_S5

Q_RES_0402LF-56K,1%,1/16W,CHIP,CS35602FB00  I25  PR455
   1 PVDD_33_S5_FB      A @T6G_MB_LIB.T6G(SCH_1):PVDD_33_S5_FB
   2 PVDD_33_S5      B @T6G_MB_LIB.T6G(SCH_1):PVDD_33_S5

Q_CAP_C0805-22UF,16V,20%,X6S,CH6223MEA01  I27  PC129
   1 PVDD_33_S5      A @T6G_MB_LIB.T6G(SCH_1):PVDD_33_S5
   2    GND      B @T6G_MB_LIB.T6G(SCH_1):GND

Q_CAP_C0805-22UF,16V,20%,X6S,CH6223MEA01  I28  PC130
   1 PVDD_33_S5      A @T6G_MB_LIB.T6G(SCH_1):PVDD_33_S5
   2    GND      B @T6G_MB_LIB.T6G(SCH_1):GND

Q_CAP_C0805-22UF,16V,20%,X6S,CH6223MEA01  I29  PC123
   1 SW_P12V_AUX_PVDD_33_S5_FLT      A @T6G_MB_LIB.T6G(SCH_1):SW_P12V_AUX_PVDD_33_S5_FLT
   2    GND      B @T6G_MB_LIB.T6G(SCH_1):GND

Q_CAP_C0402-1UF,25V,10%,X6S,CH5104KEB02  I30  PC126
   1 SW_P12V_AUX_PVDD_33_S5_FLT      A @T6G_MB_LIB.T6G(SCH_1):SW_P12V_AUX_PVDD_33_S5_FLT
   2    GND      B @T6G_MB_LIB.T6G(SCH_1):GND

Q_RES_0402LF-10K,5%,1/16W,CHIP,CS31002JB08  I31  R453
   1 PVDD_33_S5_VCC      A @T6G_MB_LIB.T6G(SCH_1):PVDD_33_S5_VCC
   2 PWRGD_PVDD33_S5      B @T6G_MB_LIB.T6G(SCH_1):PWRGD_PVDD33_S5

Q_RES_0402LF-33,5%,1/16W,CHIP,CS03302JB10  I33  R225
   1 PWRGD_PVDD33_S5      A @T6G_MB_LIB.T6G(SCH_1):PWRGD_PVDD33_S5
   2 FM_PWRGD_PVDD33_S5      B @T6G_MB_LIB.T6G(SCH_1):FM_PWRGD_PVDD33_S5

Q_CAP_C0805-22UF,16V,20%,X6S,CH6223MEA01  I35  PC134
   1 PVDD_33_S5      A @T6G_MB_LIB.T6G(SCH_1):PVDD_33_S5
   2    GND      B @T6G_MB_LIB.T6G(SCH_1):GND

Q_CAP_C0805-22UF,16V,20%,X6S,CH6223MEA01  I36  PC135
   1 PVDD_33_S5      A @T6G_MB_LIB.T6G(SCH_1):PVDD_33_S5
   2    GND      B @T6G_MB_LIB.T6G(SCH_1):GND

Q_CAP_0402-0.1UF,25V,10%,X7R,CH4104K1B00  I37  PC136
   1 PVDD_33_S5      A @T6G_MB_LIB.T6G(SCH_1):PVDD_33_S5
   2    GND      B @T6G_MB_LIB.T6G(SCH_1):GND

Q_CAP_0402-0.1UF,25V,10%,X7R,CH4104K1B00  I40  PC128
   1 SW_PVDD_33_S5_BST_R      A @T6G_MB_LIB.T6G(SCH_1):SW_PVDD_33_S5_BST_R
   2 SW_PVDD_33_S5_SW      B @T6G_MB_LIB.T6G(SCH_1):SW_PVDD_33_S5_SW

MPQ8633AGLEC807Z-MPQ8633AGLE-C807-Z,SMLF,IC,AL0086A  I41  PU55
  10 SW_P12V_AUX_PVDD_33_S5_FLT   VIN1 @T6G_MB_LIB.T6G(SCH_1):SW_P12V_AUX_PVDD_33_S5_FLT
   9 PWRGD_PVDD33_S5  PGOOD @T6G_MB_LIB.T6G(SCH_1):PWRGD_PVDD33_S5
11_18    GND   PGND @T6G_MB_LIB.T6G(SCH_1):GND
   8 PVDD33_S5_EN     EN @T6G_MB_LIB.T6G(SCH_1):PVDD33_S5_EN
   1 SW_PVDD_33_S5_BST    BST @T6G_MB_LIB.T6G(SCH_1):SW_PVDD_33_S5_BST
   7 PVDD_33_S5_FB     FB @T6G_MB_LIB.T6G(SCH_1):PVDD_33_S5_FB
   2    GND   AGND @T6G_MB_LIB.T6G(SCH_1):GND
  19 PVDD_33_S5_VCC    VCC @T6G_MB_LIB.T6G(SCH_1):PVDD_33_S5_VCC
   6    GND   RGND @T6G_MB_LIB.T6G(SCH_1):GND
  20 SW_PVDD_33_S5_SW     SW @T6G_MB_LIB.T6G(SCH_1):SW_PVDD_33_S5_SW
   5 PVDD_33_S5_REF TRK_REF @T6G_MB_LIB.T6G(SCH_1):PVDD_33_S5_REF
   4 PVDD_33_S5_MODE   MODE @T6G_MB_LIB.T6G(SCH_1):PVDD_33_S5_MODE
   3 PVDD_33_S5_CS     CS @T6G_MB_LIB.T6G(SCH_1):PVDD_33_S5_CS
  21 SW_P12V_AUX_PVDD_33_S5_FLT   VIN2 @T6G_MB_LIB.T6G(SCH_1):SW_P12V_AUX_PVDD_33_S5_FLT

Q_CAP_0402-1000PF,50V,5%,X7R,TMP_QCH21006JB10  I43  C5002
   1 FM_PWRGD_PVDD33_S5      A @T6G_MB_LIB.T6G(SCH_1):FM_PWRGD_PVDD33_S5
   2    GND      B @T6G_MB_LIB.T6G(SCH_1):GND

Q_CAP_C0805-22UF,16V,20%,X6S,CH6223MEA01  I44  PC8000
   1 SW_P12V_AUX_PVDD_33_S5_FLT      A @T6G_MB_LIB.T6G(SCH_1):SW_P12V_AUX_PVDD_33_S5_FLT
   2    GND      B @T6G_MB_LIB.T6G(SCH_1):GND

Q_CAP_C0805-22UF,16V,20%,X6S,CH6223MEA01  I45  PC8001
   1 SW_P12V_AUX_PVDD_33_S5_FLT      A @T6G_MB_LIB.T6G(SCH_1):SW_P12V_AUX_PVDD_33_S5_FLT
   2    GND      B @T6G_MB_LIB.T6G(SCH_1):GND

Q_RES_0402LF-0,5%,1/16W,CHIP,CS00002JB13  I46  PR8000
   1 SW_PVDD_33_S5_BST      A @T6G_MB_LIB.T6G(SCH_1):SW_PVDD_33_S5_BST
   2 SW_PVDD_33_S5_BST_R      B @T6G_MB_LIB.T6G(SCH_1):SW_PVDD_33_S5_BST_R

Q_INDUCTOR_SMLF-1.5UH,IND,CV-15I0MZ28  I47  PL72
   2 PVDD_33_S5      2 @T6G_MB_LIB.T6G(SCH_1):PVDD_33_S5
   1 SW_PVDD_33_S5_SW      1 @T6G_MB_LIB.T6G(SCH_1):SW_PVDD_33_S5_SW


DRAWING: @T6G_MB_LIB.T6G(SCH_1):PAGE171 

Q_CAP_0402-0.1UF,25V,10%,X7R,CH4104K1B00  I4  PC150_6
   1 PVDDCR_CPU0_P0_VCCS      A @T6G_MB_LIB.T6G(SCH_1):PVDDCR_CPU0_P0_VCCS
   2    GND      B @T6G_MB_LIB.T6G(SCH_1):GND

Q_RES_0402LF-8.87K,1%,1/16W,EMPTY,CS28872FB01  I8  PR431
   1    GND      A @T6G_MB_LIB.T6G(SCH_1):GND
   2 PVDDCR_CPU0_P0_LSET6      B @T6G_MB_LIB.T6G(SCH_1):PVDDCR_CPU0_P0_LSET6

Q_CAP_C0402-2.2UF,10V,10%,X6S,CH5222KEB01  I11  PC151
   1 PVDDCR_CPU0_P0_VCC6      A @T6G_MB_LIB.T6G(SCH_1):PVDDCR_CPU0_P0_VCC6
   2    GND      B @T6G_MB_LIB.T6G(SCH_1):GND

Q_RES_0402LF-2.2,1%,1/16W,CHIP,CS-2202FB01  I13  PR430
   1 PVDDCR_CPU0_P0_PVCC      A @T6G_MB_LIB.T6G(SCH_1):PVDDCR_CPU0_P0_PVCC
   2 PVDDCR_CPU0_P0_VCC6      B @T6G_MB_LIB.T6G(SCH_1):PVDDCR_CPU0_P0_VCC6

Q_CAP_C0402-2.2UF,10V,10%,X6S,CH5222KEB01  I14  PC152_C0P0_6
   1 PVDDCR_CPU0_P0_PVCC      A @T6G_MB_LIB.T6G(SCH_1):PVDDCR_CPU0_P0_PVCC
   2    GND      B @T6G_MB_LIB.T6G(SCH_1):GND

ISL99390FRZTR5935-ISL99390FRZ-TR5935,SMLF,IC,AL099A  I18  PU48
  34 PVDDCR_CPU0_P0_PWM5    PWM @T6G_MB_LIB.T6G(SCH_1):PVDDCR_CPU0_P0_PWM5
  39 PVDDCR_CPU0_P0_VCCS  REFIN @T6G_MB_LIB.T6G(SCH_1):PVDDCR_CPU0_P0_VCCS
   3 PVDDCR_CPU0_P0_VCC5    VCC @T6G_MB_LIB.T6G(SCH_1):PVDDCR_CPU0_P0_VCC5
   2    GND   AGND @T6G_MB_LIB.T6G(SCH_1):GND
  33 SW_PVDDCR_CPU0_P0_BOOT5   BOOT @T6G_MB_LIB.T6G(SCH_1):SW_PVDDCR_CPU0_P0_BOOT5
25_29 SW_P12V_AUX_PVDDCR_CPU0_P0_FLT   VIN1 @T6G_MB_LIB.T6G(SCH_1):SW_P12V_AUX_PVDDCR_CPU0_P0_FLT
  32 SW_PVDDCR_CPU0_P0_PH5  PHASE @T6G_MB_LIB.T6G(SCH_1):SW_PVDDCR_CPU0_P0_PH5
   4 PVDDCR_CPU0_P0_PVCC   PVCC @T6G_MB_LIB.T6G(SCH_1):PVDDCR_CPU0_P0_PVCC
  36 PVDDCR_CPU0_P0_TEMP0 TOUT_FLT @T6G_MB_LIB.T6G(SCH_1):PVDDCR_CPU0_P0_TEMP0
  38 PVDDCR_CPU0_P0_IMON5   IOUT @T6G_MB_LIB.T6G(SCH_1):PVDDCR_CPU0_P0_IMON5
  37 PVDDCR_CPU0_P0_LSET5   LSET @T6G_MB_LIB.T6G(SCH_1):PVDDCR_CPU0_P0_LSET5
10_19 SW_PVDDCR_CPU0_P0_SW5     SW @T6G_MB_LIB.T6G(SCH_1):SW_PVDDCR_CPU0_P0_SW5
   5    GND  PGND1 @T6G_MB_LIB.T6G(SCH_1):GND
  30 SW_P12V_AUX_PVDDCR_CPU0_P0_FLT   VIN2 @T6G_MB_LIB.T6G(SCH_1):SW_P12V_AUX_PVDDCR_CPU0_P0_FLT
   1 PVDDCR_CPU0_P0_VOS5    VOS @T6G_MB_LIB.T6G(SCH_1):PVDDCR_CPU0_P0_VOS5
  40    GND  PGND3 @T6G_MB_LIB.T6G(SCH_1):GND
  35 PVDDCR_CPU0_P0_VCC5     EN @T6G_MB_LIB.T6G(SCH_1):PVDDCR_CPU0_P0_VCC5
  31 NC_PVDDCR_CPU0_P0_DNC5    DNC @T6G_MB_LIB.T6G(SCH_1):NC_PVDDCR_CPU0_P0_DNC5
   6 NC_PVDDCR_CPU0_P0_GL1_5    GL1 @T6G_MB_LIB.T6G(SCH_1):NC_PVDDCR_CPU0_P0_GL1_5
  41 NC_PVDDCR_CPU0_P0_GL2_5    GL2 @T6G_MB_LIB.T6G(SCH_1):NC_PVDDCR_CPU0_P0_GL2_5
7_9-20_24    GND  PGND2 @T6G_MB_LIB.T6G(SCH_1):GND

Q_RES_0402LF-0,5%,1/16W,CHIP,CS00002JB13  I21  PR433
   1 PVDDCR_CPU0_P0_VOS6      A @T6G_MB_LIB.T6G(SCH_1):PVDDCR_CPU0_P0_VOS6
   2 PVDDCR_CPU0_P0      B @T6G_MB_LIB.T6G(SCH_1):PVDDCR_CPU0_P0

Q_RES_0402LF-1.5,1%,1/8W,EMPTY,CS-1504FB00  I22  PR500
   1 SW_PVDDCR_CPU0_P0_SW6_RC      A @T6G_MB_LIB.T6G(SCH_1):SW_PVDDCR_CPU0_P0_SW6_RC
   2    GND      B @T6G_MB_LIB.T6G(SCH_1):GND

Q_CAP_C0402-560PF,50V,10%,EMPTY,CH1566K1B09  I23  PC182
   1 SW_PVDDCR_CPU0_P0_SW6      A @T6G_MB_LIB.T6G(SCH_1):SW_PVDDCR_CPU0_P0_SW6
   2 SW_PVDDCR_CPU0_P0_SW6_RC      B @T6G_MB_LIB.T6G(SCH_1):SW_PVDDCR_CPU0_P0_SW6_RC

Q_CAP_0402-0.1UF,25V,10%,X7R,CH4104K1B00  I24  PC153_6
   1 SW_P12V_AUX_PVDDCR_CPU0_P0_FLT      A @T6G_MB_LIB.T6G(SCH_1):SW_P12V_AUX_PVDDCR_CPU0_P0_FLT
   2    GND      B @T6G_MB_LIB.T6G(SCH_1):GND

Q_RES_0402LF-5.6,1%,1/16W,CHIP,CS-5602FB01  I26  PR432
   1 SW_PVDDCR_CPU0_P0_BOOT6      A @T6G_MB_LIB.T6G(SCH_1):SW_PVDDCR_CPU0_P0_BOOT6
   2 SW_PVDDCR_CPU0_P0_BOOT6_RC      B @T6G_MB_LIB.T6G(SCH_1):SW_PVDDCR_CPU0_P0_BOOT6_RC

Q_CAP_C0402-1UF,25V,10%,X6S,CH5104KEB02  I27  PC154_6
   1 SW_P12V_AUX_PVDDCR_CPU0_P0_FLT      A @T6G_MB_LIB.T6G(SCH_1):SW_P12V_AUX_PVDDCR_CPU0_P0_FLT
   2    GND      B @T6G_MB_LIB.T6G(SCH_1):GND

Q_CAP_C0805-22UF,16V,20%,X6S,CH6223MEA01  I28  PC157_6
   1 SW_P12V_AUX_PVDDCR_CPU0_P0_FLT      A @T6G_MB_LIB.T6G(SCH_1):SW_P12V_AUX_PVDDCR_CPU0_P0_FLT
   2    GND      B @T6G_MB_LIB.T6G(SCH_1):GND

Q_CAP_C0805-22UF,16V,20%,X6S,CH6223MEA01  I29  PC158_6
   1 SW_P12V_AUX_PVDDCR_CPU0_P0_FLT      A @T6G_MB_LIB.T6G(SCH_1):SW_P12V_AUX_PVDDCR_CPU0_P0_FLT
   2    GND      B @T6G_MB_LIB.T6G(SCH_1):GND

Q_RES_0402LF-1.5,1%,1/8W,EMPTY,CS-1504FB00  I31  PR501
   1 SW_PVDDCR_CPU0_P0_SW5_RC      A @T6G_MB_LIB.T6G(SCH_1):SW_PVDDCR_CPU0_P0_SW5_RC
   2    GND      B @T6G_MB_LIB.T6G(SCH_1):GND

Q_RES_0402LF-0,5%,1/16W,CHIP,CS00002JB13  I32  PR355
   1 PVDDCR_CPU0_P0_VOS5      A @T6G_MB_LIB.T6G(SCH_1):PVDDCR_CPU0_P0_VOS5
   2 PVDDCR_CPU0_P0      B @T6G_MB_LIB.T6G(SCH_1):PVDDCR_CPU0_P0

Q_CAP_0402-0.1UF,25V,10%,X7R,CH4104K1B00  I33  PC566_5
   1 PVDDCR_CPU0_P0_VCCS      A @T6G_MB_LIB.T6G(SCH_1):PVDDCR_CPU0_P0_VCCS
   2    GND      B @T6G_MB_LIB.T6G(SCH_1):GND

Q_RES_0402LF-8.87K,1%,1/16W,EMPTY,CS28872FB01  I36  PR353
   1    GND      A @T6G_MB_LIB.T6G(SCH_1):GND
   2 PVDDCR_CPU0_P0_LSET5      B @T6G_MB_LIB.T6G(SCH_1):PVDDCR_CPU0_P0_LSET5

Q_CAP_C0402-2.2UF,10V,10%,X6S,CH5222KEB01  I38  PC567
   1 PVDDCR_CPU0_P0_VCC5      A @T6G_MB_LIB.T6G(SCH_1):PVDDCR_CPU0_P0_VCC5
   2    GND      B @T6G_MB_LIB.T6G(SCH_1):GND

Q_RES_0402LF-2.2,1%,1/16W,CHIP,CS-2202FB01  I40  PR352
   1 PVDDCR_CPU0_P0_PVCC      A @T6G_MB_LIB.T6G(SCH_1):PVDDCR_CPU0_P0_PVCC
   2 PVDDCR_CPU0_P0_VCC5      B @T6G_MB_LIB.T6G(SCH_1):PVDDCR_CPU0_P0_VCC5

Q_CAP_C0402-2.2UF,10V,10%,X6S,CH5222KEB01  I42  PC568_C0P0_5
   1 PVDDCR_CPU0_P0_PVCC      A @T6G_MB_LIB.T6G(SCH_1):PVDDCR_CPU0_P0_PVCC
   2    GND      B @T6G_MB_LIB.T6G(SCH_1):GND

Q_CAP_0402-0.1UF,25V,10%,X7R,CH4104K1B00  I44  PC570_5
   1 SW_P12V_AUX_PVDDCR_CPU0_P0_FLT      A @T6G_MB_LIB.T6G(SCH_1):SW_P12V_AUX_PVDDCR_CPU0_P0_FLT
   2    GND      B @T6G_MB_LIB.T6G(SCH_1):GND

Q_RES_0402LF-5.6,1%,1/16W,CHIP,CS-5602FB01  I45  PR354
   1 SW_PVDDCR_CPU0_P0_BOOT5      A @T6G_MB_LIB.T6G(SCH_1):SW_PVDDCR_CPU0_P0_BOOT5
   2 SW_PVDDCR_CPU0_P0_BOOT5_RC      B @T6G_MB_LIB.T6G(SCH_1):SW_PVDDCR_CPU0_P0_BOOT5_RC

Q_CAP_C0402-560PF,50V,10%,EMPTY,CH1566K1B09  I46  PC184
   1 SW_PVDDCR_CPU0_P0_SW5      A @T6G_MB_LIB.T6G(SCH_1):SW_PVDDCR_CPU0_P0_SW5
   2 SW_PVDDCR_CPU0_P0_SW5_RC      B @T6G_MB_LIB.T6G(SCH_1):SW_PVDDCR_CPU0_P0_SW5_RC

Q_CAP_C0402-1UF,25V,10%,X6S,CH5104KEB02  I47  PC569_5
   1 SW_P12V_AUX_PVDDCR_CPU0_P0_FLT      A @T6G_MB_LIB.T6G(SCH_1):SW_P12V_AUX_PVDDCR_CPU0_P0_FLT
   2    GND      B @T6G_MB_LIB.T6G(SCH_1):GND

Q_CAP_C0805-22UF,16V,20%,X6S,CH6223MEA01  I48  PC571_5
   1 SW_P12V_AUX_PVDDCR_CPU0_P0_FLT      A @T6G_MB_LIB.T6G(SCH_1):SW_P12V_AUX_PVDDCR_CPU0_P0_FLT
   2    GND      B @T6G_MB_LIB.T6G(SCH_1):GND

Q_CAP_C0805-22UF,16V,20%,X6S,CH6223MEA01  I49  PC572_5
   1 SW_P12V_AUX_PVDDCR_CPU0_P0_FLT      A @T6G_MB_LIB.T6G(SCH_1):SW_P12V_AUX_PVDDCR_CPU0_P0_FLT
   2    GND      B @T6G_MB_LIB.T6G(SCH_1):GND

Q_INDUCTOR_SMLF-120NH/69A,IND,CV+12^0EZ03  I51  PL50
   2 IND_CPU0_P0_CPL0      2 @T6G_MB_LIB.T6G(SCH_1):IND_CPU0_P0_CPL0
   1    GND      1 @T6G_MB_LIB.T6G(SCH_1):GND

Q_INDUCTOR4P_14-150NH,SMLF,IND,CV+15^0TZ04  I52  PL70
   2 IND_CPU0_P0_CPL0      2 @T6G_MB_LIB.T6G(SCH_1):IND_CPU0_P0_CPL0
   3 IND_CPU0_P0_CPL6      3 @T6G_MB_LIB.T6G(SCH_1):IND_CPU0_P0_CPL6
   4 PVDDCR_CPU0_P0      4 @T6G_MB_LIB.T6G(SCH_1):PVDDCR_CPU0_P0
   1 SW_PVDDCR_CPU0_P0_SW6      1 @T6G_MB_LIB.T6G(SCH_1):SW_PVDDCR_CPU0_P0_SW6

Q_CAP_0402-0.22UF,16V,10%,X7R,CH4223K1B00  I54  PC161
   1 SW_PVDDCR_CPU0_P0_BOOT6_RC      A @T6G_MB_LIB.T6G(SCH_1):SW_PVDDCR_CPU0_P0_BOOT6_RC
   2 SW_PVDDCR_CPU0_P0_PH6      B @T6G_MB_LIB.T6G(SCH_1):SW_PVDDCR_CPU0_P0_PH6

Q_CAP_C0805-22UF,16V,20%,X6S,CH6223MEA01  I55  PC159_6
   1 SW_P12V_AUX_PVDDCR_CPU0_P0_FLT      A @T6G_MB_LIB.T6G(SCH_1):SW_P12V_AUX_PVDDCR_CPU0_P0_FLT
   2    GND      B @T6G_MB_LIB.T6G(SCH_1):GND

Q_CAP_C0805-22UF,4V,20%,X6S,CH622KMEA03  I59  PC163_6
   1 PVDDCR_CPU0_P0      A @T6G_MB_LIB.T6G(SCH_1):PVDDCR_CPU0_P0
   2    GND      B @T6G_MB_LIB.T6G(SCH_1):GND

Q_CAP_C0805-22UF,4V,20%,X6S,CH622KMEA03  I60  PC166_6
   1 PVDDCR_CPU0_P0      A @T6G_MB_LIB.T6G(SCH_1):PVDDCR_CPU0_P0
   2    GND      B @T6G_MB_LIB.T6G(SCH_1):GND

Q_CAP_0402-0.22UF,16V,10%,X7R,CH4223K1B00  I63  PC574
   1 SW_PVDDCR_CPU0_P0_BOOT5_RC      A @T6G_MB_LIB.T6G(SCH_1):SW_PVDDCR_CPU0_P0_BOOT5_RC
   2 SW_PVDDCR_CPU0_P0_PH5      B @T6G_MB_LIB.T6G(SCH_1):SW_PVDDCR_CPU0_P0_PH5

Q_INDUCTOR4P_14-150NH,SMLF,IND,CV+15^0TZ04  I64  PL61
   2 IND_CPU0_P0_CPL6      2 @T6G_MB_LIB.T6G(SCH_1):IND_CPU0_P0_CPL6
   3 IND_CPU0_P0_CPL5      3 @T6G_MB_LIB.T6G(SCH_1):IND_CPU0_P0_CPL5
   4 PVDDCR_CPU0_P0      4 @T6G_MB_LIB.T6G(SCH_1):PVDDCR_CPU0_P0
   1 SW_PVDDCR_CPU0_P0_SW5      1 @T6G_MB_LIB.T6G(SCH_1):SW_PVDDCR_CPU0_P0_SW5

Q_CAP_C0805-22UF,16V,20%,X6S,CH6223MEA01  I66  PC573_5
   1 SW_P12V_AUX_PVDDCR_CPU0_P0_FLT      A @T6G_MB_LIB.T6G(SCH_1):SW_P12V_AUX_PVDDCR_CPU0_P0_FLT
   2    GND      B @T6G_MB_LIB.T6G(SCH_1):GND

Q_CAP_C0805-22UF,4V,20%,X6S,CH622KMEA03  I69  PC575_5
   1 PVDDCR_CPU0_P0      A @T6G_MB_LIB.T6G(SCH_1):PVDDCR_CPU0_P0
   2    GND      B @T6G_MB_LIB.T6G(SCH_1):GND

Q_CAP_C0805-22UF,4V,20%,X6S,CH622KMEA03  I71  PC576_5
   1 PVDDCR_CPU0_P0      A @T6G_MB_LIB.T6G(SCH_1):PVDDCR_CPU0_P0
   2    GND      B @T6G_MB_LIB.T6G(SCH_1):GND

ISL99390FRZTR5935-ISL99390FRZ-TR5935,SMLF,IC,AL099A  I73  PU10
  34 PVDDCR_CPU0_P0_PWM6    PWM @T6G_MB_LIB.T6G(SCH_1):PVDDCR_CPU0_P0_PWM6
  39 PVDDCR_CPU0_P0_VCCS  REFIN @T6G_MB_LIB.T6G(SCH_1):PVDDCR_CPU0_P0_VCCS
   3 PVDDCR_CPU0_P0_VCC6    VCC @T6G_MB_LIB.T6G(SCH_1):PVDDCR_CPU0_P0_VCC6
   2    GND   AGND @T6G_MB_LIB.T6G(SCH_1):GND
  33 SW_PVDDCR_CPU0_P0_BOOT6   BOOT @T6G_MB_LIB.T6G(SCH_1):SW_PVDDCR_CPU0_P0_BOOT6
25_29 SW_P12V_AUX_PVDDCR_CPU0_P0_FLT   VIN1 @T6G_MB_LIB.T6G(SCH_1):SW_P12V_AUX_PVDDCR_CPU0_P0_FLT
  32 SW_PVDDCR_CPU0_P0_PH6  PHASE @T6G_MB_LIB.T6G(SCH_1):SW_PVDDCR_CPU0_P0_PH6
   4 PVDDCR_CPU0_P0_PVCC   PVCC @T6G_MB_LIB.T6G(SCH_1):PVDDCR_CPU0_P0_PVCC
  36 PVDDCR_CPU0_P0_TEMP0 TOUT_FLT @T6G_MB_LIB.T6G(SCH_1):PVDDCR_CPU0_P0_TEMP0
  38 PVDDCR_CPU0_P0_IMON6   IOUT @T6G_MB_LIB.T6G(SCH_1):PVDDCR_CPU0_P0_IMON6
  37 PVDDCR_CPU0_P0_LSET6   LSET @T6G_MB_LIB.T6G(SCH_1):PVDDCR_CPU0_P0_LSET6
10_19 SW_PVDDCR_CPU0_P0_SW6     SW @T6G_MB_LIB.T6G(SCH_1):SW_PVDDCR_CPU0_P0_SW6
   5    GND  PGND1 @T6G_MB_LIB.T6G(SCH_1):GND
  30 SW_P12V_AUX_PVDDCR_CPU0_P0_FLT   VIN2 @T6G_MB_LIB.T6G(SCH_1):SW_P12V_AUX_PVDDCR_CPU0_P0_FLT
   1 PVDDCR_CPU0_P0_VOS6    VOS @T6G_MB_LIB.T6G(SCH_1):PVDDCR_CPU0_P0_VOS6
  40    GND  PGND3 @T6G_MB_LIB.T6G(SCH_1):GND
  35 PVDDCR_CPU0_P0_VCC6     EN @T6G_MB_LIB.T6G(SCH_1):PVDDCR_CPU0_P0_VCC6
  31 NC_PVDDCR_CPU0_P0_DNC6    DNC @T6G_MB_LIB.T6G(SCH_1):NC_PVDDCR_CPU0_P0_DNC6
   6 NC_PVDDCR_CPU0_P0_GL1_6    GL1 @T6G_MB_LIB.T6G(SCH_1):NC_PVDDCR_CPU0_P0_GL1_6
  41 NC_PVDDCR_CPU0_P0_GL2_6    GL2 @T6G_MB_LIB.T6G(SCH_1):NC_PVDDCR_CPU0_P0_GL2_6
7_9-20_24    GND  PGND2 @T6G_MB_LIB.T6G(SCH_1):GND


DRAWING: @T6G_MB_LIB.T6G(SCH_1):PAGE175 

Q_RES_0402LF-0,5%,1/16W,CHIP,CS00002JB13  I2  R8047
   1 PVDDIO_P0_EN      A @T6G_MB_LIB.T6G(SCH_1):PVDDIO_P0_EN
   2 PVDDIO_P0_EN_R      B @T6G_MB_LIB.T6G(SCH_1):PVDDIO_P0_EN_R

Q_CAP_0402-1000PF,50V,5%,X7R,TMP_QCH21006JB10  I3  C8066
   1 PVDDIO_P0_EN_R      A @T6G_MB_LIB.T6G(SCH_1):PVDDIO_P0_EN_R
   2    GND      B @T6G_MB_LIB.T6G(SCH_1):GND

MOSFET_N_SMLF-BSS138K,BSS138K,IC,BAM138K0000  I6  PQ14
   G PVDDIO_P0_EN_R   GATE @T6G_MB_LIB.T6G(SCH_1):PVDDIO_P0_EN_R
   D PVDDIO_P0_EN_G  DRAIN @T6G_MB_LIB.T6G(SCH_1):PVDDIO_P0_EN_G
   S    GND SOURCE @T6G_MB_LIB.T6G(SCH_1):GND

Q_RES_0402LF-10K,1%,1/16W,CHIP,CS31002FB08  I8  PR54
   1 PVDDCR_CPU1_P0_VMON      A @T6G_MB_LIB.T6G(SCH_1):PVDDCR_CPU1_P0_VMON
   2    GND      B @T6G_MB_LIB.T6G(SCH_1):GND

Q_RES_0402LF-40.2K,1%,1/16W,CHIP,CS34022FB04  I9  PR53
   1 P5V_AUX      A @T6G_MB_LIB.T6G(SCH_1):P5V_AUX
   2 PVDDCR_CPU1_P0_VMON      B @T6G_MB_LIB.T6G(SCH_1):PVDDCR_CPU1_P0_VMON

Q_RES_0402LF-1.96K,1%,1/16W,CHIP,CS21962FB05  I12  PR67
   1 PVDDCR_CPU1_P0_EN1_ADDR_CFG      A @T6G_MB_LIB.T6G(SCH_1):PVDDCR_CPU1_P0_EN1_ADDR_CFG
   2    GND      B @T6G_MB_LIB.T6G(SCH_1):GND

MOSFET_PCH_GDS_ESD_PROTECTED-PJA3415AE,SMLF,IC,BAMA  I13  PQ10
   D PVDDCR_CPU1_P0_EN1_ADDR_CFG      D @T6G_MB_LIB.T6G(SCH_1):PVDDCR_CPU1_P0_EN1_ADDR_CFG
   G PVDDIO_P0_EN_G      G @T6G_MB_LIB.T6G(SCH_1):PVDDIO_P0_EN_G
   S P3V3_AUX      S @T6G_MB_LIB.T6G(SCH_1):P3V3_AUX

Q_RES_0402LF-1K,1%,1/16W,CHIP,CS21002FB06  I17  PR55
   1 P3V3_AUX      A @T6G_MB_LIB.T6G(SCH_1):P3V3_AUX
   2 PVDDIO_P0_EN_G      B @T6G_MB_LIB.T6G(SCH_1):PVDDIO_P0_EN_G

Q_RES_0402LF-49.9,1%,1/16W,CHIP,CS04992FB07  I19  PR50
   1 VSENSE_VSS_SENSE_B_P0      A @T6G_MB_LIB.T6G(SCH_1):VSENSE_VSS_SENSE_B_P0
   2    GND      B @T6G_MB_LIB.T6G(SCH_1):GND

Q_RES_0402LF-49.9,1%,1/16W,CHIP,CS04992FB07  I22  PR52
   1 VSENSE_PVDDIO_P0_DP      A @T6G_MB_LIB.T6G(SCH_1):VSENSE_PVDDIO_P0_DP
   2 PVDDIO_P0      B @T6G_MB_LIB.T6G(SCH_1):PVDDIO_P0

Q_RES_0402LF-49.9,1%,1/16W,CHIP,CS04992FB07  I23  PR49
   1 VSENSE_VSS_SENSE_C_P0      A @T6G_MB_LIB.T6G(SCH_1):VSENSE_VSS_SENSE_C_P0
   2    GND      B @T6G_MB_LIB.T6G(SCH_1):GND

Q_RES_0402LF-0,5%,1/16W,CHIP,CS00002JB13  I28  PR40
   1 SVID_PVDDCR_CPU1_P0_SVTI      A @T6G_MB_LIB.T6G(SCH_1):SVID_PVDDCR_CPU1_P0_SVTI
   2    GND      B @T6G_MB_LIB.T6G(SCH_1):GND

Q_RES_0402LF-1K,1%,1/16W,EMPTY,CS21002FB06  I32  R8042
   1 SVID_PVDDCR_CPU1_P0_SVTO      A @T6G_MB_LIB.T6G(SCH_1):SVID_PVDDCR_CPU1_P0_SVTO
   2    GND      B @T6G_MB_LIB.T6G(SCH_1):GND

Q_CAP_0402-10PF,50V,5%,EMPTY,CH01006JB08  I33  C303
   1 SVID_PVDDCR_CPU1_P0_SVTO      A @T6G_MB_LIB.T6G(SCH_1):SVID_PVDDCR_CPU1_P0_SVTO
   2    GND      B @T6G_MB_LIB.T6G(SCH_1):GND

Q_CAP_0402-10PF,50V,5%,EMPTY,CH01006JB08  I34  C304
   1 SVID_PVDDCR_CPU1_P0_SVD_R      A @T6G_MB_LIB.T6G(SCH_1):SVID_PVDDCR_CPU1_P0_SVD_R
   2    GND      B @T6G_MB_LIB.T6G(SCH_1):GND

Q_CAP_0402-10PF,50V,5%,EMPTY,CH01006JB08  I35  C305
   1 SVID_PVDDCR_CPU1_P0_SVC_R      A @T6G_MB_LIB.T6G(SCH_1):SVID_PVDDCR_CPU1_P0_SVC_R
   2    GND      B @T6G_MB_LIB.T6G(SCH_1):GND

Q_RES_0402LF-49.9,1%,1/16W,CHIP,CS04992FB07  I36  PR51
   1 VSENSE_PVDDCR_CPU1_P0_DP      A @T6G_MB_LIB.T6G(SCH_1):VSENSE_PVDDCR_CPU1_P0_DP
   2 PVDDCR_CPU1_P0      B @T6G_MB_LIB.T6G(SCH_1):PVDDCR_CPU1_P0

Q_RES_0402LF-1K,1%,1/16W,EMPTY,CS21002FB06  I40  PR41
   1 PVDD18_S5_P0      A @T6G_MB_LIB.T6G(SCH_1):PVDD18_S5_P0
   2 SVID_PVDDCR_CPU1_P0_SVTI      B @T6G_MB_LIB.T6G(SCH_1):SVID_PVDDCR_CPU1_P0_SVTI

Q_RES_0402LF-1K,1%,1/16W,EMPTY,CS21002FB06  I42  R8043
   1 PVDD18_S5_P0      A @T6G_MB_LIB.T6G(SCH_1):PVDD18_S5_P0
   2 SVID_PVDDCR_CPU1_P0_SVTO      B @T6G_MB_LIB.T6G(SCH_1):SVID_PVDDCR_CPU1_P0_SVTO

Q_RES_0402LF-1K,1%,1/16W,EMPTY,CS21002FB06  I43  R8045
   1 PVDD18_S5_P0      A @T6G_MB_LIB.T6G(SCH_1):PVDD18_S5_P0
   2 SVID_PVDDCR_CPU1_P0_SVD_R      B @T6G_MB_LIB.T6G(SCH_1):SVID_PVDDCR_CPU1_P0_SVD_R

Q_RES_0402LF-1K,1%,1/16W,EMPTY,CS21002FB06  I44  R8048
   1 PVDD18_S5_P0      A @T6G_MB_LIB.T6G(SCH_1):PVDD18_S5_P0
   2 SVID_PVDDCR_CPU1_P0_SVC_R      B @T6G_MB_LIB.T6G(SCH_1):SVID_PVDDCR_CPU1_P0_SVC_R

Q_CAP_0402-0.1UF,25V,10%,X7R,CH4104K1B00  I50  PC67
   1 PVDDCR_CPU1_P0_VMON      A @T6G_MB_LIB.T6G(SCH_1):PVDDCR_CPU1_P0_VMON
   2    GND      B @T6G_MB_LIB.T6G(SCH_1):GND

Q_RES_0402LF-0,5%,1/16W,CHIP,CS00002JB13  I51  PR74
   1 P12V_AUX      A @T6G_MB_LIB.T6G(SCH_1):P12V_AUX
   2 PVDDCR_CPU1_P0_VINSEN      B @T6G_MB_LIB.T6G(SCH_1):PVDDCR_CPU1_P0_VINSEN

Q_RES_0402LF-33,5%,1/16W,CHIP,CS03302JB10  I53  R8066
   1 PWRGD_PVDDIO_P0      A @T6G_MB_LIB.T6G(SCH_1):PWRGD_PVDDIO_P0
   2 PWRGD_PVDDIO_P0_R      B @T6G_MB_LIB.T6G(SCH_1):PWRGD_PVDDIO_P0_R

Q_RES_0402LF-1K,1%,1/16W,CHIP,CS21002FB06  I54  R8065
   1 P3V3_AUX      A @T6G_MB_LIB.T6G(SCH_1):P3V3_AUX
   2 PWRGD_PVDDIO_P0_R      B @T6G_MB_LIB.T6G(SCH_1):PWRGD_PVDDIO_P0_R

Q_CAP_0402-1000PF,50V,5%,EMPTY,TMP_QCH21006JB10  I55  C8072
   1 PWRGD_PVDDIO_P0_R      A @T6G_MB_LIB.T6G(SCH_1):PWRGD_PVDDIO_P0_R
   2    GND      B @T6G_MB_LIB.T6G(SCH_1):GND

Q_RES_0402LF-4.99K,1%,1/16W,EMPTY,CS24992FB07  I59  PR600
   1 PVDDCR_CPU1_P0_VINSEN      A @T6G_MB_LIB.T6G(SCH_1):PVDDCR_CPU1_P0_VINSEN
   2    GND      B @T6G_MB_LIB.T6G(SCH_1):GND

Q_CAP_0402-0.1UF,25V,10%,X7R,CH4104K1B00  I60  PC74
   1 PVDDCR_CPU1_P0_VINSEN      A @T6G_MB_LIB.T6G(SCH_1):PVDDCR_CPU1_P0_VINSEN
   2    GND      B @T6G_MB_LIB.T6G(SCH_1):GND

Q_CAP_0402-1UF,6.3V,10%,X7R,CH5101K1B01  I63  PC73
   1 PVDD18_S5_P0      A @T6G_MB_LIB.T6G(SCH_1):PVDD18_S5_P0
   2    GND      B @T6G_MB_LIB.T6G(SCH_1):GND

Q_RES_0402LF-0,5%,1/16W,CHIP,CS00002JB13  I66  R8064
   1 PVDDCR_CPU1_P0_OCP_N      A @T6G_MB_LIB.T6G(SCH_1):PVDDCR_CPU1_P0_OCP_N
   2 PVDDCR_CPU1_P0_OCP_N_R      B @T6G_MB_LIB.T6G(SCH_1):PVDDCR_CPU1_P0_OCP_N_R

Q_RES_0402LF-100,1%,1/16W,CHIP,CS11002FB07  I67  R8063
   1 PVDDCR_CPU1_P0_RESET_N      A @T6G_MB_LIB.T6G(SCH_1):PVDDCR_CPU1_P0_RESET_N
   2 PVDDCR_CPU1_P0_RESET_N_R      B @T6G_MB_LIB.T6G(SCH_1):PVDDCR_CPU1_P0_RESET_N_R

Q_RES_0402LF-1K,1%,1/16W,CHIP,CS21002FB06  I68  R8070
   1 PVDD18_S5_P0      A @T6G_MB_LIB.T6G(SCH_1):PVDD18_S5_P0
   2 PVDDCR_CPU1_P0_RESET_N_R      B @T6G_MB_LIB.T6G(SCH_1):PVDDCR_CPU1_P0_RESET_N_R

Q_CAP_0402-3300PF,50V,10%,X7R,TMP_QCH2336K1B12  I69  PC71
   1 VSENSE_PVDDIO_P0_VSEN1      A @T6G_MB_LIB.T6G(SCH_1):VSENSE_PVDDIO_P0_VSEN1
   2 VSENSE_VSS_SENSE_B_P0      B @T6G_MB_LIB.T6G(SCH_1):VSENSE_VSS_SENSE_B_P0

Q_RES_0402LF-0,5%,1/16W,CHIP,CS00002JB13  I70  PR69
   1 VSENSE_PVDDIO_P0_DP      A @T6G_MB_LIB.T6G(SCH_1):VSENSE_PVDDIO_P0_DP
   2 VSENSE_PVDDIO_P0_VSEN1      B @T6G_MB_LIB.T6G(SCH_1):VSENSE_PVDDIO_P0_VSEN1

Q_RES_0402LF-1K,1%,1/16W,CHIP,CS21002FB06  I71  R8075
   1 PVDD18_S5_P0      A @T6G_MB_LIB.T6G(SCH_1):PVDD18_S5_P0
   2 PVDDCR_CPU1_P0_OCP_N_R      B @T6G_MB_LIB.T6G(SCH_1):PVDDCR_CPU1_P0_OCP_N_R

Q_CAP_0402-470PF,50V,10%,X7R,TMP_QCH14706KB18  I73  PC78
   1 PVDDCR_CPU1_P0_TEMP0      A @T6G_MB_LIB.T6G(SCH_1):PVDDCR_CPU1_P0_TEMP0
   2    GND      B @T6G_MB_LIB.T6G(SCH_1):GND

Q_CAP_0402-470PF,50V,10%,X7R,TMP_QCH14706KB18  I75  PC77
   1 PVDDIO_P0_TEMP1      A @T6G_MB_LIB.T6G(SCH_1):PVDDIO_P0_TEMP1
   2    GND      B @T6G_MB_LIB.T6G(SCH_1):GND

Q_RES_0402LF-0,5%,1/16W,CHIP,CS00002JB13  I76  PR532
   1 NC_PVDDCR_CPU1_P0_IMON7      A @T6G_MB_LIB.T6G(SCH_1):NC_PVDDCR_CPU1_P0_IMON7
   2    GND      B @T6G_MB_LIB.T6G(SCH_1):GND

Q_RES_0402LF-0,5%,1/16W,CHIP,CS00002JB13  I77  PR32
   1 NC_PVDDCR_CPU1_P0_IMON8      A @T6G_MB_LIB.T6G(SCH_1):NC_PVDDCR_CPU1_P0_IMON8
   2    GND      B @T6G_MB_LIB.T6G(SCH_1):GND

Q_RES_0402LF-0,5%,1/16W,CHIP,CS00002JB13  I78  PR68
   1 VSENSE_PVDDCR_CPU1_P0_DP      A @T6G_MB_LIB.T6G(SCH_1):VSENSE_PVDDCR_CPU1_P0_DP
   2 VSENSE_PVDDCR_CPU1_P0_VSEN0      B @T6G_MB_LIB.T6G(SCH_1):VSENSE_PVDDCR_CPU1_P0_VSEN0

Q_CAP_0402-3300PF,50V,10%,X7R,TMP_QCH2336K1B12  I80  PC68
   1 VSENSE_PVDDCR_CPU1_P0_VSEN0      A @T6G_MB_LIB.T6G(SCH_1):VSENSE_PVDDCR_CPU1_P0_VSEN0
   2 VSENSE_VSS_SENSE_C_P0      B @T6G_MB_LIB.T6G(SCH_1):VSENSE_VSS_SENSE_C_P0

Q_RES_0402LF-33,5%,1/16W,CHIP,CS03302JB10  I81  R8073
   1 PVDDCR_CPU1_P0_SMB_ALERT      A @T6G_MB_LIB.T6G(SCH_1):PVDDCR_CPU1_P0_SMB_ALERT
   2 PVDDCR_CPU1_P0_SMB_ALERT_R      B @T6G_MB_LIB.T6G(SCH_1):PVDDCR_CPU1_P0_SMB_ALERT_R

Q_RES_0402LF-0,5%,1/16W,CHIP,CS00002JB13  I82  R8072
   1 SMB_SCM_2_R5_SDA      A @T6G_MB_LIB.T6G(SCH_1):SMB_SCM_2_R5_SDA
   2 SMB_DIO_PVDDCR_CPU1_P0_R      B @T6G_MB_LIB.T6G(SCH_1):SMB_DIO_PVDDCR_CPU1_P0_R

Q_RES_0402LF-49.9,1%,1/16W,CHIP,CS04992FB07  I83  R61
   1 SVID_PVDDCR_CPU1_P0_SVTO      A @T6G_MB_LIB.T6G(SCH_1):SVID_PVDDCR_CPU1_P0_SVTO
   2 SVID_PVDDCR_CPU1_P0_SVTO_R      B @T6G_MB_LIB.T6G(SCH_1):SVID_PVDDCR_CPU1_P0_SVTO_R

Q_RES_0402LF-0,5%,1/16W,CHIP,CS00002JB13  I84  PR62
   1 SVID_PVDDCR_CPU1_P0_SVTI      A @T6G_MB_LIB.T6G(SCH_1):SVID_PVDDCR_CPU1_P0_SVTI
   2 SVID_PVDDCR_CPU1_P0_SVTI_R      B @T6G_MB_LIB.T6G(SCH_1):SVID_PVDDCR_CPU1_P0_SVTI_R

Q_RES_0402LF-0,5%,1/16W,CHIP,CS00002JB13  I85  R8071
   1 SMB_SCM_2_R5_SCL      A @T6G_MB_LIB.T6G(SCH_1):SMB_SCM_2_R5_SCL
   2 SMB_CLK_PVDDCR_CPU1_P0_R      B @T6G_MB_LIB.T6G(SCH_1):SMB_CLK_PVDDCR_CPU1_P0_R

Q_CAP_0402-1000PF,50V,5%,X7R,TMP_QCH21006JB10  I86  C8069
   1 PVDDCR_CPU1_P0_EN_R      A @T6G_MB_LIB.T6G(SCH_1):PVDDCR_CPU1_P0_EN_R
   2    GND      B @T6G_MB_LIB.T6G(SCH_1):GND

Q_RES_0402LF-0,5%,1/16W,CHIP,CS00002JB13  I88  R8058
   1 FM_PVDDCR_CPU1_P0_EN      A @T6G_MB_LIB.T6G(SCH_1):FM_PVDDCR_CPU1_P0_EN
   2 PVDDCR_CPU1_P0_EN_R      B @T6G_MB_LIB.T6G(SCH_1):PVDDCR_CPU1_P0_EN_R

Q_RES_0402LF-33,5%,1/16W,CHIP,CS03302JB10  I89  R8057
   1 PWRGD_PVDDCR_CPU1_P0      A @T6G_MB_LIB.T6G(SCH_1):PWRGD_PVDDCR_CPU1_P0
   2 PWRGD_PVDDCR_CPU1_P0_R      B @T6G_MB_LIB.T6G(SCH_1):PWRGD_PVDDCR_CPU1_P0_R

Q_RES_0402LF-1K,1%,1/16W,CHIP,CS21002FB06  I90  R8056
   1 P3V3_AUX      A @T6G_MB_LIB.T6G(SCH_1):P3V3_AUX
   2 PWRGD_PVDDCR_CPU1_P0_R      B @T6G_MB_LIB.T6G(SCH_1):PWRGD_PVDDCR_CPU1_P0_R

Q_CAP_0402-1000PF,50V,5%,EMPTY,TMP_QCH21006JB10  I91  C8070
   1 PWRGD_PVDDCR_CPU1_P0_R      A @T6G_MB_LIB.T6G(SCH_1):PWRGD_PVDDCR_CPU1_P0_R
   2    GND      B @T6G_MB_LIB.T6G(SCH_1):GND

Q_CAP_0402-0.1UF,25V,10%,X7R,CH4104K1B00  I94  PC15
   1 PVDDCR_CPU1_P0_VCCS      A @T6G_MB_LIB.T6G(SCH_1):PVDDCR_CPU1_P0_VCCS
   2    GND      B @T6G_MB_LIB.T6G(SCH_1):GND

Q_CAP_0402-0.1UF,25V,10%,X7R,CH4104K1B00  I96  PC14
   1 PVDDCR_CPU1_P0_VCC      A @T6G_MB_LIB.T6G(SCH_1):PVDDCR_CPU1_P0_VCC
   2    GND      B @T6G_MB_LIB.T6G(SCH_1):GND

Q_CAP_C0402-10UF,6.3V,20%,X6S,CH6101MEB03  I98  PC76
   1 PVDDCR_CPU1_P0_VCCS      A @T6G_MB_LIB.T6G(SCH_1):PVDDCR_CPU1_P0_VCCS
   2    GND      B @T6G_MB_LIB.T6G(SCH_1):GND

Q_CAP_C0402-1UF,16V,10%,X6S,CH5103KEB01  I100  PC75
   1 PVDDCR_CPU1_P0_VCC      A @T6G_MB_LIB.T6G(SCH_1):PVDDCR_CPU1_P0_VCC
   2    GND      B @T6G_MB_LIB.T6G(SCH_1):GND

Q_RES_0402LF-1,1%,1/16W,CHIP,CS-1002FB04  I126  PR76
   1 PVDDCR_CPU1_P0_VCC      A @T6G_MB_LIB.T6G(SCH_1):PVDDCR_CPU1_P0_VCC
   2 P3V3_AUX      B @T6G_MB_LIB.T6G(SCH_1):P3V3_AUX

RAA229620GNPHA0-RAA229620GNP#HA0,SMLF,IC,ARF0TGP40A  I128  PU12
  27 PVDDCR_CPU1_P0_IMON1   CS11 @T6G_MB_LIB.T6G(SCH_1):PVDDCR_CPU1_P0_IMON1
  47 PVDDCR_CPU1_P0_VCC    VCC @T6G_MB_LIB.T6G(SCH_1):PVDDCR_CPU1_P0_VCC
  24 SVID_PVDDCR_CPU1_P0_SVTI_R   SVTI @T6G_MB_LIB.T6G(SCH_1):SVID_PVDDCR_CPU1_P0_SVTI_R
  14 SMB_CLK_PVDDCR_CPU1_P0_R  PMSCL @T6G_MB_LIB.T6G(SCH_1):SMB_CLK_PVDDCR_CPU1_P0_R
  22 SVID_PVDDCR_CPU1_P0_SVC_R1    SVC @T6G_MB_LIB.T6G(SCH_1):SVID_PVDDCR_CPU1_P0_SVC_R1
  32 PVDDCR_CPU1_P0_IMON6    CS6 @T6G_MB_LIB.T6G(SCH_1):PVDDCR_CPU1_P0_IMON6
  23 SVID_PVDDCR_CPU1_P0_SVTO_R   SVTO @T6G_MB_LIB.T6G(SCH_1):SVID_PVDDCR_CPU1_P0_SVTO_R
  18 PVDDCR_CPU1_P0_RESET_N_R RESET_L @T6G_MB_LIB.T6G(SCH_1):PVDDCR_CPU1_P0_RESET_N_R
  33 NC_PVDDCR_CPU1_P0_IMON7    CS5 @T6G_MB_LIB.T6G(SCH_1):NC_PVDDCR_CPU1_P0_IMON7
  34 NC_PVDDCR_CPU1_P0_IMON8    CS4 @T6G_MB_LIB.T6G(SCH_1):NC_PVDDCR_CPU1_P0_IMON8
  20 PWRGD_PVDDIO_P0_R    PG1 @T6G_MB_LIB.T6G(SCH_1):PWRGD_PVDDIO_P0_R
  21 SVID_PVDDCR_CPU1_P0_SVD_R1    SVD @T6G_MB_LIB.T6G(SCH_1):SVID_PVDDCR_CPU1_P0_SVD_R1
  15 PVDDCR_CPU1_P0_SMB_ALERT_R NPMALERT @T6G_MB_LIB.T6G(SCH_1):PVDDCR_CPU1_P0_SMB_ALERT_R
  17 PVDDCR_CPU1_P0_EN_R    EN0 @T6G_MB_LIB.T6G(SCH_1):PVDDCR_CPU1_P0_EN_R
  26 VSENSE_VSS_SENSE_C_P0  RGND0 @T6G_MB_LIB.T6G(SCH_1):VSENSE_VSS_SENSE_C_P0
  13 SMB_DIO_PVDDCR_CPU1_P0_R  PMSDA @T6G_MB_LIB.T6G(SCH_1):SMB_DIO_PVDDCR_CPU1_P0_R
   5 NC_PVDDCR_CPU1_P0_PWM8   PWM4 @T6G_MB_LIB.T6G(SCH_1):NC_PVDDCR_CPU1_P0_PWM8
   6 NC_PVDDCR_CPU1_P0_PWM7   PWM5 @T6G_MB_LIB.T6G(SCH_1):NC_PVDDCR_CPU1_P0_PWM7
  25 VSENSE_PVDDCR_CPU1_P0_VSEN0  VSEN0 @T6G_MB_LIB.T6G(SCH_1):VSENSE_PVDDCR_CPU1_P0_VSEN0
   2 PVDDIO_P0_PWM2   PWM1 @T6G_MB_LIB.T6G(SCH_1):PVDDIO_P0_PWM2
  16 PWRGD_PVDDCR_CPU1_P0_R    PG0 @T6G_MB_LIB.T6G(SCH_1):PWRGD_PVDDCR_CPU1_P0_R
   7 PVDDCR_CPU1_P0_PWM6   PWM6 @T6G_MB_LIB.T6G(SCH_1):PVDDCR_CPU1_P0_PWM6
  48 PVDDCR_CPU1_P0_VCCS   VCCS @T6G_MB_LIB.T6G(SCH_1):PVDDCR_CPU1_P0_VCCS
  45 PVDDCR_CPU1_P0_VMON VMON||IINSEN @T6G_MB_LIB.T6G(SCH_1):PVDDCR_CPU1_P0_VMON
  46 PVDDCR_CPU1_P0_VINSEN VINSEN @T6G_MB_LIB.T6G(SCH_1):PVDDCR_CPU1_P0_VINSEN
  44 PVDDCR_CPU1_P0_TEMP0  TEMP0 @T6G_MB_LIB.T6G(SCH_1):PVDDCR_CPU1_P0_TEMP0
  19 PVDD18_S5_P0  VDDIO @T6G_MB_LIB.T6G(SCH_1):PVDD18_S5_P0
  40 VSENSE_PVDDIO_P0_VSEN1  VSEN1 @T6G_MB_LIB.T6G(SCH_1):VSENSE_PVDDIO_P0_VSEN1
  39 VSENSE_VSS_SENSE_B_P0  RGND1 @T6G_MB_LIB.T6G(SCH_1):VSENSE_VSS_SENSE_B_P0
  37 PVDDIO_P0_IMON2    CS1 @T6G_MB_LIB.T6G(SCH_1):PVDDIO_P0_IMON2
  12 PVDDCR_CPU1_P0_PWM1  PWM11 @T6G_MB_LIB.T6G(SCH_1):PVDDCR_CPU1_P0_PWM1
   4 PVDDIO_P0_PWM4   PWM3 @T6G_MB_LIB.T6G(SCH_1):PVDDIO_P0_PWM4
  35 PVDDIO_P0_IMON4    CS3 @T6G_MB_LIB.T6G(SCH_1):PVDDIO_P0_IMON4
   3 PVDDIO_P0_PWM3   PWM2 @T6G_MB_LIB.T6G(SCH_1):PVDDIO_P0_PWM3
  36 PVDDIO_P0_IMON3    CS2 @T6G_MB_LIB.T6G(SCH_1):PVDDIO_P0_IMON3
  41 PVDDCR_CPU1_P0_OCP_N_R  OCP_L @T6G_MB_LIB.T6G(SCH_1):PVDDCR_CPU1_P0_OCP_N_R
  TH    GND TH_GND @T6G_MB_LIB.T6G(SCH_1):GND
  42 PVDDCR_CPU1_P0_EN1_ADDR_CFG EN1||ADDR_CFG @T6G_MB_LIB.T6G(SCH_1):PVDDCR_CPU1_P0_EN1_ADDR_CFG
  43 PVDDIO_P0_TEMP1  TEMP1 @T6G_MB_LIB.T6G(SCH_1):PVDDIO_P0_TEMP1
   1 PVDDIO_P0_PWM1   PWM0 @T6G_MB_LIB.T6G(SCH_1):PVDDIO_P0_PWM1
  38 PVDDIO_P0_IMON1    CS0 @T6G_MB_LIB.T6G(SCH_1):PVDDIO_P0_IMON1
   8 PVDDCR_CPU1_P0_PWM5   PWM7 @T6G_MB_LIB.T6G(SCH_1):PVDDCR_CPU1_P0_PWM5
  31 PVDDCR_CPU1_P0_IMON5    CS7 @T6G_MB_LIB.T6G(SCH_1):PVDDCR_CPU1_P0_IMON5
   9 PVDDCR_CPU1_P0_PWM4   PWM8 @T6G_MB_LIB.T6G(SCH_1):PVDDCR_CPU1_P0_PWM4
  30 PVDDCR_CPU1_P0_IMON4    CS8 @T6G_MB_LIB.T6G(SCH_1):PVDDCR_CPU1_P0_IMON4
  10 PVDDCR_CPU1_P0_PWM3   PWM9 @T6G_MB_LIB.T6G(SCH_1):PVDDCR_CPU1_P0_PWM3
  29 PVDDCR_CPU1_P0_IMON3    CS9 @T6G_MB_LIB.T6G(SCH_1):PVDDCR_CPU1_P0_IMON3
  11 PVDDCR_CPU1_P0_PWM2  PWM10 @T6G_MB_LIB.T6G(SCH_1):PVDDCR_CPU1_P0_PWM2
  28 PVDDCR_CPU1_P0_IMON2   CS10 @T6G_MB_LIB.T6G(SCH_1):PVDDCR_CPU1_P0_IMON2

Q_RES_0402LF-10K,1%,1/16W,EMPTY,CS31002FB08  I129  R6086
   1 PVDDIO_P0_EN_R      A @T6G_MB_LIB.T6G(SCH_1):PVDDIO_P0_EN_R
   2    GND      B @T6G_MB_LIB.T6G(SCH_1):GND

Q_CAP_0402-1000PF,50V,5%,X7R,TMP_QCH21006JB10  I130  C5013
   1 PVDDCR_CPU1_P0_SMB_ALERT      A @T6G_MB_LIB.T6G(SCH_1):PVDDCR_CPU1_P0_SMB_ALERT
   2    GND      B @T6G_MB_LIB.T6G(SCH_1):GND

Q_CAP_0402-1000PF,50V,5%,X7R,TMP_QCH21006JB10  I133  C5005
   1    GND      A @T6G_MB_LIB.T6G(SCH_1):GND
   2 PWRGD_PVDDIO_P0      B @T6G_MB_LIB.T6G(SCH_1):PWRGD_PVDDIO_P0

Q_CAP_0402-1000PF,50V,5%,X7R,TMP_QCH21006JB10  I135  C5004
   1    GND      A @T6G_MB_LIB.T6G(SCH_1):GND
   2 PWRGD_PVDDCR_CPU1_P0      B @T6G_MB_LIB.T6G(SCH_1):PWRGD_PVDDCR_CPU1_P0

Q_RES_0402LF-0,5%,1/16W,CHIP,CS00002JB13  I136  PR8008
   1 SVID_PVDDCR_CPU1_P0_SVD_R      A @T6G_MB_LIB.T6G(SCH_1):SVID_PVDDCR_CPU1_P0_SVD_R
   2 SVID_PVDDCR_CPU1_P0_SVD_R1      B @T6G_MB_LIB.T6G(SCH_1):SVID_PVDDCR_CPU1_P0_SVD_R1

Q_RES_0402LF-0,5%,1/16W,CHIP,CS00002JB13  I137  PR8007
   1 SVID_PVDDCR_CPU1_P0_SVC_R      A @T6G_MB_LIB.T6G(SCH_1):SVID_PVDDCR_CPU1_P0_SVC_R
   2 SVID_PVDDCR_CPU1_P0_SVC_R1      B @T6G_MB_LIB.T6G(SCH_1):SVID_PVDDCR_CPU1_P0_SVC_R1


DRAWING: @T6G_MB_LIB.T6G(SCH_1):PAGE180 

Q_CAP_0402-0.1UF,25V,10%,X7R,CH4104K1B00  I2  PC146_8
   1 PVDDCR_CPU1_P0_VCCS      A @T6G_MB_LIB.T6G(SCH_1):PVDDCR_CPU1_P0_VCCS
   2    GND      B @T6G_MB_LIB.T6G(SCH_1):GND

Q_RES_0402LF-8.87K,1%,1/16W,EMPTY,CS28872FB01  I4  PR97
   1 PVDDIO_P0_LSET2      A @T6G_MB_LIB.T6G(SCH_1):PVDDIO_P0_LSET2
   2    GND      B @T6G_MB_LIB.T6G(SCH_1):GND

Q_CAP_C0402-2.2UF,10V,10%,X6S,CH5222KEB01  I10  PC142
   1 PVDDIO_P0_VCC2      A @T6G_MB_LIB.T6G(SCH_1):PVDDIO_P0_VCC2
   2    GND      B @T6G_MB_LIB.T6G(SCH_1):GND

Q_RES_0402LF-2.2,1%,1/16W,CHIP,CS-2202FB01  I12  PR99
   1 PVDDCR_CPU1_P0_PVCC      A @T6G_MB_LIB.T6G(SCH_1):PVDDCR_CPU1_P0_PVCC
   2 PVDDIO_P0_VCC2      B @T6G_MB_LIB.T6G(SCH_1):PVDDIO_P0_VCC2

Q_CAP_C0402-2.2UF,10V,10%,X6S,CH5222KEB01  I13  PC144_IOP0_2
   1 PVDDCR_CPU1_P0_PVCC      A @T6G_MB_LIB.T6G(SCH_1):PVDDCR_CPU1_P0_PVCC
   2    GND      B @T6G_MB_LIB.T6G(SCH_1):GND

ISL99390FRZTR5935-ISL99390FRZ-TR5935,SMLF,IC,AL099A  I15  PU18
  34 PVDDIO_P0_PWM2    PWM @T6G_MB_LIB.T6G(SCH_1):PVDDIO_P0_PWM2
  39 PVDDCR_CPU1_P0_VCCS  REFIN @T6G_MB_LIB.T6G(SCH_1):PVDDCR_CPU1_P0_VCCS
   3 PVDDIO_P0_VCC2    VCC @T6G_MB_LIB.T6G(SCH_1):PVDDIO_P0_VCC2
   2    GND   AGND @T6G_MB_LIB.T6G(SCH_1):GND
  33 SW_PVDDIO_P0_BOOT2   BOOT @T6G_MB_LIB.T6G(SCH_1):SW_PVDDIO_P0_BOOT2
25_29 SW_P12V_AUX_PVDDIO_P0_FLT   VIN1 @T6G_MB_LIB.T6G(SCH_1):SW_P12V_AUX_PVDDIO_P0_FLT
  32 SW_PVDDIO_P0_BOOTR2  PHASE @T6G_MB_LIB.T6G(SCH_1):SW_PVDDIO_P0_BOOTR2
   4 PVDDCR_CPU1_P0_PVCC   PVCC @T6G_MB_LIB.T6G(SCH_1):PVDDCR_CPU1_P0_PVCC
  36 PVDDIO_P0_TEMP1 TOUT_FLT @T6G_MB_LIB.T6G(SCH_1):PVDDIO_P0_TEMP1
  38 PVDDIO_P0_IMON2   IOUT @T6G_MB_LIB.T6G(SCH_1):PVDDIO_P0_IMON2
  37 PVDDIO_P0_LSET2   LSET @T6G_MB_LIB.T6G(SCH_1):PVDDIO_P0_LSET2
10_19 SW_PVDDIO_P0_SW2     SW @T6G_MB_LIB.T6G(SCH_1):SW_PVDDIO_P0_SW2
   5    GND  PGND1 @T6G_MB_LIB.T6G(SCH_1):GND
  30 SW_P12V_AUX_PVDDIO_P0_FLT   VIN2 @T6G_MB_LIB.T6G(SCH_1):SW_P12V_AUX_PVDDIO_P0_FLT
   1 PVDDIO_P0_VOS2    VOS @T6G_MB_LIB.T6G(SCH_1):PVDDIO_P0_VOS2
  40    GND  PGND3 @T6G_MB_LIB.T6G(SCH_1):GND
  35 PVDDIO_P0_VCC2     EN @T6G_MB_LIB.T6G(SCH_1):PVDDIO_P0_VCC2
  31 NC_PVDDIO_P0_DNC2    DNC @T6G_MB_LIB.T6G(SCH_1):NC_PVDDIO_P0_DNC2
   6 NC_PVDDIO_P0_GL1_2    GL1 @T6G_MB_LIB.T6G(SCH_1):NC_PVDDIO_P0_GL1_2
  41 NC_PVDDIO_P0_GL2_2    GL2 @T6G_MB_LIB.T6G(SCH_1):NC_PVDDIO_P0_GL2_2
7_9-20_24    GND  PGND2 @T6G_MB_LIB.T6G(SCH_1):GND

Q_RES_0402LF-5.6,1%,1/16W,CHIP,CS-5602FB01  I17  PR102
   1 SW_PVDDIO_P0_BOOT2      A @T6G_MB_LIB.T6G(SCH_1):SW_PVDDIO_P0_BOOT2
   2 SW_PVDDIO_P0_BOOT2_R      B @T6G_MB_LIB.T6G(SCH_1):SW_PVDDIO_P0_BOOT2_R

Q_CAP_0402-0.1UF,25V,10%,X7R,CH4104K1B00  I18  PC149_2
   1 SW_P12V_AUX_PVDDIO_P0_FLT      A @T6G_MB_LIB.T6G(SCH_1):SW_P12V_AUX_PVDDIO_P0_FLT
   2    GND      B @T6G_MB_LIB.T6G(SCH_1):GND

Q_CAP_0402-0.1UF,25V,10%,X7R,CH4104K1B00  I20  PC145_7
   1 PVDDCR_CPU1_P0_VCCS      A @T6G_MB_LIB.T6G(SCH_1):PVDDCR_CPU1_P0_VCCS
   2    GND      B @T6G_MB_LIB.T6G(SCH_1):GND

Q_RES_0402LF-8.87K,1%,1/16W,EMPTY,CS28872FB01  I22  PR98
   1 PVDDIO_P0_LSET1      A @T6G_MB_LIB.T6G(SCH_1):PVDDIO_P0_LSET1
   2    GND      B @T6G_MB_LIB.T6G(SCH_1):GND

Q_CAP_C0402-2.2UF,10V,10%,X6S,CH5222KEB01  I28  PC143
   1 PVDDIO_P0_VCC1      A @T6G_MB_LIB.T6G(SCH_1):PVDDIO_P0_VCC1
   2    GND      B @T6G_MB_LIB.T6G(SCH_1):GND

Q_RES_0402LF-2.2,1%,1/16W,CHIP,CS-2202FB01  I29  PR100
   1 PVDDCR_CPU1_P0_PVCC      A @T6G_MB_LIB.T6G(SCH_1):PVDDCR_CPU1_P0_PVCC
   2 PVDDIO_P0_VCC1      B @T6G_MB_LIB.T6G(SCH_1):PVDDIO_P0_VCC1

Q_CAP_C0402-2.2UF,10V,10%,X6S,CH5222KEB01  I31  PC147_IOP0_1
   1 PVDDCR_CPU1_P0_PVCC      A @T6G_MB_LIB.T6G(SCH_1):PVDDCR_CPU1_P0_PVCC
   2    GND      B @T6G_MB_LIB.T6G(SCH_1):GND

Q_RES_0402LF-5.6,1%,1/16W,CHIP,CS-5602FB01  I34  PR101
   1 SW_PVDDIO_P0_BOOT1      A @T6G_MB_LIB.T6G(SCH_1):SW_PVDDIO_P0_BOOT1
   2 SW_PVDDIO_P0_BOOT1_R      B @T6G_MB_LIB.T6G(SCH_1):SW_PVDDIO_P0_BOOT1_R

Q_RES_0402LF-1.5,1%,1/8W,EMPTY,CS-1504FB00  I36  PR223
   1 SW_PVDDIO_P0_SW2_RC      A @T6G_MB_LIB.T6G(SCH_1):SW_PVDDIO_P0_SW2_RC
   2    GND      B @T6G_MB_LIB.T6G(SCH_1):GND

Q_CAP_C0402-560PF,50V,10%,EMPTY,CH1566K1B09  I37  PC159
   1 SW_PVDDIO_P0_SW2      A @T6G_MB_LIB.T6G(SCH_1):SW_PVDDIO_P0_SW2
   2 SW_PVDDIO_P0_SW2_RC      B @T6G_MB_LIB.T6G(SCH_1):SW_PVDDIO_P0_SW2_RC

Q_RES_0402LF-0,5%,1/16W,CHIP,CS00002JB13  I39  PR104
   1 PVDDIO_P0_VOS2      A @T6G_MB_LIB.T6G(SCH_1):PVDDIO_P0_VOS2
   2 PVDDIO_P0      B @T6G_MB_LIB.T6G(SCH_1):PVDDIO_P0

Q_INDUCTOR4P_14-150NH,SMLF,IND,CV+15^0TZ04  I40  PL18
   2 IND_PVDDIO_P0_CPL3      2 @T6G_MB_LIB.T6G(SCH_1):IND_PVDDIO_P0_CPL3
   3 IND_PVDDIO_P0_CPL2      3 @T6G_MB_LIB.T6G(SCH_1):IND_PVDDIO_P0_CPL2
   4 PVDDIO_P0      4 @T6G_MB_LIB.T6G(SCH_1):PVDDIO_P0
   1 SW_PVDDIO_P0_SW2      1 @T6G_MB_LIB.T6G(SCH_1):SW_PVDDIO_P0_SW2

Q_CAP_0402-0.22UF,16V,10%,X7R,CH4223K1B00  I41  PC156
   1 SW_PVDDIO_P0_BOOT2_R      A @T6G_MB_LIB.T6G(SCH_1):SW_PVDDIO_P0_BOOT2_R
   2 SW_PVDDIO_P0_BOOTR2      B @T6G_MB_LIB.T6G(SCH_1):SW_PVDDIO_P0_BOOTR2

Q_CAP_C0402-1UF,25V,10%,X6S,CH5104KEB02  I42  PC151_2
   1 SW_P12V_AUX_PVDDIO_P0_FLT      A @T6G_MB_LIB.T6G(SCH_1):SW_P12V_AUX_PVDDIO_P0_FLT
   2    GND      B @T6G_MB_LIB.T6G(SCH_1):GND

Q_CAP_C0805-22UF,16V,20%,X6S,CH6223MEA01  I43  PC153_2
   1 SW_P12V_AUX_PVDDIO_P0_FLT      A @T6G_MB_LIB.T6G(SCH_1):SW_P12V_AUX_PVDDIO_P0_FLT
   2    GND      B @T6G_MB_LIB.T6G(SCH_1):GND

Q_CAP_C0805-22UF,16V,20%,X6S,CH6223MEA01  I45  PC157_2
   1 SW_P12V_AUX_PVDDIO_P0_FLT      A @T6G_MB_LIB.T6G(SCH_1):SW_P12V_AUX_PVDDIO_P0_FLT
   2    GND      B @T6G_MB_LIB.T6G(SCH_1):GND

Q_CAP_C0805-22UF,16V,20%,X6S,CH6223MEA01  I47  PC159_2
   1 SW_P12V_AUX_PVDDIO_P0_FLT      A @T6G_MB_LIB.T6G(SCH_1):SW_P12V_AUX_PVDDIO_P0_FLT
   2    GND      B @T6G_MB_LIB.T6G(SCH_1):GND

Q_RES_0402LF-0,5%,1/16W,CHIP,CS00002JB13  I49  PR103
   1 PVDDIO_P0_VOS1      A @T6G_MB_LIB.T6G(SCH_1):PVDDIO_P0_VOS1
   2 PVDDIO_P0      B @T6G_MB_LIB.T6G(SCH_1):PVDDIO_P0

Q_CAP_C0805-22UF,4V,20%,X6S,CH622KMEA03  I51  PC168_2
   1 PVDDIO_P0      A @T6G_MB_LIB.T6G(SCH_1):PVDDIO_P0
   2    GND      B @T6G_MB_LIB.T6G(SCH_1):GND

Q_CAP_C0805-22UF,4V,20%,X6S,CH622KMEA03  I53  PC170_2
   1 PVDDIO_P0      A @T6G_MB_LIB.T6G(SCH_1):PVDDIO_P0
   2    GND      B @T6G_MB_LIB.T6G(SCH_1):GND

Q_CAPP_SMLF-470UF,2.5V,20%,EMPTY,CH747LM8825  I54  PC160
   1 PVDDIO_P0      A @T6G_MB_LIB.T6G(SCH_1):PVDDIO_P0
   2    GND      B @T6G_MB_LIB.T6G(SCH_1):GND

Q_CAPP_SMLF-470UF,2.5V,20%,SPCAP,CH747LM8825  I57  PC162
   1 PVDDIO_P0      A @T6G_MB_LIB.T6G(SCH_1):PVDDIO_P0
   2    GND      B @T6G_MB_LIB.T6G(SCH_1):GND

Q_CAPP_SMLF-470UF,2.5V,20%,SPCAP,CH747LM8825  I58  PC165
   1 PVDDIO_P0      A @T6G_MB_LIB.T6G(SCH_1):PVDDIO_P0
   2    GND      B @T6G_MB_LIB.T6G(SCH_1):GND

Q_RES_0402LF-1.5,1%,1/8W,EMPTY,CS-1504FB00  I60  PR221
   1 SW_PVDDIO_P0_SW1_RC      A @T6G_MB_LIB.T6G(SCH_1):SW_PVDDIO_P0_SW1_RC
   2    GND      B @T6G_MB_LIB.T6G(SCH_1):GND

Q_CAP_C0402-560PF,50V,10%,EMPTY,CH1566K1B09  I61  PC158
   1 SW_PVDDIO_P0_SW1      A @T6G_MB_LIB.T6G(SCH_1):SW_PVDDIO_P0_SW1
   2 SW_PVDDIO_P0_SW1_RC      B @T6G_MB_LIB.T6G(SCH_1):SW_PVDDIO_P0_SW1_RC

Q_CAP_0402-0.22UF,16V,10%,X7R,CH4223K1B00  I63  PC155
   1 SW_PVDDIO_P0_BOOT1_R      A @T6G_MB_LIB.T6G(SCH_1):SW_PVDDIO_P0_BOOT1_R
   2 SW_PVDDIO_P0_BOOTR1      B @T6G_MB_LIB.T6G(SCH_1):SW_PVDDIO_P0_BOOTR1

Q_INDUCTOR4P_14-150NH,SMLF,IND,CV+15^0TZ04  I64  PL17
   2 IND_PVDDIO_P0_CPL2      2 @T6G_MB_LIB.T6G(SCH_1):IND_PVDDIO_P0_CPL2
   3    GND      3 @T6G_MB_LIB.T6G(SCH_1):GND
   4 PVDDIO_P0      4 @T6G_MB_LIB.T6G(SCH_1):PVDDIO_P0
   1 SW_PVDDIO_P0_SW1      1 @T6G_MB_LIB.T6G(SCH_1):SW_PVDDIO_P0_SW1

Q_CAP_C0805-22UF,16V,20%,X6S,CH6223MEA01  I66  PC158_1
   1 SW_P12V_AUX_PVDDIO_P0_FLT      A @T6G_MB_LIB.T6G(SCH_1):SW_P12V_AUX_PVDDIO_P0_FLT
   2    GND      B @T6G_MB_LIB.T6G(SCH_1):GND

Q_CAPP_THLF-270UF,16V,20%,OSCON,CC72703MD38  I67  PC164
   1 SW_P12V_AUX_PVDDIO_P0_FLT      A @T6G_MB_LIB.T6G(SCH_1):SW_P12V_AUX_PVDDIO_P0_FLT
   2    GND      B @T6G_MB_LIB.T6G(SCH_1):GND

Q_INDUCTOR_SMLF-50NH/86A,IND,CVA50^0MZ09  I69  PL19
   2 P12V_AUX      2 @T6G_MB_LIB.T6G(SCH_1):P12V_AUX
   1 SW_P12V_AUX_PVDDIO_P0_FLT      1 @T6G_MB_LIB.T6G(SCH_1):SW_P12V_AUX_PVDDIO_P0_FLT

Q_CAP_0402-0.1UF,25V,10%,X7R,CH4104K1B00  I72  PC148
   1 P12V_AUX      A @T6G_MB_LIB.T6G(SCH_1):P12V_AUX
   2    GND      B @T6G_MB_LIB.T6G(SCH_1):GND

Q_CAP_0402-0.1UF,25V,10%,X7R,CH4104K1B00  I73  PC107
   1 PVDDIO_P0      A @T6G_MB_LIB.T6G(SCH_1):PVDDIO_P0
   2    GND      B @T6G_MB_LIB.T6G(SCH_1):GND

Q_CAP_C0805-22UF,4V,20%,X6S,CH622KMEA03  I74  PC166_1
   1 PVDDIO_P0      A @T6G_MB_LIB.T6G(SCH_1):PVDDIO_P0
   2    GND      B @T6G_MB_LIB.T6G(SCH_1):GND

Q_CAP_C0805-22UF,4V,20%,X6S,CH622KMEA03  I75  PC169_1
   1 PVDDIO_P0      A @T6G_MB_LIB.T6G(SCH_1):PVDDIO_P0
   2    GND      B @T6G_MB_LIB.T6G(SCH_1):GND

Q_RES_0402LF-1K,1%,1/16W,CHIP,CS21002FB06  I78  PR410
   1 PVDDIO_P0      A @T6G_MB_LIB.T6G(SCH_1):PVDDIO_P0
   2    GND      B @T6G_MB_LIB.T6G(SCH_1):GND

Q_CAP_C0805-22UF,16V,20%,X6S,CH6223MEA01  I80  PC154_1
   1 SW_P12V_AUX_PVDDIO_P0_FLT      A @T6G_MB_LIB.T6G(SCH_1):SW_P12V_AUX_PVDDIO_P0_FLT
   2    GND      B @T6G_MB_LIB.T6G(SCH_1):GND

Q_CAP_C0805-22UF,16V,20%,X6S,CH6223MEA01  I81  PC152_1
   1 SW_P12V_AUX_PVDDIO_P0_FLT      A @T6G_MB_LIB.T6G(SCH_1):SW_P12V_AUX_PVDDIO_P0_FLT
   2    GND      B @T6G_MB_LIB.T6G(SCH_1):GND

Q_CAP_C0402-1UF,25V,10%,X6S,CH5104KEB02  I82  PC150_1
   1 SW_P12V_AUX_PVDDIO_P0_FLT      A @T6G_MB_LIB.T6G(SCH_1):SW_P12V_AUX_PVDDIO_P0_FLT
   2    GND      B @T6G_MB_LIB.T6G(SCH_1):GND

Q_CAP_0402-0.1UF,25V,10%,X7R,CH4104K1B00  I83  PC148_1
   1 SW_P12V_AUX_PVDDIO_P0_FLT      A @T6G_MB_LIB.T6G(SCH_1):SW_P12V_AUX_PVDDIO_P0_FLT
   2    GND      B @T6G_MB_LIB.T6G(SCH_1):GND

ISL99390FRZTR5935-ISL99390FRZ-TR5935,SMLF,IC,AL099A  I84  PU17
  34 PVDDIO_P0_PWM1    PWM @T6G_MB_LIB.T6G(SCH_1):PVDDIO_P0_PWM1
  39 PVDDCR_CPU1_P0_VCCS  REFIN @T6G_MB_LIB.T6G(SCH_1):PVDDCR_CPU1_P0_VCCS
   3 PVDDIO_P0_VCC1    VCC @T6G_MB_LIB.T6G(SCH_1):PVDDIO_P0_VCC1
   2    GND   AGND @T6G_MB_LIB.T6G(SCH_1):GND
  33 SW_PVDDIO_P0_BOOT1   BOOT @T6G_MB_LIB.T6G(SCH_1):SW_PVDDIO_P0_BOOT1
25_29 SW_P12V_AUX_PVDDIO_P0_FLT   VIN1 @T6G_MB_LIB.T6G(SCH_1):SW_P12V_AUX_PVDDIO_P0_FLT
  32 SW_PVDDIO_P0_BOOTR1  PHASE @T6G_MB_LIB.T6G(SCH_1):SW_PVDDIO_P0_BOOTR1
   4 PVDDCR_CPU1_P0_PVCC   PVCC @T6G_MB_LIB.T6G(SCH_1):PVDDCR_CPU1_P0_PVCC
  36 PVDDIO_P0_TEMP1 TOUT_FLT @T6G_MB_LIB.T6G(SCH_1):PVDDIO_P0_TEMP1
  38 PVDDIO_P0_IMON1   IOUT @T6G_MB_LIB.T6G(SCH_1):PVDDIO_P0_IMON1
  37 PVDDIO_P0_LSET1   LSET @T6G_MB_LIB.T6G(SCH_1):PVDDIO_P0_LSET1
10_19 SW_PVDDIO_P0_SW1     SW @T6G_MB_LIB.T6G(SCH_1):SW_PVDDIO_P0_SW1
   5    GND  PGND1 @T6G_MB_LIB.T6G(SCH_1):GND
  30 SW_P12V_AUX_PVDDIO_P0_FLT   VIN2 @T6G_MB_LIB.T6G(SCH_1):SW_P12V_AUX_PVDDIO_P0_FLT
   1 PVDDIO_P0_VOS1    VOS @T6G_MB_LIB.T6G(SCH_1):PVDDIO_P0_VOS1
  40    GND  PGND3 @T6G_MB_LIB.T6G(SCH_1):GND
  35 PVDDIO_P0_VCC1     EN @T6G_MB_LIB.T6G(SCH_1):PVDDIO_P0_VCC1
  31 NC_PVDDIO_P0_DNC1    DNC @T6G_MB_LIB.T6G(SCH_1):NC_PVDDIO_P0_DNC1
   6 NC_PVDDIO_P0_GL1_1    GL1 @T6G_MB_LIB.T6G(SCH_1):NC_PVDDIO_P0_GL1_1
  41 NC_PVDDIO_P0_GL2_1    GL2 @T6G_MB_LIB.T6G(SCH_1):NC_PVDDIO_P0_GL2_1
7_9-20_24    GND  PGND2 @T6G_MB_LIB.T6G(SCH_1):GND

Q_CAP_C0805-22UF,16V,20%,X6S,CH6223MEA01  I85  PC7000
   1 SW_P12V_AUX_PVDDIO_P0_FLT      A @T6G_MB_LIB.T6G(SCH_1):SW_P12V_AUX_PVDDIO_P0_FLT
   2    GND      B @T6G_MB_LIB.T6G(SCH_1):GND


DRAWING: @T6G_MB_LIB.T6G(SCH_1):PAGE184 

Q_CAP_0402-0.1UF,25V,10%,EMPTY,CH4104K1B00  I4  C674
   1 PVDD18_S5_P0_EN      A @T6G_MB_LIB.T6G(SCH_1):PVDD18_S5_P0_EN
   2    GND      B @T6G_MB_LIB.T6G(SCH_1):GND

Q_CAP_C0402-0.1UF,25V,10%,X6S,CH4104KEB00  I5  PC6001
   1 P12V_AUX      A @T6G_MB_LIB.T6G(SCH_1):P12V_AUX
   2    GND      B @T6G_MB_LIB.T6G(SCH_1):GND

Q_INDUCTOR_SMLF-BLM18SN220TN1D/8000MA,IND,CX220TN1A  I7  PL77
   2 SW_P12V_AUX_PVDD18_S5_P0_FLT      2 @T6G_MB_LIB.T6G(SCH_1):SW_P12V_AUX_PVDD18_S5_P0_FLT
   1 P12V_AUX      1 @T6G_MB_LIB.T6G(SCH_1):P12V_AUX

Q_CAP_C0805-22UF,16V,20%,X6S,CH6223MEA01  I8  PC111
   1 SW_P12V_AUX_PVDD18_S5_P0_FLT      A @T6G_MB_LIB.T6G(SCH_1):SW_P12V_AUX_PVDD18_S5_P0_FLT
   2    GND      B @T6G_MB_LIB.T6G(SCH_1):GND

Q_CAP_C0402-1UF,25V,10%,X6S,CH5104KEB02  I11  PC212
   1 PVDD18_S5_P0_VCC      A @T6G_MB_LIB.T6G(SCH_1):PVDD18_S5_P0_VCC
   2    GND      B @T6G_MB_LIB.T6G(SCH_1):GND

Q_RES_0402LF-0,5%,1/16W,CHIP,CS00002JB13  I12  PR477
   1 P3V3_AUX      A @T6G_MB_LIB.T6G(SCH_1):P3V3_AUX
   2 PVDD18_S5_P0_VCC      B @T6G_MB_LIB.T6G(SCH_1):PVDD18_S5_P0_VCC

Q_RES_0402LF-0,5%,1/16W,CHIP,CS00002JB13  I15  PR417
   1    GND      A @T6G_MB_LIB.T6G(SCH_1):GND
   2 PVDD18_S5_P0_MODE      B @T6G_MB_LIB.T6G(SCH_1):PVDD18_S5_P0_MODE

Q_RES_0402LF-8.66K,1%,1/16W,CHIP,CS28662FB02  I17  PR448
   1 PVDD18_S5_P0_CS      A @T6G_MB_LIB.T6G(SCH_1):PVDD18_S5_P0_CS
   2    GND      B @T6G_MB_LIB.T6G(SCH_1):GND

MPQ8633BGLEC838Z-MPQ8633BGLE-C838-Z,SMLF,IC,AL0086A  I18  PU57
  10 SW_P12V_AUX_PVDD18_S5_P0_FLT   VIN1 @T6G_MB_LIB.T6G(SCH_1):SW_P12V_AUX_PVDD18_S5_P0_FLT
   9 PWRGD_PVDD18_S5_P0  PGOOD @T6G_MB_LIB.T6G(SCH_1):PWRGD_PVDD18_S5_P0
11_18    GND   PGND @T6G_MB_LIB.T6G(SCH_1):GND
   8 PVDD18_S5_P0_EN     EN @T6G_MB_LIB.T6G(SCH_1):PVDD18_S5_P0_EN
   1 SW_PVDD18_S5_P0_BST    BST @T6G_MB_LIB.T6G(SCH_1):SW_PVDD18_S5_P0_BST
   7 PVDD18_S5_P0_FB     FB @T6G_MB_LIB.T6G(SCH_1):PVDD18_S5_P0_FB
   2    GND   AGND @T6G_MB_LIB.T6G(SCH_1):GND
  19 PVDD18_S5_P0_VCC    VCC @T6G_MB_LIB.T6G(SCH_1):PVDD18_S5_P0_VCC
   6 PVDD18_S5_P0_RGND   RGND @T6G_MB_LIB.T6G(SCH_1):PVDD18_S5_P0_RGND
  20 SW_PVDD18_S5_P0_SW     SW @T6G_MB_LIB.T6G(SCH_1):SW_PVDD18_S5_P0_SW
   5 PVDD18_S5_P0_REF TRK_REF @T6G_MB_LIB.T6G(SCH_1):PVDD18_S5_P0_REF
   4 PVDD18_S5_P0_MODE   MODE @T6G_MB_LIB.T6G(SCH_1):PVDD18_S5_P0_MODE
   3 PVDD18_S5_P0_CS     CS @T6G_MB_LIB.T6G(SCH_1):PVDD18_S5_P0_CS
  21 SW_P12V_AUX_PVDD18_S5_P0_FLT   VIN2 @T6G_MB_LIB.T6G(SCH_1):SW_P12V_AUX_PVDD18_S5_P0_FLT

Q_CAP_0402-0.022UF,25V,10%,X7R,CH3224K1B01  I21  PC258
   1 PVDD18_S5_P0_REF      A @T6G_MB_LIB.T6G(SCH_1):PVDD18_S5_P0_REF
   2    GND      B @T6G_MB_LIB.T6G(SCH_1):GND

Q_CAP_0402-0.1UF,25V,10%,X7R,CH4104K1B00  I22  PC113
   1 PVDD18_S5_P0_REF      A @T6G_MB_LIB.T6G(SCH_1):PVDD18_S5_P0_REF
   2 PVDD18_S5_P0_RGND      B @T6G_MB_LIB.T6G(SCH_1):PVDD18_S5_P0_RGND

Q_RES_0402LF-10K,1%,1/16W,CHIP,CS31002FB08  I23  PR470
   1 PVDD18_S5_P0_FB      A @T6G_MB_LIB.T6G(SCH_1):PVDD18_S5_P0_FB
   2 PVDD18_S5_P0_RGND      B @T6G_MB_LIB.T6G(SCH_1):PVDD18_S5_P0_RGND

Q_CAP_0402-0.22UF,16V,10%,X7R,CH4223K1B00  I24  PC209
   1 SW_PVDD18_S5_P0_BST_R      A @T6G_MB_LIB.T6G(SCH_1):SW_PVDD18_S5_P0_BST_R
   2 SW_PVDD18_S5_P0_SW      B @T6G_MB_LIB.T6G(SCH_1):SW_PVDD18_S5_P0_SW

Q_CAP_C0805-22UF,16V,20%,X6S,CH6223MEA01  I25  PC227
   1 SW_P12V_AUX_PVDD18_S5_P0_FLT      A @T6G_MB_LIB.T6G(SCH_1):SW_P12V_AUX_PVDD18_S5_P0_FLT
   2    GND      B @T6G_MB_LIB.T6G(SCH_1):GND

Q_CAP_C0805-22UF,16V,20%,X6S,CH6223MEA01  I26  PC254
   1 SW_P12V_AUX_PVDD18_S5_P0_FLT      A @T6G_MB_LIB.T6G(SCH_1):SW_P12V_AUX_PVDD18_S5_P0_FLT
   2    GND      B @T6G_MB_LIB.T6G(SCH_1):GND

Q_CAP_C0805-22UF,16V,20%,X6S,CH6223MEA01  I27  PC81
   1 SW_P12V_AUX_PVDD18_S5_P0_FLT      A @T6G_MB_LIB.T6G(SCH_1):SW_P12V_AUX_PVDD18_S5_P0_FLT
   2    GND      B @T6G_MB_LIB.T6G(SCH_1):GND

Q_CAP_C0402-1UF,25V,10%,X6S,CH5104KEB02  I28  PC237
   1 SW_P12V_AUX_PVDD18_S5_P0_FLT      A @T6G_MB_LIB.T6G(SCH_1):SW_P12V_AUX_PVDD18_S5_P0_FLT
   2    GND      B @T6G_MB_LIB.T6G(SCH_1):GND

Q_RES_0402LF-10K,5%,1/16W,CHIP,CS31002JB08  I29  R8465
   1 P3V3_AUX      A @T6G_MB_LIB.T6G(SCH_1):P3V3_AUX
   2 PWRGD_PVDD18_S5_P0      B @T6G_MB_LIB.T6G(SCH_1):PWRGD_PVDD18_S5_P0

Q_RES_0402LF-49.9,1%,1/16W,CHIP,CS04992FB07  I31  PR418
   1    GND      A @T6G_MB_LIB.T6G(SCH_1):GND
   2 PVDD18_S5_P0_RGND      B @T6G_MB_LIB.T6G(SCH_1):PVDD18_S5_P0_RGND

Q_CAP_0402-220PF,50V,10%,X7R,TMP_QCH12206KB14  I33  PC259
   1 PVDD18_S5_P0_FB      A @T6G_MB_LIB.T6G(SCH_1):PVDD18_S5_P0_FB
   2 PVDD18_S5_P0_FB_RC      B @T6G_MB_LIB.T6G(SCH_1):PVDD18_S5_P0_FB_RC

Q_CAP_C0402-0.01UF,25V,10%,EMPTY,CH3104K1B11  I34  PC6005
   1 PVDD18_S5_P0_FB_RC      A @T6G_MB_LIB.T6G(SCH_1):PVDD18_S5_P0_FB_RC
   2 PVDD18_S5_P0_RGND      B @T6G_MB_LIB.T6G(SCH_1):PVDD18_S5_P0_RGND

Q_RES_0402LF-20K,1%,1/16W,CHIP,CS32002FB06  I35  PR471
   1 PVDD18_S5_P0_FB      A @T6G_MB_LIB.T6G(SCH_1):PVDD18_S5_P0_FB
   2 PVDD18_S5_P0_FB_RC      B @T6G_MB_LIB.T6G(SCH_1):PVDD18_S5_P0_FB_RC

Q_INDUCTOR_SMLF-1.0UH/18A,IND,CV-10I0MZ01  I36  PL78
   2 PVDD18_S5_P0      2 @T6G_MB_LIB.T6G(SCH_1):PVDD18_S5_P0
   1 SW_PVDD18_S5_P0_SW      1 @T6G_MB_LIB.T6G(SCH_1):SW_PVDD18_S5_P0_SW

Q_RES_0402LF-0,5%,1/16W,CHIP,CS00002JB13  I37  PR435
   1 PVDD18_S5_P0_RGND      A @T6G_MB_LIB.T6G(SCH_1):PVDD18_S5_P0_RGND
   2 VSENSE_PVDD18_S5_P0_DN      B @T6G_MB_LIB.T6G(SCH_1):VSENSE_PVDD18_S5_P0_DN

Q_RES_0402LF-10,1%,1/16W,CHIP,CS01002FB07  I38  PR434
   1 PVDD18_S5_P0_FB_RC      A @T6G_MB_LIB.T6G(SCH_1):PVDD18_S5_P0_FB_RC
   2 VSENSE_PVDD18_S5_P0_DP      B @T6G_MB_LIB.T6G(SCH_1):VSENSE_PVDD18_S5_P0_DP

Q_CAP_C0805-22UF,4V,20%,X6S,CH622KMEA03  I39  PC114
   1 PVDD18_S5_P0      A @T6G_MB_LIB.T6G(SCH_1):PVDD18_S5_P0
   2    GND      B @T6G_MB_LIB.T6G(SCH_1):GND

Q_CAP_C0805-22UF,4V,20%,X6S,CH622KMEA03  I40  PC288
   1 PVDD18_S5_P0      A @T6G_MB_LIB.T6G(SCH_1):PVDD18_S5_P0
   2    GND      B @T6G_MB_LIB.T6G(SCH_1):GND

Q_CAP_C0805-22UF,4V,20%,EMPTY,CH622KMEA03  I41  PC260
   1 PVDD18_S5_P0      A @T6G_MB_LIB.T6G(SCH_1):PVDD18_S5_P0
   2    GND      B @T6G_MB_LIB.T6G(SCH_1):GND

Q_RES_0402LF-49.9,1%,1/16W,CHIP,CS04992FB07  I42  PR438
   1 PVDD18_S5_P0_FB_RC      A @T6G_MB_LIB.T6G(SCH_1):PVDD18_S5_P0_FB_RC
   2 PVDD18_S5_P0      B @T6G_MB_LIB.T6G(SCH_1):PVDD18_S5_P0

Q_CAP_C0805-22UF,4V,20%,EMPTY,CH622KMEA03  I46  PC261
   1 PVDD18_S5_P0      A @T6G_MB_LIB.T6G(SCH_1):PVDD18_S5_P0
   2    GND      B @T6G_MB_LIB.T6G(SCH_1):GND

Q_CAPP_SMLF-390UF,2.5V,20%,ALUM,CC7390JMZ13  I47  PC115
   1 PVDD18_S5_P0      A @T6G_MB_LIB.T6G(SCH_1):PVDD18_S5_P0
   2    GND      B @T6G_MB_LIB.T6G(SCH_1):GND

Q_CAP_0402-0.1UF,25V,10%,X7R,CH4104K1B00  I48  PC215
   1 PVDD18_S5_P0      A @T6G_MB_LIB.T6G(SCH_1):PVDD18_S5_P0
   2    GND      B @T6G_MB_LIB.T6G(SCH_1):GND

Q_RES_0402LF-1K,1%,1/16W,CHIP,CS21002FB06  I51  PR439
   1 PVDD18_S5_P0      A @T6G_MB_LIB.T6G(SCH_1):PVDD18_S5_P0
   2    GND      B @T6G_MB_LIB.T6G(SCH_1):GND

Q_RES_0402LF-33,5%,1/16W,CHIP,CS03302JB10  I52  R177
   1 PWRGD_PVDD18_S5_P0      A @T6G_MB_LIB.T6G(SCH_1):PWRGD_PVDD18_S5_P0
   2 FM_PWRGD_PVDD18_S5_P0      B @T6G_MB_LIB.T6G(SCH_1):FM_PWRGD_PVDD18_S5_P0

Q_CAP_C0805-22UF,4V,20%,X6S,CH622KMEA03  I54  PC285
   1 PVDD18_S5_P0      A @T6G_MB_LIB.T6G(SCH_1):PVDD18_S5_P0
   2    GND      B @T6G_MB_LIB.T6G(SCH_1):GND

Q_CAP_0402-1000PF,50V,5%,X7R,TMP_QCH21006JB10  I56  C5001
   1 FM_PWRGD_PVDD18_S5_P0      A @T6G_MB_LIB.T6G(SCH_1):FM_PWRGD_PVDD18_S5_P0
   2    GND      B @T6G_MB_LIB.T6G(SCH_1):GND

Q_CAP_C0805-22UF,16V,20%,X6S,CH6223MEA01  I57  PC8002
   1 SW_P12V_AUX_PVDD18_S5_P0_FLT      A @T6G_MB_LIB.T6G(SCH_1):SW_P12V_AUX_PVDD18_S5_P0_FLT
   2    GND      B @T6G_MB_LIB.T6G(SCH_1):GND

Q_RES_0402LF-2.2,1%,1/16W,CHIP,CS-2202FB01  I58  PR8001
   1 SW_PVDD18_S5_P0_BST      A @T6G_MB_LIB.T6G(SCH_1):SW_PVDD18_S5_P0_BST
   2 SW_PVDD18_S5_P0_BST_R      B @T6G_MB_LIB.T6G(SCH_1):SW_PVDD18_S5_P0_BST_R


DRAWING: @T6G_MB_LIB.T6G(SCH_1):PAGE187 

Q_CAP_0402-0.1UF,25V,10%,X7R,CH4104K1B00  I2  PC285_4
   1 PVDDCR_CPU0_P1_VCCS      A @T6G_MB_LIB.T6G(SCH_1):PVDDCR_CPU0_P1_VCCS
   2    GND      B @T6G_MB_LIB.T6G(SCH_1):GND

Q_CAP_C0402-2.2UF,10V,10%,X6S,CH5222KEB01  I6  PC287
   1 PVDDCR_CPU0_P1_VCC4      A @T6G_MB_LIB.T6G(SCH_1):PVDDCR_CPU0_P1_VCC4
   2    GND      B @T6G_MB_LIB.T6G(SCH_1):GND

ISL99390FRZTR5935-ISL99390FRZ-TR5935,SMLF,IC,AL099A  I9  PU28
  34 PVDDCR_CPU0_P1_PWM4    PWM @T6G_MB_LIB.T6G(SCH_1):PVDDCR_CPU0_P1_PWM4
  39 PVDDCR_CPU0_P1_VCCS  REFIN @T6G_MB_LIB.T6G(SCH_1):PVDDCR_CPU0_P1_VCCS
   3 PVDDCR_CPU0_P1_VCC4    VCC @T6G_MB_LIB.T6G(SCH_1):PVDDCR_CPU0_P1_VCC4
   2    GND   AGND @T6G_MB_LIB.T6G(SCH_1):GND
  33 SW_PVDDCR_CPU0_P1_BOOT4   BOOT @T6G_MB_LIB.T6G(SCH_1):SW_PVDDCR_CPU0_P1_BOOT4
25_29 SW_P12V_AUX_PVDDCR_CPU0_P1_FLT   VIN1 @T6G_MB_LIB.T6G(SCH_1):SW_P12V_AUX_PVDDCR_CPU0_P1_FLT
  32 SW_PVDDCR_CPU0_P1_PH4  PHASE @T6G_MB_LIB.T6G(SCH_1):SW_PVDDCR_CPU0_P1_PH4
   4 PVDDCR_CPU0_P1_PVCC   PVCC @T6G_MB_LIB.T6G(SCH_1):PVDDCR_CPU0_P1_PVCC
  36 PVDDCR_CPU0_P1_TEMP0 TOUT_FLT @T6G_MB_LIB.T6G(SCH_1):PVDDCR_CPU0_P1_TEMP0
  38 PVDDCR_CPU0_P1_IMON4   IOUT @T6G_MB_LIB.T6G(SCH_1):PVDDCR_CPU0_P1_IMON4
  37 PVDDCR_CPU0_P1_LSET4   LSET @T6G_MB_LIB.T6G(SCH_1):PVDDCR_CPU0_P1_LSET4
10_19 SW_PVDDCR_CPU0_P1_SW4     SW @T6G_MB_LIB.T6G(SCH_1):SW_PVDDCR_CPU0_P1_SW4
   5    GND  PGND1 @T6G_MB_LIB.T6G(SCH_1):GND
  30 SW_P12V_AUX_PVDDCR_CPU0_P1_FLT   VIN2 @T6G_MB_LIB.T6G(SCH_1):SW_P12V_AUX_PVDDCR_CPU0_P1_FLT
   1 PVDDCR_CPU0_P1_VOS4    VOS @T6G_MB_LIB.T6G(SCH_1):PVDDCR_CPU0_P1_VOS4
  40    GND  PGND3 @T6G_MB_LIB.T6G(SCH_1):GND
  35 PVDDCR_CPU0_P1_VCC4     EN @T6G_MB_LIB.T6G(SCH_1):PVDDCR_CPU0_P1_VCC4
  31 NC_PVDDCR_CPU0_P1_DNC4    DNC @T6G_MB_LIB.T6G(SCH_1):NC_PVDDCR_CPU0_P1_DNC4
   6 NC_PVDDCR_CPU0_P1_GL1_4    GL1 @T6G_MB_LIB.T6G(SCH_1):NC_PVDDCR_CPU0_P1_GL1_4
  41 NC_PVDDCR_CPU0_P1_GL2_4    GL2 @T6G_MB_LIB.T6G(SCH_1):NC_PVDDCR_CPU0_P1_GL2_4
7_9-20_24    GND  PGND2 @T6G_MB_LIB.T6G(SCH_1):GND

Q_RES_0402LF-8.87K,1%,1/16W,EMPTY,CS28872FB01  I11  PR196
   1    GND      A @T6G_MB_LIB.T6G(SCH_1):GND
   2 PVDDCR_CPU0_P1_LSET4      B @T6G_MB_LIB.T6G(SCH_1):PVDDCR_CPU0_P1_LSET4

Q_RES_0402LF-2.2,1%,1/16W,CHIP,CS-2202FB01  I12  PR194
   1 PVDDCR_CPU0_P1_PVCC      A @T6G_MB_LIB.T6G(SCH_1):PVDDCR_CPU0_P1_PVCC
   2 PVDDCR_CPU0_P1_VCC4      B @T6G_MB_LIB.T6G(SCH_1):PVDDCR_CPU0_P1_VCC4

Q_CAP_C0402-2.2UF,10V,10%,X6S,CH5222KEB01  I15  PC289_C0P1_4
   1 PVDDCR_CPU0_P1_PVCC      A @T6G_MB_LIB.T6G(SCH_1):PVDDCR_CPU0_P1_PVCC
   2    GND      B @T6G_MB_LIB.T6G(SCH_1):GND

Q_RES_0402LF-0,5%,1/16W,CHIP,CS00002JB13  I17  PR200
   1 PVDDCR_CPU0_P1_VOS4      A @T6G_MB_LIB.T6G(SCH_1):PVDDCR_CPU0_P1_VOS4
   2 PVDDCR_CPU0_P1      B @T6G_MB_LIB.T6G(SCH_1):PVDDCR_CPU0_P1

Q_RES_0402LF-1.5,1%,1/8W,EMPTY,CS-1504FB00  I19  PR523
   1 SW_PVDDCR_CPU0_P1_SW4_RC      A @T6G_MB_LIB.T6G(SCH_1):SW_PVDDCR_CPU0_P1_SW4_RC
   2    GND      B @T6G_MB_LIB.T6G(SCH_1):GND

Q_CAP_C0402-560PF,50V,10%,EMPTY,CH1566K1B09  I20  PC317
   1 SW_PVDDCR_CPU0_P1_SW4      A @T6G_MB_LIB.T6G(SCH_1):SW_PVDDCR_CPU0_P1_SW4
   2 SW_PVDDCR_CPU0_P1_SW4_RC      B @T6G_MB_LIB.T6G(SCH_1):SW_PVDDCR_CPU0_P1_SW4_RC

Q_RES_0402LF-5.6,1%,1/16W,CHIP,CS-5602FB01  I21  PR198
   1 SW_PVDDCR_CPU0_P1_BOOT4      A @T6G_MB_LIB.T6G(SCH_1):SW_PVDDCR_CPU0_P1_BOOT4
   2 SW_PVDDCR_CPU0_P1_BOOT4_RC      B @T6G_MB_LIB.T6G(SCH_1):SW_PVDDCR_CPU0_P1_BOOT4_RC

Q_CAP_0402-0.1UF,25V,10%,X7R,CH4104K1B00  I22  PC293_4
   1 SW_P12V_AUX_PVDDCR_CPU0_P1_FLT      A @T6G_MB_LIB.T6G(SCH_1):SW_P12V_AUX_PVDDCR_CPU0_P1_FLT
   2    GND      B @T6G_MB_LIB.T6G(SCH_1):GND

Q_CAP_C0402-1UF,25V,10%,X6S,CH5104KEB02  I23  PC291_4
   1 SW_P12V_AUX_PVDDCR_CPU0_P1_FLT      A @T6G_MB_LIB.T6G(SCH_1):SW_P12V_AUX_PVDDCR_CPU0_P1_FLT
   2    GND      B @T6G_MB_LIB.T6G(SCH_1):GND

Q_CAP_C0805-22UF,16V,20%,X6S,CH6223MEA01  I24  PC295_4
   1 SW_P12V_AUX_PVDDCR_CPU0_P1_FLT      A @T6G_MB_LIB.T6G(SCH_1):SW_P12V_AUX_PVDDCR_CPU0_P1_FLT
   2    GND      B @T6G_MB_LIB.T6G(SCH_1):GND

Q_CAP_C0805-22UF,16V,20%,X6S,CH6223MEA01  I25  PC297_4
   1 SW_P12V_AUX_PVDDCR_CPU0_P1_FLT      A @T6G_MB_LIB.T6G(SCH_1):SW_P12V_AUX_PVDDCR_CPU0_P1_FLT
   2    GND      B @T6G_MB_LIB.T6G(SCH_1):GND

Q_RES_0402LF-0,5%,1/16W,CHIP,CS00002JB13  I27  PR199
   1 PVDDCR_CPU0_P1_VOS3      A @T6G_MB_LIB.T6G(SCH_1):PVDDCR_CPU0_P1_VOS3
   2 PVDDCR_CPU0_P1      B @T6G_MB_LIB.T6G(SCH_1):PVDDCR_CPU0_P1

Q_CAP_0402-0.1UF,25V,10%,X7R,CH4104K1B00  I28  PC284_3
   1 PVDDCR_CPU0_P1_VCCS      A @T6G_MB_LIB.T6G(SCH_1):PVDDCR_CPU0_P1_VCCS
   2    GND      B @T6G_MB_LIB.T6G(SCH_1):GND

Q_RES_0402LF-8.87K,1%,1/16W,EMPTY,CS28872FB01  I34  PR195
   1    GND      A @T6G_MB_LIB.T6G(SCH_1):GND
   2 PVDDCR_CPU0_P1_LSET3      B @T6G_MB_LIB.T6G(SCH_1):PVDDCR_CPU0_P1_LSET3

Q_CAP_C0402-2.2UF,10V,10%,X6S,CH5222KEB01  I37  PC286
   1 PVDDCR_CPU0_P1_VCC3      A @T6G_MB_LIB.T6G(SCH_1):PVDDCR_CPU0_P1_VCC3
   2    GND      B @T6G_MB_LIB.T6G(SCH_1):GND

Q_RES_0402LF-2.2,1%,1/16W,CHIP,CS-2202FB01  I38  PR193
   1 PVDDCR_CPU0_P1_PVCC      A @T6G_MB_LIB.T6G(SCH_1):PVDDCR_CPU0_P1_PVCC
   2 PVDDCR_CPU0_P1_VCC3      B @T6G_MB_LIB.T6G(SCH_1):PVDDCR_CPU0_P1_VCC3

ISL99390FRZTR5935-ISL99390FRZ-TR5935,SMLF,IC,AL099A  I39  PU27
  34 PVDDCR_CPU0_P1_PWM3    PWM @T6G_MB_LIB.T6G(SCH_1):PVDDCR_CPU0_P1_PWM3
  39 PVDDCR_CPU0_P1_VCCS  REFIN @T6G_MB_LIB.T6G(SCH_1):PVDDCR_CPU0_P1_VCCS
   3 PVDDCR_CPU0_P1_VCC3    VCC @T6G_MB_LIB.T6G(SCH_1):PVDDCR_CPU0_P1_VCC3
   2    GND   AGND @T6G_MB_LIB.T6G(SCH_1):GND
  33 SW_PVDDCR_CPU0_P1_BOOT3   BOOT @T6G_MB_LIB.T6G(SCH_1):SW_PVDDCR_CPU0_P1_BOOT3
25_29 SW_P12V_AUX_PVDDCR_CPU0_P1_FLT   VIN1 @T6G_MB_LIB.T6G(SCH_1):SW_P12V_AUX_PVDDCR_CPU0_P1_FLT
  32 SW_PVDDCR_CPU0_P1_PH3  PHASE @T6G_MB_LIB.T6G(SCH_1):SW_PVDDCR_CPU0_P1_PH3
   4 PVDDCR_CPU0_P1_PVCC   PVCC @T6G_MB_LIB.T6G(SCH_1):PVDDCR_CPU0_P1_PVCC
  36 PVDDCR_CPU0_P1_TEMP0 TOUT_FLT @T6G_MB_LIB.T6G(SCH_1):PVDDCR_CPU0_P1_TEMP0
  38 PVDDCR_CPU0_P1_IMON3   IOUT @T6G_MB_LIB.T6G(SCH_1):PVDDCR_CPU0_P1_IMON3
  37 PVDDCR_CPU0_P1_LSET3   LSET @T6G_MB_LIB.T6G(SCH_1):PVDDCR_CPU0_P1_LSET3
10_19 SW_PVDDCR_CPU0_P1_SW3     SW @T6G_MB_LIB.T6G(SCH_1):SW_PVDDCR_CPU0_P1_SW3
   5    GND  PGND1 @T6G_MB_LIB.T6G(SCH_1):GND
  30 SW_P12V_AUX_PVDDCR_CPU0_P1_FLT   VIN2 @T6G_MB_LIB.T6G(SCH_1):SW_P12V_AUX_PVDDCR_CPU0_P1_FLT
   1 PVDDCR_CPU0_P1_VOS3    VOS @T6G_MB_LIB.T6G(SCH_1):PVDDCR_CPU0_P1_VOS3
  40    GND  PGND3 @T6G_MB_LIB.T6G(SCH_1):GND
  35 PVDDCR_CPU0_P1_VCC3     EN @T6G_MB_LIB.T6G(SCH_1):PVDDCR_CPU0_P1_VCC3
  31 NC_PVDDCR_CPU0_P1_DNC3    DNC @T6G_MB_LIB.T6G(SCH_1):NC_PVDDCR_CPU0_P1_DNC3
   6 NC_PVDDCR_CPU0_P1_GL1_3    GL1 @T6G_MB_LIB.T6G(SCH_1):NC_PVDDCR_CPU0_P1_GL1_3
  41 NC_PVDDCR_CPU0_P1_GL2_3    GL2 @T6G_MB_LIB.T6G(SCH_1):NC_PVDDCR_CPU0_P1_GL2_3
7_9-20_24    GND  PGND2 @T6G_MB_LIB.T6G(SCH_1):GND

Q_CAP_C0402-2.2UF,10V,10%,X6S,CH5222KEB01  I41  PC288_C0P1_3
   1 PVDDCR_CPU0_P1_PVCC      A @T6G_MB_LIB.T6G(SCH_1):PVDDCR_CPU0_P1_PVCC
   2    GND      B @T6G_MB_LIB.T6G(SCH_1):GND

Q_CAP_0402-0.1UF,25V,10%,X7R,CH4104K1B00  I44  PC290_3
   1 SW_P12V_AUX_PVDDCR_CPU0_P1_FLT      A @T6G_MB_LIB.T6G(SCH_1):SW_P12V_AUX_PVDDCR_CPU0_P1_FLT
   2    GND      B @T6G_MB_LIB.T6G(SCH_1):GND

Q_RES_0402LF-1.5,1%,1/8W,EMPTY,CS-1504FB00  I45  PR522
   1 SW_PVDDCR_CPU0_P1_SW3_RC      A @T6G_MB_LIB.T6G(SCH_1):SW_PVDDCR_CPU0_P1_SW3_RC
   2    GND      B @T6G_MB_LIB.T6G(SCH_1):GND

Q_CAP_C0402-560PF,50V,10%,EMPTY,CH1566K1B09  I46  PC316
   1 SW_PVDDCR_CPU0_P1_SW3      A @T6G_MB_LIB.T6G(SCH_1):SW_PVDDCR_CPU0_P1_SW3
   2 SW_PVDDCR_CPU0_P1_SW3_RC      B @T6G_MB_LIB.T6G(SCH_1):SW_PVDDCR_CPU0_P1_SW3_RC

Q_RES_0402LF-5.6,1%,1/16W,CHIP,CS-5602FB01  I47  PR197
   1 SW_PVDDCR_CPU0_P1_BOOT3      A @T6G_MB_LIB.T6G(SCH_1):SW_PVDDCR_CPU0_P1_BOOT3
   2 SW_PVDDCR_CPU0_P1_BOOT3_RC      B @T6G_MB_LIB.T6G(SCH_1):SW_PVDDCR_CPU0_P1_BOOT3_RC

Q_CAP_C0402-1UF,25V,10%,X6S,CH5104KEB02  I48  PC292_3
   1 SW_P12V_AUX_PVDDCR_CPU0_P1_FLT      A @T6G_MB_LIB.T6G(SCH_1):SW_P12V_AUX_PVDDCR_CPU0_P1_FLT
   2    GND      B @T6G_MB_LIB.T6G(SCH_1):GND

Q_CAP_C0805-22UF,16V,20%,X6S,CH6223MEA01  I49  PC294_3
   1 SW_P12V_AUX_PVDDCR_CPU0_P1_FLT      A @T6G_MB_LIB.T6G(SCH_1):SW_P12V_AUX_PVDDCR_CPU0_P1_FLT
   2    GND      B @T6G_MB_LIB.T6G(SCH_1):GND

Q_CAP_C0805-22UF,16V,20%,X6S,CH6223MEA01  I50  PC296_3
   1 SW_P12V_AUX_PVDDCR_CPU0_P1_FLT      A @T6G_MB_LIB.T6G(SCH_1):SW_P12V_AUX_PVDDCR_CPU0_P1_FLT
   2    GND      B @T6G_MB_LIB.T6G(SCH_1):GND

Q_CAP_0402-0.22UF,16V,10%,X7R,CH4223K1B00  I52  PC301
   1 SW_PVDDCR_CPU0_P1_BOOT4_RC      A @T6G_MB_LIB.T6G(SCH_1):SW_PVDDCR_CPU0_P1_BOOT4_RC
   2 SW_PVDDCR_CPU0_P1_PH4      B @T6G_MB_LIB.T6G(SCH_1):SW_PVDDCR_CPU0_P1_PH4

Q_INDUCTOR4P_14-150NH,SMLF,IND,CV+15^0TZ04  I53  PL32
   2 IND_CPU0_P1_CPL3      2 @T6G_MB_LIB.T6G(SCH_1):IND_CPU0_P1_CPL3
   3    GND      3 @T6G_MB_LIB.T6G(SCH_1):GND
   4 PVDDCR_CPU0_P1      4 @T6G_MB_LIB.T6G(SCH_1):PVDDCR_CPU0_P1
   1 SW_PVDDCR_CPU0_P1_SW4      1 @T6G_MB_LIB.T6G(SCH_1):SW_PVDDCR_CPU0_P1_SW4

Q_CAP_C0805-22UF,16V,20%,X6S,CH6223MEA01  I55  PC299_4
   1 SW_P12V_AUX_PVDDCR_CPU0_P1_FLT      A @T6G_MB_LIB.T6G(SCH_1):SW_P12V_AUX_PVDDCR_CPU0_P1_FLT
   2    GND      B @T6G_MB_LIB.T6G(SCH_1):GND

Q_CAP_C0805-22UF,4V,20%,X6S,CH622KMEA03  I58  PC303_4
   1 PVDDCR_CPU0_P1      A @T6G_MB_LIB.T6G(SCH_1):PVDDCR_CPU0_P1
   2    GND      B @T6G_MB_LIB.T6G(SCH_1):GND

Q_CAP_C0805-22UF,4V,20%,X6S,CH622KMEA03  I60  PC305_4
   1 PVDDCR_CPU0_P1      A @T6G_MB_LIB.T6G(SCH_1):PVDDCR_CPU0_P1
   2    GND      B @T6G_MB_LIB.T6G(SCH_1):GND

Q_CAP_0402-0.22UF,16V,10%,X7R,CH4223K1B00  I63  PC300
   1 SW_PVDDCR_CPU0_P1_BOOT3_RC      A @T6G_MB_LIB.T6G(SCH_1):SW_PVDDCR_CPU0_P1_BOOT3_RC
   2 SW_PVDDCR_CPU0_P1_PH3      B @T6G_MB_LIB.T6G(SCH_1):SW_PVDDCR_CPU0_P1_PH3

Q_CAP_C0805-22UF,16V,20%,X6S,CH6223MEA01  I65  PC298_3
   1 SW_P12V_AUX_PVDDCR_CPU0_P1_FLT      A @T6G_MB_LIB.T6G(SCH_1):SW_P12V_AUX_PVDDCR_CPU0_P1_FLT
   2    GND      B @T6G_MB_LIB.T6G(SCH_1):GND

Q_INDUCTOR4P_14-150NH,SMLF,IND,CV+15^0TZ04  I67  PL31
   2 IND_CPU0_P1_CPL2      2 @T6G_MB_LIB.T6G(SCH_1):IND_CPU0_P1_CPL2
   3 IND_CPU0_P1_CPL3      3 @T6G_MB_LIB.T6G(SCH_1):IND_CPU0_P1_CPL3
   4 PVDDCR_CPU0_P1      4 @T6G_MB_LIB.T6G(SCH_1):PVDDCR_CPU0_P1
   1 SW_PVDDCR_CPU0_P1_SW3      1 @T6G_MB_LIB.T6G(SCH_1):SW_PVDDCR_CPU0_P1_SW3

Q_CAP_C0805-22UF,4V,20%,X6S,CH622KMEA03  I69  PC302_3
   1 PVDDCR_CPU0_P1      A @T6G_MB_LIB.T6G(SCH_1):PVDDCR_CPU0_P1
   2    GND      B @T6G_MB_LIB.T6G(SCH_1):GND

Q_CAP_C0805-22UF,4V,20%,X6S,CH622KMEA03  I71  PC304_3
   1 PVDDCR_CPU0_P1      A @T6G_MB_LIB.T6G(SCH_1):PVDDCR_CPU0_P1
   2    GND      B @T6G_MB_LIB.T6G(SCH_1):GND


DRAWING: @T6G_MB_LIB.T6G(SCH_1):PAGE188 

Q_CAP_0402-0.1UF,25V,10%,X7R,CH4104K1B00  I4  PC124_6
   1 PVDDCR_CPU0_P1_VCCS      A @T6G_MB_LIB.T6G(SCH_1):PVDDCR_CPU0_P1_VCCS
   2    GND      B @T6G_MB_LIB.T6G(SCH_1):GND

Q_RES_0402LF-8.87K,1%,1/16W,EMPTY,CS28872FB01  I8  PR423
   1    GND      A @T6G_MB_LIB.T6G(SCH_1):GND
   2 PVDDCR_CPU0_P1_LSET6      B @T6G_MB_LIB.T6G(SCH_1):PVDDCR_CPU0_P1_LSET6

Q_CAP_C0402-2.2UF,10V,10%,X6S,CH5222KEB01  I10  PC125
   1 PVDDCR_CPU0_P1_VCC6      A @T6G_MB_LIB.T6G(SCH_1):PVDDCR_CPU0_P1_VCC6
   2    GND      B @T6G_MB_LIB.T6G(SCH_1):GND

Q_RES_0402LF-2.2,1%,1/16W,CHIP,CS-2202FB01  I12  PR422
   1 PVDDCR_CPU0_P1_PVCC      A @T6G_MB_LIB.T6G(SCH_1):PVDDCR_CPU0_P1_PVCC
   2 PVDDCR_CPU0_P1_VCC6      B @T6G_MB_LIB.T6G(SCH_1):PVDDCR_CPU0_P1_VCC6

Q_CAP_C0402-2.2UF,10V,10%,X6S,CH5222KEB01  I15  PC126_C0P1_6
   1 PVDDCR_CPU0_P1_PVCC      A @T6G_MB_LIB.T6G(SCH_1):PVDDCR_CPU0_P1_PVCC
   2    GND      B @T6G_MB_LIB.T6G(SCH_1):GND

ISL99390FRZTR5935-ISL99390FRZ-TR5935,SMLF,IC,AL099A  I18  PU29
  34 PVDDCR_CPU0_P1_PWM5    PWM @T6G_MB_LIB.T6G(SCH_1):PVDDCR_CPU0_P1_PWM5
  39 PVDDCR_CPU0_P1_VCCS  REFIN @T6G_MB_LIB.T6G(SCH_1):PVDDCR_CPU0_P1_VCCS
   3 PVDDCR_CPU0_P1_VCC5    VCC @T6G_MB_LIB.T6G(SCH_1):PVDDCR_CPU0_P1_VCC5
   2    GND   AGND @T6G_MB_LIB.T6G(SCH_1):GND
  33 SW_PVDDCR_CPU0_P1_BOOT5   BOOT @T6G_MB_LIB.T6G(SCH_1):SW_PVDDCR_CPU0_P1_BOOT5
25_29 SW_P12V_AUX_PVDDCR_CPU0_P1_FLT   VIN1 @T6G_MB_LIB.T6G(SCH_1):SW_P12V_AUX_PVDDCR_CPU0_P1_FLT
  32 SW_PVDDCR_CPU0_P1_PH5  PHASE @T6G_MB_LIB.T6G(SCH_1):SW_PVDDCR_CPU0_P1_PH5
   4 PVDDCR_CPU0_P1_PVCC   PVCC @T6G_MB_LIB.T6G(SCH_1):PVDDCR_CPU0_P1_PVCC
  36 PVDDCR_CPU0_P1_TEMP0 TOUT_FLT @T6G_MB_LIB.T6G(SCH_1):PVDDCR_CPU0_P1_TEMP0
  38 PVDDCR_CPU0_P1_IMON5   IOUT @T6G_MB_LIB.T6G(SCH_1):PVDDCR_CPU0_P1_IMON5
  37 PVDDCR_CPU0_P1_LSET5   LSET @T6G_MB_LIB.T6G(SCH_1):PVDDCR_CPU0_P1_LSET5
10_19 SW_PVDDCR_CPU0_P1_SW5     SW @T6G_MB_LIB.T6G(SCH_1):SW_PVDDCR_CPU0_P1_SW5
   5    GND  PGND1 @T6G_MB_LIB.T6G(SCH_1):GND
  30 SW_P12V_AUX_PVDDCR_CPU0_P1_FLT   VIN2 @T6G_MB_LIB.T6G(SCH_1):SW_P12V_AUX_PVDDCR_CPU0_P1_FLT
   1 PVDDCR_CPU0_P1_VOS5    VOS @T6G_MB_LIB.T6G(SCH_1):PVDDCR_CPU0_P1_VOS5
  40    GND  PGND3 @T6G_MB_LIB.T6G(SCH_1):GND
  35 PVDDCR_CPU0_P1_VCC5     EN @T6G_MB_LIB.T6G(SCH_1):PVDDCR_CPU0_P1_VCC5
  31 NC_PVDDCR_CPU0_P1_DNC5    DNC @T6G_MB_LIB.T6G(SCH_1):NC_PVDDCR_CPU0_P1_DNC5
   6 NC_PVDDCR_CPU0_P1_GL1_5    GL1 @T6G_MB_LIB.T6G(SCH_1):NC_PVDDCR_CPU0_P1_GL1_5
  41 NC_PVDDCR_CPU0_P1_GL2_5    GL2 @T6G_MB_LIB.T6G(SCH_1):NC_PVDDCR_CPU0_P1_GL2_5
7_9-20_24    GND  PGND2 @T6G_MB_LIB.T6G(SCH_1):GND

Q_RES_0402LF-1.5,1%,1/8W,EMPTY,CS-1504FB00  I21  PR524
   1 SW_PVDDCR_CPU0_P1_SW6_RC      A @T6G_MB_LIB.T6G(SCH_1):SW_PVDDCR_CPU0_P1_SW6_RC
   2    GND      B @T6G_MB_LIB.T6G(SCH_1):GND

Q_RES_0402LF-0,5%,1/16W,CHIP,CS00002JB13  I22  PR425
   1 PVDDCR_CPU0_P1_VOS6      A @T6G_MB_LIB.T6G(SCH_1):PVDDCR_CPU0_P1_VOS6
   2 PVDDCR_CPU0_P1      B @T6G_MB_LIB.T6G(SCH_1):PVDDCR_CPU0_P1

Q_CAP_C0402-560PF,50V,10%,EMPTY,CH1566K1B09  I23  PC321
   1 SW_PVDDCR_CPU0_P1_SW6      A @T6G_MB_LIB.T6G(SCH_1):SW_PVDDCR_CPU0_P1_SW6
   2 SW_PVDDCR_CPU0_P1_SW6_RC      B @T6G_MB_LIB.T6G(SCH_1):SW_PVDDCR_CPU0_P1_SW6_RC

Q_CAP_0402-0.1UF,25V,10%,X7R,CH4104K1B00  I25  PC127_6
   1 SW_P12V_AUX_PVDDCR_CPU0_P1_FLT      A @T6G_MB_LIB.T6G(SCH_1):SW_P12V_AUX_PVDDCR_CPU0_P1_FLT
   2    GND      B @T6G_MB_LIB.T6G(SCH_1):GND

Q_CAP_C0402-1UF,25V,10%,X6S,CH5104KEB02  I27  PC128_6
   1 SW_P12V_AUX_PVDDCR_CPU0_P1_FLT      A @T6G_MB_LIB.T6G(SCH_1):SW_P12V_AUX_PVDDCR_CPU0_P1_FLT
   2    GND      B @T6G_MB_LIB.T6G(SCH_1):GND

Q_RES_0402LF-5.6,1%,1/16W,CHIP,CS-5602FB01  I28  PR424
   1 SW_PVDDCR_CPU0_P1_BOOT6      A @T6G_MB_LIB.T6G(SCH_1):SW_PVDDCR_CPU0_P1_BOOT6
   2 SW_PVDDCR_CPU0_P1_BOOT6_RC      B @T6G_MB_LIB.T6G(SCH_1):SW_PVDDCR_CPU0_P1_BOOT6_RC

Q_CAP_C0805-22UF,16V,20%,X6S,CH6223MEA01  I29  PC129_6
   1 SW_P12V_AUX_PVDDCR_CPU0_P1_FLT      A @T6G_MB_LIB.T6G(SCH_1):SW_P12V_AUX_PVDDCR_CPU0_P1_FLT
   2    GND      B @T6G_MB_LIB.T6G(SCH_1):GND

Q_CAP_C0805-22UF,16V,20%,X6S,CH6223MEA01  I30  PC130_6
   1 SW_P12V_AUX_PVDDCR_CPU0_P1_FLT      A @T6G_MB_LIB.T6G(SCH_1):SW_P12V_AUX_PVDDCR_CPU0_P1_FLT
   2    GND      B @T6G_MB_LIB.T6G(SCH_1):GND

Q_RES_0402LF-1.5,1%,1/8W,EMPTY,CS-1504FB00  I32  PR46
   1 SW_PVDDCR_CPU0_P1_SW5_RC      A @T6G_MB_LIB.T6G(SCH_1):SW_PVDDCR_CPU0_P1_SW5_RC
   2    GND      B @T6G_MB_LIB.T6G(SCH_1):GND

Q_RES_0402LF-0,5%,1/16W,CHIP,CS00002JB13  I33  PR204
   1 PVDDCR_CPU0_P1_VOS5      A @T6G_MB_LIB.T6G(SCH_1):PVDDCR_CPU0_P1_VOS5
   2 PVDDCR_CPU0_P1      B @T6G_MB_LIB.T6G(SCH_1):PVDDCR_CPU0_P1

Q_CAP_0402-0.1UF,25V,10%,X7R,CH4104K1B00  I34  PC306_5
   1 PVDDCR_CPU0_P1_VCCS      A @T6G_MB_LIB.T6G(SCH_1):PVDDCR_CPU0_P1_VCCS
   2    GND      B @T6G_MB_LIB.T6G(SCH_1):GND

Q_RES_0402LF-8.87K,1%,1/16W,EMPTY,CS28872FB01  I37  PR202
   1    GND      A @T6G_MB_LIB.T6G(SCH_1):GND
   2 PVDDCR_CPU0_P1_LSET5      B @T6G_MB_LIB.T6G(SCH_1):PVDDCR_CPU0_P1_LSET5

Q_CAP_C0402-2.2UF,10V,10%,X6S,CH5222KEB01  I39  PC307
   1 PVDDCR_CPU0_P1_VCC5      A @T6G_MB_LIB.T6G(SCH_1):PVDDCR_CPU0_P1_VCC5
   2    GND      B @T6G_MB_LIB.T6G(SCH_1):GND

Q_RES_0402LF-2.2,1%,1/16W,CHIP,CS-2202FB01  I41  PR201
   1 PVDDCR_CPU0_P1_PVCC      A @T6G_MB_LIB.T6G(SCH_1):PVDDCR_CPU0_P1_PVCC
   2 PVDDCR_CPU0_P1_VCC5      B @T6G_MB_LIB.T6G(SCH_1):PVDDCR_CPU0_P1_VCC5

Q_CAP_C0402-2.2UF,10V,10%,X6S,CH5222KEB01  I43  PC308_C0P1_5
   1 PVDDCR_CPU0_P1_PVCC      A @T6G_MB_LIB.T6G(SCH_1):PVDDCR_CPU0_P1_PVCC
   2    GND      B @T6G_MB_LIB.T6G(SCH_1):GND

Q_CAP_0402-0.1UF,25V,10%,X7R,CH4104K1B00  I45  PC309_5
   1 SW_P12V_AUX_PVDDCR_CPU0_P1_FLT      A @T6G_MB_LIB.T6G(SCH_1):SW_P12V_AUX_PVDDCR_CPU0_P1_FLT
   2    GND      B @T6G_MB_LIB.T6G(SCH_1):GND

Q_CAP_C0402-560PF,50V,10%,EMPTY,CH1566K1B09  I46  PC318
   1 SW_PVDDCR_CPU0_P1_SW5      A @T6G_MB_LIB.T6G(SCH_1):SW_PVDDCR_CPU0_P1_SW5
   2 SW_PVDDCR_CPU0_P1_SW5_RC      B @T6G_MB_LIB.T6G(SCH_1):SW_PVDDCR_CPU0_P1_SW5_RC

Q_RES_0402LF-5.6,1%,1/16W,CHIP,CS-5602FB01  I47  PR203
   1 SW_PVDDCR_CPU0_P1_BOOT5      A @T6G_MB_LIB.T6G(SCH_1):SW_PVDDCR_CPU0_P1_BOOT5
   2 SW_PVDDCR_CPU0_P1_BOOT5_RC      B @T6G_MB_LIB.T6G(SCH_1):SW_PVDDCR_CPU0_P1_BOOT5_RC

Q_CAP_C0402-1UF,25V,10%,X6S,CH5104KEB02  I48  PC310_5
   1 SW_P12V_AUX_PVDDCR_CPU0_P1_FLT      A @T6G_MB_LIB.T6G(SCH_1):SW_P12V_AUX_PVDDCR_CPU0_P1_FLT
   2    GND      B @T6G_MB_LIB.T6G(SCH_1):GND

Q_CAP_C0805-22UF,16V,20%,X6S,CH6223MEA01  I49  PC311_5
   1 SW_P12V_AUX_PVDDCR_CPU0_P1_FLT      A @T6G_MB_LIB.T6G(SCH_1):SW_P12V_AUX_PVDDCR_CPU0_P1_FLT
   2    GND      B @T6G_MB_LIB.T6G(SCH_1):GND

Q_CAP_C0805-22UF,16V,20%,X6S,CH6223MEA01  I50  PC312_5
   1 SW_P12V_AUX_PVDDCR_CPU0_P1_FLT      A @T6G_MB_LIB.T6G(SCH_1):SW_P12V_AUX_PVDDCR_CPU0_P1_FLT
   2    GND      B @T6G_MB_LIB.T6G(SCH_1):GND

Q_INDUCTOR_SMLF-120NH/69A,IND,CV+12^0EZ03  I51  PL27
   2 IND_CPU0_P1_CPL0      2 @T6G_MB_LIB.T6G(SCH_1):IND_CPU0_P1_CPL0
   1    GND      1 @T6G_MB_LIB.T6G(SCH_1):GND

Q_CAP_0402-0.22UF,16V,10%,X7R,CH4223K1B00  I52  PC133
   1 SW_PVDDCR_CPU0_P1_BOOT6_RC      A @T6G_MB_LIB.T6G(SCH_1):SW_PVDDCR_CPU0_P1_BOOT6_RC
   2 SW_PVDDCR_CPU0_P1_PH6      B @T6G_MB_LIB.T6G(SCH_1):SW_PVDDCR_CPU0_P1_PH6

Q_INDUCTOR4P_14-150NH,SMLF,IND,CV+15^0TZ04  I53  PL8
   2 IND_CPU0_P1_CPL0      2 @T6G_MB_LIB.T6G(SCH_1):IND_CPU0_P1_CPL0
   3 IND_CPU0_P1_CPL6      3 @T6G_MB_LIB.T6G(SCH_1):IND_CPU0_P1_CPL6
   4 PVDDCR_CPU0_P1      4 @T6G_MB_LIB.T6G(SCH_1):PVDDCR_CPU0_P1
   1 SW_PVDDCR_CPU0_P1_SW6      1 @T6G_MB_LIB.T6G(SCH_1):SW_PVDDCR_CPU0_P1_SW6

Q_CAP_C0805-22UF,16V,20%,X6S,CH6223MEA01  I55  PC132_6
   1 SW_P12V_AUX_PVDDCR_CPU0_P1_FLT      A @T6G_MB_LIB.T6G(SCH_1):SW_P12V_AUX_PVDDCR_CPU0_P1_FLT
   2    GND      B @T6G_MB_LIB.T6G(SCH_1):GND

Q_CAP_C0805-22UF,4V,20%,X6S,CH622KMEA03  I58  PC134_6
   1 PVDDCR_CPU0_P1      A @T6G_MB_LIB.T6G(SCH_1):PVDDCR_CPU0_P1
   2    GND      B @T6G_MB_LIB.T6G(SCH_1):GND

Q_CAP_C0805-22UF,4V,20%,X6S,CH622KMEA03  I60  PC135_6
   1 PVDDCR_CPU0_P1      A @T6G_MB_LIB.T6G(SCH_1):PVDDCR_CPU0_P1
   2    GND      B @T6G_MB_LIB.T6G(SCH_1):GND

Q_CAP_0402-0.22UF,16V,10%,X7R,CH4223K1B00  I63  PC314
   1 SW_PVDDCR_CPU0_P1_BOOT5_RC      A @T6G_MB_LIB.T6G(SCH_1):SW_PVDDCR_CPU0_P1_BOOT5_RC
   2 SW_PVDDCR_CPU0_P1_PH5      B @T6G_MB_LIB.T6G(SCH_1):SW_PVDDCR_CPU0_P1_PH5

Q_INDUCTOR4P_14-150NH,SMLF,IND,CV+15^0TZ04  I64  PL33
   2 IND_CPU0_P1_CPL6      2 @T6G_MB_LIB.T6G(SCH_1):IND_CPU0_P1_CPL6
   3 IND_CPU0_P1_CPL5      3 @T6G_MB_LIB.T6G(SCH_1):IND_CPU0_P1_CPL5
   4 PVDDCR_CPU0_P1      4 @T6G_MB_LIB.T6G(SCH_1):PVDDCR_CPU0_P1
   1 SW_PVDDCR_CPU0_P1_SW5      1 @T6G_MB_LIB.T6G(SCH_1):SW_PVDDCR_CPU0_P1_SW5

Q_CAP_C0805-22UF,16V,20%,X6S,CH6223MEA01  I66  PC313_5
   1 SW_P12V_AUX_PVDDCR_CPU0_P1_FLT      A @T6G_MB_LIB.T6G(SCH_1):SW_P12V_AUX_PVDDCR_CPU0_P1_FLT
   2    GND      B @T6G_MB_LIB.T6G(SCH_1):GND

Q_CAP_C0805-22UF,4V,20%,X6S,CH622KMEA03  I69  PC315_5
   1 PVDDCR_CPU0_P1      A @T6G_MB_LIB.T6G(SCH_1):PVDDCR_CPU0_P1
   2    GND      B @T6G_MB_LIB.T6G(SCH_1):GND

Q_CAP_C0805-22UF,4V,20%,X6S,CH622KMEA03  I71  PC316_5
   1 PVDDCR_CPU0_P1      A @T6G_MB_LIB.T6G(SCH_1):PVDDCR_CPU0_P1
   2    GND      B @T6G_MB_LIB.T6G(SCH_1):GND

ISL99390FRZTR5935-ISL99390FRZ-TR5935,SMLF,IC,AL099A  I73  PU24
  34 PVDDCR_CPU0_P1_PWM6    PWM @T6G_MB_LIB.T6G(SCH_1):PVDDCR_CPU0_P1_PWM6
  39 PVDDCR_CPU0_P1_VCCS  REFIN @T6G_MB_LIB.T6G(SCH_1):PVDDCR_CPU0_P1_VCCS
   3 PVDDCR_CPU0_P1_VCC6    VCC @T6G_MB_LIB.T6G(SCH_1):PVDDCR_CPU0_P1_VCC6
   2    GND   AGND @T6G_MB_LIB.T6G(SCH_1):GND
  33 SW_PVDDCR_CPU0_P1_BOOT6   BOOT @T6G_MB_LIB.T6G(SCH_1):SW_PVDDCR_CPU0_P1_BOOT6
25_29 SW_P12V_AUX_PVDDCR_CPU0_P1_FLT   VIN1 @T6G_MB_LIB.T6G(SCH_1):SW_P12V_AUX_PVDDCR_CPU0_P1_FLT
  32 SW_PVDDCR_CPU0_P1_PH6  PHASE @T6G_MB_LIB.T6G(SCH_1):SW_PVDDCR_CPU0_P1_PH6
   4 PVDDCR_CPU0_P1_PVCC   PVCC @T6G_MB_LIB.T6G(SCH_1):PVDDCR_CPU0_P1_PVCC
  36 PVDDCR_CPU0_P1_TEMP0 TOUT_FLT @T6G_MB_LIB.T6G(SCH_1):PVDDCR_CPU0_P1_TEMP0
  38 PVDDCR_CPU0_P1_IMON6   IOUT @T6G_MB_LIB.T6G(SCH_1):PVDDCR_CPU0_P1_IMON6
  37 PVDDCR_CPU0_P1_LSET6   LSET @T6G_MB_LIB.T6G(SCH_1):PVDDCR_CPU0_P1_LSET6
10_19 SW_PVDDCR_CPU0_P1_SW6     SW @T6G_MB_LIB.T6G(SCH_1):SW_PVDDCR_CPU0_P1_SW6
   5    GND  PGND1 @T6G_MB_LIB.T6G(SCH_1):GND
  30 SW_P12V_AUX_PVDDCR_CPU0_P1_FLT   VIN2 @T6G_MB_LIB.T6G(SCH_1):SW_P12V_AUX_PVDDCR_CPU0_P1_FLT
   1 PVDDCR_CPU0_P1_VOS6    VOS @T6G_MB_LIB.T6G(SCH_1):PVDDCR_CPU0_P1_VOS6
  40    GND  PGND3 @T6G_MB_LIB.T6G(SCH_1):GND
  35 PVDDCR_CPU0_P1_VCC6     EN @T6G_MB_LIB.T6G(SCH_1):PVDDCR_CPU0_P1_VCC6
  31 NC_PVDDCR_CPU0_P1_DNC6    DNC @T6G_MB_LIB.T6G(SCH_1):NC_PVDDCR_CPU0_P1_DNC6
   6 NC_PVDDCR_CPU0_P1_GL1_6    GL1 @T6G_MB_LIB.T6G(SCH_1):NC_PVDDCR_CPU0_P1_GL1_6
  41 NC_PVDDCR_CPU0_P1_GL2_6    GL2 @T6G_MB_LIB.T6G(SCH_1):NC_PVDDCR_CPU0_P1_GL2_6
7_9-20_24    GND  PGND2 @T6G_MB_LIB.T6G(SCH_1):GND


DRAWING: @T6G_MB_LIB.T6G(SCH_1):PAGE192 

Q_RES_0402LF-0,5%,1/16W,CHIP,CS00002JB13  I2  R8224
   1 PVDDIO_P1_EN      A @T6G_MB_LIB.T6G(SCH_1):PVDDIO_P1_EN
   2 PVDDIO_P1_EN_R      B @T6G_MB_LIB.T6G(SCH_1):PVDDIO_P1_EN_R

Q_CAP_0402-1000PF,50V,5%,X7R,TMP_QCH21006JB10  I3  C8356
   1 PVDDIO_P1_EN_R      A @T6G_MB_LIB.T6G(SCH_1):PVDDIO_P1_EN_R
   2    GND      B @T6G_MB_LIB.T6G(SCH_1):GND

MOSFET_N_SMLF-BSS138K,BSS138K,IC,BAM138K0000  I6  PQ16
   G PVDDIO_P1_EN_R   GATE @T6G_MB_LIB.T6G(SCH_1):PVDDIO_P1_EN_R
   D PVDDIO_P1_EN_G  DRAIN @T6G_MB_LIB.T6G(SCH_1):PVDDIO_P1_EN_G
   S    GND SOURCE @T6G_MB_LIB.T6G(SCH_1):GND

Q_RES_0402LF-10K,1%,1/16W,CHIP,CS31002FB08  I8  PR231
   1 PVDDCR_CPU1_P1_VMON      A @T6G_MB_LIB.T6G(SCH_1):PVDDCR_CPU1_P1_VMON
   2    GND      B @T6G_MB_LIB.T6G(SCH_1):GND

Q_RES_0402LF-40.2K,1%,1/16W,CHIP,CS34022FB04  I9  PR230
   1 P5V_AUX      A @T6G_MB_LIB.T6G(SCH_1):P5V_AUX
   2 PVDDCR_CPU1_P1_VMON      B @T6G_MB_LIB.T6G(SCH_1):PVDDCR_CPU1_P1_VMON

Q_RES_0402LF-9.53K,1%,1/16W,CHIP,CS29532FB06  I12  PR244
   1 PVDDCR_CPU1_P1_EN1_ADDR_CFG      A @T6G_MB_LIB.T6G(SCH_1):PVDDCR_CPU1_P1_EN1_ADDR_CFG
   2    GND      B @T6G_MB_LIB.T6G(SCH_1):GND

MOSFET_PCH_GDS_ESD_PROTECTED-PJA3415AE,SMLF,IC,BAMA  I13  PQ12
   D PVDDCR_CPU1_P1_EN1_ADDR_CFG      D @T6G_MB_LIB.T6G(SCH_1):PVDDCR_CPU1_P1_EN1_ADDR_CFG
   G PVDDIO_P1_EN_G      G @T6G_MB_LIB.T6G(SCH_1):PVDDIO_P1_EN_G
   S P3V3_AUX      S @T6G_MB_LIB.T6G(SCH_1):P3V3_AUX

Q_RES_0402LF-1K,1%,1/16W,CHIP,CS21002FB06  I17  PR232
   1 P3V3_AUX      A @T6G_MB_LIB.T6G(SCH_1):P3V3_AUX
   2 PVDDIO_P1_EN_G      B @T6G_MB_LIB.T6G(SCH_1):PVDDIO_P1_EN_G

Q_RES_0402LF-49.9,1%,1/16W,CHIP,CS04992FB07  I19  PR460
   1 VSENSE_VSS_SENSE_B_P1      A @T6G_MB_LIB.T6G(SCH_1):VSENSE_VSS_SENSE_B_P1
   2    GND      B @T6G_MB_LIB.T6G(SCH_1):GND

Q_RES_0402LF-49.9,1%,1/16W,CHIP,CS04992FB07  I22  PR227
   1 VSENSE_PVDDIO_P1_DP      A @T6G_MB_LIB.T6G(SCH_1):VSENSE_PVDDIO_P1_DP
   2 PVDDIO_P1      B @T6G_MB_LIB.T6G(SCH_1):PVDDIO_P1

Q_RES_0402LF-49.9,1%,1/16W,CHIP,CS04992FB07  I23  PR226
   1 VSENSE_VSS_SENSE_C_P1      A @T6G_MB_LIB.T6G(SCH_1):VSENSE_VSS_SENSE_C_P1
   2    GND      B @T6G_MB_LIB.T6G(SCH_1):GND

Q_RES_0402LF-0,5%,1/16W,CHIP,CS00002JB13  I29  PR217
   1 SVID_PVDDCR_CPU1_P1_SVTI      A @T6G_MB_LIB.T6G(SCH_1):SVID_PVDDCR_CPU1_P1_SVTI
   2    GND      B @T6G_MB_LIB.T6G(SCH_1):GND

Q_RES_0402LF-1K,1%,1/16W,EMPTY,CS21002FB06  I30  R8219
   1 SVID_PVDDCR_CPU1_P1_SVTO      A @T6G_MB_LIB.T6G(SCH_1):SVID_PVDDCR_CPU1_P1_SVTO
   2    GND      B @T6G_MB_LIB.T6G(SCH_1):GND

Q_CAP_0402-10PF,50V,5%,EMPTY,CH01006JB08  I31  C308
   1 SVID_PVDDCR_CPU1_P1_SVTO      A @T6G_MB_LIB.T6G(SCH_1):SVID_PVDDCR_CPU1_P1_SVTO
   2    GND      B @T6G_MB_LIB.T6G(SCH_1):GND

Q_CAP_0402-10PF,50V,5%,EMPTY,CH01006JB08  I32  C309
   1 SVID_PVDDCR_CPU1_P1_SVD_R      A @T6G_MB_LIB.T6G(SCH_1):SVID_PVDDCR_CPU1_P1_SVD_R
   2    GND      B @T6G_MB_LIB.T6G(SCH_1):GND

Q_CAP_0402-10PF,50V,5%,EMPTY,CH01006JB08  I33  C310
   1 SVID_PVDDCR_CPU1_P1_SVC_R      A @T6G_MB_LIB.T6G(SCH_1):SVID_PVDDCR_CPU1_P1_SVC_R
   2    GND      B @T6G_MB_LIB.T6G(SCH_1):GND

Q_RES_0402LF-49.9,1%,1/16W,CHIP,CS04992FB07  I34  PR228
   1 VSENSE_PVDDCR_CPU1_P1_DP      A @T6G_MB_LIB.T6G(SCH_1):VSENSE_PVDDCR_CPU1_P1_DP
   2 PVDDCR_CPU1_P1      B @T6G_MB_LIB.T6G(SCH_1):PVDDCR_CPU1_P1

Q_RES_0402LF-1K,1%,1/16W,EMPTY,CS21002FB06  I38  PR218
   1 PVDD18_S5_P1      A @T6G_MB_LIB.T6G(SCH_1):PVDD18_S5_P1
   2 SVID_PVDDCR_CPU1_P1_SVTI      B @T6G_MB_LIB.T6G(SCH_1):SVID_PVDDCR_CPU1_P1_SVTI

Q_RES_0402LF-1K,1%,1/16W,EMPTY,CS21002FB06  I40  R8220
   1 PVDD18_S5_P1      A @T6G_MB_LIB.T6G(SCH_1):PVDD18_S5_P1
   2 SVID_PVDDCR_CPU1_P1_SVTO      B @T6G_MB_LIB.T6G(SCH_1):SVID_PVDDCR_CPU1_P1_SVTO

Q_RES_0402LF-1K,1%,1/16W,EMPTY,CS21002FB06  I41  R8222
   1 PVDD18_S5_P1      A @T6G_MB_LIB.T6G(SCH_1):PVDD18_S5_P1
   2 SVID_PVDDCR_CPU1_P1_SVD_R      B @T6G_MB_LIB.T6G(SCH_1):SVID_PVDDCR_CPU1_P1_SVD_R

Q_RES_0402LF-1K,1%,1/16W,EMPTY,CS21002FB06  I42  R8225
   1 PVDD18_S5_P1      A @T6G_MB_LIB.T6G(SCH_1):PVDD18_S5_P1
   2 SVID_PVDDCR_CPU1_P1_SVC_R      B @T6G_MB_LIB.T6G(SCH_1):SVID_PVDDCR_CPU1_P1_SVC_R

Q_CAP_0402-0.1UF,25V,10%,X7R,CH4104K1B00  I47  PC357
   1 PVDDCR_CPU1_P1_VMON      A @T6G_MB_LIB.T6G(SCH_1):PVDDCR_CPU1_P1_VMON
   2    GND      B @T6G_MB_LIB.T6G(SCH_1):GND

Q_RES_0402LF-0,5%,1/16W,CHIP,CS00002JB13  I49  PR251
   1 P12V_AUX      A @T6G_MB_LIB.T6G(SCH_1):P12V_AUX
   2 PVDDCR_CPU1_P1_VINSEN      B @T6G_MB_LIB.T6G(SCH_1):PVDDCR_CPU1_P1_VINSEN

Q_RES_0402LF-33,5%,1/16W,CHIP,CS03302JB10  I50  R8243
   1 PWRGD_PVDDIO_P1      A @T6G_MB_LIB.T6G(SCH_1):PWRGD_PVDDIO_P1
   2 PWRGD_PVDDIO_P1_R      B @T6G_MB_LIB.T6G(SCH_1):PWRGD_PVDDIO_P1_R

Q_RES_0402LF-1K,1%,1/16W,CHIP,CS21002FB06  I51  R8242
   1 P3V3_AUX      A @T6G_MB_LIB.T6G(SCH_1):P3V3_AUX
   2 PWRGD_PVDDIO_P1_R      B @T6G_MB_LIB.T6G(SCH_1):PWRGD_PVDDIO_P1_R

Q_CAP_0402-1000PF,50V,5%,EMPTY,TMP_QCH21006JB10  I52  C8362
   1 PWRGD_PVDDIO_P1_R      A @T6G_MB_LIB.T6G(SCH_1):PWRGD_PVDDIO_P1_R
   2    GND      B @T6G_MB_LIB.T6G(SCH_1):GND

Q_RES_0402LF-4.99K,1%,1/16W,EMPTY,CS24992FB07  I55  PR603
   1 PVDDCR_CPU1_P1_VINSEN      A @T6G_MB_LIB.T6G(SCH_1):PVDDCR_CPU1_P1_VINSEN
   2    GND      B @T6G_MB_LIB.T6G(SCH_1):GND

Q_CAP_0402-0.1UF,25V,10%,X7R,CH4104K1B00  I56  PC364
   1 PVDDCR_CPU1_P1_VINSEN      A @T6G_MB_LIB.T6G(SCH_1):PVDDCR_CPU1_P1_VINSEN
   2    GND      B @T6G_MB_LIB.T6G(SCH_1):GND

Q_CAP_0402-1UF,6.3V,10%,X7R,CH5101K1B01  I60  PC363
   1 PVDD18_S5_P1      A @T6G_MB_LIB.T6G(SCH_1):PVDD18_S5_P1
   2    GND      B @T6G_MB_LIB.T6G(SCH_1):GND

Q_RES_0402LF-0,5%,1/16W,CHIP,CS00002JB13  I64  R8241
   1 PVDDCR_CPU1_P1_OCP_N      A @T6G_MB_LIB.T6G(SCH_1):PVDDCR_CPU1_P1_OCP_N
   2 PVDDCR_CPU1_P1_OCP_N_R      B @T6G_MB_LIB.T6G(SCH_1):PVDDCR_CPU1_P1_OCP_N_R

Q_RES_0402LF-100,1%,1/16W,CHIP,CS11002FB07  I65  R240
   1 PVDDCR_CPU1_P1_RESET_N      A @T6G_MB_LIB.T6G(SCH_1):PVDDCR_CPU1_P1_RESET_N
   2 PVDDCR_CPU1_P1_RESET_N_R      B @T6G_MB_LIB.T6G(SCH_1):PVDDCR_CPU1_P1_RESET_N_R

Q_RES_0402LF-1K,1%,1/16W,CHIP,CS21002FB06  I66  R8247
   1 PVDD18_S5_P1      A @T6G_MB_LIB.T6G(SCH_1):PVDD18_S5_P1
   2 PVDDCR_CPU1_P1_RESET_N_R      B @T6G_MB_LIB.T6G(SCH_1):PVDDCR_CPU1_P1_RESET_N_R

Q_CAP_0402-3300PF,50V,10%,X7R,TMP_QCH2336K1B12  I67  PC361
   1 VSENSE_PVDDIO_P1_VSEN1      A @T6G_MB_LIB.T6G(SCH_1):VSENSE_PVDDIO_P1_VSEN1
   2 VSENSE_VSS_SENSE_B_P1      B @T6G_MB_LIB.T6G(SCH_1):VSENSE_VSS_SENSE_B_P1

Q_RES_0402LF-0,5%,1/16W,CHIP,CS00002JB13  I69  PR246
   1 VSENSE_PVDDIO_P1_DP      A @T6G_MB_LIB.T6G(SCH_1):VSENSE_PVDDIO_P1_DP
   2 VSENSE_PVDDIO_P1_VSEN1      B @T6G_MB_LIB.T6G(SCH_1):VSENSE_PVDDIO_P1_VSEN1

Q_RES_0402LF-1K,1%,1/16W,CHIP,CS21002FB06  I71  R8252
   1 PVDD18_S5_P1      A @T6G_MB_LIB.T6G(SCH_1):PVDD18_S5_P1
   2 PVDDCR_CPU1_P1_OCP_N_R      B @T6G_MB_LIB.T6G(SCH_1):PVDDCR_CPU1_P1_OCP_N_R

Q_CAP_0402-470PF,50V,10%,X7R,TMP_QCH14706KB18  I73  PC368
   1 PVDDCR_CPU1_P1_TEMP0      A @T6G_MB_LIB.T6G(SCH_1):PVDDCR_CPU1_P1_TEMP0
   2    GND      B @T6G_MB_LIB.T6G(SCH_1):GND

Q_CAP_0402-470PF,50V,10%,X7R,TMP_QCH14706KB18  I75  PC367
   1 PVDDIO_P1_TEMP1      A @T6G_MB_LIB.T6G(SCH_1):PVDDIO_P1_TEMP1
   2    GND      B @T6G_MB_LIB.T6G(SCH_1):GND

Q_RES_0402LF-0,5%,1/16W,CHIP,CS00002JB13  I76  PR533
   1 NC_PVDDCR_CPU1_P1_IMON7      A @T6G_MB_LIB.T6G(SCH_1):NC_PVDDCR_CPU1_P1_IMON7
   2    GND      B @T6G_MB_LIB.T6G(SCH_1):GND

Q_RES_0402LF-0,5%,1/16W,CHIP,CS00002JB13  I77  PR245
   1 VSENSE_PVDDCR_CPU1_P1_DP      A @T6G_MB_LIB.T6G(SCH_1):VSENSE_PVDDCR_CPU1_P1_DP
   2 VSENSE_PVDDCR_CPU1_P1_VSEN0      B @T6G_MB_LIB.T6G(SCH_1):VSENSE_PVDDCR_CPU1_P1_VSEN0

Q_CAP_0402-3300PF,50V,10%,X7R,TMP_QCH2336K1B12  I79  PC358
   1 VSENSE_PVDDCR_CPU1_P1_VSEN0      A @T6G_MB_LIB.T6G(SCH_1):VSENSE_PVDDCR_CPU1_P1_VSEN0
   2 VSENSE_VSS_SENSE_C_P1      B @T6G_MB_LIB.T6G(SCH_1):VSENSE_VSS_SENSE_C_P1

Q_RES_0402LF-33,5%,1/16W,CHIP,CS03302JB10  I80  R8250
   1 PVDDCR_CPU1_P1_SMB_ALERT      A @T6G_MB_LIB.T6G(SCH_1):PVDDCR_CPU1_P1_SMB_ALERT
   2 PVDDCR_CPU1_P1_SMB_ALERT_R      B @T6G_MB_LIB.T6G(SCH_1):PVDDCR_CPU1_P1_SMB_ALERT_R

Q_RES_0402LF-0,5%,1/16W,CHIP,CS00002JB13  I81  R8249
   1 SMB_SCM_2_R1_SDA      A @T6G_MB_LIB.T6G(SCH_1):SMB_SCM_2_R1_SDA
   2 SMB_DIO_PVDDCR_CPU1_P1_R      B @T6G_MB_LIB.T6G(SCH_1):SMB_DIO_PVDDCR_CPU1_P1_R

Q_RES_0402LF-49.9,1%,1/16W,CHIP,CS04992FB07  I82  R8238
   1 SVID_PVDDCR_CPU1_P1_SVTO      A @T6G_MB_LIB.T6G(SCH_1):SVID_PVDDCR_CPU1_P1_SVTO
   2 SVID_PVDDCR_CPU1_P1_SVTO_R      B @T6G_MB_LIB.T6G(SCH_1):SVID_PVDDCR_CPU1_P1_SVTO_R

Q_RES_0402LF-0,5%,1/16W,CHIP,CS00002JB13  I83  PR239
   1 SVID_PVDDCR_CPU1_P1_SVTI      A @T6G_MB_LIB.T6G(SCH_1):SVID_PVDDCR_CPU1_P1_SVTI
   2 SVID_PVDDCR_CPU1_P1_SVTI_R      B @T6G_MB_LIB.T6G(SCH_1):SVID_PVDDCR_CPU1_P1_SVTI_R

Q_RES_0402LF-0,5%,1/16W,CHIP,CS00002JB13  I84  R8248
   1 SMB_SCM_2_R1_SCL      A @T6G_MB_LIB.T6G(SCH_1):SMB_SCM_2_R1_SCL
   2 SMB_CLK_PVDDCR_CPU1_P1_R      B @T6G_MB_LIB.T6G(SCH_1):SMB_CLK_PVDDCR_CPU1_P1_R

Q_CAP_0402-1000PF,50V,5%,X7R,TMP_QCH21006JB10  I85  C8359
   1 PVDDCR_CPU1_P1_EN_R      A @T6G_MB_LIB.T6G(SCH_1):PVDDCR_CPU1_P1_EN_R
   2    GND      B @T6G_MB_LIB.T6G(SCH_1):GND

Q_RES_0402LF-0,5%,1/16W,CHIP,CS00002JB13  I87  R8235
   1 FM_PVDDCR_CPU1_P1_EN      A @T6G_MB_LIB.T6G(SCH_1):FM_PVDDCR_CPU1_P1_EN
   2 PVDDCR_CPU1_P1_EN_R      B @T6G_MB_LIB.T6G(SCH_1):PVDDCR_CPU1_P1_EN_R

Q_RES_0402LF-33,5%,1/16W,CHIP,CS03302JB10  I88  R8234
   1 PWRGD_PVDDCR_CPU1_P1      A @T6G_MB_LIB.T6G(SCH_1):PWRGD_PVDDCR_CPU1_P1
   2 PWRGD_PVDDCR_CPU1_P1_R      B @T6G_MB_LIB.T6G(SCH_1):PWRGD_PVDDCR_CPU1_P1_R

Q_RES_0402LF-1K,1%,1/16W,CHIP,CS21002FB06  I89  R8233
   1 P3V3_AUX      A @T6G_MB_LIB.T6G(SCH_1):P3V3_AUX
   2 PWRGD_PVDDCR_CPU1_P1_R      B @T6G_MB_LIB.T6G(SCH_1):PWRGD_PVDDCR_CPU1_P1_R

Q_CAP_0402-1000PF,50V,5%,EMPTY,TMP_QCH21006JB10  I90  C8360
   1 PWRGD_PVDDCR_CPU1_P1_R      A @T6G_MB_LIB.T6G(SCH_1):PWRGD_PVDDCR_CPU1_P1_R
   2    GND      B @T6G_MB_LIB.T6G(SCH_1):GND

Q_CAP_0402-0.1UF,25V,10%,X7R,CH4104K1B00  I93  PC93
   1 PVDDCR_CPU1_P1_VCCS      A @T6G_MB_LIB.T6G(SCH_1):PVDDCR_CPU1_P1_VCCS
   2    GND      B @T6G_MB_LIB.T6G(SCH_1):GND

Q_CAP_0402-0.1UF,25V,10%,X7R,CH4104K1B00  I95  PC29
   1 PVDDCR_CPU1_P1_VCC      A @T6G_MB_LIB.T6G(SCH_1):PVDDCR_CPU1_P1_VCC
   2    GND      B @T6G_MB_LIB.T6G(SCH_1):GND

Q_CAP_C0402-10UF,6.3V,20%,X6S,CH6101MEB03  I97  PC366
   1 PVDDCR_CPU1_P1_VCCS      A @T6G_MB_LIB.T6G(SCH_1):PVDDCR_CPU1_P1_VCCS
   2    GND      B @T6G_MB_LIB.T6G(SCH_1):GND

Q_CAP_C0402-1UF,16V,10%,X6S,CH5103KEB01  I99  PC365
   1 PVDDCR_CPU1_P1_VCC      A @T6G_MB_LIB.T6G(SCH_1):PVDDCR_CPU1_P1_VCC
   2    GND      B @T6G_MB_LIB.T6G(SCH_1):GND

Q_RES_0402LF-1,1%,1/16W,CHIP,CS-1002FB04  I124  PR253
   1 PVDDCR_CPU1_P1_VCC      A @T6G_MB_LIB.T6G(SCH_1):PVDDCR_CPU1_P1_VCC
   2 P3V3_AUX      B @T6G_MB_LIB.T6G(SCH_1):P3V3_AUX

Q_RES_0402LF-0,5%,1/16W,CHIP,CS00002JB13  I127  PR12
   1 NC_PVDDCR_CPU1_P1_IMON8      A @T6G_MB_LIB.T6G(SCH_1):NC_PVDDCR_CPU1_P1_IMON8
   2    GND      B @T6G_MB_LIB.T6G(SCH_1):GND

RAA229620GNPHA0-RAA229620GNP#HA0,SMLF,IC,ARF0TGP40A  I128  PU34
  27 PVDDCR_CPU1_P1_IMON1   CS11 @T6G_MB_LIB.T6G(SCH_1):PVDDCR_CPU1_P1_IMON1
  47 PVDDCR_CPU1_P1_VCC    VCC @T6G_MB_LIB.T6G(SCH_1):PVDDCR_CPU1_P1_VCC
  24 SVID_PVDDCR_CPU1_P1_SVTI_R   SVTI @T6G_MB_LIB.T6G(SCH_1):SVID_PVDDCR_CPU1_P1_SVTI_R
  14 SMB_CLK_PVDDCR_CPU1_P1_R  PMSCL @T6G_MB_LIB.T6G(SCH_1):SMB_CLK_PVDDCR_CPU1_P1_R
  22 SVID_PVDDCR_CPU1_P1_SVC_R1    SVC @T6G_MB_LIB.T6G(SCH_1):SVID_PVDDCR_CPU1_P1_SVC_R1
  32 PVDDCR_CPU1_P1_IMON6    CS6 @T6G_MB_LIB.T6G(SCH_1):PVDDCR_CPU1_P1_IMON6
  23 SVID_PVDDCR_CPU1_P1_SVTO_R   SVTO @T6G_MB_LIB.T6G(SCH_1):SVID_PVDDCR_CPU1_P1_SVTO_R
  18 PVDDCR_CPU1_P1_RESET_N_R RESET_L @T6G_MB_LIB.T6G(SCH_1):PVDDCR_CPU1_P1_RESET_N_R
  33 NC_PVDDCR_CPU1_P1_IMON7    CS5 @T6G_MB_LIB.T6G(SCH_1):NC_PVDDCR_CPU1_P1_IMON7
  34 NC_PVDDCR_CPU1_P1_IMON8    CS4 @T6G_MB_LIB.T6G(SCH_1):NC_PVDDCR_CPU1_P1_IMON8
  20 PWRGD_PVDDIO_P1_R    PG1 @T6G_MB_LIB.T6G(SCH_1):PWRGD_PVDDIO_P1_R
  21 SVID_PVDDCR_CPU1_P1_SVD_R1    SVD @T6G_MB_LIB.T6G(SCH_1):SVID_PVDDCR_CPU1_P1_SVD_R1
  15 PVDDCR_CPU1_P1_SMB_ALERT_R NPMALERT @T6G_MB_LIB.T6G(SCH_1):PVDDCR_CPU1_P1_SMB_ALERT_R
  17 PVDDCR_CPU1_P1_EN_R    EN0 @T6G_MB_LIB.T6G(SCH_1):PVDDCR_CPU1_P1_EN_R
  26 VSENSE_VSS_SENSE_C_P1  RGND0 @T6G_MB_LIB.T6G(SCH_1):VSENSE_VSS_SENSE_C_P1
  13 SMB_DIO_PVDDCR_CPU1_P1_R  PMSDA @T6G_MB_LIB.T6G(SCH_1):SMB_DIO_PVDDCR_CPU1_P1_R
   5 NC_PVDDCR_CPU1_P1_PWM8   PWM4 @T6G_MB_LIB.T6G(SCH_1):NC_PVDDCR_CPU1_P1_PWM8
   6 NC_PVDDCR_CPU1_P1_PWM7   PWM5 @T6G_MB_LIB.T6G(SCH_1):NC_PVDDCR_CPU1_P1_PWM7
  25 VSENSE_PVDDCR_CPU1_P1_VSEN0  VSEN0 @T6G_MB_LIB.T6G(SCH_1):VSENSE_PVDDCR_CPU1_P1_VSEN0
   2 PVDDIO_P1_PWM2   PWM1 @T6G_MB_LIB.T6G(SCH_1):PVDDIO_P1_PWM2
  16 PWRGD_PVDDCR_CPU1_P1_R    PG0 @T6G_MB_LIB.T6G(SCH_1):PWRGD_PVDDCR_CPU1_P1_R
   7 PVDDCR_CPU1_P1_PWM6   PWM6 @T6G_MB_LIB.T6G(SCH_1):PVDDCR_CPU1_P1_PWM6
  48 PVDDCR_CPU1_P1_VCCS   VCCS @T6G_MB_LIB.T6G(SCH_1):PVDDCR_CPU1_P1_VCCS
  45 PVDDCR_CPU1_P1_VMON VMON||IINSEN @T6G_MB_LIB.T6G(SCH_1):PVDDCR_CPU1_P1_VMON
  46 PVDDCR_CPU1_P1_VINSEN VINSEN @T6G_MB_LIB.T6G(SCH_1):PVDDCR_CPU1_P1_VINSEN
  44 PVDDCR_CPU1_P1_TEMP0  TEMP0 @T6G_MB_LIB.T6G(SCH_1):PVDDCR_CPU1_P1_TEMP0
  19 PVDD18_S5_P1  VDDIO @T6G_MB_LIB.T6G(SCH_1):PVDD18_S5_P1
  40 VSENSE_PVDDIO_P1_VSEN1  VSEN1 @T6G_MB_LIB.T6G(SCH_1):VSENSE_PVDDIO_P1_VSEN1
  39 VSENSE_VSS_SENSE_B_P1  RGND1 @T6G_MB_LIB.T6G(SCH_1):VSENSE_VSS_SENSE_B_P1
  37 PVDDIO_P1_IMON2    CS1 @T6G_MB_LIB.T6G(SCH_1):PVDDIO_P1_IMON2
  12 PVDDCR_CPU1_P1_PWM1  PWM11 @T6G_MB_LIB.T6G(SCH_1):PVDDCR_CPU1_P1_PWM1
   4 PVDDIO_P1_PWM4   PWM3 @T6G_MB_LIB.T6G(SCH_1):PVDDIO_P1_PWM4
  35 PVDDIO_P1_IMON4    CS3 @T6G_MB_LIB.T6G(SCH_1):PVDDIO_P1_IMON4
   3 PVDDIO_P1_PWM3   PWM2 @T6G_MB_LIB.T6G(SCH_1):PVDDIO_P1_PWM3
  36 PVDDIO_P1_IMON3    CS2 @T6G_MB_LIB.T6G(SCH_1):PVDDIO_P1_IMON3
  41 PVDDCR_CPU1_P1_OCP_N_R  OCP_L @T6G_MB_LIB.T6G(SCH_1):PVDDCR_CPU1_P1_OCP_N_R
  TH    GND TH_GND @T6G_MB_LIB.T6G(SCH_1):GND
  42 PVDDCR_CPU1_P1_EN1_ADDR_CFG EN1||ADDR_CFG @T6G_MB_LIB.T6G(SCH_1):PVDDCR_CPU1_P1_EN1_ADDR_CFG
  43 PVDDIO_P1_TEMP1  TEMP1 @T6G_MB_LIB.T6G(SCH_1):PVDDIO_P1_TEMP1
   1 PVDDIO_P1_PWM1   PWM0 @T6G_MB_LIB.T6G(SCH_1):PVDDIO_P1_PWM1
  38 PVDDIO_P1_IMON1    CS0 @T6G_MB_LIB.T6G(SCH_1):PVDDIO_P1_IMON1
   8 PVDDCR_CPU1_P1_PWM5   PWM7 @T6G_MB_LIB.T6G(SCH_1):PVDDCR_CPU1_P1_PWM5
  31 PVDDCR_CPU1_P1_IMON5    CS7 @T6G_MB_LIB.T6G(SCH_1):PVDDCR_CPU1_P1_IMON5
   9 PVDDCR_CPU1_P1_PWM4   PWM8 @T6G_MB_LIB.T6G(SCH_1):PVDDCR_CPU1_P1_PWM4
  30 PVDDCR_CPU1_P1_IMON4    CS8 @T6G_MB_LIB.T6G(SCH_1):PVDDCR_CPU1_P1_IMON4
  10 PVDDCR_CPU1_P1_PWM3   PWM9 @T6G_MB_LIB.T6G(SCH_1):PVDDCR_CPU1_P1_PWM3
  29 PVDDCR_CPU1_P1_IMON3    CS9 @T6G_MB_LIB.T6G(SCH_1):PVDDCR_CPU1_P1_IMON3
  11 PVDDCR_CPU1_P1_PWM2  PWM10 @T6G_MB_LIB.T6G(SCH_1):PVDDCR_CPU1_P1_PWM2
  28 PVDDCR_CPU1_P1_IMON2   CS10 @T6G_MB_LIB.T6G(SCH_1):PVDDCR_CPU1_P1_IMON2

Q_RES_0402LF-10K,1%,1/16W,EMPTY,CS31002FB08  I130  R6088
   1 PVDDIO_P1_EN_R      A @T6G_MB_LIB.T6G(SCH_1):PVDDIO_P1_EN_R
   2    GND      B @T6G_MB_LIB.T6G(SCH_1):GND

Q_CAP_0402-1000PF,50V,5%,X7R,TMP_QCH21006JB10  I131  C5022
   1    GND      A @T6G_MB_LIB.T6G(SCH_1):GND
   2 PWRGD_PVDDCR_CPU1_P1      B @T6G_MB_LIB.T6G(SCH_1):PWRGD_PVDDCR_CPU1_P1

Q_CAP_0402-1000PF,50V,5%,X7R,TMP_QCH21006JB10  I133  C5020
   1    GND      A @T6G_MB_LIB.T6G(SCH_1):GND
   2 PVDDCR_CPU1_P1_SMB_ALERT      B @T6G_MB_LIB.T6G(SCH_1):PVDDCR_CPU1_P1_SMB_ALERT

Q_CAP_0402-1000PF,50V,5%,X7R,TMP_QCH21006JB10  I136  C5006
   1    GND      A @T6G_MB_LIB.T6G(SCH_1):GND
   2 PWRGD_PVDDIO_P1      B @T6G_MB_LIB.T6G(SCH_1):PWRGD_PVDDIO_P1

Q_RES_0402LF-0,5%,1/16W,CHIP,CS00002JB13  I137  PR8011
   1 SVID_PVDDCR_CPU1_P1_SVC_R      A @T6G_MB_LIB.T6G(SCH_1):SVID_PVDDCR_CPU1_P1_SVC_R
   2 SVID_PVDDCR_CPU1_P1_SVC_R1      B @T6G_MB_LIB.T6G(SCH_1):SVID_PVDDCR_CPU1_P1_SVC_R1

Q_RES_0402LF-0,5%,1/16W,CHIP,CS00002JB13  I138  PR8012
   1 SVID_PVDDCR_CPU1_P1_SVD_R      A @T6G_MB_LIB.T6G(SCH_1):SVID_PVDDCR_CPU1_P1_SVD_R
   2 SVID_PVDDCR_CPU1_P1_SVD_R1      B @T6G_MB_LIB.T6G(SCH_1):SVID_PVDDCR_CPU1_P1_SVD_R1


DRAWING: @T6G_MB_LIB.T6G(SCH_1):PAGE197 

Q_CAP_0402-0.1UF,25V,10%,X7R,CH4104K1B00  I3  PC436_8
   1 PVDDCR_CPU1_P1_VCCS      A @T6G_MB_LIB.T6G(SCH_1):PVDDCR_CPU1_P1_VCCS
   2    GND      B @T6G_MB_LIB.T6G(SCH_1):GND

Q_CAP_0402-0.1UF,25V,10%,X7R,CH4104K1B00  I4  PC435_7
   1 PVDDCR_CPU1_P1_VCCS      A @T6G_MB_LIB.T6G(SCH_1):PVDDCR_CPU1_P1_VCCS
   2    GND      B @T6G_MB_LIB.T6G(SCH_1):GND

Q_RES_0402LF-8.87K,1%,1/16W,EMPTY,CS28872FB01  I6  PR274
   1 PVDDIO_P1_LSET2      A @T6G_MB_LIB.T6G(SCH_1):PVDDIO_P1_LSET2
   2    GND      B @T6G_MB_LIB.T6G(SCH_1):GND

Q_CAP_C0402-2.2UF,10V,10%,X6S,CH5222KEB01  I12  PC432
   1 PVDDIO_P1_VCC2      A @T6G_MB_LIB.T6G(SCH_1):PVDDIO_P1_VCC2
   2    GND      B @T6G_MB_LIB.T6G(SCH_1):GND

Q_RES_0402LF-2.2,1%,1/16W,CHIP,CS-2202FB01  I13  PR276
   1 PVDDCR_CPU1_P1_PVCC      A @T6G_MB_LIB.T6G(SCH_1):PVDDCR_CPU1_P1_PVCC
   2 PVDDIO_P1_VCC2      B @T6G_MB_LIB.T6G(SCH_1):PVDDIO_P1_VCC2

Q_CAP_C0402-2.2UF,10V,10%,X6S,CH5222KEB01  I16  PC434_IOP1_2
   1 PVDDCR_CPU1_P1_PVCC      A @T6G_MB_LIB.T6G(SCH_1):PVDDCR_CPU1_P1_PVCC
   2    GND      B @T6G_MB_LIB.T6G(SCH_1):GND

Q_RES_0402LF-1.5,1%,1/8W,EMPTY,CS-1504FB00  I19  PR489
   1 SW_PVDDIO_P1_SW2_RC      A @T6G_MB_LIB.T6G(SCH_1):SW_PVDDIO_P1_SW2_RC
   2    GND      B @T6G_MB_LIB.T6G(SCH_1):GND

Q_CAP_C0402-560PF,50V,10%,EMPTY,CH1566K1B09  I20  PC175
   1 SW_PVDDIO_P1_SW2      A @T6G_MB_LIB.T6G(SCH_1):SW_PVDDIO_P1_SW2
   2 SW_PVDDIO_P1_SW2_RC      B @T6G_MB_LIB.T6G(SCH_1):SW_PVDDIO_P1_SW2_RC

Q_CAP_0402-0.1UF,25V,10%,X7R,CH4104K1B00  I21  PC439_2
   1 SW_P12V_AUX_PVDDIO_P1_FLT      A @T6G_MB_LIB.T6G(SCH_1):SW_P12V_AUX_PVDDIO_P1_FLT
   2    GND      B @T6G_MB_LIB.T6G(SCH_1):GND

Q_RES_0402LF-5.6,1%,1/16W,CHIP,CS-5602FB01  I22  PR278
   1 SW_PVDDIO_P1_BOOT2      A @T6G_MB_LIB.T6G(SCH_1):SW_PVDDIO_P1_BOOT2
   2 SW_PVDDIO_P1_BOOT2_R      B @T6G_MB_LIB.T6G(SCH_1):SW_PVDDIO_P1_BOOT2_R

Q_CAP_C0402-1UF,25V,10%,X6S,CH5104KEB02  I23  PC441_2
   1 SW_P12V_AUX_PVDDIO_P1_FLT      A @T6G_MB_LIB.T6G(SCH_1):SW_P12V_AUX_PVDDIO_P1_FLT
   2    GND      B @T6G_MB_LIB.T6G(SCH_1):GND

Q_RES_0402LF-1.5,1%,1/8W,EMPTY,CS-1504FB00  I26  PR488
   1 SW_PVDDIO_P1_SW1_RC      A @T6G_MB_LIB.T6G(SCH_1):SW_PVDDIO_P1_SW1_RC
   2    GND      B @T6G_MB_LIB.T6G(SCH_1):GND

Q_RES_0402LF-8.87K,1%,1/16W,EMPTY,CS28872FB01  I28  PR275
   1 PVDDIO_P1_LSET1      A @T6G_MB_LIB.T6G(SCH_1):PVDDIO_P1_LSET1
   2    GND      B @T6G_MB_LIB.T6G(SCH_1):GND

Q_CAP_C0402-2.2UF,10V,10%,X6S,CH5222KEB01  I34  PC433
   1 PVDDIO_P1_VCC1      A @T6G_MB_LIB.T6G(SCH_1):PVDDIO_P1_VCC1
   2    GND      B @T6G_MB_LIB.T6G(SCH_1):GND

Q_RES_0402LF-2.2,1%,1/16W,CHIP,CS-2202FB01  I35  PR277
   1 PVDDCR_CPU1_P1_PVCC      A @T6G_MB_LIB.T6G(SCH_1):PVDDCR_CPU1_P1_PVCC
   2 PVDDIO_P1_VCC1      B @T6G_MB_LIB.T6G(SCH_1):PVDDIO_P1_VCC1

Q_CAP_C0402-2.2UF,10V,10%,X6S,CH5222KEB01  I38  PC437_IOP1_1
   1 PVDDCR_CPU1_P1_PVCC      A @T6G_MB_LIB.T6G(SCH_1):PVDDCR_CPU1_P1_PVCC
   2    GND      B @T6G_MB_LIB.T6G(SCH_1):GND

ISL99390FRZTR5935-ISL99390FRZ-TR5935,SMLF,IC,AL099A  I39  PU39
  34 PVDDIO_P1_PWM1    PWM @T6G_MB_LIB.T6G(SCH_1):PVDDIO_P1_PWM1
  39 PVDDCR_CPU1_P1_VCCS  REFIN @T6G_MB_LIB.T6G(SCH_1):PVDDCR_CPU1_P1_VCCS
   3 PVDDIO_P1_VCC1    VCC @T6G_MB_LIB.T6G(SCH_1):PVDDIO_P1_VCC1
   2    GND   AGND @T6G_MB_LIB.T6G(SCH_1):GND
  33 SW_PVDDIO_P1_BOOT1   BOOT @T6G_MB_LIB.T6G(SCH_1):SW_PVDDIO_P1_BOOT1
25_29 SW_P12V_AUX_PVDDIO_P1_FLT   VIN1 @T6G_MB_LIB.T6G(SCH_1):SW_P12V_AUX_PVDDIO_P1_FLT
  32 SW_PVDDIO_P1_BOOTR1  PHASE @T6G_MB_LIB.T6G(SCH_1):SW_PVDDIO_P1_BOOTR1
   4 PVDDCR_CPU1_P1_PVCC   PVCC @T6G_MB_LIB.T6G(SCH_1):PVDDCR_CPU1_P1_PVCC
  36 PVDDIO_P1_TEMP1 TOUT_FLT @T6G_MB_LIB.T6G(SCH_1):PVDDIO_P1_TEMP1
  38 PVDDIO_P1_IMON1   IOUT @T6G_MB_LIB.T6G(SCH_1):PVDDIO_P1_IMON1
  37 PVDDIO_P1_LSET1   LSET @T6G_MB_LIB.T6G(SCH_1):PVDDIO_P1_LSET1
10_19 SW_PVDDIO_P1_SW1     SW @T6G_MB_LIB.T6G(SCH_1):SW_PVDDIO_P1_SW1
   5    GND  PGND1 @T6G_MB_LIB.T6G(SCH_1):GND
  30 SW_P12V_AUX_PVDDIO_P1_FLT   VIN2 @T6G_MB_LIB.T6G(SCH_1):SW_P12V_AUX_PVDDIO_P1_FLT
   1 PVDDIO_P1_VOS1    VOS @T6G_MB_LIB.T6G(SCH_1):PVDDIO_P1_VOS1
  40    GND  PGND3 @T6G_MB_LIB.T6G(SCH_1):GND
  35 PVDDIO_P1_VCC1     EN @T6G_MB_LIB.T6G(SCH_1):PVDDIO_P1_VCC1
  31 NC_PVDDIO_P1_DNC1    DNC @T6G_MB_LIB.T6G(SCH_1):NC_PVDDIO_P1_DNC1
   6 NC_PVDDIO_P1_GL1_1    GL1 @T6G_MB_LIB.T6G(SCH_1):NC_PVDDIO_P1_GL1_1
  41 NC_PVDDIO_P1_GL2_1    GL2 @T6G_MB_LIB.T6G(SCH_1):NC_PVDDIO_P1_GL2_1
7_9-20_24    GND  PGND2 @T6G_MB_LIB.T6G(SCH_1):GND

Q_CAP_C0402-560PF,50V,10%,EMPTY,CH1566K1B09  I40  PC174
   1 SW_PVDDIO_P1_SW1      A @T6G_MB_LIB.T6G(SCH_1):SW_PVDDIO_P1_SW1
   2 SW_PVDDIO_P1_SW1_RC      B @T6G_MB_LIB.T6G(SCH_1):SW_PVDDIO_P1_SW1_RC

Q_CAP_0402-0.1UF,25V,10%,X7R,CH4104K1B00  I41  PC438_1
   1 SW_P12V_AUX_PVDDIO_P1_FLT      A @T6G_MB_LIB.T6G(SCH_1):SW_P12V_AUX_PVDDIO_P1_FLT
   2    GND      B @T6G_MB_LIB.T6G(SCH_1):GND

Q_CAP_C0402-1UF,25V,10%,X6S,CH5104KEB02  I42  PC440_1
   1 SW_P12V_AUX_PVDDIO_P1_FLT      A @T6G_MB_LIB.T6G(SCH_1):SW_P12V_AUX_PVDDIO_P1_FLT
   2    GND      B @T6G_MB_LIB.T6G(SCH_1):GND

Q_RES_0402LF-5.6,1%,1/16W,CHIP,CS-5602FB01  I43  PR279
   1 SW_PVDDIO_P1_BOOT1      A @T6G_MB_LIB.T6G(SCH_1):SW_PVDDIO_P1_BOOT1
   2 SW_PVDDIO_P1_BOOT1_R      B @T6G_MB_LIB.T6G(SCH_1):SW_PVDDIO_P1_BOOT1_R

Q_CAP_C0805-22UF,16V,20%,X6S,CH6223MEA01  I44  PC442_1
   1 SW_P12V_AUX_PVDDIO_P1_FLT      A @T6G_MB_LIB.T6G(SCH_1):SW_P12V_AUX_PVDDIO_P1_FLT
   2    GND      B @T6G_MB_LIB.T6G(SCH_1):GND

Q_RES_0402LF-0,5%,1/16W,CHIP,CS00002JB13  I45  PR281
   1 PVDDIO_P1_VOS2      A @T6G_MB_LIB.T6G(SCH_1):PVDDIO_P1_VOS2
   2 PVDDIO_P1      B @T6G_MB_LIB.T6G(SCH_1):PVDDIO_P1

Q_CAP_0402-0.22UF,16V,10%,X7R,CH4223K1B00  I47  PC445
   1 SW_PVDDIO_P1_BOOT2_R      A @T6G_MB_LIB.T6G(SCH_1):SW_PVDDIO_P1_BOOT2_R
   2 SW_PVDDIO_P1_BOOTR2      B @T6G_MB_LIB.T6G(SCH_1):SW_PVDDIO_P1_BOOTR2

Q_CAP_C0805-22UF,16V,20%,X6S,CH6223MEA01  I48  PC443_2
   1 SW_P12V_AUX_PVDDIO_P1_FLT      A @T6G_MB_LIB.T6G(SCH_1):SW_P12V_AUX_PVDDIO_P1_FLT
   2    GND      B @T6G_MB_LIB.T6G(SCH_1):GND

Q_CAP_C0805-22UF,16V,20%,X6S,CH6223MEA01  I49  PC446_2
   1 SW_P12V_AUX_PVDDIO_P1_FLT      A @T6G_MB_LIB.T6G(SCH_1):SW_P12V_AUX_PVDDIO_P1_FLT
   2    GND      B @T6G_MB_LIB.T6G(SCH_1):GND

Q_RES_0402LF-0,5%,1/16W,CHIP,CS00002JB13  I50  PR280
   1 PVDDIO_P1_VOS1      A @T6G_MB_LIB.T6G(SCH_1):PVDDIO_P1_VOS1
   2 PVDDIO_P1      B @T6G_MB_LIB.T6G(SCH_1):PVDDIO_P1

Q_CAP_C0805-22UF,16V,20%,X6S,CH6223MEA01  I52  PC449_2
   1 SW_P12V_AUX_PVDDIO_P1_FLT      A @T6G_MB_LIB.T6G(SCH_1):SW_P12V_AUX_PVDDIO_P1_FLT
   2    GND      B @T6G_MB_LIB.T6G(SCH_1):GND

Q_CAP_C0805-22UF,4V,20%,X6S,CH622KMEA03  I55  PC458_2
   1 PVDDIO_P1      A @T6G_MB_LIB.T6G(SCH_1):PVDDIO_P1
   2    GND      B @T6G_MB_LIB.T6G(SCH_1):GND

Q_CAP_C0805-22UF,4V,20%,X6S,CH622KMEA03  I57  PC460_2
   1 PVDDIO_P1      A @T6G_MB_LIB.T6G(SCH_1):PVDDIO_P1
   2    GND      B @T6G_MB_LIB.T6G(SCH_1):GND

Q_CAPP_SMLF-470UF,2.5V,20%,SPCAP,CH747LM8825  I58  PC450
   1 PVDDIO_P1      A @T6G_MB_LIB.T6G(SCH_1):PVDDIO_P1
   2    GND      B @T6G_MB_LIB.T6G(SCH_1):GND

Q_CAPP_SMLF-470UF,2.5V,20%,SPCAP,CH747LM8825  I59  PC452
   1 PVDDIO_P1      A @T6G_MB_LIB.T6G(SCH_1):PVDDIO_P1
   2    GND      B @T6G_MB_LIB.T6G(SCH_1):GND

Q_CAPP_SMLF-470UF,2.5V,20%,EMPTY,CH747LM8825  I62  PC455
   1 PVDDIO_P1      A @T6G_MB_LIB.T6G(SCH_1):PVDDIO_P1
   2    GND      B @T6G_MB_LIB.T6G(SCH_1):GND

Q_CAP_0402-0.22UF,16V,10%,X7R,CH4223K1B00  I65  PC447
   1 SW_PVDDIO_P1_BOOT1_R      A @T6G_MB_LIB.T6G(SCH_1):SW_PVDDIO_P1_BOOT1_R
   2 SW_PVDDIO_P1_BOOTR1      B @T6G_MB_LIB.T6G(SCH_1):SW_PVDDIO_P1_BOOTR1

Q_CAP_C0805-22UF,16V,20%,X6S,CH6223MEA01  I66  PC444_1
   1 SW_P12V_AUX_PVDDIO_P1_FLT      A @T6G_MB_LIB.T6G(SCH_1):SW_P12V_AUX_PVDDIO_P1_FLT
   2    GND      B @T6G_MB_LIB.T6G(SCH_1):GND

Q_CAP_C0805-22UF,16V,20%,X6S,CH6223MEA01  I69  PC448_1
   1 SW_P12V_AUX_PVDDIO_P1_FLT      A @T6G_MB_LIB.T6G(SCH_1):SW_P12V_AUX_PVDDIO_P1_FLT
   2    GND      B @T6G_MB_LIB.T6G(SCH_1):GND

Q_INDUCTOR4P_14-150NH,SMLF,IND,CV+15^0TZ04  I71  PL47
   2 IND_PVDDIO_P1_CPL2      2 @T6G_MB_LIB.T6G(SCH_1):IND_PVDDIO_P1_CPL2
   3    GND      3 @T6G_MB_LIB.T6G(SCH_1):GND
   4 PVDDIO_P1      4 @T6G_MB_LIB.T6G(SCH_1):PVDDIO_P1
   1 SW_PVDDIO_P1_SW1      1 @T6G_MB_LIB.T6G(SCH_1):SW_PVDDIO_P1_SW1

Q_INDUCTOR_SMLF-50NH/86A,IND,CVA50^0MZ09  I72  PL49
   2 P12V_AUX      2 @T6G_MB_LIB.T6G(SCH_1):P12V_AUX
   1 SW_P12V_AUX_PVDDIO_P1_FLT      1 @T6G_MB_LIB.T6G(SCH_1):SW_P12V_AUX_PVDDIO_P1_FLT

Q_CAP_0402-0.1UF,25V,10%,X7R,CH4104K1B00  I74  PC438
   1 P12V_AUX      A @T6G_MB_LIB.T6G(SCH_1):P12V_AUX
   2    GND      B @T6G_MB_LIB.T6G(SCH_1):GND

Q_CAP_C0402-100NF,50V,10%,X7R,CH4106K1B01  I77  PC451
   1 PVDDIO_P1      A @T6G_MB_LIB.T6G(SCH_1):PVDDIO_P1
   2    GND      B @T6G_MB_LIB.T6G(SCH_1):GND

Q_CAP_C0805-22UF,4V,20%,X6S,CH622KMEA03  I78  PC456_1
   1 PVDDIO_P1      A @T6G_MB_LIB.T6G(SCH_1):PVDDIO_P1
   2    GND      B @T6G_MB_LIB.T6G(SCH_1):GND

Q_CAP_C0805-22UF,4V,20%,X6S,CH622KMEA03  I79  PC459_1
   1 PVDDIO_P1      A @T6G_MB_LIB.T6G(SCH_1):PVDDIO_P1
   2    GND      B @T6G_MB_LIB.T6G(SCH_1):GND

Q_RES_0402LF-1K,1%,1/16W,CHIP,CS21002FB06  I81  PR378
   1 PVDDIO_P1      A @T6G_MB_LIB.T6G(SCH_1):PVDDIO_P1
   2    GND      B @T6G_MB_LIB.T6G(SCH_1):GND

Q_INDUCTOR4P_14-150NH,SMLF,IND,CV+15^0TZ04  I83  PL48
   2 IND_PVDDIO_P1_CPL3      2 @T6G_MB_LIB.T6G(SCH_1):IND_PVDDIO_P1_CPL3
   3 IND_PVDDIO_P1_CPL2      3 @T6G_MB_LIB.T6G(SCH_1):IND_PVDDIO_P1_CPL2
   4 PVDDIO_P1      4 @T6G_MB_LIB.T6G(SCH_1):PVDDIO_P1
   1 SW_PVDDIO_P1_SW2      1 @T6G_MB_LIB.T6G(SCH_1):SW_PVDDIO_P1_SW2

ISL99390FRZTR5935-ISL99390FRZ-TR5935,SMLF,IC,AL099A  I84  PU40
  34 PVDDIO_P1_PWM2    PWM @T6G_MB_LIB.T6G(SCH_1):PVDDIO_P1_PWM2
  39 PVDDCR_CPU1_P1_VCCS  REFIN @T6G_MB_LIB.T6G(SCH_1):PVDDCR_CPU1_P1_VCCS
   3 PVDDIO_P1_VCC2    VCC @T6G_MB_LIB.T6G(SCH_1):PVDDIO_P1_VCC2
   2    GND   AGND @T6G_MB_LIB.T6G(SCH_1):GND
  33 SW_PVDDIO_P1_BOOT2   BOOT @T6G_MB_LIB.T6G(SCH_1):SW_PVDDIO_P1_BOOT2
25_29 SW_P12V_AUX_PVDDIO_P1_FLT   VIN1 @T6G_MB_LIB.T6G(SCH_1):SW_P12V_AUX_PVDDIO_P1_FLT
  32 SW_PVDDIO_P1_BOOTR2  PHASE @T6G_MB_LIB.T6G(SCH_1):SW_PVDDIO_P1_BOOTR2
   4 PVDDCR_CPU1_P1_PVCC   PVCC @T6G_MB_LIB.T6G(SCH_1):PVDDCR_CPU1_P1_PVCC
  36 PVDDIO_P1_TEMP1 TOUT_FLT @T6G_MB_LIB.T6G(SCH_1):PVDDIO_P1_TEMP1
  38 PVDDIO_P1_IMON2   IOUT @T6G_MB_LIB.T6G(SCH_1):PVDDIO_P1_IMON2
  37 PVDDIO_P1_LSET2   LSET @T6G_MB_LIB.T6G(SCH_1):PVDDIO_P1_LSET2
10_19 SW_PVDDIO_P1_SW2     SW @T6G_MB_LIB.T6G(SCH_1):SW_PVDDIO_P1_SW2
   5    GND  PGND1 @T6G_MB_LIB.T6G(SCH_1):GND
  30 SW_P12V_AUX_PVDDIO_P1_FLT   VIN2 @T6G_MB_LIB.T6G(SCH_1):SW_P12V_AUX_PVDDIO_P1_FLT
   1 PVDDIO_P1_VOS2    VOS @T6G_MB_LIB.T6G(SCH_1):PVDDIO_P1_VOS2
  40    GND  PGND3 @T6G_MB_LIB.T6G(SCH_1):GND
  35 PVDDIO_P1_VCC2     EN @T6G_MB_LIB.T6G(SCH_1):PVDDIO_P1_VCC2
  31 NC_PVDDIO_P1_DNC2    DNC @T6G_MB_LIB.T6G(SCH_1):NC_PVDDIO_P1_DNC2
   6 NC_PVDDIO_P1_GL1_2    GL1 @T6G_MB_LIB.T6G(SCH_1):NC_PVDDIO_P1_GL1_2
  41 NC_PVDDIO_P1_GL2_2    GL2 @T6G_MB_LIB.T6G(SCH_1):NC_PVDDIO_P1_GL2_2
7_9-20_24    GND  PGND2 @T6G_MB_LIB.T6G(SCH_1):GND

Q_CAPP_SMLF-270UF,16V,20%,OSCON,CC72703MZ11  I85  PC454
   1 SW_P12V_AUX_PVDDIO_P1_FLT      A @T6G_MB_LIB.T6G(SCH_1):SW_P12V_AUX_PVDDIO_P1_FLT
   2    GND      B @T6G_MB_LIB.T6G(SCH_1):GND

Q_CAP_C0805-22UF,16V,20%,X6S,CH6223MEA01  I86  PC7001
   1 SW_P12V_AUX_PVDDIO_P1_FLT      A @T6G_MB_LIB.T6G(SCH_1):SW_P12V_AUX_PVDDIO_P1_FLT
   2    GND      B @T6G_MB_LIB.T6G(SCH_1):GND


DRAWING: @T6G_MB_LIB.T6G(SCH_1):PAGE199 

Q_RES_0402LF-40.2K,1%,1/16W,CHIP,CS34022FB04  I2  PR376
   1 P5V_AUX      A @T6G_MB_LIB.T6G(SCH_1):P5V_AUX
   2 PVDD11_S3_P1_VMON      B @T6G_MB_LIB.T6G(SCH_1):PVDD11_S3_P1_VMON

Q_CAP_0402-0.1UF,25V,10%,X7R,CH4104K1B00  I4  PC638
   1 PVDD11_S3_P1_VMON      A @T6G_MB_LIB.T6G(SCH_1):PVDD11_S3_P1_VMON
   2    GND      B @T6G_MB_LIB.T6G(SCH_1):GND

Q_RES_0402LF-10K,1%,1/16W,CHIP,CS31002FB08  I6  PR6
   1 PVDD11_S3_P1_VMON      A @T6G_MB_LIB.T6G(SCH_1):PVDD11_S3_P1_VMON
   2    GND      B @T6G_MB_LIB.T6G(SCH_1):GND

Q_RES_0402LF-0,5%,1/16W,EMPTY,CS00002JB13  I9  R8146
   1 P3V3_AUX      A @T6G_MB_LIB.T6G(SCH_1):P3V3_AUX
   2 PVDD11_S3_P1_VDDIO      B @T6G_MB_LIB.T6G(SCH_1):PVDD11_S3_P1_VDDIO

Q_RES_0402LF-0,5%,1/16W,EMPTY,CS00002JB13  I13  R8010
   1 PVDD11_S3_P1_OCP_N      A @T6G_MB_LIB.T6G(SCH_1):PVDD11_S3_P1_OCP_N
   2 PVDD11_S3_P1_OCP_N_R      B @T6G_MB_LIB.T6G(SCH_1):PVDD11_S3_P1_OCP_N_R

Q_RES_0402LF-49.9,1%,1/16W,CHIP,CS04992FB07  I15  PR288
   1 VSENSE_VSS_SENSE_C_P1      A @T6G_MB_LIB.T6G(SCH_1):VSENSE_VSS_SENSE_C_P1
   2    GND      B @T6G_MB_LIB.T6G(SCH_1):GND

Q_RES_0402LF-4.99K,1%,1/16W,EMPTY,CS24992FB07  I17  PR604
   1 PVDD11_S3_P1_VINSEN      A @T6G_MB_LIB.T6G(SCH_1):PVDD11_S3_P1_VINSEN
   2    GND      B @T6G_MB_LIB.T6G(SCH_1):GND

Q_RES_0402LF-0,5%,1/16W,CHIP,CS00002JB13  I18  PR388
   1 P12V_AUX      A @T6G_MB_LIB.T6G(SCH_1):P12V_AUX
   2 PVDD11_S3_P1_VINSEN      B @T6G_MB_LIB.T6G(SCH_1):PVDD11_S3_P1_VINSEN

Q_CAP_0402-0.1UF,25V,10%,X7R,CH4104K1B00  I20  PC8
   1 PVDD11_S3_P1_VINSEN      A @T6G_MB_LIB.T6G(SCH_1):PVDD11_S3_P1_VINSEN
   2    GND      B @T6G_MB_LIB.T6G(SCH_1):GND

Q_RES_0402LF-1K,1%,1/16W,EMPTY,CS21002FB06  I24  R8011
   1 PVDD18_S5_P1      A @T6G_MB_LIB.T6G(SCH_1):PVDD18_S5_P1
   2 PVDD11_S3_P1_OCP_N_R      B @T6G_MB_LIB.T6G(SCH_1):PVDD11_S3_P1_OCP_N_R

Q_RES_0402LF-0,5%,1/16W,CHIP,CS00002JB13  I27  PR384
   1 VSENSE_PVDD11_S3_P1_DP      A @T6G_MB_LIB.T6G(SCH_1):VSENSE_PVDD11_S3_P1_DP
   2 VSENSE_PVDD11_S3_P1_R      B @T6G_MB_LIB.T6G(SCH_1):VSENSE_PVDD11_S3_P1_R

Q_CAP_0402-3300PF,50V,10%,X7R,TMP_QCH2336K1B12  I28  PC639
   1 VSENSE_PVDD11_S3_P1_R      A @T6G_MB_LIB.T6G(SCH_1):VSENSE_PVDD11_S3_P1_R
   2 VSENSE_VSS_SENSE_C_P1      B @T6G_MB_LIB.T6G(SCH_1):VSENSE_VSS_SENSE_C_P1

Q_RES_0402LF-49.9,1%,1/16W,CHIP,CS04992FB07  I29  PR229
   1 PVDD11_S3_P1      A @T6G_MB_LIB.T6G(SCH_1):PVDD11_S3_P1
   2 VSENSE_PVDD11_S3_P1_DP      B @T6G_MB_LIB.T6G(SCH_1):VSENSE_PVDD11_S3_P1_DP

Q_RES_0402LF-1K,1%,1/16W,CHIP,CS21002FB06  I37  R8380
   1 P3V3_AUX      A @T6G_MB_LIB.T6G(SCH_1):P3V3_AUX
   2 PWRGD_PVDD11_S3_P1_R      B @T6G_MB_LIB.T6G(SCH_1):PWRGD_PVDD11_S3_P1_R

Q_RES_0402LF-33,5%,1/16W,CHIP,CS03302JB10  I38  R8383
   1 PVDD11_S3_P1_PMALERT      A @T6G_MB_LIB.T6G(SCH_1):PVDD11_S3_P1_PMALERT
   2 PVDD11_S3_P1_PMALERT_R      B @T6G_MB_LIB.T6G(SCH_1):PVDD11_S3_P1_PMALERT_R

Q_RES_0402LF-0,5%,1/16W,CHIP,CS00002JB13  I39  R8382
   1 SMB_SCM_2_R2_SDA      A @T6G_MB_LIB.T6G(SCH_1):SMB_SCM_2_R2_SDA
   2 PVDD11_S3_P1_PMSDA_R      B @T6G_MB_LIB.T6G(SCH_1):PVDD11_S3_P1_PMSDA_R

Q_RES_0402LF-0,5%,1/16W,CHIP,CS00002JB13  I40  R8381
   1 SMB_SCM_2_R2_SCL      A @T6G_MB_LIB.T6G(SCH_1):SMB_SCM_2_R2_SCL
   2 PVDD11_S3_P1_PMSCL_R      B @T6G_MB_LIB.T6G(SCH_1):PVDD11_S3_P1_PMSCL_R

Q_RES_0402LF-0,5%,1/16W,CHIP,CS00002JB13  I42  R8386
   1 PVDD11_S3_P1_EN      A @T6G_MB_LIB.T6G(SCH_1):PVDD11_S3_P1_EN
   2 PVDD11_S3_P1_EN_R      B @T6G_MB_LIB.T6G(SCH_1):PVDD11_S3_P1_EN_R

Q_RES_0402LF-0,5%,1/16W,CHIP,CS00002JB13  I43  R8385
   1 PWRGD_PVDD11_S3_P1      A @T6G_MB_LIB.T6G(SCH_1):PWRGD_PVDD11_S3_P1
   2 PWRGD_PVDD11_S3_P1_R      B @T6G_MB_LIB.T6G(SCH_1):PWRGD_PVDD11_S3_P1_R

Q_CAP_0402-1000PF,50V,5%,X7R,TMP_QCH21006JB10  I44  C642
   1 PVDD11_S3_P1_EN_R      A @T6G_MB_LIB.T6G(SCH_1):PVDD11_S3_P1_EN_R
   2    GND      B @T6G_MB_LIB.T6G(SCH_1):GND

Q_CAP_0402-1000PF,50V,5%,EMPTY,TMP_QCH21006JB10  I46  C8641
   1 PWRGD_PVDD11_S3_P1_R      A @T6G_MB_LIB.T6G(SCH_1):PWRGD_PVDD11_S3_P1_R
   2    GND      B @T6G_MB_LIB.T6G(SCH_1):GND

Q_CAP_0402-470PF,50V,10%,X7R,TMP_QCH14706KB18  I49  PC643
   1 PVDD11_S3_P1_TEMP0      A @T6G_MB_LIB.T6G(SCH_1):PVDD11_S3_P1_TEMP0
   2    GND      B @T6G_MB_LIB.T6G(SCH_1):GND

Q_RES_0402LF-0,5%,1/16W,CHIP,CS00002JB13  I51  PR415
   1 PVDD11_S3_P1_TEMP1      A @T6G_MB_LIB.T6G(SCH_1):PVDD11_S3_P1_TEMP1
   2    GND      B @T6G_MB_LIB.T6G(SCH_1):GND

Q_RES_0402LF-0,5%,1/16W,CHIP,CS00002JB13  I52  PR409
   1 NC_PVDD11_S3_P1_IMON8      A @T6G_MB_LIB.T6G(SCH_1):NC_PVDD11_S3_P1_IMON8
   2    GND      B @T6G_MB_LIB.T6G(SCH_1):GND

Q_RES_0402LF-0,5%,1/16W,EMPTY,CS00002JB13  I56  PR390
   1 PVDD11_S3_P1_RESET_N_R      A @T6G_MB_LIB.T6G(SCH_1):PVDD11_S3_P1_RESET_N_R
   2    GND      B @T6G_MB_LIB.T6G(SCH_1):GND

Q_RES_0402LF-0,5%,1/16W,CHIP,CS00002JB13  I57  PR408
   1 NC_PVDD11_S3_P1_IMON7      A @T6G_MB_LIB.T6G(SCH_1):NC_PVDD11_S3_P1_IMON7
   2    GND      B @T6G_MB_LIB.T6G(SCH_1):GND

Q_RES_0402LF-0,5%,1/16W,CHIP,CS00002JB13  I58  PR14
   1 NC_PVDD11_S3_P1_IMON6      A @T6G_MB_LIB.T6G(SCH_1):NC_PVDD11_S3_P1_IMON6
   2    GND      B @T6G_MB_LIB.T6G(SCH_1):GND

Q_RES_0402LF-0,5%,1/16W,CHIP,CS00002JB13  I59  PR13
   1 NC_PVDD11_S3_P1_IMON5      A @T6G_MB_LIB.T6G(SCH_1):NC_PVDD11_S3_P1_IMON5
   2    GND      B @T6G_MB_LIB.T6G(SCH_1):GND

Q_RES_0402LF-0,5%,1/16W,CHIP,CS00002JB13  I60  PR407
   1 NC_PVDD11_S3_P1_IMON4      A @T6G_MB_LIB.T6G(SCH_1):NC_PVDD11_S3_P1_IMON4
   2    GND      B @T6G_MB_LIB.T6G(SCH_1):GND

Q_RES_0402LF-0,5%,1/16W,EMPTY,CS00002JB13  I66  PR392
   1 PVDD11_S3_P1_RESET_N_R      A @T6G_MB_LIB.T6G(SCH_1):PVDD11_S3_P1_RESET_N_R
   2 PVDD11_S3_P1_RESET_N      B @T6G_MB_LIB.T6G(SCH_1):PVDD11_S3_P1_RESET_N

Q_RES_0402LF-1K,1%,1/16W,EMPTY,CS21002FB06  I67  PR391
   1 PVDD11_S3_P1_RESET_N_R      A @T6G_MB_LIB.T6G(SCH_1):PVDD11_S3_P1_RESET_N_R
   2 PVDD18_S5_P1      B @T6G_MB_LIB.T6G(SCH_1):PVDD18_S5_P1

Q_RES_0402LF-0,5%,1/16W,CHIP,CS00002JB13  I70  PR406
   1 NC_PVDD11_S3_P1_IMON3      A @T6G_MB_LIB.T6G(SCH_1):NC_PVDD11_S3_P1_IMON3
   2    GND      B @T6G_MB_LIB.T6G(SCH_1):GND

Q_CAP_0402-0.1UF,25V,10%,X7R,CH4104K1B00  I72  PC96
   1 PVDD11_S3_P1_VCCS      A @T6G_MB_LIB.T6G(SCH_1):PVDD11_S3_P1_VCCS
   2    GND      B @T6G_MB_LIB.T6G(SCH_1):GND

Q_CAP_0402-0.1UF,25V,10%,X7R,CH4104K1B00  I73  PC95
   1 PVDD11_S3_P1_VCC      A @T6G_MB_LIB.T6G(SCH_1):PVDD11_S3_P1_VCC
   2    GND      B @T6G_MB_LIB.T6G(SCH_1):GND

Q_CAP_C0402-10UF,6.3V,20%,X6S,CH6101MEB03  I80  PC644
   1 PVDD11_S3_P1_VCCS      A @T6G_MB_LIB.T6G(SCH_1):PVDD11_S3_P1_VCCS
   2    GND      B @T6G_MB_LIB.T6G(SCH_1):GND

Q_CAP_C0402-1UF,16V,10%,X6S,CH5103KEB01  I81  PC645
   1 PVDD11_S3_P1_VCC      A @T6G_MB_LIB.T6G(SCH_1):PVDD11_S3_P1_VCC
   2    GND      B @T6G_MB_LIB.T6G(SCH_1):GND

Q_RES_0402LF-1,1%,1/16W,CHIP,CS-1002FB04  I84  PR393
   1 PVDD11_S3_P1_VCC      A @T6G_MB_LIB.T6G(SCH_1):PVDD11_S3_P1_VCC
   2 P3V3_AUX      B @T6G_MB_LIB.T6G(SCH_1):P3V3_AUX

RAA229621GNPHA0-RAA229621GNP#HA0,SMLF,IC,ARF0TGP40A  I86  PU54
  23 PVDD11_S3_P1_IMON1    CS7 @T6G_MB_LIB.T6G(SCH_1):PVDD11_S3_P1_IMON1
  39 PVDD11_S3_P1_VCC    VCC @T6G_MB_LIB.T6G(SCH_1):PVDD11_S3_P1_VCC
  20    GND   SVTI @T6G_MB_LIB.T6G(SCH_1):GND
  10 PVDD11_S3_P1_PMSCL_R  PMSCL @T6G_MB_LIB.T6G(SCH_1):PVDD11_S3_P1_PMSCL_R
  18    GND    SVC @T6G_MB_LIB.T6G(SCH_1):GND
  24 PVDD11_S3_P1_IMON2    CS6 @T6G_MB_LIB.T6G(SCH_1):PVDD11_S3_P1_IMON2
  19 NC_PVDD11_S3_P1_SVTO   SVTO @T6G_MB_LIB.T6G(SCH_1):NC_PVDD11_S3_P1_SVTO
  14 PVDD11_S3_P1_RESET_N_R RESET_L @T6G_MB_LIB.T6G(SCH_1):PVDD11_S3_P1_RESET_N_R
  25 NC_PVDD11_S3_P1_IMON3    CS5 @T6G_MB_LIB.T6G(SCH_1):NC_PVDD11_S3_P1_IMON3
  26 NC_PVDD11_S3_P1_IMON4    CS4 @T6G_MB_LIB.T6G(SCH_1):NC_PVDD11_S3_P1_IMON4
  16 NC_PVDD11_S3_P1_PG1    PG1 @T6G_MB_LIB.T6G(SCH_1):NC_PVDD11_S3_P1_PG1
  17    GND    SVD @T6G_MB_LIB.T6G(SCH_1):GND
  11 PVDD11_S3_P1_PMALERT_R NPMALERT @T6G_MB_LIB.T6G(SCH_1):PVDD11_S3_P1_PMALERT_R
  13 PVDD11_S3_P1_EN_R    EN0 @T6G_MB_LIB.T6G(SCH_1):PVDD11_S3_P1_EN_R
  22 VSENSE_VSS_SENSE_C_P1  RGND0 @T6G_MB_LIB.T6G(SCH_1):VSENSE_VSS_SENSE_C_P1
   9 PVDD11_S3_P1_PMSDA_R  PMSDA @T6G_MB_LIB.T6G(SCH_1):PVDD11_S3_P1_PMSDA_R
   5 NC_PVDD11_S3_P1_PWM4   PWM4 @T6G_MB_LIB.T6G(SCH_1):NC_PVDD11_S3_P1_PWM4
   6 NC_PVDD11_S3_P1_PWM3   PWM5 @T6G_MB_LIB.T6G(SCH_1):NC_PVDD11_S3_P1_PWM3
  21 VSENSE_PVDD11_S3_P1_R  VSEN0 @T6G_MB_LIB.T6G(SCH_1):VSENSE_PVDD11_S3_P1_R
   2 NC_PVDD11_S3_P1_PWM7   PWM1 @T6G_MB_LIB.T6G(SCH_1):NC_PVDD11_S3_P1_PWM7
  12 PWRGD_PVDD11_S3_P1_R    PG0 @T6G_MB_LIB.T6G(SCH_1):PWRGD_PVDD11_S3_P1_R
   7 PVDD11_S3_P1_PWM2   PWM6 @T6G_MB_LIB.T6G(SCH_1):PVDD11_S3_P1_PWM2
  40 PVDD11_S3_P1_VCCS   VCCS @T6G_MB_LIB.T6G(SCH_1):PVDD11_S3_P1_VCCS
  37 PVDD11_S3_P1_VMON VMON||IINSEN @T6G_MB_LIB.T6G(SCH_1):PVDD11_S3_P1_VMON
  38 PVDD11_S3_P1_VINSEN VINSEN @T6G_MB_LIB.T6G(SCH_1):PVDD11_S3_P1_VINSEN
  36 PVDD11_S3_P1_TEMP0  TEMP0 @T6G_MB_LIB.T6G(SCH_1):PVDD11_S3_P1_TEMP0
  15 PVDD11_S3_P1_VDDIO  VDDIO @T6G_MB_LIB.T6G(SCH_1):PVDD11_S3_P1_VDDIO
  32    GND  VSEN1 @T6G_MB_LIB.T6G(SCH_1):GND
  31    GND  RGND1 @T6G_MB_LIB.T6G(SCH_1):GND
  29 NC_PVDD11_S3_P1_IMON7    CS1 @T6G_MB_LIB.T6G(SCH_1):NC_PVDD11_S3_P1_IMON7
   8 PVDD11_S3_P1_PWM1   PWM7 @T6G_MB_LIB.T6G(SCH_1):PVDD11_S3_P1_PWM1
   4 NC_PVDD11_S3_P1_PWM5   PWM3 @T6G_MB_LIB.T6G(SCH_1):NC_PVDD11_S3_P1_PWM5
  27 NC_PVDD11_S3_P1_IMON5    CS3 @T6G_MB_LIB.T6G(SCH_1):NC_PVDD11_S3_P1_IMON5
   3 NC_PVDD11_S3_P1_PWM6   PWM2 @T6G_MB_LIB.T6G(SCH_1):NC_PVDD11_S3_P1_PWM6
  28 NC_PVDD11_S3_P1_IMON6    CS2 @T6G_MB_LIB.T6G(SCH_1):NC_PVDD11_S3_P1_IMON6
  33 PVDD11_S3_P1_OCP_N_R  OCP_L @T6G_MB_LIB.T6G(SCH_1):PVDD11_S3_P1_OCP_N_R
  TH    GND TH_GND @T6G_MB_LIB.T6G(SCH_1):GND
  34 PVDD11_S3_P1_ADDR_CFG EN1||ADDR_CFG @T6G_MB_LIB.T6G(SCH_1):PVDD11_S3_P1_ADDR_CFG
  35 PVDD11_S3_P1_TEMP1  TEMP1 @T6G_MB_LIB.T6G(SCH_1):PVDD11_S3_P1_TEMP1
   1 NC_PVDD11_S3_P1_PWM8   PWM0 @T6G_MB_LIB.T6G(SCH_1):NC_PVDD11_S3_P1_PWM8
  30 NC_PVDD11_S3_P1_IMON8    CS0 @T6G_MB_LIB.T6G(SCH_1):NC_PVDD11_S3_P1_IMON8

Q_CAP_0402-1000PF,50V,5%,X7R,TMP_QCH21006JB10  I88  C5010
   1 PVDD11_S3_P1_PMALERT      A @T6G_MB_LIB.T6G(SCH_1):PVDD11_S3_P1_PMALERT
   2    GND      B @T6G_MB_LIB.T6G(SCH_1):GND

Q_RES_0402LF-13.7K,1%,1/16W,CHIP,CS31372FB03  I89  PR464
   1    GND      A @T6G_MB_LIB.T6G(SCH_1):GND
   2 PVDD11_S3_P1_ADDR_CFG      B @T6G_MB_LIB.T6G(SCH_1):PVDD11_S3_P1_ADDR_CFG


DRAWING: @T6G_MB_LIB.T6G(SCH_1):PAGE369 

Q_RES_0402LF-7.87K,1%,1/16W,CHIP,CS27872FB02  I6  R1799
   1 P12V_AUX      A @T6G_MB_LIB.T6G(SCH_1):P12V_AUX
   2 P12V_AUX_ADC      B @T6G_MB_LIB.T6G(SCH_1):P12V_AUX_ADC

Q_RES_0402LF-4.7K,1%,1/16W,CHIP,CS24702FB06  I7  R4568
   1 P1V581_PDB_ADC      A @T6G_MB_LIB.T6G(SCH_1):P1V581_PDB_ADC
   2    GND      B @T6G_MB_LIB.T6G(SCH_1):GND

Q_RES_0402LF-5.11K,1%,1/16W,CHIP,CS25112FB04  I8  R4567
   1 P3V3_PDB_AUX_ADC      A @T6G_MB_LIB.T6G(SCH_1):P3V3_PDB_AUX_ADC
   2 P1V581_PDB_ADC      B @T6G_MB_LIB.T6G(SCH_1):P1V581_PDB_ADC

Q_RES_0402LF-0,5%,1/16W,CHIP,CS00002JB13  I9  R3680
   1 P12V_AUX_ADC      A @T6G_MB_LIB.T6G(SCH_1):P12V_AUX_ADC
   2 P12V_AUX_ADC_TIC      B @T6G_MB_LIB.T6G(SCH_1):P12V_AUX_ADC_TIC

Q_RES_0402LF-0,5%,1/16W,EMPTY,CS00002JB13  I10  R3679
   1 P12V_AUX_ADC      A @T6G_MB_LIB.T6G(SCH_1):P12V_AUX_ADC
   2 P12V_AUX_ADC_MAM      B @T6G_MB_LIB.T6G(SCH_1):P12V_AUX_ADC_MAM

Q_RES_0402LF-9.09K,1%,1/16W,CHIP,CS29092FB05  I14  R1791
   1 P5V_ADC      A @T6G_MB_LIB.T6G(SCH_1):P5V_ADC
   2    GND      B @T6G_MB_LIB.T6G(SCH_1):GND

Q_RES_0402LF-18K,1%,1/16W,CHIP,CS31802FB04  I15  R3005
   1    P5V      A @T6G_MB_LIB.T6G(SCH_1):P5V
   2 P5V_ADC      B @T6G_MB_LIB.T6G(SCH_1):P5V_ADC

Q_RES_0402LF-0,5%,1/16W,CHIP,CS00002JB13  I16  R3686
   1 P5V_ADC      A @T6G_MB_LIB.T6G(SCH_1):P5V_ADC
   2 P5V_ADC_TIC      B @T6G_MB_LIB.T6G(SCH_1):P5V_ADC_TIC

Q_CAP_0402-0.1UF,25V,10%,X7R,CH4104K1B00  I17  C2049
   1 P5V_ADC_TIC      A @T6G_MB_LIB.T6G(SCH_1):P5V_ADC_TIC
   2    GND      B @T6G_MB_LIB.T6G(SCH_1):GND

Q_RES_0402LF-0,5%,1/16W,EMPTY,CS00002JB13  I18  R3685
   1 P5V_ADC      A @T6G_MB_LIB.T6G(SCH_1):P5V_ADC
   2 P5V_ADC_MAM      B @T6G_MB_LIB.T6G(SCH_1):P5V_ADC_MAM

Q_RES_0402LF-4.7K,1%,1/16W,CHIP,CS24702FB06  I20  R2843
   1 P3V3_ADC      A @T6G_MB_LIB.T6G(SCH_1):P3V3_ADC
   2    GND      B @T6G_MB_LIB.T6G(SCH_1):GND

Q_RES_0402LF-5.11K,1%,1/16W,CHIP,CS25112FB04  I21  R2908
   1   P3V3      A @T6G_MB_LIB.T6G(SCH_1):P3V3
   2 P3V3_ADC      B @T6G_MB_LIB.T6G(SCH_1):P3V3_ADC

Q_RES_0402LF-0,5%,1/16W,CHIP,CS00002JB13  I22  R3684
   1 P3V3_ADC      A @T6G_MB_LIB.T6G(SCH_1):P3V3_ADC
   2 P3V3_ADC_TIC      B @T6G_MB_LIB.T6G(SCH_1):P3V3_ADC_TIC

Q_RES_0402LF-0,5%,1/16W,EMPTY,CS00002JB13  I23  R3683
   1 P3V3_ADC      A @T6G_MB_LIB.T6G(SCH_1):P3V3_ADC
   2 P3V3_ADC_MAM      B @T6G_MB_LIB.T6G(SCH_1):P3V3_ADC_MAM

Q_RES_0402LF-4.7K,1%,1/16W,CHIP,CS24702FB06  I26  R1785
   1 P3V3_AUX_ADC      A @T6G_MB_LIB.T6G(SCH_1):P3V3_AUX_ADC
   2    GND      B @T6G_MB_LIB.T6G(SCH_1):GND

Q_RES_0402LF-0,5%,1/16W,CHIP,CS00002JB13  I27  R3682
   1 P3V3_AUX_ADC      A @T6G_MB_LIB.T6G(SCH_1):P3V3_AUX_ADC
   2 P3V3_AUX_ADC_TIC      B @T6G_MB_LIB.T6G(SCH_1):P3V3_AUX_ADC_TIC

Q_RES_0402LF-5.11K,1%,1/16W,CHIP,CS25112FB04  I28  R2907
   1 P3V3_AUX      A @T6G_MB_LIB.T6G(SCH_1):P3V3_AUX
   2 P3V3_AUX_ADC      B @T6G_MB_LIB.T6G(SCH_1):P3V3_AUX_ADC

Q_RES_0402LF-0,5%,1/16W,EMPTY,CS00002JB13  I30  R3681
   1 P3V3_AUX_ADC      A @T6G_MB_LIB.T6G(SCH_1):P3V3_AUX_ADC
   2 P3V3_AUX_ADC_MAM      B @T6G_MB_LIB.T6G(SCH_1):P3V3_AUX_ADC_MAM

Q_CAP_0402-0.1UF,25V,10%,X7R,CH4104K1B00  I32  C2048
   1 P3V3_ADC_TIC      A @T6G_MB_LIB.T6G(SCH_1):P3V3_ADC_TIC
   2    GND      B @T6G_MB_LIB.T6G(SCH_1):GND

Q_CAP_0402-0.1UF,25V,10%,X7R,CH4104K1B00  I34  C2050
   1 P3V3_PDB_AUX_ADC_TIC      A @T6G_MB_LIB.T6G(SCH_1):P3V3_PDB_AUX_ADC_TIC
   2    GND      B @T6G_MB_LIB.T6G(SCH_1):GND

Q_CAP_0402-100PF,50V,5%,EMPTY,CH11006JB18  I36  C2045
   1 P3V3_PDB_AUX_ADC_MAM      A @T6G_MB_LIB.T6G(SCH_1):P3V3_PDB_AUX_ADC_MAM
   2    GND      B @T6G_MB_LIB.T6G(SCH_1):GND

Q_RES_0402LF-1K,1%,1/16W,CHIP,CS21002FB06  I38  R3668
   1 ADC128_A1      A @T6G_MB_LIB.T6G(SCH_1):ADC128_A1
   2    GND      B @T6G_MB_LIB.T6G(SCH_1):GND

Q_RES_0402LF-1K,1%,1/16W,CHIP,CS21002FB06  I40  R3670
   1 ADC128_A0      A @T6G_MB_LIB.T6G(SCH_1):ADC128_A0
   2    GND      B @T6G_MB_LIB.T6G(SCH_1):GND

Q_RES_0402LF-0,5%,1/16W,CHIP,CS00002JB13  I41  R3688
   1 P1V581_PDB_ADC      A @T6G_MB_LIB.T6G(SCH_1):P1V581_PDB_ADC
   2 P3V3_PDB_AUX_ADC_TIC      B @T6G_MB_LIB.T6G(SCH_1):P3V3_PDB_AUX_ADC_TIC

Q_RES_0402LF-0,5%,1/16W,EMPTY,CS00002JB13  I42  R3687
   1 P1V581_PDB_ADC      A @T6G_MB_LIB.T6G(SCH_1):P1V581_PDB_ADC
   2 P3V3_PDB_AUX_ADC_MAM      B @T6G_MB_LIB.T6G(SCH_1):P3V3_PDB_AUX_ADC_MAM

Q_CAP_0402-0.1UF,25V,10%,X7R,CH4104K1B00  I44  C2046
   1 P12V_AUX_ADC_TIC      A @T6G_MB_LIB.T6G(SCH_1):P12V_AUX_ADC_TIC
   2    GND      B @T6G_MB_LIB.T6G(SCH_1):GND

Q_CAP_0402-100PF,50V,5%,EMPTY,CH11006JB18  I46  C1344
   1 P12V_AUX_ADC_MAM      A @T6G_MB_LIB.T6G(SCH_1):P12V_AUX_ADC_MAM
   2    GND      B @T6G_MB_LIB.T6G(SCH_1):GND

Q_CAP_0402-100PF,50V,5%,EMPTY,CH11006JB18  I52  C2044
   1 P5V_ADC_MAM      A @T6G_MB_LIB.T6G(SCH_1):P5V_ADC_MAM
   2    GND      B @T6G_MB_LIB.T6G(SCH_1):GND

Q_CAP_0402-100PF,50V,5%,EMPTY,CH11006JB18  I55  C2043
   1 P3V3_ADC_MAM      A @T6G_MB_LIB.T6G(SCH_1):P3V3_ADC_MAM
   2    GND      B @T6G_MB_LIB.T6G(SCH_1):GND

Q_RES_0402LF-1K,1%,1/16W,EMPTY,CS21002FB06  I66  R3667
   1 P3V3_AUX      A @T6G_MB_LIB.T6G(SCH_1):P3V3_AUX
   2 ADC128_A1      B @T6G_MB_LIB.T6G(SCH_1):ADC128_A1

Q_RES_0402LF-1K,1%,1/16W,EMPTY,CS21002FB06  I68  R3669
   1 P3V3_AUX      A @T6G_MB_LIB.T6G(SCH_1):P3V3_AUX
   2 ADC128_A0      B @T6G_MB_LIB.T6G(SCH_1):ADC128_A0

Q_INDUCTOR_SMLF-BLM18PG300SN1D ,IND,TMP_QCX8PG3000A  I69  L16
   2 P3V3_ADC128_VCC      2 @T6G_MB_LIB.T6G(SCH_1):P3V3_ADC128_VCC
   1 P3V3_AUX      1 @T6G_MB_LIB.T6G(SCH_1):P3V3_AUX

Q_CAP_0402-0.1UF,25V,10%,X7R,CH4104K1B00  I71  C2051
   1 P3V3_ADC128_VCC      A @T6G_MB_LIB.T6G(SCH_1):P3V3_ADC128_VCC
   2    GND      B @T6G_MB_LIB.T6G(SCH_1):GND

Q_CAP_0402-0.1UF,25V,10%,X7R,CH4104K1B00  I72  C2052
   1 P3V3_ADC128_VCC      A @T6G_MB_LIB.T6G(SCH_1):P3V3_ADC128_VCC
   2    GND      B @T6G_MB_LIB.T6G(SCH_1):GND

Q_RES_0402LF-0,5%,1/16W,EMPTY,CS00002JB13  I73  R3942
   1 P12V_E1S_0_ISENSE_MPS_TIC      A @T6G_MB_LIB.T6G(SCH_1):P12V_E1S_0_ISENSE_MPS_TIC
   2 P12V_E1S_0_ISENSE_TIC      B @T6G_MB_LIB.T6G(SCH_1):P12V_E1S_0_ISENSE_TIC

Q_RES_0402LF-0,5%,1/16W,CHIP,CS00002JB13  I74  R3941
   1 P12V_E1S_0_ISENSE_MAM_TIC      A @T6G_MB_LIB.T6G(SCH_1):P12V_E1S_0_ISENSE_MAM_TIC
   2 P12V_E1S_0_ISENSE_TIC      B @T6G_MB_LIB.T6G(SCH_1):P12V_E1S_0_ISENSE_TIC

Q_CAP_0402-0.1UF,25V,10%,X7R,CH4104K1B00  I76  C2194
   1 P12V_E1S_0_ISENSE_TIC      A @T6G_MB_LIB.T6G(SCH_1):P12V_E1S_0_ISENSE_TIC
   2    GND      B @T6G_MB_LIB.T6G(SCH_1):GND

Q_CAP_0402-100PF,50V,5%,EMPTY,CH11006JB18  I78  C35
   1 P12V_E1S_0_ISENSE_MAM      A @T6G_MB_LIB.T6G(SCH_1):P12V_E1S_0_ISENSE_MAM
   2    GND      B @T6G_MB_LIB.T6G(SCH_1):GND

Q_RES_0402LF-0,5%,1/16W,EMPTY,CS00002JB13  I79  R3940
   1 P12V_E1S_0_ISENSE_MPS_MAM      A @T6G_MB_LIB.T6G(SCH_1):P12V_E1S_0_ISENSE_MPS_MAM
   2 P12V_E1S_0_ISENSE_MAM      B @T6G_MB_LIB.T6G(SCH_1):P12V_E1S_0_ISENSE_MAM

Q_RES_0402LF-0,5%,1/16W,EMPTY,CS00002JB13  I80  R3939
   1 P12V_E1S_0_ISENSE_MAM_MAM      A @T6G_MB_LIB.T6G(SCH_1):P12V_E1S_0_ISENSE_MAM_MAM
   2 P12V_E1S_0_ISENSE_MAM      B @T6G_MB_LIB.T6G(SCH_1):P12V_E1S_0_ISENSE_MAM

Q_RES_0402LF-0,5%,1/16W,EMPTY,CS00002JB13  I81  R3862
   1 P12V_OCP_V3_2_ISENSE_MPS_TIC      A @T6G_MB_LIB.T6G(SCH_1):P12V_OCP_V3_2_ISENSE_MPS_TIC
   2 P12V_OCP_V3_2_ISENSE_TIC      B @T6G_MB_LIB.T6G(SCH_1):P12V_OCP_V3_2_ISENSE_TIC

Q_RES_0402LF-0,5%,1/16W,CHIP,CS00002JB13  I82  R3861
   1 P12V_OCP_V3_2_ISENSE_MAM_TIC      A @T6G_MB_LIB.T6G(SCH_1):P12V_OCP_V3_2_ISENSE_MAM_TIC
   2 P12V_OCP_V3_2_ISENSE_TIC      B @T6G_MB_LIB.T6G(SCH_1):P12V_OCP_V3_2_ISENSE_TIC

Q_RES_0402LF-0,5%,1/16W,EMPTY,CS00002JB13  I83  R3860
   1 P12V_OCP_V3_2_ISENSE_MPS_MAM      A @T6G_MB_LIB.T6G(SCH_1):P12V_OCP_V3_2_ISENSE_MPS_MAM
   2 P12V_OCP_V3_2_ISENSE_MAM      B @T6G_MB_LIB.T6G(SCH_1):P12V_OCP_V3_2_ISENSE_MAM

Q_CAP_0402-0.1UF,25V,10%,X7R,CH4104K1B00  I84  C33
   1 P12V_OCP_V3_2_ISENSE_TIC      A @T6G_MB_LIB.T6G(SCH_1):P12V_OCP_V3_2_ISENSE_TIC
   2    GND      B @T6G_MB_LIB.T6G(SCH_1):GND

Q_CAP_0402-100PF,50V,5%,EMPTY,CH11006JB18  I87  C59
   1 P12V_OCP_V3_2_ISENSE_MAM      A @T6G_MB_LIB.T6G(SCH_1):P12V_OCP_V3_2_ISENSE_MAM
   2    GND      B @T6G_MB_LIB.T6G(SCH_1):GND

Q_CAP_0402-0.1UF,25V,10%,X7R,CH4104K1B00  I98  C2047
   1 P3V3_AUX_ADC_TIC      A @T6G_MB_LIB.T6G(SCH_1):P3V3_AUX_ADC_TIC
   2    GND      B @T6G_MB_LIB.T6G(SCH_1):GND

Q_CAP_0402-100PF,50V,5%,EMPTY,CH11006JB18  I99  C2042
   1 P3V3_AUX_ADC_MAM      A @T6G_MB_LIB.T6G(SCH_1):P3V3_AUX_ADC_MAM
   2    GND      B @T6G_MB_LIB.T6G(SCH_1):GND

Q_RES_0402LF-0,5%,1/16W,EMPTY,CS00002JB13  I107  R3859
   1 P12V_OCP_V3_2_ISENSE_MAM_MAM      A @T6G_MB_LIB.T6G(SCH_1):P12V_OCP_V3_2_ISENSE_MAM_MAM
   2 P12V_OCP_V3_2_ISENSE_MAM      B @T6G_MB_LIB.T6G(SCH_1):P12V_OCP_V3_2_ISENSE_MAM

Q_RES_0402LF-0,5%,1/16W,EMPTY,CS00002JB13  I108  R3866
   1 P12V_OCP_SFF_ISENSE_MPS_TIC      A @T6G_MB_LIB.T6G(SCH_1):P12V_OCP_SFF_ISENSE_MPS_TIC
   2 P12V_OCP_SFF_ISENSE_TIC      B @T6G_MB_LIB.T6G(SCH_1):P12V_OCP_SFF_ISENSE_TIC

Q_RES_0402LF-0,5%,1/16W,CHIP,CS00002JB13  I109  R3865
   1 P12V_OCP_SFF_ISENSE_MAM_TIC      A @T6G_MB_LIB.T6G(SCH_1):P12V_OCP_SFF_ISENSE_MAM_TIC
   2 P12V_OCP_SFF_ISENSE_TIC      B @T6G_MB_LIB.T6G(SCH_1):P12V_OCP_SFF_ISENSE_TIC

Q_RES_0402LF-0,5%,1/16W,EMPTY,CS00002JB13  I110  R3864
   1 P12V_OCP_SFF_ISENSE_MPS_MAM      A @T6G_MB_LIB.T6G(SCH_1):P12V_OCP_SFF_ISENSE_MPS_MAM
   2 P12V_OCP_SFF_ISENSE_MAM      B @T6G_MB_LIB.T6G(SCH_1):P12V_OCP_SFF_ISENSE_MAM

Q_CAP_0402-0.1UF,25V,10%,X7R,CH4104K1B00  I112  C37
   1 P12V_OCP_SFF_ISENSE_TIC      A @T6G_MB_LIB.T6G(SCH_1):P12V_OCP_SFF_ISENSE_TIC
   2    GND      B @T6G_MB_LIB.T6G(SCH_1):GND

Q_CAP_0402-100PF,50V,5%,EMPTY,CH11006JB18  I114  C2176
   1 P12V_OCP_SFF_ISENSE_MAM      A @T6G_MB_LIB.T6G(SCH_1):P12V_OCP_SFF_ISENSE_MAM
   2    GND      B @T6G_MB_LIB.T6G(SCH_1):GND

Q_RES_0402LF-0,5%,1/16W,EMPTY,CS00002JB13  I115  R3863
   1 P12V_OCP_SFF_ISENSE_MAM_MAM      A @T6G_MB_LIB.T6G(SCH_1):P12V_OCP_SFF_ISENSE_MAM_MAM
   2 P12V_OCP_SFF_ISENSE_MAM      B @T6G_MB_LIB.T6G(SCH_1):P12V_OCP_SFF_ISENSE_MAM

Q_CAP_0402-0.1UF,25V,10%,X7R,CH4104K1B00  I119  C1347
   1 MAX11617_VREF      A @T6G_MB_LIB.T6G(SCH_1):MAX11617_VREF
   2    GND      B @T6G_MB_LIB.T6G(SCH_1):GND

Q_CAP_C0805-10UF,16V,10%,X6S,CH6103KEA00  I121  C1767
   1 MAX11617_VREF      A @T6G_MB_LIB.T6G(SCH_1):MAX11617_VREF
   2    GND      B @T6G_MB_LIB.T6G(SCH_1):GND

Q_RES_0402LF-4.7K,1%,1/16W,EMPTY,CS24702FB06  I130  R3690
   1 ADC128_VREF      A @T6G_MB_LIB.T6G(SCH_1):ADC128_VREF
   2    GND      B @T6G_MB_LIB.T6G(SCH_1):GND

Q_RES_0402LF-4.7K,1%,1/16W,EMPTY,CS24702FB06  I131  R3689
   1 P3V3_ADC128_VCC      A @T6G_MB_LIB.T6G(SCH_1):P3V3_ADC128_VCC
   2 ADC128_VREF      B @T6G_MB_LIB.T6G(SCH_1):ADC128_VREF

ADC128D818CIMTXNOPB-ADC128D818CIMTX/NOPB,SMLF,IC,AA  I142  U269
   1 ADC128_VREF   VREF @T6G_MB_LIB.T6G(SCH_1):ADC128_VREF
   5 P3V3_ADC128_VCC     V+ @T6G_MB_LIB.T6G(SCH_1):P3V3_ADC128_VCC
   7 ADC128_A0     A0 @T6G_MB_LIB.T6G(SCH_1):ADC128_A0
   8 ADC128_A1     A1 @T6G_MB_LIB.T6G(SCH_1):ADC128_A1
   9 P12V_E1S_0_ISENSE_TIC    IN7 @T6G_MB_LIB.T6G(SCH_1):P12V_E1S_0_ISENSE_TIC
  10 P3V3_PDB_AUX_ADC_TIC    IN6 @T6G_MB_LIB.T6G(SCH_1):P3V3_PDB_AUX_ADC_TIC
  11 P3V3_AUX_ADC_TIC    IN5 @T6G_MB_LIB.T6G(SCH_1):P3V3_AUX_ADC_TIC
  12 P3V3_ADC_TIC    IN4 @T6G_MB_LIB.T6G(SCH_1):P3V3_ADC_TIC
  13 P5V_ADC_TIC    IN3 @T6G_MB_LIB.T6G(SCH_1):P5V_ADC_TIC
  14 P12V_OCP_V3_2_ISENSE_TIC    IN2 @T6G_MB_LIB.T6G(SCH_1):P12V_OCP_V3_2_ISENSE_TIC
  15 P12V_OCP_SFF_ISENSE_TIC    IN1 @T6G_MB_LIB.T6G(SCH_1):P12V_OCP_SFF_ISENSE_TIC
  16 P12V_AUX_ADC_TIC    IN0 @T6G_MB_LIB.T6G(SCH_1):P12V_AUX_ADC_TIC
   2 SMB_SEN_TIC_3V3AUX_SDA    SDA @T6G_MB_LIB.T6G(SCH_1):SMB_SEN_TIC_3V3AUX_SDA
   3 SMB_SEN_TIC_3V3AUX_SCL    SCL @T6G_MB_LIB.T6G(SCH_1):SMB_SEN_TIC_3V3AUX_SCL
   4    GND    GND @T6G_MB_LIB.T6G(SCH_1):GND
   6 TP_ADC128_INT   INT# @T6G_MB_LIB.T6G(SCH_1):TP_ADC128_INT

Q_RES_0402LF-0,5%,1/16W,EMPTY,CS00002JB13  I146  R1792
   1 SMB_SCM_2_R4_SDA      A @T6G_MB_LIB.T6G(SCH_1):SMB_SCM_2_R4_SDA
   2 SMB_SEN_MAM_3V3AUX_SDA      B @T6G_MB_LIB.T6G(SCH_1):SMB_SEN_MAM_3V3AUX_SDA

Q_RES_0402LF-0,5%,1/16W,EMPTY,CS00002JB13  I147  R1793
   1 SMB_SCM_2_R4_SCL      A @T6G_MB_LIB.T6G(SCH_1):SMB_SCM_2_R4_SCL
   2 SMB_SEN_MAM_3V3AUX_SCL      B @T6G_MB_LIB.T6G(SCH_1):SMB_SEN_MAM_3V3AUX_SCL

Q_RES_0402LF-0,5%,1/16W,CHIP,CS00002JB13  I149  R3671
   1 SMB_SCM_2_R4_SDA      A @T6G_MB_LIB.T6G(SCH_1):SMB_SCM_2_R4_SDA
   2 SMB_SEN_TIC_3V3AUX_SDA      B @T6G_MB_LIB.T6G(SCH_1):SMB_SEN_TIC_3V3AUX_SDA

Q_RES_0402LF-0,5%,1/16W,CHIP,CS00002JB13  I150  R3672
   1 SMB_SCM_2_R4_SCL      A @T6G_MB_LIB.T6G(SCH_1):SMB_SCM_2_R4_SCL
   2 SMB_SEN_TIC_3V3AUX_SCL      B @T6G_MB_LIB.T6G(SCH_1):SMB_SEN_TIC_3V3AUX_SCL

Q_RES_0402LF-2K,1%,1/16W,CHIP,CS22002FB07  I160  R2900
   1 MAX11617_VREF      A @T6G_MB_LIB.T6G(SCH_1):MAX11617_VREF
   2 MAX11617_VREF_R      B @T6G_MB_LIB.T6G(SCH_1):MAX11617_VREF_R

Q_CAP_0402-0.1UF,25V,10%,X7R,CH4104K1B00  I162  C1757
   1 P3V3_MAX11617_VDD      A @T6G_MB_LIB.T6G(SCH_1):P3V3_MAX11617_VDD
   2    GND      B @T6G_MB_LIB.T6G(SCH_1):GND

Q_CAP_C0805-10UF,16V,10%,X6S,CH6103KEA00  I166  C1768
   1 P3V3_MAX11617_VDD      A @T6G_MB_LIB.T6G(SCH_1):P3V3_MAX11617_VDD
   2    GND      B @T6G_MB_LIB.T6G(SCH_1):GND

Q_INDUCTOR_SMLF-BLM18PG300SN1D ,IND,TMP_QCX8PG3000A  I167  L15
   2 P3V3_AUX      2 @T6G_MB_LIB.T6G(SCH_1):P3V3_AUX
   1 P3V3_MAX11617_VDD      1 @T6G_MB_LIB.T6G(SCH_1):P3V3_MAX11617_VDD

MAX11617EEET-MAX11617EEE+T,SMLF,EMPTY,AL011617W00  I169  U193
   1 MAX11617_VREF_R AIN11||REF @T6G_MB_LIB.T6G(SCH_1):MAX11617_VREF_R
   2    GND  AIN10 @T6G_MB_LIB.T6G(SCH_1):GND
   3    GND   AIN9 @T6G_MB_LIB.T6G(SCH_1):GND
   4    GND   AIN8 @T6G_MB_LIB.T6G(SCH_1):GND
   5 P12V_AUX_ADC_MAM   AIN0 @T6G_MB_LIB.T6G(SCH_1):P12V_AUX_ADC_MAM
   6 P12V_OCP_SFF_ISENSE_MAM   AIN1 @T6G_MB_LIB.T6G(SCH_1):P12V_OCP_SFF_ISENSE_MAM
   7 P12V_OCP_V3_2_ISENSE_MAM   AIN2 @T6G_MB_LIB.T6G(SCH_1):P12V_OCP_V3_2_ISENSE_MAM
   8 P5V_ADC_MAM   AIN3 @T6G_MB_LIB.T6G(SCH_1):P5V_ADC_MAM
   9 P3V3_ADC_MAM   AIN4 @T6G_MB_LIB.T6G(SCH_1):P3V3_ADC_MAM
  10 P3V3_AUX_ADC_MAM   AIN5 @T6G_MB_LIB.T6G(SCH_1):P3V3_AUX_ADC_MAM
  11 P3V3_PDB_AUX_ADC_MAM   AIN6 @T6G_MB_LIB.T6G(SCH_1):P3V3_PDB_AUX_ADC_MAM
  12 P12V_E1S_0_ISENSE_MAM   AIN7 @T6G_MB_LIB.T6G(SCH_1):P12V_E1S_0_ISENSE_MAM
  13 SMB_SEN_MAM_3V3AUX_SCL    SCL @T6G_MB_LIB.T6G(SCH_1):SMB_SEN_MAM_3V3AUX_SCL
  14 SMB_SEN_MAM_3V3AUX_SDA    SDA @T6G_MB_LIB.T6G(SCH_1):SMB_SEN_MAM_3V3AUX_SDA
  15    GND    GND @T6G_MB_LIB.T6G(SCH_1):GND
  16 P3V3_MAX11617_VDD    VDD @T6G_MB_LIB.T6G(SCH_1):P3V3_MAX11617_VDD

Q_RES_0402LF-1.21K,1%,1/16W,CHIP,CS21212FB05  I170  R1800
   1 P12V_AUX_ADC      A @T6G_MB_LIB.T6G(SCH_1):P12V_AUX_ADC
   2    GND      B @T6G_MB_LIB.T6G(SCH_1):GND


DRAWING: @T6G_MB_LIB.T6G(SCH_1):PAGE212 

HOLE_TH-EMPTY,HOLE1226  I4  H53
   1    GND      1 @T6G_MB_LIB.T6G(SCH_1):GND

HOLE_TH-EMPTY,HOLE1226  I5  H21
   1    GND      1 @T6G_MB_LIB.T6G(SCH_1):GND

HOLE_TH-EMPTY,HOLE1226  I7  H8027
   1    GND      1 @T6G_MB_LIB.T6G(SCH_1):GND

HOLE_TH-EMPTY,HOLE1187  I10  H76
   1    GND      1 @T6G_MB_LIB.T6G(SCH_1):GND

HOLE_TH-EMPTY,HOLE1187  I12  H77
   1    GND      1 @T6G_MB_LIB.T6G(SCH_1):GND

GND_HOLE_TH-EMPTY,GND_HOLE140  I25  H113
   3    GND   GND3 @T6G_MB_LIB.T6G(SCH_1):GND
   2    GND   GND2 @T6G_MB_LIB.T6G(SCH_1):GND
   9    GND   GND9 @T6G_MB_LIB.T6G(SCH_1):GND
   8    GND   GND8 @T6G_MB_LIB.T6G(SCH_1):GND
   7    GND   GND7 @T6G_MB_LIB.T6G(SCH_1):GND
   6    GND   GND6 @T6G_MB_LIB.T6G(SCH_1):GND
   5    GND   GND5 @T6G_MB_LIB.T6G(SCH_1):GND
   4    GND   GND4 @T6G_MB_LIB.T6G(SCH_1):GND

HOLE_TH-EMPTY,HOLE1226  I26  H22
   1    GND      1 @T6G_MB_LIB.T6G(SCH_1):GND

HOLE_TH-EMPTY,HOLE1226  I27  H8028
   1    GND      1 @T6G_MB_LIB.T6G(SCH_1):GND

GND_HOLE_TH-EMPTY,GND_HOLE140  I30  H114
   3    GND   GND3 @T6G_MB_LIB.T6G(SCH_1):GND
   2    GND   GND2 @T6G_MB_LIB.T6G(SCH_1):GND
   9    GND   GND9 @T6G_MB_LIB.T6G(SCH_1):GND
   8    GND   GND8 @T6G_MB_LIB.T6G(SCH_1):GND
   7    GND   GND7 @T6G_MB_LIB.T6G(SCH_1):GND
   6    GND   GND6 @T6G_MB_LIB.T6G(SCH_1):GND
   5    GND   GND5 @T6G_MB_LIB.T6G(SCH_1):GND
   4    GND   GND4 @T6G_MB_LIB.T6G(SCH_1):GND

HOLE_TH-EMPTY,HOLE1226  I31  H34
   1    GND      1 @T6G_MB_LIB.T6G(SCH_1):GND

HOLE_TH-EMPTY,HOLE1226  I33  H38
   1    GND      1 @T6G_MB_LIB.T6G(SCH_1):GND

HOLE_TH-EMPTY,HOLE1226  I36  H33
   1    GND      1 @T6G_MB_LIB.T6G(SCH_1):GND

HOLE_TH-EMPTY,HOLE1226  I38  H37
   1    GND      1 @T6G_MB_LIB.T6G(SCH_1):GND

HOLE_TH-EMPTY,HOLE1226  I40  H43
   1    GND      1 @T6G_MB_LIB.T6G(SCH_1):GND

HOLE_TH-EMPTY,DUMMY50  I41  H27
   1     NC      1     NC

GND_HOLE_TH-EMPTY,GND_HOLE514  I43  H115
   3    GND   GND3 @T6G_MB_LIB.T6G(SCH_1):GND
   2    GND   GND2 @T6G_MB_LIB.T6G(SCH_1):GND
   9    GND   GND9 @T6G_MB_LIB.T6G(SCH_1):GND
   8    GND   GND8 @T6G_MB_LIB.T6G(SCH_1):GND
   7    GND   GND7 @T6G_MB_LIB.T6G(SCH_1):GND
   6    GND   GND6 @T6G_MB_LIB.T6G(SCH_1):GND
   5    GND   GND5 @T6G_MB_LIB.T6G(SCH_1):GND
   4    GND   GND4 @T6G_MB_LIB.T6G(SCH_1):GND

HOLE_TH-EMPTY,HOLE1226  I45  H44
   1    GND      1 @T6G_MB_LIB.T6G(SCH_1):GND

HOLE_TH-EMPTY,HOLE1226  I46  H49
   1    GND      1 @T6G_MB_LIB.T6G(SCH_1):GND

HOLE_TH-EMPTY,HOLE1226  I49  H50
   1    GND      1 @T6G_MB_LIB.T6G(SCH_1):GND

HOLE_TH-EMPTY,DUMMY50  I50  H28
   1     NC      1     NC

HOLE_TH-EMPTY,DUMMY50  I51  H29
   1     NC      1     NC

HOLE_TH-EMPTY,HOLE1226  I52  H54
   1    GND      1 @T6G_MB_LIB.T6G(SCH_1):GND

HOLE_TH-EMPTY,HOLE1226  I55  H13
   1    GND      1 @T6G_MB_LIB.T6G(SCH_1):GND

HOLE_TH-EMPTY,DUMMY50  I56  H30
   1     NC      1     NC

HOLE_TH-EMPTY,TMP-C_T2I_ALEX_1121_1  I84  H124
   1     NC      1     NC

HOLE_TH-EMPTY,TMP-C_T2I_ALEX_1121_1  I85  H125
   1     NC      1     NC

HOLE_TH-EMPTY,HOLE1226  I87  H11
   1    GND      1 @T6G_MB_LIB.T6G(SCH_1):GND

HOLE_TH-EMPTY,HOLE1247  I88  H74
   1     NC      1     NC

HOLE_TH-EMPTY,HOLE1247  I89  H75
   1     NC      1     NC

HOLE_TH-EMPTY,HOLE1248  I91  H31
   1    GND      1 @T6G_MB_LIB.T6G(SCH_1):GND

HOLE_TH-EMPTY,HOLE1248  I93  H32
   1    GND      1 @T6G_MB_LIB.T6G(SCH_1):GND

HOLE_TH-EMPTY,TMP-C_T2I_ALEX_1121_1  I94  H127
   1     NC      1     NC

CONN1_10165288101LF-CONN1_10165288-101LF,THLF,IO,DA  I101  J122
SCR_H1     NC    NC1     NC

CONN1_10165288101LF-CONN1_10165288-101LF,THLF,IO,DA  I106  J123
SCR_H1     NC    NC1     NC

HOLE_TH-EMPTY,TMP-C_T2I_ALEX_1121_1  I111  H126
   1     NC      1     NC

HOLE_TH-EMPTY,HOLE1226  I113  H6000
   1    GND      1 @T6G_MB_LIB.T6G(SCH_1):GND

HOLE_TH-EMPTY,HOLE1226  I116  H6001
   1    GND      1 @T6G_MB_LIB.T6G(SCH_1):GND

GND_HOLE_TH-EMPTY,TMP-QGND_HOLE12  I120  H111
   3    GND   GND3 @T6G_MB_LIB.T6G(SCH_1):GND
   2    GND   GND2 @T6G_MB_LIB.T6G(SCH_1):GND
   9    GND   GND9 @T6G_MB_LIB.T6G(SCH_1):GND
   8    GND   GND8 @T6G_MB_LIB.T6G(SCH_1):GND
   7    GND   GND7 @T6G_MB_LIB.T6G(SCH_1):GND
   6    GND   GND6 @T6G_MB_LIB.T6G(SCH_1):GND
   5    GND   GND5 @T6G_MB_LIB.T6G(SCH_1):GND
   4    GND   GND4 @T6G_MB_LIB.T6G(SCH_1):GND

GND_HOLE_TH-EMPTY,TMP-QGND_HOLE12  I123  H112
   3    GND   GND3 @T6G_MB_LIB.T6G(SCH_1):GND
   2    GND   GND2 @T6G_MB_LIB.T6G(SCH_1):GND
   9    GND   GND9 @T6G_MB_LIB.T6G(SCH_1):GND
   8    GND   GND8 @T6G_MB_LIB.T6G(SCH_1):GND
   7    GND   GND7 @T6G_MB_LIB.T6G(SCH_1):GND
   6    GND   GND6 @T6G_MB_LIB.T6G(SCH_1):GND
   5    GND   GND5 @T6G_MB_LIB.T6G(SCH_1):GND
   4    GND   GND4 @T6G_MB_LIB.T6G(SCH_1):GND

HOLE_TH-EMPTY,HOLE596  I125  H86
   1    GND      1 @T6G_MB_LIB.T6G(SCH_1):GND

HOLE_TH-EMPTY,HOLE596  I127  H87
   1    GND      1 @T6G_MB_LIB.T6G(SCH_1):GND

HOLE_TH-EMPTY,HOLE596  I129  H88
   1    GND      1 @T6G_MB_LIB.T6G(SCH_1):GND

HOLE_TH-EMPTY,HOLE596  I132  H89
   1    GND      1 @T6G_MB_LIB.T6G(SCH_1):GND

HOLE_TH-EMPTY,HOLE596  I133  H91
   1    GND      1 @T6G_MB_LIB.T6G(SCH_1):GND

HOLE_TH-EMPTY,HOLE596  I135  H92
   1    GND      1 @T6G_MB_LIB.T6G(SCH_1):GND

HOLE_TH-EMPTY,HOLE596  I138  H93
   1    GND      1 @T6G_MB_LIB.T6G(SCH_1):GND

HOLE_TH-EMPTY,HOLE596  I140  H94
   1    GND      1 @T6G_MB_LIB.T6G(SCH_1):GND

HOLE_TH-EMPTY,HOLE596  I141  H95
   1    GND      1 @T6G_MB_LIB.T6G(SCH_1):GND

HOLE_TH-EMPTY,HOLE596  I142  H96
   1    GND      1 @T6G_MB_LIB.T6G(SCH_1):GND

HOLE_TH-EMPTY,HOLE596  I145  H97
   1    GND      1 @T6G_MB_LIB.T6G(SCH_1):GND

HOLE_TH-EMPTY,HOLE596  I147  H98
   1    GND      1 @T6G_MB_LIB.T6G(SCH_1):GND

HOLE_TH-EMPTY,HOLE596  I149  H99
   1    GND      1 @T6G_MB_LIB.T6G(SCH_1):GND

HOLE_TH-EMPTY,HOLE596  I152  H100
   1    GND      1 @T6G_MB_LIB.T6G(SCH_1):GND

HOLE_TH-EMPTY,HOLE596  I153  H101
   1    GND      1 @T6G_MB_LIB.T6G(SCH_1):GND

HOLE_TH-EMPTY,HOLE596  I156  H102
   1    GND      1 @T6G_MB_LIB.T6G(SCH_1):GND

HOLE_TH-EMPTY,HOLE596  I157  H103
   1    GND      1 @T6G_MB_LIB.T6G(SCH_1):GND

HOLE_TH-EMPTY,HOLE596  I159  H104
   1    GND      1 @T6G_MB_LIB.T6G(SCH_1):GND

HOLE_TH-EMPTY,HOLE596  I161  H105
   1    GND      1 @T6G_MB_LIB.T6G(SCH_1):GND

HOLE_TH-EMPTY,HOLE596  I163  H106
   1    GND      1 @T6G_MB_LIB.T6G(SCH_1):GND

HOLE_TH-EMPTY,HOLE596  I166  H128
   1    GND      1 @T6G_MB_LIB.T6G(SCH_1):GND

HOLE_TH-EMPTY,HOLE372  I167  H90
   1     NC      1     NC

HOLE_TH-EMPTY,HOLE1195  I168  H6002
   1    GND      1 @T6G_MB_LIB.T6G(SCH_1):GND

HOLE_TH-EMPTY,HOLE1226  I170  H2
   1    GND      1 @T6G_MB_LIB.T6G(SCH_1):GND

HOLE_TH-EMPTY,HOLE1226  I176  H8
   1    GND      1 @T6G_MB_LIB.T6G(SCH_1):GND

HOLE_TH-EMPTY,HOLE1226  I178  H10
   1    GND      1 @T6G_MB_LIB.T6G(SCH_1):GND

HOLE_TH-EMPTY,HOLE1226  I187  H12
   1    GND      1 @T6G_MB_LIB.T6G(SCH_1):GND

HOLE_TH-EMPTY,HOLE1226  I193  H5
   1    GND      1 @T6G_MB_LIB.T6G(SCH_1):GND

HOLE_TH-EMPTY,HOLE1226  I195  H3
   1    GND      1 @T6G_MB_LIB.T6G(SCH_1):GND


DRAWING: @T6G_MB_LIB.T6G(SCH_1):PAGE374 

MOSFET_NCH_DUAL-PJT138K,SMLF,IC,BAM138K0003  I3  Q80
   3 LED_PWRGD_PVDDCR_CPU1_P0_D     D2 @T6G_MB_LIB.T6G(SCH_1):LED_PWRGD_PVDDCR_CPU1_P0_D
   5 FM_LED_PWRGD_PVDDCR_CPU1_P0     G2 @T6G_MB_LIB.T6G(SCH_1):FM_LED_PWRGD_PVDDCR_CPU1_P0
   4    GND     S2 @T6G_MB_LIB.T6G(SCH_1):GND

MOSFET_NCH_DUAL-PJT138K,SMLF,IC,BAM138K0003  I6  Q80
   1    GND     S1 @T6G_MB_LIB.T6G(SCH_1):GND
   2 FM_LED_PWRGD_PVDDCR_SOC_P0     G1 @T6G_MB_LIB.T6G(SCH_1):FM_LED_PWRGD_PVDDCR_SOC_P0
   6 LED_PWRGD_PVDDCR_SOC_P0_D     D1 @T6G_MB_LIB.T6G(SCH_1):LED_PWRGD_PVDDCR_SOC_P0_D

MOSFET_NCH_DUAL-PJT138K,SMLF,IC,BAM138K0003  I8  Q79
   3 LED_PWRGD_PVDDCR_CPU0_P0_D     D2 @T6G_MB_LIB.T6G(SCH_1):LED_PWRGD_PVDDCR_CPU0_P0_D
   5 FM_LED_PWRGD_PVDDCR_CPU0_P0     G2 @T6G_MB_LIB.T6G(SCH_1):FM_LED_PWRGD_PVDDCR_CPU0_P0
   4    GND     S2 @T6G_MB_LIB.T6G(SCH_1):GND

Q_LED_SMLF-LED_BLUE,LTST-C281TBKT-5A,IC,BEBL0172Z00  I11  D76
   A LED_PWRGD_PVDDCR_CPU1_P0_R      A @T6G_MB_LIB.T6G(SCH_1):LED_PWRGD_PVDDCR_CPU1_P0_R
   C LED_PWRGD_PVDDCR_CPU1_P0_D      C @T6G_MB_LIB.T6G(SCH_1):LED_PWRGD_PVDDCR_CPU1_P0_D

Q_RES_0402LF-130,1%,1/16W,CHIP,CS11302FB03  I12  R3088
   1 LED_PWRGD_PVDDCR_CPU1_P0_R      A @T6G_MB_LIB.T6G(SCH_1):LED_PWRGD_PVDDCR_CPU1_P0_R
   2 P3V3_AUX      B @T6G_MB_LIB.T6G(SCH_1):P3V3_AUX

Q_LED_SMLF-LED_BLUE,LTST-C281TBKT-5A,IC,BEBL0172Z00  I13  D75
   A LED_PWRGD_PVDDCR_SOC_P0_R      A @T6G_MB_LIB.T6G(SCH_1):LED_PWRGD_PVDDCR_SOC_P0_R
   C LED_PWRGD_PVDDCR_SOC_P0_D      C @T6G_MB_LIB.T6G(SCH_1):LED_PWRGD_PVDDCR_SOC_P0_D

Q_LED_SMLF-LED_BLUE,LTST-C281TBKT-5A,IC,BEBL0172Z00  I14  D74
   A LED_PWRGD_PVDDCR_CPU0_P0_R      A @T6G_MB_LIB.T6G(SCH_1):LED_PWRGD_PVDDCR_CPU0_P0_R
   C LED_PWRGD_PVDDCR_CPU0_P0_D      C @T6G_MB_LIB.T6G(SCH_1):LED_PWRGD_PVDDCR_CPU0_P0_D

Q_RES_0402LF-130,1%,1/16W,CHIP,CS11302FB03  I15  R3089
   1 LED_PWRGD_PVDDCR_SOC_P0_R      A @T6G_MB_LIB.T6G(SCH_1):LED_PWRGD_PVDDCR_SOC_P0_R
   2 P3V3_AUX      B @T6G_MB_LIB.T6G(SCH_1):P3V3_AUX

Q_RES_0402LF-130,1%,1/16W,CHIP,CS11302FB03  I16  R3087
   1 LED_PWRGD_PVDDCR_CPU0_P0_R      A @T6G_MB_LIB.T6G(SCH_1):LED_PWRGD_PVDDCR_CPU0_P0_R
   2 P3V3_AUX      B @T6G_MB_LIB.T6G(SCH_1):P3V3_AUX

MOSFET_NCH_DUAL-PJT138K,SMLF,IC,BAM138K0003  I18  Q79
   1    GND     S1 @T6G_MB_LIB.T6G(SCH_1):GND
   2 FM_LED_PWRGD_PVDD33_S5     G1 @T6G_MB_LIB.T6G(SCH_1):FM_LED_PWRGD_PVDD33_S5
   6 LED_PWRGD_PVDD33_S5_D     D1 @T6G_MB_LIB.T6G(SCH_1):LED_PWRGD_PVDD33_S5_D

Q_LED_SMLF-LED_BLUE,LTST-C281TBKT-5A,IC,BEBL0172Z00  I19  D73
   A LED_PWRGD_PVDD33_S5_R      A @T6G_MB_LIB.T6G(SCH_1):LED_PWRGD_PVDD33_S5_R
   C LED_PWRGD_PVDD33_S5_D      C @T6G_MB_LIB.T6G(SCH_1):LED_PWRGD_PVDD33_S5_D

Q_RES_0402LF-130,1%,1/16W,CHIP,CS11302FB03  I20  R3086
   1 LED_PWRGD_PVDD33_S5_R      A @T6G_MB_LIB.T6G(SCH_1):LED_PWRGD_PVDD33_S5_R
   2 P3V3_AUX      B @T6G_MB_LIB.T6G(SCH_1):P3V3_AUX

MOSFET_NCH_DUAL-PJT138K,SMLF,IC,BAM138K0003  I23  Q83
   1    GND     S1 @T6G_MB_LIB.T6G(SCH_1):GND
   2 FM_LED_PWRGD_PVDD18_S5_P0     G1 @T6G_MB_LIB.T6G(SCH_1):FM_LED_PWRGD_PVDD18_S5_P0
   6 LED_PWRGD_PVDD18_S5_P0_D     D1 @T6G_MB_LIB.T6G(SCH_1):LED_PWRGD_PVDD18_S5_P0_D

MOSFET_NCH_DUAL-PJT138K,SMLF,IC,BAM138K0003  I27  Q81
   3 LED_PWRGD_PVDD11_S3_P0_D     D2 @T6G_MB_LIB.T6G(SCH_1):LED_PWRGD_PVDD11_S3_P0_D
   5 FM_LED_PWRGD_PVDD11_S3_P0     G2 @T6G_MB_LIB.T6G(SCH_1):FM_LED_PWRGD_PVDD11_S3_P0
   4    GND     S2 @T6G_MB_LIB.T6G(SCH_1):GND

Q_LED_SMLF-LED_BLUE,LTST-C281TBKT-5A,IC,BEBL0172Z00  I30  D79
   A LED_PWRGD_PVDD18_S5_P0_R      A @T6G_MB_LIB.T6G(SCH_1):LED_PWRGD_PVDD18_S5_P0_R
   C LED_PWRGD_PVDD18_S5_P0_D      C @T6G_MB_LIB.T6G(SCH_1):LED_PWRGD_PVDD18_S5_P0_D

Q_LED_SMLF-LED_BLUE,LTST-C281TBKT-5A,IC,BEBL0172Z00  I32  D78
   A LED_PWRGD_PVDD11_S3_P0_R      A @T6G_MB_LIB.T6G(SCH_1):LED_PWRGD_PVDD11_S3_P0_R
   C LED_PWRGD_PVDD11_S3_P0_D      C @T6G_MB_LIB.T6G(SCH_1):LED_PWRGD_PVDD11_S3_P0_D

MOSFET_NCH_DUAL-PJT138K,SMLF,IC,BAM138K0003  I35  Q81
   1    GND     S1 @T6G_MB_LIB.T6G(SCH_1):GND
   2 FM_LED_PWRGD_PVDDIO_P0     G1 @T6G_MB_LIB.T6G(SCH_1):FM_LED_PWRGD_PVDDIO_P0
   6 LED_PWRGD_PVDDIO_P0_D     D1 @T6G_MB_LIB.T6G(SCH_1):LED_PWRGD_PVDDIO_P0_D

Q_LED_SMLF-LED_BLUE,LTST-C281TBKT-5A,IC,BEBL0172Z00  I36  D77
   A LED_PWRGD_PVDDIO_P0_R      A @T6G_MB_LIB.T6G(SCH_1):LED_PWRGD_PVDDIO_P0_R
   C LED_PWRGD_PVDDIO_P0_D      C @T6G_MB_LIB.T6G(SCH_1):LED_PWRGD_PVDDIO_P0_D

Q_RES_0402LF-130,1%,1/16W,CHIP,CS11302FB03  I37  R3091
   1 LED_PWRGD_PVDD18_S5_P0_R      A @T6G_MB_LIB.T6G(SCH_1):LED_PWRGD_PVDD18_S5_P0_R
   2 P3V3_AUX      B @T6G_MB_LIB.T6G(SCH_1):P3V3_AUX

Q_RES_0402LF-130,1%,1/16W,CHIP,CS11302FB03  I38  R3090
   1 LED_PWRGD_PVDD11_S3_P0_R      A @T6G_MB_LIB.T6G(SCH_1):LED_PWRGD_PVDD11_S3_P0_R
   2 P3V3_AUX      B @T6G_MB_LIB.T6G(SCH_1):P3V3_AUX

Q_RES_0402LF-130,1%,1/16W,CHIP,CS11302FB03  I41  R3092
   1 LED_PWRGD_PVDDIO_P0_R      A @T6G_MB_LIB.T6G(SCH_1):LED_PWRGD_PVDDIO_P0_R
   2 P3V3_AUX      B @T6G_MB_LIB.T6G(SCH_1):P3V3_AUX

MOSFET_NCH_DUAL-PJT138K,SMLF,IC,BAM138K0003  I43  Q83
   3 NC_Q83_D2     D2 @T6G_MB_LIB.T6G(SCH_1):NC_Q83_D2
   5 NC_Q83_G2     G2 @T6G_MB_LIB.T6G(SCH_1):NC_Q83_G2
   4 NC_Q83_S2     S2 @T6G_MB_LIB.T6G(SCH_1):NC_Q83_S2


DRAWING: @T6G_MB_LIB.T6G(SCH_1):PAGE375 

MOSFET_NCH_DUAL-PJT138K,SMLF,IC,BAM138K0003  I2  Q85
   3 LED_PWRGD_PVDDIO_P1_D     D2 @T6G_MB_LIB.T6G(SCH_1):LED_PWRGD_PVDDIO_P1_D
   5 FM_LED_PWRGD_PVDDIO_P1     G2 @T6G_MB_LIB.T6G(SCH_1):FM_LED_PWRGD_PVDDIO_P1
   4    GND     S2 @T6G_MB_LIB.T6G(SCH_1):GND

MOSFET_NCH_DUAL-PJT138K,SMLF,IC,BAM138K0003  I7  Q85
   1    GND     S1 @T6G_MB_LIB.T6G(SCH_1):GND
   2 FM_LED_PWRGD_PVDDCR_CPU1_P1     G1 @T6G_MB_LIB.T6G(SCH_1):FM_LED_PWRGD_PVDDCR_CPU1_P1
   6 LED_PWRGD_PVDDCR_CPU1_P1_D     D1 @T6G_MB_LIB.T6G(SCH_1):LED_PWRGD_PVDDCR_CPU1_P1_D

MOSFET_NCH_DUAL-PJT138K,SMLF,IC,BAM138K0003  I10  Q84
   3 LED_PWRGD_PVDDCR_SOC_P1_D     D2 @T6G_MB_LIB.T6G(SCH_1):LED_PWRGD_PVDDCR_SOC_P1_D
   5 FM_LED_PWRGD_PVDDCR_SOC_P1     G2 @T6G_MB_LIB.T6G(SCH_1):FM_LED_PWRGD_PVDDCR_SOC_P1
   4    GND     S2 @T6G_MB_LIB.T6G(SCH_1):GND

MOSFET_NCH_DUAL-PJT138K,SMLF,IC,BAM138K0003  I11  Q84
   1    GND     S1 @T6G_MB_LIB.T6G(SCH_1):GND
   2 FM_LED_PWRGD_PVDDCR_CPU0_P1     G1 @T6G_MB_LIB.T6G(SCH_1):FM_LED_PWRGD_PVDDCR_CPU0_P1
   6 LED_PWRGD_PVDDCR_CPU0_P1_D     D1 @T6G_MB_LIB.T6G(SCH_1):LED_PWRGD_PVDDCR_CPU0_P1_D

Q_LED_SMLF-LED_BLUE,LTST-C281TBKT-5A,IC,BEBL0172Z00  I13  D83
   A LED_PWRGD_PVDDIO_P1_R      A @T6G_MB_LIB.T6G(SCH_1):LED_PWRGD_PVDDIO_P1_R
   C LED_PWRGD_PVDDIO_P1_D      C @T6G_MB_LIB.T6G(SCH_1):LED_PWRGD_PVDDIO_P1_D

Q_LED_SMLF-LED_BLUE,LTST-C281TBKT-5A,IC,BEBL0172Z00  I14  D82
   A LED_PWRGD_PVDDCR_CPU1_P1_R      A @T6G_MB_LIB.T6G(SCH_1):LED_PWRGD_PVDDCR_CPU1_P1_R
   C LED_PWRGD_PVDDCR_CPU1_P1_D      C @T6G_MB_LIB.T6G(SCH_1):LED_PWRGD_PVDDCR_CPU1_P1_D

Q_RES_0402LF-130,1%,1/16W,CHIP,CS11302FB03  I15  R3095
   1 LED_PWRGD_PVDDIO_P1_R      A @T6G_MB_LIB.T6G(SCH_1):LED_PWRGD_PVDDIO_P1_R
   2 P3V3_AUX      B @T6G_MB_LIB.T6G(SCH_1):P3V3_AUX

Q_RES_0402LF-130,1%,1/16W,CHIP,CS11302FB03  I16  R3096
   1 LED_PWRGD_PVDDCR_CPU1_P1_R      A @T6G_MB_LIB.T6G(SCH_1):LED_PWRGD_PVDDCR_CPU1_P1_R
   2 P3V3_AUX      B @T6G_MB_LIB.T6G(SCH_1):P3V3_AUX

Q_LED_SMLF-LED_BLUE,LTST-C281TBKT-5A,IC,BEBL0172Z00  I17  D81
   A LED_PWRGD_PVDDCR_SOC_P1_R      A @T6G_MB_LIB.T6G(SCH_1):LED_PWRGD_PVDDCR_SOC_P1_R
   C LED_PWRGD_PVDDCR_SOC_P1_D      C @T6G_MB_LIB.T6G(SCH_1):LED_PWRGD_PVDDCR_SOC_P1_D

Q_RES_0402LF-130,1%,1/16W,CHIP,CS11302FB03  I18  R3094
   1 LED_PWRGD_PVDDCR_SOC_P1_R      A @T6G_MB_LIB.T6G(SCH_1):LED_PWRGD_PVDDCR_SOC_P1_R
   2 P3V3_AUX      B @T6G_MB_LIB.T6G(SCH_1):P3V3_AUX

Q_LED_SMLF-LED_BLUE,LTST-C281TBKT-5A,IC,BEBL0172Z00  I19  D80
   A LED_PWRGD_PVDDCR_CPU0_P1_R      A @T6G_MB_LIB.T6G(SCH_1):LED_PWRGD_PVDDCR_CPU0_P1_R
   C LED_PWRGD_PVDDCR_CPU0_P1_D      C @T6G_MB_LIB.T6G(SCH_1):LED_PWRGD_PVDDCR_CPU0_P1_D

Q_RES_0402LF-130,1%,1/16W,CHIP,CS11302FB03  I20  R3093
   1 LED_PWRGD_PVDDCR_CPU0_P1_R      A @T6G_MB_LIB.T6G(SCH_1):LED_PWRGD_PVDDCR_CPU0_P1_R
   2 P3V3_AUX      B @T6G_MB_LIB.T6G(SCH_1):P3V3_AUX

MOSFET_NCH_DUAL-PJT138K,SMLF,IC,BAM138K0003  I29  Q86
   3 LED_PWRGD_PVDD18_S5_P1_D     D2 @T6G_MB_LIB.T6G(SCH_1):LED_PWRGD_PVDD18_S5_P1_D
   5 FM_LED_PWRGD_PVDD18_S5_P1     G2 @T6G_MB_LIB.T6G(SCH_1):FM_LED_PWRGD_PVDD18_S5_P1
   4    GND     S2 @T6G_MB_LIB.T6G(SCH_1):GND

MOSFET_NCH_DUAL-PJT138K,SMLF,IC,BAM138K0003  I30  Q86
   1    GND     S1 @T6G_MB_LIB.T6G(SCH_1):GND
   2 FM_LED_PWRGD_PVDD11_S3_P1     G1 @T6G_MB_LIB.T6G(SCH_1):FM_LED_PWRGD_PVDD11_S3_P1
   6 LED_PWRGD_PVDD11_S3_P1_D     D1 @T6G_MB_LIB.T6G(SCH_1):LED_PWRGD_PVDD11_S3_P1_D

Q_LED_SMLF-LED_BLUE,LTST-C281TBKT-5A,IC,BEBL0172Z00  I33  D85
   A LED_PWRGD_PVDD18_S5_P1_R      A @T6G_MB_LIB.T6G(SCH_1):LED_PWRGD_PVDD18_S5_P1_R
   C LED_PWRGD_PVDD18_S5_P1_D      C @T6G_MB_LIB.T6G(SCH_1):LED_PWRGD_PVDD18_S5_P1_D

Q_LED_SMLF-LED_BLUE,LTST-C281TBKT-5A,IC,BEBL0172Z00  I35  D84
   A LED_PWRGD_PVDD11_S3_P1_R      A @T6G_MB_LIB.T6G(SCH_1):LED_PWRGD_PVDD11_S3_P1_R
   C LED_PWRGD_PVDD11_S3_P1_D      C @T6G_MB_LIB.T6G(SCH_1):LED_PWRGD_PVDD11_S3_P1_D

Q_RES_0402LF-130,1%,1/16W,CHIP,CS11302FB03  I38  R3097
   1 LED_PWRGD_PVDD18_S5_P1_R      A @T6G_MB_LIB.T6G(SCH_1):LED_PWRGD_PVDD18_S5_P1_R
   2 P3V3_AUX      B @T6G_MB_LIB.T6G(SCH_1):P3V3_AUX

Q_RES_0402LF-130,1%,1/16W,CHIP,CS11302FB03  I40  R3099
   1 LED_PWRGD_PVDD11_S3_P1_R      A @T6G_MB_LIB.T6G(SCH_1):LED_PWRGD_PVDD11_S3_P1_R
   2 P3V3_AUX      B @T6G_MB_LIB.T6G(SCH_1):P3V3_AUX

Q_LED_SMLF-LED_BLUE,LTST-C281TBKT-5A,IC,BEBL0172Z00  I42  D8000
   A LED_P12V_AUX_R1      A @T6G_MB_LIB.T6G(SCH_1):LED_P12V_AUX_R1
   C    GND      C @T6G_MB_LIB.T6G(SCH_1):GND

Q_RES_0402LF-560,1%,1/16W,CHIP,CS15602FB03  I44  R8022
   1 LED_P12V_AUX_R1      A @T6G_MB_LIB.T6G(SCH_1):LED_P12V_AUX_R1
   2 LED_P12V_AUX_R2      B @T6G_MB_LIB.T6G(SCH_1):LED_P12V_AUX_R2

Q_RES_0402LF-560,1%,1/16W,CHIP,CS15602FB03  I45  R8023
   1 LED_P12V_AUX_R2      A @T6G_MB_LIB.T6G(SCH_1):LED_P12V_AUX_R2
   2 LED_P12V_AUX_R3      B @T6G_MB_LIB.T6G(SCH_1):LED_P12V_AUX_R3

Q_RES_0402LF-560,1%,1/16W,CHIP,CS15602FB03  I46  R8024
   1 LED_P12V_AUX_R3      A @T6G_MB_LIB.T6G(SCH_1):LED_P12V_AUX_R3
   2 P12V_AUX      B @T6G_MB_LIB.T6G(SCH_1):P12V_AUX

Q_RES_0402LF-560,1%,1/16W,CHIP,CS15602FB03  I49  R8027
   1 LED_P12V_PSU_R3      A @T6G_MB_LIB.T6G(SCH_1):LED_P12V_PSU_R3
   2 P12V_PSU      B @T6G_MB_LIB.T6G(SCH_1):P12V_PSU

Q_RES_0402LF-560,1%,1/16W,CHIP,CS15602FB03  I50  R8026
   1 LED_P12V_PSU_R2      A @T6G_MB_LIB.T6G(SCH_1):LED_P12V_PSU_R2
   2 LED_P12V_PSU_R3      B @T6G_MB_LIB.T6G(SCH_1):LED_P12V_PSU_R3

Q_RES_0402LF-560,1%,1/16W,CHIP,CS15602FB03  I51  R8025
   1 LED_P12V_PSU_R1      A @T6G_MB_LIB.T6G(SCH_1):LED_P12V_PSU_R1
   2 LED_P12V_PSU_R2      B @T6G_MB_LIB.T6G(SCH_1):LED_P12V_PSU_R2

Q_LED_SMLF-LED_BLUE,LTST-C281TBKT-5A,IC,BEBL0172Z00  I52  D8001
   A LED_P12V_PSU_R1      A @T6G_MB_LIB.T6G(SCH_1):LED_P12V_PSU_R1
   C    GND      C @T6G_MB_LIB.T6G(SCH_1):GND

Q_RES_0402LF-249,1%,1/16W,CHIP,CS12492FB02  I55  R8029
   1 LED_P12V_SCM_FAULT      A @T6G_MB_LIB.T6G(SCH_1):LED_P12V_SCM_FAULT
   2 P3V3_AUX      B @T6G_MB_LIB.T6G(SCH_1):P3V3_AUX

Q_LED_SMLF-LED_YELLOW,LTST-C190KSKT-P,IC,BEYL0159ZA  I56  D8002
   A LED_P12V_SCM_FAULT      A @T6G_MB_LIB.T6G(SCH_1):LED_P12V_SCM_FAULT
   C LED_P12V_SCM_FAULT_D2      C @T6G_MB_LIB.T6G(SCH_1):LED_P12V_SCM_FAULT_D2

MOSFET_NCH_DUAL-PJT138K,SMLF,IC,BAM138K0003  I57  Q8001
   1    GND     S1 @T6G_MB_LIB.T6G(SCH_1):GND
   2 P12V_SCM_FAULT_R_N     G1 @T6G_MB_LIB.T6G(SCH_1):P12V_SCM_FAULT_R_N
   6 LED_P12V_SCM_FAULT_D1     D1 @T6G_MB_LIB.T6G(SCH_1):LED_P12V_SCM_FAULT_D1

MOSFET_NCH_DUAL-PJT138K,SMLF,IC,BAM138K0003  I58  Q8001
   3 LED_P12V_SCM_FAULT_D2     D2 @T6G_MB_LIB.T6G(SCH_1):LED_P12V_SCM_FAULT_D2
   5 LED_P12V_SCM_FAULT_D1     G2 @T6G_MB_LIB.T6G(SCH_1):LED_P12V_SCM_FAULT_D1
   4    GND     S2 @T6G_MB_LIB.T6G(SCH_1):GND

Q_RES_0402LF-4.7K,5%,1/16W,CHIP,CS24702JB10  I62  R8028
   1 P3V3_AUX      A @T6G_MB_LIB.T6G(SCH_1):P3V3_AUX
   2 LED_P12V_SCM_FAULT_D1      B @T6G_MB_LIB.T6G(SCH_1):LED_P12V_SCM_FAULT_D1


DRAWING: @T6G_MB_LIB.T6G(SCH_1):PAGE111 

DS125BR111RTWR-DS125BR111RTWR,SMLF,IC,AL000125003  I1  U6000
   1 FM_P2E_BUF2_EQB0 EQB0||AD3 @T6G_MB_LIB.T6G(SCH_1):FM_P2E_BUF2_EQB0
   2 FM_P2E_BUF2_EQB1 EQB1||AD2 @T6G_MB_LIB.T6G(SCH_1):FM_P2E_BUF2_EQB1
   3 PD_P2E_BUF2_ENSMB  ENSMB @T6G_MB_LIB.T6G(SCH_1):PD_P2E_BUF2_ENSMB
   4 FM_P2E_BUF2_VODA_DB SDA||VODA_DB @T6G_MB_LIB.T6G(SCH_1):FM_P2E_BUF2_VODA_DB
   5 FM_P2E_BUF2_VODB_DB SCL||VODB_DB @T6G_MB_LIB.T6G(SCH_1):FM_P2E_BUF2_VODB_DB
   6 FM_P2E_EN2_N   PWDN @T6G_MB_LIB.T6G(SCH_1):FM_P2E_EN2_N
   7 P2E_MB_BMC_TX_BUF2_DP<0>  OUTA+ @T6G_MB_LIB.T6G(SCH_1):P2E_MB_BMC_TX_BUF2_DP(0)
   8 P2E_MB_BMC_TX_BUF2_DN<0>  OUTA- @T6G_MB_LIB.T6G(SCH_1):P2E_MB_BMC_TX_BUF2_DN(0)
   9 FM_P2E_BUF2_EQA1 EQA1||AD1 @T6G_MB_LIB.T6G(SCH_1):FM_P2E_BUF2_EQA1
  10 FM_P2E_BUF2_EQA0 EQA0||AD0 @T6G_MB_LIB.T6G(SCH_1):FM_P2E_BUF2_EQA0
  11 P2E_MB_BMC_RX_R2_DP<0>   INB+ @T6G_MB_LIB.T6G(SCH_1):P2E_MB_BMC_RX_R2_DP(0)
  12 P2E_MB_BMC_RX_R2_DN<0>   INB- @T6G_MB_LIB.T6G(SCH_1):P2E_MB_BMC_RX_R2_DN(0)
  13 NC_RES    RES @T6G_MB_LIB.T6G(SCH_1):NC_RES
  14 FM_P2E_BUF2_SD_TH  SD_TH @T6G_MB_LIB.T6G(SCH_1):FM_P2E_BUF2_SD_TH
  15 P3V3_AUX    VIN @T6G_MB_LIB.T6G(SCH_1):P3V3_AUX
  16    GND VDD_SEL @T6G_MB_LIB.T6G(SCH_1):GND
  17 FM_P2E_BUF2_VOD_SEL VOD_SEL||READEN# @T6G_MB_LIB.T6G(SCH_1):FM_P2E_BUF2_VOD_SEL
  18 FM_P2E_BUF2_RXDET RXDET||DONE# @T6G_MB_LIB.T6G(SCH_1):FM_P2E_BUF2_RXDET
  19 P2E_MB_BMC_RX_BUF2_C_DN<0>  OUTB- @T6G_MB_LIB.T6G(SCH_1):P2E_MB_BMC_RX_BUF2_C_DN(0)
  20 P2E_MB_BMC_RX_BUF2_C_DP<0>  OUTB+ @T6G_MB_LIB.T6G(SCH_1):P2E_MB_BMC_RX_BUF2_C_DP(0)
  21 BUF2_VDD VDD_21 @T6G_MB_LIB.T6G(SCH_1):BUF2_VDD
  22 BUF2_VDD VDD_22 @T6G_MB_LIB.T6G(SCH_1):BUF2_VDD
  23 P2E_MB_BMC_TX_C_R2_DN<0>   INA- @T6G_MB_LIB.T6G(SCH_1):P2E_MB_BMC_TX_C_R2_DN(0)
  24 P2E_MB_BMC_TX_C_R2_DP<0>   INA+ @T6G_MB_LIB.T6G(SCH_1):P2E_MB_BMC_TX_C_R2_DP(0)
  25    GND TH_GND @T6G_MB_LIB.T6G(SCH_1):GND

Q_CAP_C0402-1UF,25V,10%,X6S,CH5104KEB02  I3  C6009
   1 P3V3_AUX      A @T6G_MB_LIB.T6G(SCH_1):P3V3_AUX
   2    GND      B @T6G_MB_LIB.T6G(SCH_1):GND

Q_CAP_C0805-10UF,16V,10%,X6S,CH6103KEA00  I5  C6010
   1 P3V3_AUX      A @T6G_MB_LIB.T6G(SCH_1):P3V3_AUX
   2    GND      B @T6G_MB_LIB.T6G(SCH_1):GND

Q_CAP_0402-0.1UF,25V,10%,X7R,CH4104K1B00  I6  C6011
   1 BUF2_VDD      A @T6G_MB_LIB.T6G(SCH_1):BUF2_VDD
   2    GND      B @T6G_MB_LIB.T6G(SCH_1):GND

Q_CAP_0402-0.1UF,25V,10%,X7R,CH4104K1B00  I7  C6012
   1 BUF2_VDD      A @T6G_MB_LIB.T6G(SCH_1):BUF2_VDD
   2    GND      B @T6G_MB_LIB.T6G(SCH_1):GND

Q_RES_0402LF-1K,1%,1/16W,CHIP,CS21002FB06  I12  R6160
   1 PD_P2E_BUF2_ENSMB      A @T6G_MB_LIB.T6G(SCH_1):PD_P2E_BUF2_ENSMB
   2    GND      B @T6G_MB_LIB.T6G(SCH_1):GND

Q_RES_0402LF-0,5%,1/16W,CHIP,CS00002JB13  I23  R6162
   1 FM_P2E_EN2_N      A @T6G_MB_LIB.T6G(SCH_1):FM_P2E_EN2_N
   2 CLK_GEN2_GPU_FPGA_OE_OR_N      B @T6G_MB_LIB.T6G(SCH_1):CLK_GEN2_GPU_FPGA_OE_OR_N

Q_RES_0402LF-1K,1%,1/16W,CHIP,CS21002FB06  I32  R6164
   1 FM_P2E_BUF2_EQB1      A @T6G_MB_LIB.T6G(SCH_1):FM_P2E_BUF2_EQB1
   2    GND      B @T6G_MB_LIB.T6G(SCH_1):GND

Q_RES_0402LF-1K,1%,1/16W,EMPTY,CS21002FB06  I39  R6163
   1 P3V3_AUX      A @T6G_MB_LIB.T6G(SCH_1):P3V3_AUX
   2 FM_P2E_BUF2_EQB1      B @T6G_MB_LIB.T6G(SCH_1):FM_P2E_BUF2_EQB1

Q_RES_0402LF-1K,1%,1/16W,EMPTY,CS21002FB06  I40  R6166
   1 FM_P2E_BUF2_EQB0      A @T6G_MB_LIB.T6G(SCH_1):FM_P2E_BUF2_EQB0
   2    GND      B @T6G_MB_LIB.T6G(SCH_1):GND

Q_RES_0402LF-1K,1%,1/16W,EMPTY,CS21002FB06  I41  R6165
   1 P3V3_AUX      A @T6G_MB_LIB.T6G(SCH_1):P3V3_AUX
   2 FM_P2E_BUF2_EQB0      B @T6G_MB_LIB.T6G(SCH_1):FM_P2E_BUF2_EQB0

Q_RES_0402LF-1K,1%,1/16W,EMPTY,CS21002FB06  I44  R6173
   1 P3V3_AUX      A @T6G_MB_LIB.T6G(SCH_1):P3V3_AUX
   2 FM_P2E_BUF2_EQA0      B @T6G_MB_LIB.T6G(SCH_1):FM_P2E_BUF2_EQA0

Q_RES_0402LF-1K,1%,1/16W,EMPTY,CS21002FB06  I45  R6174
   1 FM_P2E_BUF2_EQA0      A @T6G_MB_LIB.T6G(SCH_1):FM_P2E_BUF2_EQA0
   2    GND      B @T6G_MB_LIB.T6G(SCH_1):GND

Q_RES_0402LF-1K,1%,1/16W,EMPTY,CS21002FB06  I48  R6171
   1 P3V3_AUX      A @T6G_MB_LIB.T6G(SCH_1):P3V3_AUX
   2 FM_P2E_BUF2_EQA1      B @T6G_MB_LIB.T6G(SCH_1):FM_P2E_BUF2_EQA1

Q_RES_0402LF-1K,1%,1/16W,CHIP,CS21002FB06  I49  R6172
   1 FM_P2E_BUF2_EQA1      A @T6G_MB_LIB.T6G(SCH_1):FM_P2E_BUF2_EQA1
   2    GND      B @T6G_MB_LIB.T6G(SCH_1):GND

Q_RES_0402LF-1K,1%,1/16W,EMPTY,CS21002FB06  I53  R6169
   1 P3V3_AUX      A @T6G_MB_LIB.T6G(SCH_1):P3V3_AUX
   2 FM_P2E_BUF2_VODA_DB      B @T6G_MB_LIB.T6G(SCH_1):FM_P2E_BUF2_VODA_DB

Q_RES_0402LF-1K,1%,1/16W,EMPTY,CS21002FB06  I57  R6167
   1 P3V3_AUX      A @T6G_MB_LIB.T6G(SCH_1):P3V3_AUX
   2 FM_P2E_BUF2_VODB_DB      B @T6G_MB_LIB.T6G(SCH_1):FM_P2E_BUF2_VODB_DB

Q_RES_0402LF-1K,1%,1/16W,CHIP,CS21002FB06  I58  R6168
   1 FM_P2E_BUF2_VODB_DB      A @T6G_MB_LIB.T6G(SCH_1):FM_P2E_BUF2_VODB_DB
   2    GND      B @T6G_MB_LIB.T6G(SCH_1):GND

Q_RES_0402LF-1K,1%,1/16W,CHIP,CS21002FB06  I60  R6170
   1 FM_P2E_BUF2_VODA_DB      A @T6G_MB_LIB.T6G(SCH_1):FM_P2E_BUF2_VODA_DB
   2    GND      B @T6G_MB_LIB.T6G(SCH_1):GND

Q_RES_0402LF-1K,1%,1/16W,EMPTY,CS21002FB06  I63  R6175
   1 P3V3_AUX      A @T6G_MB_LIB.T6G(SCH_1):P3V3_AUX
   2 FM_P2E_BUF2_RXDET      B @T6G_MB_LIB.T6G(SCH_1):FM_P2E_BUF2_RXDET

Q_RES_0402LF-1K,1%,1/16W,EMPTY,CS21002FB06  I64  R6176
   1 FM_P2E_BUF2_RXDET      A @T6G_MB_LIB.T6G(SCH_1):FM_P2E_BUF2_RXDET
   2    GND      B @T6G_MB_LIB.T6G(SCH_1):GND

Q_RES_0402LF-1K,1%,1/16W,EMPTY,CS21002FB06  I68  R6178
   1 FM_P2E_BUF2_SD_TH      A @T6G_MB_LIB.T6G(SCH_1):FM_P2E_BUF2_SD_TH
   2    GND      B @T6G_MB_LIB.T6G(SCH_1):GND

Q_RES_0402LF-1K,1%,1/16W,EMPTY,CS21002FB06  I73  R6180
   1 FM_P2E_BUF2_VOD_SEL      A @T6G_MB_LIB.T6G(SCH_1):FM_P2E_BUF2_VOD_SEL
   2    GND      B @T6G_MB_LIB.T6G(SCH_1):GND

Q_RES_0402LF-1K,1%,1/16W,CHIP,CS21002FB06  I77  R6177
   1 P3V3_AUX      A @T6G_MB_LIB.T6G(SCH_1):P3V3_AUX
   2 FM_P2E_BUF2_SD_TH      B @T6G_MB_LIB.T6G(SCH_1):FM_P2E_BUF2_SD_TH

Q_RES_0402LF-1K,1%,1/16W,CHIP,CS21002FB06  I78  R6179
   1 P3V3_AUX      A @T6G_MB_LIB.T6G(SCH_1):P3V3_AUX
   2 FM_P2E_BUF2_VOD_SEL      B @T6G_MB_LIB.T6G(SCH_1):FM_P2E_BUF2_VOD_SEL


DRAWING: @T6G_MB_LIB.T6G(SCH_1):PAGE112 

Q_RES_0201LF-0,5%,1/20W,CHIP,CS00001JE10  I1  R6154
   1 P2E_MB_BMC_TX_C_DP<0>      A @T6G_MB_LIB.T6G(SCH_1):P2E_MB_BMC_TX_C_DP(0)
   2 P2E_MB_BMC_TX_C_R2_DP<0>      B @T6G_MB_LIB.T6G(SCH_1):P2E_MB_BMC_TX_C_R2_DP(0)

Q_RES_0201LF-0,5%,1/20W,CHIP,CS00001JE10  I2  R6155
   1 P2E_MB_BMC_TX_C_DN<0>      A @T6G_MB_LIB.T6G(SCH_1):P2E_MB_BMC_TX_C_DN(0)
   2 P2E_MB_BMC_TX_C_R2_DN<0>      B @T6G_MB_LIB.T6G(SCH_1):P2E_MB_BMC_TX_C_R2_DN(0)

Q_RES_0201LF-0,5%,1/20W,CHIP,CS00001JE10  I3  R6153
   1 P2E_MB_BMC_TX_C_DN<0>      A @T6G_MB_LIB.T6G(SCH_1):P2E_MB_BMC_TX_C_DN(0)
   2 P2E_MB_BMC_TX_C_R1_DN<0>      B @T6G_MB_LIB.T6G(SCH_1):P2E_MB_BMC_TX_C_R1_DN(0)

Q_RES_0201LF-0,5%,1/20W,CHIP,CS00001JE10  I8  R6152
   1 P2E_MB_BMC_TX_C_DP<0>      A @T6G_MB_LIB.T6G(SCH_1):P2E_MB_BMC_TX_C_DP(0)
   2 P2E_MB_BMC_TX_C_R1_DP<0>      B @T6G_MB_LIB.T6G(SCH_1):P2E_MB_BMC_TX_C_R1_DP(0)

Q_CAP_0402-0.1UF,25V,10%,X7R,CH4104K1B00  I11  C1868
   1 P2E_MB_BMC_RX_BUF_C_DP<0>      A @T6G_MB_LIB.T6G(SCH_1):P2E_MB_BMC_RX_BUF_C_DP(0)
   2 P2E_MB_BMC_RX_BUF_DP<0>      B @T6G_MB_LIB.T6G(SCH_1):P2E_MB_BMC_RX_BUF_DP(0)

Q_CAP_0402-0.1UF,25V,10%,X7R,CH4104K1B00  I12  C1869
   1 P2E_MB_BMC_RX_BUF_C_DN<0>      A @T6G_MB_LIB.T6G(SCH_1):P2E_MB_BMC_RX_BUF_C_DN(0)
   2 P2E_MB_BMC_RX_BUF_DN<0>      B @T6G_MB_LIB.T6G(SCH_1):P2E_MB_BMC_RX_BUF_DN(0)

Q_CAP_0402-0.1UF,25V,10%,X7R,CH4104K1B00  I13  C1870
   1 P2E_MB_BMC_TX_BUF_DP<0>      A @T6G_MB_LIB.T6G(SCH_1):P2E_MB_BMC_TX_BUF_DP(0)
   2 P2E_MB_BMC_TX_BUF_C_DP<0>      B @T6G_MB_LIB.T6G(SCH_1):P2E_MB_BMC_TX_BUF_C_DP(0)

Q_CAP_0402-0.1UF,25V,10%,X7R,CH4104K1B00  I14  C1871
   1 P2E_MB_BMC_TX_BUF_DN<0>      A @T6G_MB_LIB.T6G(SCH_1):P2E_MB_BMC_TX_BUF_DN(0)
   2 P2E_MB_BMC_TX_BUF_C_DN<0>      B @T6G_MB_LIB.T6G(SCH_1):P2E_MB_BMC_TX_BUF_C_DN(0)

Q_RES_0201LF-0,5%,1/20W,CHIP,CS00001JE10  I21  R6156
   1 P2E_MB_BMC_RX_DP<0>      A @T6G_MB_LIB.T6G(SCH_1):P2E_MB_BMC_RX_DP(0)
   2 P2E_MB_BMC_RX_R1_DP<0>      B @T6G_MB_LIB.T6G(SCH_1):P2E_MB_BMC_RX_R1_DP(0)

Q_RES_0201LF-0,5%,1/20W,CHIP,CS00001JE10  I22  R6157
   1 P2E_MB_BMC_RX_DN<0>      A @T6G_MB_LIB.T6G(SCH_1):P2E_MB_BMC_RX_DN(0)
   2 P2E_MB_BMC_RX_R1_DN<0>      B @T6G_MB_LIB.T6G(SCH_1):P2E_MB_BMC_RX_R1_DN(0)

Q_RES_0201LF-0,5%,1/20W,CHIP,CS00001JE10  I23  R6159
   1 P2E_MB_BMC_RX_DN<0>      A @T6G_MB_LIB.T6G(SCH_1):P2E_MB_BMC_RX_DN(0)
   2 P2E_MB_BMC_RX_R2_DN<0>      B @T6G_MB_LIB.T6G(SCH_1):P2E_MB_BMC_RX_R2_DN(0)

Q_RES_0201LF-0,5%,1/20W,CHIP,CS00001JE10  I24  R6158
   1 P2E_MB_BMC_RX_DP<0>      A @T6G_MB_LIB.T6G(SCH_1):P2E_MB_BMC_RX_DP(0)
   2 P2E_MB_BMC_RX_R2_DP<0>      B @T6G_MB_LIB.T6G(SCH_1):P2E_MB_BMC_RX_R2_DP(0)

Q_CAP_0402-0.1UF,25V,10%,X7R,CH4104K1B00  I35  C6006
   1 P2E_MB_BMC_TX_BUF2_DN<0>      A @T6G_MB_LIB.T6G(SCH_1):P2E_MB_BMC_TX_BUF2_DN(0)
   2 P2E_MB_BMC_TX_BUF_C_DN<0>      B @T6G_MB_LIB.T6G(SCH_1):P2E_MB_BMC_TX_BUF_C_DN(0)

Q_CAP_0402-0.1UF,25V,10%,X7R,CH4104K1B00  I36  C6005
   1 P2E_MB_BMC_TX_BUF2_DP<0>      A @T6G_MB_LIB.T6G(SCH_1):P2E_MB_BMC_TX_BUF2_DP(0)
   2 P2E_MB_BMC_TX_BUF_C_DP<0>      B @T6G_MB_LIB.T6G(SCH_1):P2E_MB_BMC_TX_BUF_C_DP(0)

Q_CAP_0402-0.1UF,25V,10%,X7R,CH4104K1B00  I43  C6007
   1 P2E_MB_BMC_RX_BUF2_C_DP<0>      A @T6G_MB_LIB.T6G(SCH_1):P2E_MB_BMC_RX_BUF2_C_DP(0)
   2 P2E_MB_BMC_RX_BUF_DP<0>      B @T6G_MB_LIB.T6G(SCH_1):P2E_MB_BMC_RX_BUF_DP(0)

Q_CAP_0402-0.1UF,25V,10%,X7R,CH4104K1B00  I44  C6008
   1 P2E_MB_BMC_RX_BUF2_C_DN<0>      A @T6G_MB_LIB.T6G(SCH_1):P2E_MB_BMC_RX_BUF2_C_DN(0)
   2 P2E_MB_BMC_RX_BUF_DN<0>      B @T6G_MB_LIB.T6G(SCH_1):P2E_MB_BMC_RX_BUF_DN(0)


DRAWING: @T6G_MB_LIB.T6G(SCH_1):PAGE267 

Q_RES_0402LF-6.19K,1%,1/16W,CHIP,CS26192FB03  I22  R1117
   1 MB0_P12V_STBY_PWRGD      A @T6G_MB_LIB.T6G(SCH_1):MB0_P12V_STBY_PWRGD
   2 AGND_HSC      B @T6G_MB_LIB.T6G(SCH_1):AGND_HSC

Q_RES_0402LF-0,5%,1/16W,CHIP,CS00002JB13  I24  R3924
   1 IRQ_SML1_PMBUS_ALERT_N      A @T6G_MB_LIB.T6G(SCH_1):IRQ_SML1_PMBUS_ALERT_N
   2 IRQ_SML1_PMBUS_ALERT      B @T6G_MB_LIB.T6G(SCH_1):IRQ_SML1_PMBUS_ALERT

Q_CAP_C0402-1UF,25V,10%,X6S,CH5104KEB02  I27  PC2186
   1 HSC_VDD_R      A @T6G_MB_LIB.T6G(SCH_1):HSC_VDD_R
   2 AGND_HSC      B @T6G_MB_LIB.T6G(SCH_1):AGND_HSC

Q_CAP_C0402-1UF,25V,10%,X6S,CH5104KEB02  I30  PC2187
   1 HSC_VDD_R      A @T6G_MB_LIB.T6G(SCH_1):HSC_VDD_R
   2 AGND_HSC      B @T6G_MB_LIB.T6G(SCH_1):AGND_HSC

Q_RES_0402LF-1K,1%,1/16W,CHIP,CS21002FB06  I34  R3925
   1 IRQ_SML1_PMBUS_ALERT      A @T6G_MB_LIB.T6G(SCH_1):IRQ_SML1_PMBUS_ALERT
   2 P3V3_AUX      B @T6G_MB_LIB.T6G(SCH_1):P3V3_AUX

Q_RES_0402LF-0,5%,1/16W,CHIP,CS00002JB13  I36  R1714
   1 SMB_SML1_PMBUS_HSC_SDA      A @T6G_MB_LIB.T6G(SCH_1):SMB_SML1_PMBUS_HSC_SDA
   2 SMB_SML1_PMBUS_HSC_R_SDA      B @T6G_MB_LIB.T6G(SCH_1):SMB_SML1_PMBUS_HSC_R_SDA

Q_RES_0402LF-33.2,1%,1/16W,CHIP,CS03322FB03  I37  R3909
   1 SMB_SML1_PMBUS_HSC_SCL      A @T6G_MB_LIB.T6G(SCH_1):SMB_SML1_PMBUS_HSC_SCL
   2 SMB_SML1_PMBUS_HSC_L_SCL      B @T6G_MB_LIB.T6G(SCH_1):SMB_SML1_PMBUS_HSC_L_SCL

Q_RES_0402LF-0,5%,1/16W,CHIP,CS00002JB13  I39  PR2149
   1 HSC_VDD_R      A @T6G_MB_LIB.T6G(SCH_1):HSC_VDD_R
   2 HSC_VDD      B @T6G_MB_LIB.T6G(SCH_1):HSC_VDD

Q_CAP_C0402-1UF,25V,10%,X6S,CH5104KEB02  I46  PC2188
   1 P12V_PSU      A @T6G_MB_LIB.T6G(SCH_1):P12V_PSU
   2    GND      B @T6G_MB_LIB.T6G(SCH_1):GND

Q_RES_0402LF-4.99K,0.1%,1/16W,CHIP,CS24992BB04  I47  PR3927
   1 HSC_VSENSE      A @T6G_MB_LIB.T6G(SCH_1):HSC_VSENSE
   2 AGND_HSC      B @T6G_MB_LIB.T6G(SCH_1):AGND_HSC

Q_RES_0402LF-75K,0.1%,1/16W,CHIP,CS37502BB01  I48  PR3926
   1 P12V_PSU      A @T6G_MB_LIB.T6G(SCH_1):P12V_PSU
   2 HSC_VSENSE      B @T6G_MB_LIB.T6G(SCH_1):HSC_VSENSE

Q_CAP_C0402-1UF,25V,10%,X6S,CH5104KEB02  I50  PC2103
   1 HSC_VDD18      A @T6G_MB_LIB.T6G(SCH_1):HSC_VDD18
   2 AGND_HSC      B @T6G_MB_LIB.T6G(SCH_1):AGND_HSC

Q_RES_0402LF-0,5%,1/16W,CHIP,CS00002JB13  I51  PR3928
   1 HSC_ON      A @T6G_MB_LIB.T6G(SCH_1):HSC_ON
   2 HSC_ON_R      B @T6G_MB_LIB.T6G(SCH_1):HSC_ON_R

Q_RES_0402LF-0,5%,1/16W,CHIP,CS00002JB13  I52  PR3930
   1 AGND_HSC      A @T6G_MB_LIB.T6G(SCH_1):AGND_HSC
   2 HSC_ADDR      B @T6G_MB_LIB.T6G(SCH_1):HSC_ADDR

Q_RES_0402LF-1K,1%,1/16W,EMPTY,CS21002FB06  I53  PR3929
   1 HSC_ADDR      A @T6G_MB_LIB.T6G(SCH_1):HSC_ADDR
   2 HSC_VDD18      B @T6G_MB_LIB.T6G(SCH_1):HSC_VDD18

Q_RES_0402LF-0,5%,1/16W,CHIP,CS00002JB13  I54  R2586
   1 HSC_EN      A @T6G_MB_LIB.T6G(SCH_1):HSC_EN
   2 HSC_EN_R      B @T6G_MB_LIB.T6G(SCH_1):HSC_EN_R

Q_RES_0402LF-10K,1%,1/16W,CHIP,CS31002FB08  I56  PR2106
   1 HSC_VDD      A @T6G_MB_LIB.T6G(SCH_1):HSC_VDD
   2 HSC_VIN_UVW_N      B @T6G_MB_LIB.T6G(SCH_1):HSC_VIN_UVW_N

MP5990GMA1111Z-MP5990GMA-1111-Z,SMLF,IC,AR0F0TP4023  I58  PU289
  29 P12V_AUX  VOUT3 @T6G_MB_LIB.T6G(SCH_1):P12V_AUX
  28 P12V_AUX  VOUT2 @T6G_MB_LIB.T6G(SCH_1):P12V_AUX
  27 P12V_AUX  VOUT1 @T6G_MB_LIB.T6G(SCH_1):P12V_AUX
   2 P12V_PSU   VIN2 @T6G_MB_LIB.T6G(SCH_1):P12V_PSU
  26 HSC_EN_R     EN @T6G_MB_LIB.T6G(SCH_1):HSC_EN_R
   3 P12V_PSU   VIN3 @T6G_MB_LIB.T6G(SCH_1):P12V_PSU
   4 P12V_PSU   VIN4 @T6G_MB_LIB.T6G(SCH_1):P12V_PSU
  18 AGND_HSC   GND1 @T6G_MB_LIB.T6G(SCH_1):AGND_HSC
  12 SMB_SML1_PMBUS_HSC_R_SDA    SDA @T6G_MB_LIB.T6G(SCH_1):SMB_SML1_PMBUS_HSC_R_SDA
  14 HSC_VIN_UVW_N VIN_UVW# @T6G_MB_LIB.T6G(SCH_1):HSC_VIN_UVW_N
  11 SMB_SML1_PMBUS_HSC_L_SCL    SCL @T6G_MB_LIB.T6G(SCH_1):SMB_SML1_PMBUS_HSC_L_SCL
  37 HSC_D_OC_R   D_OC @T6G_MB_LIB.T6G(SCH_1):HSC_D_OC_R
  31 P12V_AUX  VOUT5 @T6G_MB_LIB.T6G(SCH_1):P12V_AUX
  35 P12V_AUX  VOUT9 @T6G_MB_LIB.T6G(SCH_1):P12V_AUX
  10 IRQ_SML1_PMBUS_ALERT   ALT# @T6G_MB_LIB.T6G(SCH_1):IRQ_SML1_PMBUS_ALERT
  39 HSC_FAULT    GOK @T6G_MB_LIB.T6G(SCH_1):HSC_FAULT
   7 P12V_PSU   VIN7 @T6G_MB_LIB.T6G(SCH_1):P12V_PSU
  33 P12V_AUX  VOUT7 @T6G_MB_LIB.T6G(SCH_1):P12V_AUX
  41 HSC_MODE   MODE @T6G_MB_LIB.T6G(SCH_1):HSC_MODE
   8 P12V_PSU   VIN8 @T6G_MB_LIB.T6G(SCH_1):P12V_PSU
  13 MB0_P12V_STBY_PWRGD PG||OCW# @T6G_MB_LIB.T6G(SCH_1):MB0_P12V_STBY_PWRGD
  34 P12V_AUX  VOUT8 @T6G_MB_LIB.T6G(SCH_1):P12V_AUX
  38 HSC_ON_R     ON @T6G_MB_LIB.T6G(SCH_1):HSC_ON_R
   5 P12V_PSU   VIN5 @T6G_MB_LIB.T6G(SCH_1):P12V_PSU
   6 P12V_PSU   VIN6 @T6G_MB_LIB.T6G(SCH_1):P12V_PSU
  15 HSC_VTEMP  VTEMP @T6G_MB_LIB.T6G(SCH_1):HSC_VTEMP
  22 HSC_OCREF  OCREF @T6G_MB_LIB.T6G(SCH_1):HSC_OCREF
  25 HSC_SCREF SCREF_OCWREF @T6G_MB_LIB.T6G(SCH_1):HSC_SCREF
  16 HSC_SS     SS @T6G_MB_LIB.T6G(SCH_1):HSC_SS
  32 P12V_AUX  VOUT6 @T6G_MB_LIB.T6G(SCH_1):P12V_AUX
  21 HSC_IMON   IMON @T6G_MB_LIB.T6G(SCH_1):HSC_IMON
  20 HSC_CS     CS @T6G_MB_LIB.T6G(SCH_1):HSC_CS
  42 P12V_PSU   VIN9 @T6G_MB_LIB.T6G(SCH_1):P12V_PSU
  36 P12V_AUX VOUT10 @T6G_MB_LIB.T6G(SCH_1):P12V_AUX
  24 HSC_VOSEN  VOSEN @T6G_MB_LIB.T6G(SCH_1):HSC_VOSEN
  30 P12V_AUX  VOUT4 @T6G_MB_LIB.T6G(SCH_1):P12V_AUX
   1 P12V_PSU   VIN1 @T6G_MB_LIB.T6G(SCH_1):P12V_PSU
  44 AGND_HSC   GND2 @T6G_MB_LIB.T6G(SCH_1):AGND_HSC
  40 HSC_FLT_TYPE FLT_TYPE @T6G_MB_LIB.T6G(SCH_1):HSC_FLT_TYPE
  43 P12V_PSU  VIN10 @T6G_MB_LIB.T6G(SCH_1):P12V_PSU
   9 HSC_VSENSE VINSEN @T6G_MB_LIB.T6G(SCH_1):HSC_VSENSE
  17 HSC_VDD_R VDD33_1 @T6G_MB_LIB.T6G(SCH_1):HSC_VDD_R
  45 HSC_VDD_R VDD33_2 @T6G_MB_LIB.T6G(SCH_1):HSC_VDD_R
  19 HSC_VDD18  VDD18 @T6G_MB_LIB.T6G(SCH_1):HSC_VDD18
  23 HSC_ADDR   ADDR @T6G_MB_LIB.T6G(SCH_1):HSC_ADDR

Q_CAP_C0402-0.01UF,50V,10%,X7R,CH31006KB18  I59  PC2189
   1 HSC_VSENSE      A @T6G_MB_LIB.T6G(SCH_1):HSC_VSENSE
   2 AGND_HSC      B @T6G_MB_LIB.T6G(SCH_1):AGND_HSC

Q_RES_0402LF-16.9K,1%,1/16W,CHIP,CS31692FB03  I63  R3933
   1 P12V_AUX      A @T6G_MB_LIB.T6G(SCH_1):P12V_AUX
   2 MB0_P12V_STBY_PWRGD      B @T6G_MB_LIB.T6G(SCH_1):MB0_P12V_STBY_PWRGD

Q_RES_0402LF-2K,0.1%,1/16W,CHIP,CS22002BB07  I65  PR1131
   1 HSC_CS      A @T6G_MB_LIB.T6G(SCH_1):HSC_CS
   2 AGND_HSC      B @T6G_MB_LIB.T6G(SCH_1):AGND_HSC

Q_RES_0402LF-4.99K,0.1%,1/16W,CHIP,CS24992BB04  I70  PR3932
   1 HSC_VOSEN      A @T6G_MB_LIB.T6G(SCH_1):HSC_VOSEN
   2 AGND_HSC      B @T6G_MB_LIB.T6G(SCH_1):AGND_HSC

Q_RES_0402LF-75K,0.1%,1/16W,CHIP,CS37502BB01  I71  PR3931
   1 P12V_AUX      A @T6G_MB_LIB.T6G(SCH_1):P12V_AUX
   2 HSC_VOSEN      B @T6G_MB_LIB.T6G(SCH_1):HSC_VOSEN

Q_CAP_C0402-0.01UF,50V,10%,X7R,CH31006KB18  I72  PC2190
   1 HSC_VOSEN      A @T6G_MB_LIB.T6G(SCH_1):HSC_VOSEN
   2 AGND_HSC      B @T6G_MB_LIB.T6G(SCH_1):AGND_HSC

Q_CAP_0402-0.068UF,16V,10%,X7R,CH3683K1B09  I75  PC2191
   1 HSC_SS      A @T6G_MB_LIB.T6G(SCH_1):HSC_SS
   2 AGND_HSC      B @T6G_MB_LIB.T6G(SCH_1):AGND_HSC

Q_CAP_C0402-0.001UF,50V,10%,X7R,CH30106KB19  I78  PC2192
   1 HSC_VTEMP      A @T6G_MB_LIB.T6G(SCH_1):HSC_VTEMP
   2 AGND_HSC      B @T6G_MB_LIB.T6G(SCH_1):AGND_HSC

Q_RES_0402LF-22,1%,1/16W,CHIP,CS02202FB02  I79  R2588
   1 HSC_FAULT      A @T6G_MB_LIB.T6G(SCH_1):HSC_FAULT
   2 IRQ_HSC_FAULT_N      B @T6G_MB_LIB.T6G(SCH_1):IRQ_HSC_FAULT_N

Q_RES_0402LF-22,1%,1/16W,CHIP,CS02202FB02  I80  R3934
   1 HSC_D_OC_R      A @T6G_MB_LIB.T6G(SCH_1):HSC_D_OC_R
   2 HSC_D_OC      B @T6G_MB_LIB.T6G(SCH_1):HSC_D_OC

Q_RES_0402LF-10K,1%,1/16W,CHIP,CS31002FB08  I81  PR3935
   1 HSC_VTEMP      A @T6G_MB_LIB.T6G(SCH_1):HSC_VTEMP
   2 AGND_HSC      B @T6G_MB_LIB.T6G(SCH_1):AGND_HSC

Q_CAP_C0402-0.047UF,25V,10%,X7R,CH3474K1B04  I84  PC2193
   1 HSC_IMON      A @T6G_MB_LIB.T6G(SCH_1):HSC_IMON
   2 AGND_HSC      B @T6G_MB_LIB.T6G(SCH_1):AGND_HSC

Q_RES_0402LF-120K,1%,1/16W,CHIP,CS41202FB05  I85  PR3937
   1 HSC_MODE      A @T6G_MB_LIB.T6G(SCH_1):HSC_MODE
   2 AGND_HSC      B @T6G_MB_LIB.T6G(SCH_1):AGND_HSC

Q_RES_0402LF-2K,0.1%,1/16W,CHIP,CS22002BB07  I86  PR1133
   1 HSC_IMON      A @T6G_MB_LIB.T6G(SCH_1):HSC_IMON
   2 AGND_HSC      B @T6G_MB_LIB.T6G(SCH_1):AGND_HSC

SS15P3SM386A-SS15P3S-M3/86A,SMLF,IC,BC015P3SZ00  I89  PD111
   1    GND ANODE_1 @T6G_MB_LIB.T6G(SCH_1):GND
   K P12V_AUX CATHODE @T6G_MB_LIB.T6G(SCH_1):P12V_AUX
   2    GND ANODE_2 @T6G_MB_LIB.T6G(SCH_1):GND

Q_RES_0402LF-4.7K,1%,1/16W,CHIP,CS24702FB06  I91  R3936
   1 HSC_VDD      A @T6G_MB_LIB.T6G(SCH_1):HSC_VDD
   2 HSC_D_OC      B @T6G_MB_LIB.T6G(SCH_1):HSC_D_OC

Q_RES_0402LF-1K,1%,1/16W,CHIP,CS21002FB06  I99  R2587
   1 IRQ_HSC_FAULT_N      A @T6G_MB_LIB.T6G(SCH_1):IRQ_HSC_FAULT_N
   2 HSC_VDD      B @T6G_MB_LIB.T6G(SCH_1):HSC_VDD


DRAWING: @T6G_MB_LIB.T6G(SCH_1):PAGE372 

ZENER_AC-5.0SMDJ14A,SMLF,IC,BC0MDJ14000  I1  PD15
   A    GND      A @T6G_MB_LIB.T6G(SCH_1):GND
   C P12V_PSU_FUSE      C @T6G_MB_LIB.T6G(SCH_1):P12V_PSU_FUSE

ZENER_AC-5.0SMDJ14A,SMLF,IC,BC0MDJ14000  I3  PD13
   A    GND      A @T6G_MB_LIB.T6G(SCH_1):GND
   C P12V_PSU_FUSE      C @T6G_MB_LIB.T6G(SCH_1):P12V_PSU_FUSE

Q_FUSE_SMLF-20A/125V,IC,DKK00XFU000  I6  FS1
   1 P12V_PSU      1 @T6G_MB_LIB.T6G(SCH_1):P12V_PSU
   2 P12V_PSU_FUSE      2 @T6G_MB_LIB.T6G(SCH_1):P12V_PSU_FUSE

Q_CAP_0402-0.1UF,25V,10%,X7R,CH4104K1B00  I9  C1797
   1 PDB_PRSNT_R_N      A @T6G_MB_LIB.T6G(SCH_1):PDB_PRSNT_R_N
   2    GND      B @T6G_MB_LIB.T6G(SCH_1):GND

Q_RES_0402LF-33K,1%,1/16W,CHIP,CS33302FB00  I10  R3907
   1 PDB_PRSNT_R_N      A @T6G_MB_LIB.T6G(SCH_1):PDB_PRSNT_R_N
   2    GND      B @T6G_MB_LIB.T6G(SCH_1):GND

MOSFET_NCH_GDS_ESD_PROTECTED-2N7002K,SMLF,IC,BAM70A  I11  U290
   D HSC_EN      D @T6G_MB_LIB.T6G(SCH_1):HSC_EN
   G PDB_PRSNT_R_N      G @T6G_MB_LIB.T6G(SCH_1):PDB_PRSNT_R_N
   S    GND      S @T6G_MB_LIB.T6G(SCH_1):GND

Q_RES_0402LF-31.6K,1%,1/16W,CHIP,CS33162FB02  I13  R2585
   1 HSC_EN      A @T6G_MB_LIB.T6G(SCH_1):HSC_EN
   2    GND      B @T6G_MB_LIB.T6G(SCH_1):GND

Q_RES_0402LF-63.4K,1%,1/16W,CHIP,CS36342FB04  I16  R3923
   1 P12V_PSU_FUSE      A @T6G_MB_LIB.T6G(SCH_1):P12V_PSU_FUSE
   2 PDB_PRSNT_R_N      B @T6G_MB_LIB.T6G(SCH_1):PDB_PRSNT_R_N

CONN3_210HP1030BR1-CONN3_210-HP1-030BR1,THLF,IO,DFA  I18  JP4003
   3    GND      3 @T6G_MB_LIB.T6G(SCH_1):GND
   2 PDB_PRSNT_R_N      2 @T6G_MB_LIB.T6G(SCH_1):PDB_PRSNT_R_N
   1     NC      1     NC

Q_RES_0402LF-82K,1%,1/16W,CHIP,CS38202FB01  I19  R4901
   1 P12V_PSU_FUSE      A @T6G_MB_LIB.T6G(SCH_1):P12V_PSU_FUSE
   2 HSC_EN      B @T6G_MB_LIB.T6G(SCH_1):HSC_EN

Q_CAP_C0402-100NF,50V,10%,X7R,CH4106K1B01  I22  C2179
   1 HSC_EN      A @T6G_MB_LIB.T6G(SCH_1):HSC_EN
   2    GND      B @T6G_MB_LIB.T6G(SCH_1):GND

Q_RES_0402LF-0,5%,1/16W,CHIP,CS00002JB13  I27  PR3002
   1    GND      A @T6G_MB_LIB.T6G(SCH_1):GND
   2 AGND_HSC      B @T6G_MB_LIB.T6G(SCH_1):AGND_HSC

Q_RES_0402LF-10K,1%,1/16W,EMPTY,CS31002FB08  I29  R2227
   1 A_P12V_STBY_ADR_TRIGGER      A @T6G_MB_LIB.T6G(SCH_1):A_P12V_STBY_ADR_TRIGGER
   2    GND      B @T6G_MB_LIB.T6G(SCH_1):GND

Q_RES_0402LF-267K,1%,1/16W,EMPTY,CS42672FB03  I30  R2219
   1 P12V_AUX      A @T6G_MB_LIB.T6G(SCH_1):P12V_AUX
   2 A_P12V_STBY_ADR_TRIGGER      B @T6G_MB_LIB.T6G(SCH_1):A_P12V_STBY_ADR_TRIGGER

Q_RES_0402LF-1K,1%,1/16W,EMPTY,CS21002FB06  I33  R2222
   1 A_P12V_STBY_FP_TRIGGER      A @T6G_MB_LIB.T6G(SCH_1):A_P12V_STBY_FP_TRIGGER
   2    GND      B @T6G_MB_LIB.T6G(SCH_1):GND

Q_RES_0402LF-26.7K,1%,1/16W,EMPTY,CS32672FB03  I35  R2221
   1 P12V_AUX      A @T6G_MB_LIB.T6G(SCH_1):P12V_AUX
   2 A_P12V_STBY_FP_TRIGGER      B @T6G_MB_LIB.T6G(SCH_1):A_P12V_STBY_FP_TRIGGER

MOSFET_N_SMLF-BSS138K,BSS138K,EMPTY,BAM138K0000  I42  U325
   G A_P12V_STBY_FPH_GATE   GATE @T6G_MB_LIB.T6G(SCH_1):A_P12V_STBY_FPH_GATE
   D IRQ_UV_DETECT_N  DRAIN @T6G_MB_LIB.T6G(SCH_1):IRQ_UV_DETECT_N
   S    GND SOURCE @T6G_MB_LIB.T6G(SCH_1):GND

Q_RES_0402LF-10K,1%,1/16W,EMPTY,CS31002FB08  I43  R2230
   1 P3V3_AUX      A @T6G_MB_LIB.T6G(SCH_1):P3V3_AUX
   2 A_P12V_STBY_FPH_GATE      B @T6G_MB_LIB.T6G(SCH_1):A_P12V_STBY_FPH_GATE

Q_RES_0402LF-1K,1%,1/16W,EMPTY,CS21002FB06  I45  R2233
   1 P3V3_AUX      A @T6G_MB_LIB.T6G(SCH_1):P3V3_AUX
   2 FM_UV_ADR_TRIGGER_N      B @T6G_MB_LIB.T6G(SCH_1):FM_UV_ADR_TRIGGER_N

Q_RES_0402LF-1K,1%,1/16W,EMPTY,CS21002FB06  I46  R4620
   1 P3V3_AUX      A @T6G_MB_LIB.T6G(SCH_1):P3V3_AUX
   2 IRQ_UV_DETECT_N      B @T6G_MB_LIB.T6G(SCH_1):IRQ_UV_DETECT_N

LT6700CS61TRPBF-LT6700CS6-1#TRPBF,SMLF,EMPTY,AL006A  I49  U206
   5 U206_VS     VS @T6G_MB_LIB.T6G(SCH_1):U206_VS
   4 A_P12V_STBY_FP_TRIGGER   INB- @T6G_MB_LIB.T6G(SCH_1):A_P12V_STBY_FP_TRIGGER
   2    GND    GND @T6G_MB_LIB.T6G(SCH_1):GND
   1 FM_UV_ADR_TRIGGER_N   OUTA @T6G_MB_LIB.T6G(SCH_1):FM_UV_ADR_TRIGGER_N
   3 A_P12V_STBY_ADR_TRIGGER   INA+ @T6G_MB_LIB.T6G(SCH_1):A_P12V_STBY_ADR_TRIGGER
   6 A_P12V_STBY_FPH_GATE   OUTB @T6G_MB_LIB.T6G(SCH_1):A_P12V_STBY_FPH_GATE

LM4040AIM3X25NOPB-LM4040AIM3X-2.5/NOPB,SMLF,IC,AL4A  I51  U8007
   1 UV_ADR_P2V5_COMP     1+ @T6G_MB_LIB.T6G(SCH_1):UV_ADR_P2V5_COMP
   2    GND     2- @T6G_MB_LIB.T6G(SCH_1):GND
   3     NC      3     NC

Q_RES_0402LF-10K,1%,1/16W,CHIP,CS31002FB08  I52  R8113
   1 P3V3_AUX      A @T6G_MB_LIB.T6G(SCH_1):P3V3_AUX
   2 UV_ADR_P2V5_COMP      B @T6G_MB_LIB.T6G(SCH_1):UV_ADR_P2V5_COMP

Q_RES_0402LF-5.11K,1%,1/16W,CHIP,CS25112FB04  I55  R8115
   1 P12V_AUX_UV_ADR_TRIGGER      A @T6G_MB_LIB.T6G(SCH_1):P12V_AUX_UV_ADR_TRIGGER
   2    GND      B @T6G_MB_LIB.T6G(SCH_1):GND

Q_RES_0402LF-17.8K,1%,1/16W,CHIP,CS31782FB04  I56  R8114
   1 P12V_AUX      A @T6G_MB_LIB.T6G(SCH_1):P12V_AUX
   2 P12V_AUX_UV_ADR_TRIGGER      B @T6G_MB_LIB.T6G(SCH_1):P12V_AUX_UV_ADR_TRIGGER

Q_CAP_C0402-100NF,50V,10%,EMPTY,CH4106K1B01  I59  C8017
   1 UV_ADR_P2V5_COMP      A @T6G_MB_LIB.T6G(SCH_1):UV_ADR_P2V5_COMP
   2    GND      B @T6G_MB_LIB.T6G(SCH_1):GND

Q_CAP_C0402-100NF,50V,10%,EMPTY,CH4106K1B01  I61  C8018
   1 P12V_AUX_UV_ADR_TRIGGER      A @T6G_MB_LIB.T6G(SCH_1):P12V_AUX_UV_ADR_TRIGGER
   2    GND      B @T6G_MB_LIB.T6G(SCH_1):GND

Q_RES_0402LF-1M,1%,1/16W,CHIP,CS51002FB05  I63  R8117
   1 P12V_AUX_UV_ADR_TRIGGER      A @T6G_MB_LIB.T6G(SCH_1):P12V_AUX_UV_ADR_TRIGGER
   2 FM_UV_ADR_TRIGGER_N_R2      B @T6G_MB_LIB.T6G(SCH_1):FM_UV_ADR_TRIGGER_N_R2

Q_CAP_C0402-100NF,50V,10%,X7R,CH4106K1B01  I66  C8019
   1 P12V_AUX      A @T6G_MB_LIB.T6G(SCH_1):P12V_AUX
   2    GND      B @T6G_MB_LIB.T6G(SCH_1):GND

Q_RES_0402LF-33.2,1%,1/16W,CHIP,CS03322FB03  I67  R8118
   1 FM_UV_ADR_TRIGGER_N_R2      A @T6G_MB_LIB.T6G(SCH_1):FM_UV_ADR_TRIGGER_N_R2
   2 FM_UV_ADR_TRIGGER_N      B @T6G_MB_LIB.T6G(SCH_1):FM_UV_ADR_TRIGGER_N

Q_RES_0402LF-1K,1%,1/16W,CHIP,CS21002FB06  I69  R8119
   1 P3V3_AUX      A @T6G_MB_LIB.T6G(SCH_1):P3V3_AUX
   2 FM_UV_ADR_TRIGGER_N      B @T6G_MB_LIB.T6G(SCH_1):FM_UV_ADR_TRIGGER_N

AP331AWG7-AP331AWG-7,SMLF,IC,AL000331011  I71  U8008
   3 P12V_AUX_UV_ADR_TRIGGER    IN+ @T6G_MB_LIB.T6G(SCH_1):P12V_AUX_UV_ADR_TRIGGER
   1 UV_ADR_P2V5_COMP    IN- @T6G_MB_LIB.T6G(SCH_1):UV_ADR_P2V5_COMP
   4 FM_UV_ADR_TRIGGER_N_R2 OUTPUT @T6G_MB_LIB.T6G(SCH_1):FM_UV_ADR_TRIGGER_N_R2
   5 P12V_AUX    VCC @T6G_MB_LIB.T6G(SCH_1):P12V_AUX
   2    GND    GND @T6G_MB_LIB.T6G(SCH_1):GND

Q_RES_0402LF-10K,1%,1/16W,CHIP,CS31002FB08  I72  R8120
   1 P3V3_AUX      A @T6G_MB_LIB.T6G(SCH_1):P3V3_AUX
   2 UV_P2V5_COMP      B @T6G_MB_LIB.T6G(SCH_1):UV_P2V5_COMP

Q_RES_0402LF-5.11K,1%,1/16W,CHIP,CS25112FB04  I75  R8122
   1 P12V_AUX_UV_TRIGGER      A @T6G_MB_LIB.T6G(SCH_1):P12V_AUX_UV_TRIGGER
   2    GND      B @T6G_MB_LIB.T6G(SCH_1):GND

Q_RES_0402LF-17.8K,1%,1/16W,CHIP,CS31782FB04  I76  R8121
   1 P12V_AUX      A @T6G_MB_LIB.T6G(SCH_1):P12V_AUX
   2 P12V_AUX_UV_TRIGGER      B @T6G_MB_LIB.T6G(SCH_1):P12V_AUX_UV_TRIGGER

Q_CAP_C0402-100NF,50V,10%,EMPTY,CH4106K1B01  I79  C8020
   1 UV_P2V5_COMP      A @T6G_MB_LIB.T6G(SCH_1):UV_P2V5_COMP
   2    GND      B @T6G_MB_LIB.T6G(SCH_1):GND

AP331AWG7-AP331AWG-7,SMLF,IC,AL000331011  I80  U8010
   3 P12V_AUX_UV_TRIGGER    IN+ @T6G_MB_LIB.T6G(SCH_1):P12V_AUX_UV_TRIGGER
   1 UV_P2V5_COMP    IN- @T6G_MB_LIB.T6G(SCH_1):UV_P2V5_COMP
   4 IRQ_UV_DETECT_R2_N OUTPUT @T6G_MB_LIB.T6G(SCH_1):IRQ_UV_DETECT_R2_N
   5 P12V_AUX    VCC @T6G_MB_LIB.T6G(SCH_1):P12V_AUX
   2    GND    GND @T6G_MB_LIB.T6G(SCH_1):GND

Q_RES_0402LF-1M,1%,1/16W,CHIP,CS51002FB05  I81  R8123
   1 P12V_AUX_UV_TRIGGER      A @T6G_MB_LIB.T6G(SCH_1):P12V_AUX_UV_TRIGGER
   2 IRQ_UV_DETECT_R2_N      B @T6G_MB_LIB.T6G(SCH_1):IRQ_UV_DETECT_R2_N

Q_CAP_C0402-100NF,50V,10%,X7R,CH4106K1B01  I84  C8022
   1 P12V_AUX      A @T6G_MB_LIB.T6G(SCH_1):P12V_AUX
   2    GND      B @T6G_MB_LIB.T6G(SCH_1):GND

Q_RES_0402LF-33.2,1%,1/16W,CHIP,CS03322FB03  I85  R8124
   1 IRQ_UV_DETECT_R2_N      A @T6G_MB_LIB.T6G(SCH_1):IRQ_UV_DETECT_R2_N
   2 IRQ_UV_DETECT_N      B @T6G_MB_LIB.T6G(SCH_1):IRQ_UV_DETECT_N

Q_CAP_C0402-100NF,50V,10%,EMPTY,CH4106K1B01  I92  C8021
   1 P12V_AUX_UV_TRIGGER      A @T6G_MB_LIB.T6G(SCH_1):P12V_AUX_UV_TRIGGER
   2    GND      B @T6G_MB_LIB.T6G(SCH_1):GND

LM4040AIM3X25NOPB-LM4040AIM3X-2.5/NOPB,SMLF,IC,AL4A  I93  U8009
   1 UV_P2V5_COMP     1+ @T6G_MB_LIB.T6G(SCH_1):UV_P2V5_COMP
   2    GND     2- @T6G_MB_LIB.T6G(SCH_1):GND
   3     NC      3     NC

Q_CAP_0402-0.1UF,25V,10%,EMPTY,CH4104K1B00  I96  C1561
   1 U206_VS      A @T6G_MB_LIB.T6G(SCH_1):U206_VS
   2    GND      B @T6G_MB_LIB.T6G(SCH_1):GND

Q_RES_0402LF-1K,1%,1/16W,EMPTY,CS21002FB06  I97  R9021
   1 P12V_AUX      A @T6G_MB_LIB.T6G(SCH_1):P12V_AUX
   2 U206_VS      B @T6G_MB_LIB.T6G(SCH_1):U206_VS

Q_CAP_C0402-1UF,25V,10%,EMPTY,CH5104KEB02  I99  C9004
   1 U206_VS      A @T6G_MB_LIB.T6G(SCH_1):U206_VS
   2    GND      B @T6G_MB_LIB.T6G(SCH_1):GND

CONN3_210HP1030BR1-CONN3_210-HP1-030BR1,THLF,IO,DFA  I103  JP10
   3    GND      3 @T6G_MB_LIB.T6G(SCH_1):GND
   2 SMB_SML1_PMBUS_HSC_R1_SDA      2 @T6G_MB_LIB.T6G(SCH_1):SMB_SML1_PMBUS_HSC_R1_SDA
   1 SMB_SML1_PMBUS_HSC_R1_SCL      1 @T6G_MB_LIB.T6G(SCH_1):SMB_SML1_PMBUS_HSC_R1_SCL

Q_RES_0402LF-1K,1%,1/16W,CHIP,CS21002FB06  I104  R8125
   1 P3V3_AUX      A @T6G_MB_LIB.T6G(SCH_1):P3V3_AUX
   2 IRQ_UV_DETECT_N      B @T6G_MB_LIB.T6G(SCH_1):IRQ_UV_DETECT_N


DRAWING: @T6G_MB_LIB.T6G(SCH_1):PAGE302 

Q_RES_0402LF-1,1%,1/16W,CHIP,CS-1002FB04  I5  PR2523
   1 P12V_HSC_SENSE2_P      A @T6G_MB_LIB.T6G(SCH_1):P12V_HSC_SENSE2_P
   2 P12V_HSC_SENSE2_R4_P      B @T6G_MB_LIB.T6G(SCH_1):P12V_HSC_SENSE2_R4_P

Q_RES_0402LF-1,1%,1/16W,CHIP,CS-1002FB04  I6  PR2521
   1 P12V_HSC_SENSE2_P      A @T6G_MB_LIB.T6G(SCH_1):P12V_HSC_SENSE2_P
   2 P12V_HSC_SENSE2_R2_P      B @T6G_MB_LIB.T6G(SCH_1):P12V_HSC_SENSE2_R2_P

Q_RES_0402LF-1,1%,1/16W,CHIP,CS-1002FB04  I7  PR2522
   1 P12V_HSC_SENSE2_P      A @T6G_MB_LIB.T6G(SCH_1):P12V_HSC_SENSE2_P
   2 P12V_HSC_SENSE2_R3_P      B @T6G_MB_LIB.T6G(SCH_1):P12V_HSC_SENSE2_R3_P

Q_RES_0402LF-1,1%,1/16W,CHIP,CS-1002FB04  I8  PR2520
   1 P12V_HSC_SENSE2_P      A @T6G_MB_LIB.T6G(SCH_1):P12V_HSC_SENSE2_P
   2 P12V_HSC_SENSE2_R1_P      B @T6G_MB_LIB.T6G(SCH_1):P12V_HSC_SENSE2_R1_P

Q_RES_0402LF-1,1%,1/16W,CHIP,CS-1002FB04  I15  PR2513
   1 P12V_HSC_ADC_P      A @T6G_MB_LIB.T6G(SCH_1):P12V_HSC_ADC_P
   2 P12V_HSC_SENSE2_R4_P      B @T6G_MB_LIB.T6G(SCH_1):P12V_HSC_SENSE2_R4_P

Q_RES_0402LF-1,1%,1/16W,CHIP,CS-1002FB04  I16  PR2512
   1 P12V_HSC_ADC_P      A @T6G_MB_LIB.T6G(SCH_1):P12V_HSC_ADC_P
   2 P12V_HSC_SENSE2_R3_P      B @T6G_MB_LIB.T6G(SCH_1):P12V_HSC_SENSE2_R3_P

Q_RES_0402LF-1,1%,1/16W,CHIP,CS-1002FB04  I17  PR2511
   1 P12V_HSC_ADC_P      A @T6G_MB_LIB.T6G(SCH_1):P12V_HSC_ADC_P
   2 P12V_HSC_SENSE2_R2_P      B @T6G_MB_LIB.T6G(SCH_1):P12V_HSC_SENSE2_R2_P

Q_RES_0402LF-1,1%,1/16W,CHIP,CS-1002FB04  I18  PR2510
   1 P12V_HSC_ADC_P      A @T6G_MB_LIB.T6G(SCH_1):P12V_HSC_ADC_P
   2 P12V_HSC_SENSE2_R1_P      B @T6G_MB_LIB.T6G(SCH_1):P12V_HSC_SENSE2_R1_P

Q_RES_0402LF-10,1%,1/16W,CHIP,CS01002FB07  I27  PR2528
   1 P12V_HSC_GATE_G1      A @T6G_MB_LIB.T6G(SCH_1):P12V_HSC_GATE_G1
   2 P12V_HSC_GATE2      B @T6G_MB_LIB.T6G(SCH_1):P12V_HSC_GATE2

Q_RES_0402LF-10,1%,1/16W,CHIP,CS01002FB07  I28  PR2529
   1 P12V_HSC_GATE_G2      A @T6G_MB_LIB.T6G(SCH_1):P12V_HSC_GATE_G2
   2 P12V_HSC_GATE2      B @T6G_MB_LIB.T6G(SCH_1):P12V_HSC_GATE2

MOSFET_NCH_1D3S-PSMNR58-30YLH,SMLF,IC,BAMNR580000  I29  PPQ5
   3 P12V_AUX      3 @T6G_MB_LIB.T6G(SCH_1):P12V_AUX
   5 P12V_MAIN_R      5 @T6G_MB_LIB.T6G(SCH_1):P12V_MAIN_R
   2 P12V_AUX      2 @T6G_MB_LIB.T6G(SCH_1):P12V_AUX
   4 P12V_HSC_GATE_G1      4 @T6G_MB_LIB.T6G(SCH_1):P12V_HSC_GATE_G1
   1 P12V_AUX      1 @T6G_MB_LIB.T6G(SCH_1):P12V_AUX

Q_RES_0402LF-10,1%,1/16W,CHIP,CS01002FB07  I45  PR2530
   1 P12V_HSC_GATE_G3      A @T6G_MB_LIB.T6G(SCH_1):P12V_HSC_GATE_G3
   2 P12V_HSC_GATE2      B @T6G_MB_LIB.T6G(SCH_1):P12V_HSC_GATE2

MOSFET_NCH_1D3S-PSMNR58-30YLH,SMLF,IC,BAMNR580000  I46  PPQ6
   3 P12V_AUX      3 @T6G_MB_LIB.T6G(SCH_1):P12V_AUX
   5 P12V_MAIN_R      5 @T6G_MB_LIB.T6G(SCH_1):P12V_MAIN_R
   2 P12V_AUX      2 @T6G_MB_LIB.T6G(SCH_1):P12V_AUX
   4 P12V_HSC_GATE_G2      4 @T6G_MB_LIB.T6G(SCH_1):P12V_HSC_GATE_G2
   1 P12V_AUX      1 @T6G_MB_LIB.T6G(SCH_1):P12V_AUX

Q_RES_0402LF-10,1%,1/16W,CHIP,CS01002FB07  I47  PR2531
   1 P12V_HSC_GATE_G4      A @T6G_MB_LIB.T6G(SCH_1):P12V_HSC_GATE_G4
   2 P12V_HSC_GATE2      B @T6G_MB_LIB.T6G(SCH_1):P12V_HSC_GATE2

Q_SP_RES4P-0.0003,1%,4W,SMLF,CHIP,SP_CS0000FFT09  I52  PR2534
  2B P12V_HSC_SENSE2_R4_N     2B @T6G_MB_LIB.T6G(SCH_1):P12V_HSC_SENSE2_R4_N
  1B P12V_HSC_SENSE2_R4_P     1B @T6G_MB_LIB.T6G(SCH_1):P12V_HSC_SENSE2_R4_P
  2A P12V_MAIN_R     2A @T6G_MB_LIB.T6G(SCH_1):P12V_MAIN_R
  1A P12V_PSU     1A @T6G_MB_LIB.T6G(SCH_1):P12V_PSU

Q_SP_RES4P-0.0003,1%,4W,SMLF,CHIP,SP_CS0000FFT09  I53  PR2533
  2B P12V_HSC_SENSE2_R3_N     2B @T6G_MB_LIB.T6G(SCH_1):P12V_HSC_SENSE2_R3_N
  1B P12V_HSC_SENSE2_R3_P     1B @T6G_MB_LIB.T6G(SCH_1):P12V_HSC_SENSE2_R3_P
  2A P12V_MAIN_R     2A @T6G_MB_LIB.T6G(SCH_1):P12V_MAIN_R
  1A P12V_PSU     1A @T6G_MB_LIB.T6G(SCH_1):P12V_PSU

Q_SP_RES4P-0.0003,1%,4W,SMLF,CHIP,SP_CS0000FFT09  I54  PR2532
  2B P12V_HSC_SENSE2_R2_N     2B @T6G_MB_LIB.T6G(SCH_1):P12V_HSC_SENSE2_R2_N
  1B P12V_HSC_SENSE2_R2_P     1B @T6G_MB_LIB.T6G(SCH_1):P12V_HSC_SENSE2_R2_P
  2A P12V_MAIN_R     2A @T6G_MB_LIB.T6G(SCH_1):P12V_MAIN_R
  1A P12V_PSU     1A @T6G_MB_LIB.T6G(SCH_1):P12V_PSU

Q_SP_RES4P-0.0003,1%,4W,SMLF,CHIP,SP_CS0000FFT09  I55  PR6001
  2B P12V_HSC_SENSE2_R1_N     2B @T6G_MB_LIB.T6G(SCH_1):P12V_HSC_SENSE2_R1_N
  1B P12V_HSC_SENSE2_R1_P     1B @T6G_MB_LIB.T6G(SCH_1):P12V_HSC_SENSE2_R1_P
  2A P12V_MAIN_R     2A @T6G_MB_LIB.T6G(SCH_1):P12V_MAIN_R
  1A P12V_PSU     1A @T6G_MB_LIB.T6G(SCH_1):P12V_PSU

Q_RES_0402LF-10,1%,1/16W,CHIP,CS01002FB07  I60  PR2535
   1 P12V_HSC_GATE_G5      A @T6G_MB_LIB.T6G(SCH_1):P12V_HSC_GATE_G5
   2 P12V_HSC_GATE2      B @T6G_MB_LIB.T6G(SCH_1):P12V_HSC_GATE2

MOSFET_NCH_1D3S-PSMNR58-30YLH,SMLF,IC,BAMNR580000  I61  PPQ1
   3 P12V_AUX      3 @T6G_MB_LIB.T6G(SCH_1):P12V_AUX
   5 P12V_MAIN_R      5 @T6G_MB_LIB.T6G(SCH_1):P12V_MAIN_R
   2 P12V_AUX      2 @T6G_MB_LIB.T6G(SCH_1):P12V_AUX
   4 P12V_HSC_GATE_G5      4 @T6G_MB_LIB.T6G(SCH_1):P12V_HSC_GATE_G5
   1 P12V_AUX      1 @T6G_MB_LIB.T6G(SCH_1):P12V_AUX

Q_RES_0402LF-10,1%,1/16W,CHIP,CS01002FB07  I62  PR2536
   1 P12V_HSC_GATE_G6      A @T6G_MB_LIB.T6G(SCH_1):P12V_HSC_GATE_G6
   2 P12V_HSC_GATE2      B @T6G_MB_LIB.T6G(SCH_1):P12V_HSC_GATE2

Q_CAP_C0402-33NF,25V,10%,EMPTY,CH3334K1B00  I63  PC1750
   1 P12V_AUX      A @T6G_MB_LIB.T6G(SCH_1):P12V_AUX
   2 P12V_HSC_GATE2      B @T6G_MB_LIB.T6G(SCH_1):P12V_HSC_GATE2

MOSFET_NCH_1D3S-PSMNR58-30YLH,SMLF,IC,BAMNR580000  I64  PPQ2
   3 P12V_AUX      3 @T6G_MB_LIB.T6G(SCH_1):P12V_AUX
   5 P12V_MAIN_R      5 @T6G_MB_LIB.T6G(SCH_1):P12V_MAIN_R
   2 P12V_AUX      2 @T6G_MB_LIB.T6G(SCH_1):P12V_AUX
   4 P12V_HSC_GATE_G6      4 @T6G_MB_LIB.T6G(SCH_1):P12V_HSC_GATE_G6
   1 P12V_AUX      1 @T6G_MB_LIB.T6G(SCH_1):P12V_AUX

Q_CAP_0402-1NF,50V,10%,EMPTY,CH21006KB16  I70  PC1751
   1 P12V_HSC_GATE_RC      A @T6G_MB_LIB.T6G(SCH_1):P12V_HSC_GATE_RC
   2 P12V_HSC_GATE2      B @T6G_MB_LIB.T6G(SCH_1):P12V_HSC_GATE2

Q_RES_0402LF-10,1%,1/16W,EMPTY,CS01002FB07  I71  PR2537
   1 P12V_AUX      A @T6G_MB_LIB.T6G(SCH_1):P12V_AUX
   2 P12V_HSC_GATE_RC      B @T6G_MB_LIB.T6G(SCH_1):P12V_HSC_GATE_RC

SS15P3SM386A-SS15P3S-M3/86A,SMLF,IC,BC015P3SZ00  I72  PD17
   1    GND ANODE_1 @T6G_MB_LIB.T6G(SCH_1):GND
   K P12V_AUX CATHODE @T6G_MB_LIB.T6G(SCH_1):P12V_AUX
   2    GND ANODE_2 @T6G_MB_LIB.T6G(SCH_1):GND

Q_RES_0402LF-10,1%,1/16W,CHIP,CS01002FB07  I74  PR2538
   1 MB0_CM_GATE_G0      A @T6G_MB_LIB.T6G(SCH_1):MB0_CM_GATE_G0
   2 P12V_HSC_GATE1      B @T6G_MB_LIB.T6G(SCH_1):P12V_HSC_GATE1

MOSFET_NCH_1D3S-PSMNR58-30YLH,SMLF,IC,BAMNR580000  I75  PPQ9
   3 P12V_AUX      3 @T6G_MB_LIB.T6G(SCH_1):P12V_AUX
   5 P12V_MAIN_R_0      5 @T6G_MB_LIB.T6G(SCH_1):P12V_MAIN_R_0
   2 P12V_AUX      2 @T6G_MB_LIB.T6G(SCH_1):P12V_AUX
   4 MB0_CM_GATE_G0      4 @T6G_MB_LIB.T6G(SCH_1):MB0_CM_GATE_G0
   1 P12V_AUX      1 @T6G_MB_LIB.T6G(SCH_1):P12V_AUX

MOSFET_NCH_1D3S-PSMNR58-30YLH,SMLF,IC,BAMNR580000  I79  PPQ8
   3 P12V_AUX      3 @T6G_MB_LIB.T6G(SCH_1):P12V_AUX
   5 P12V_MAIN_R      5 @T6G_MB_LIB.T6G(SCH_1):P12V_MAIN_R
   2 P12V_AUX      2 @T6G_MB_LIB.T6G(SCH_1):P12V_AUX
   4 P12V_HSC_GATE_G4      4 @T6G_MB_LIB.T6G(SCH_1):P12V_HSC_GATE_G4
   1 P12V_AUX      1 @T6G_MB_LIB.T6G(SCH_1):P12V_AUX

MOSFET_NCH_1D3S-PSMNR58-30YLH,SMLF,IC,BAMNR580000  I80  PPQ7
   3 P12V_AUX      3 @T6G_MB_LIB.T6G(SCH_1):P12V_AUX
   5 P12V_MAIN_R      5 @T6G_MB_LIB.T6G(SCH_1):P12V_MAIN_R
   2 P12V_AUX      2 @T6G_MB_LIB.T6G(SCH_1):P12V_AUX
   4 P12V_HSC_GATE_G3      4 @T6G_MB_LIB.T6G(SCH_1):P12V_HSC_GATE_G3
   1 P12V_AUX      1 @T6G_MB_LIB.T6G(SCH_1):P12V_AUX

Q_SP_RES4P-0.003,1%,2W,SMLF,CHIP,SP_CS+003AFR00_1  I81  PR6002
  2B P12V_HSC_SENSE1_N     2B @T6G_MB_LIB.T6G(SCH_1):P12V_HSC_SENSE1_N
  1B P12V_HSC_SENSE1_P     1B @T6G_MB_LIB.T6G(SCH_1):P12V_HSC_SENSE1_P
  2A P12V_MAIN_R_0     2A @T6G_MB_LIB.T6G(SCH_1):P12V_MAIN_R_0
  1A P12V_PSU     1A @T6G_MB_LIB.T6G(SCH_1):P12V_PSU

Q_RES_0402LF-10,1%,1/16W,CHIP,CS01002FB07  I82  PR2514
   1 P12V_HSC_ADC_P      A @T6G_MB_LIB.T6G(SCH_1):P12V_HSC_ADC_P
   2 P12V_HSC_SENSE1_P      B @T6G_MB_LIB.T6G(SCH_1):P12V_HSC_SENSE1_P

Q_RES_0402LF-10,1%,1/16W,CHIP,CS01002FB07  I83  PR2515
   1 P12V_HSC_ADC_N      A @T6G_MB_LIB.T6G(SCH_1):P12V_HSC_ADC_N
   2 P12V_HSC_SENSE2_R1_N      B @T6G_MB_LIB.T6G(SCH_1):P12V_HSC_SENSE2_R1_N

Q_RES_0402LF-10,1%,1/16W,CHIP,CS01002FB07  I84  PR2516
   1 P12V_HSC_ADC_N      A @T6G_MB_LIB.T6G(SCH_1):P12V_HSC_ADC_N
   2 P12V_HSC_SENSE2_R2_N      B @T6G_MB_LIB.T6G(SCH_1):P12V_HSC_SENSE2_R2_N

Q_RES_0402LF-10,1%,1/16W,CHIP,CS01002FB07  I85  PR2517
   1 P12V_HSC_ADC_N      A @T6G_MB_LIB.T6G(SCH_1):P12V_HSC_ADC_N
   2 P12V_HSC_SENSE2_R3_N      B @T6G_MB_LIB.T6G(SCH_1):P12V_HSC_SENSE2_R3_N

Q_RES_0402LF-10,1%,1/16W,CHIP,CS01002FB07  I86  PR2518
   1 P12V_HSC_ADC_N      A @T6G_MB_LIB.T6G(SCH_1):P12V_HSC_ADC_N
   2 P12V_HSC_SENSE2_R4_N      B @T6G_MB_LIB.T6G(SCH_1):P12V_HSC_SENSE2_R4_N

Q_RES_0402LF-100,1%,1/16W,CHIP,CS11002FB07  I87  PR2519
   1 P12V_HSC_ADC_N      A @T6G_MB_LIB.T6G(SCH_1):P12V_HSC_ADC_N
   2 P12V_HSC_SENSE1_N      B @T6G_MB_LIB.T6G(SCH_1):P12V_HSC_SENSE1_N

Q_RES_0402LF-10,1%,1/16W,CHIP,CS01002FB07  I88  PR2524
   1 P12V_HSC_SENSE2_N      A @T6G_MB_LIB.T6G(SCH_1):P12V_HSC_SENSE2_N
   2 P12V_HSC_SENSE2_R1_N      B @T6G_MB_LIB.T6G(SCH_1):P12V_HSC_SENSE2_R1_N

Q_RES_0402LF-10,1%,1/16W,CHIP,CS01002FB07  I89  PR2525
   1 P12V_HSC_SENSE2_N      A @T6G_MB_LIB.T6G(SCH_1):P12V_HSC_SENSE2_N
   2 P12V_HSC_SENSE2_R2_N      B @T6G_MB_LIB.T6G(SCH_1):P12V_HSC_SENSE2_R2_N

Q_RES_0402LF-10,1%,1/16W,CHIP,CS01002FB07  I90  PR2526
   1 P12V_HSC_SENSE2_N      A @T6G_MB_LIB.T6G(SCH_1):P12V_HSC_SENSE2_N
   2 P12V_HSC_SENSE2_R3_N      B @T6G_MB_LIB.T6G(SCH_1):P12V_HSC_SENSE2_R3_N

Q_RES_0402LF-10,1%,1/16W,CHIP,CS01002FB07  I91  PR2527
   1 P12V_HSC_SENSE2_N      A @T6G_MB_LIB.T6G(SCH_1):P12V_HSC_SENSE2_N
   2 P12V_HSC_SENSE2_R4_N      B @T6G_MB_LIB.T6G(SCH_1):P12V_HSC_SENSE2_R4_N


DRAWING: @T6G_MB_LIB.T6G(SCH_1):PAGE371 

METR3904G-METR3904-G,SMLF,IC,BA039040020  I1  Q6001
   B P12V_HSC_TEMP_R      1 @T6G_MB_LIB.T6G(SCH_1):P12V_HSC_TEMP_R
   E P12V_HSC_TEMP_E      2 @T6G_MB_LIB.T6G(SCH_1):P12V_HSC_TEMP_E
   C P12V_HSC_TEMP_R      3 @T6G_MB_LIB.T6G(SCH_1):P12V_HSC_TEMP_R

Q_RES_0402LF-49.9,1%,1/16W,CHIP,CS04992FB07  I2  R2624
   1 P12V_HSC_TEMP_E      A @T6G_MB_LIB.T6G(SCH_1):P12V_HSC_TEMP_E
   2 P12V_HSC_TEMP_D-      B @T6G_MB_LIB.T6G(SCH_1):P12V_HSC_TEMP_D-

Q_RES_0402LF-49.9,1%,1/16W,CHIP,CS04992FB07  I3  R2625
   1 P12V_HSC_TEMP_R      A @T6G_MB_LIB.T6G(SCH_1):P12V_HSC_TEMP_R
   2 P12V_HSC_TEMP_D+      B @T6G_MB_LIB.T6G(SCH_1):P12V_HSC_TEMP_D+

Q_CAP_0603-1000PF,50V,10%,X7R,TMP_QCH21006K917  I4  C1786
   1 P12V_HSC_TEMP_D+      A @T6G_MB_LIB.T6G(SCH_1):P12V_HSC_TEMP_D+
   2 P12V_HSC_TEMP_D-      B @T6G_MB_LIB.T6G(SCH_1):P12V_HSC_TEMP_D-

Q_CAP_C0402-0.1UF,16V,10%,X7R,CH4103K1B08  I6  C1787
   1 P3V3_AUX      A @T6G_MB_LIB.T6G(SCH_1):P3V3_AUX
   2    GND      B @T6G_MB_LIB.T6G(SCH_1):GND

NCT7718W-NCT7718W,SMLF,IC,AL007718001  I8  U143
   1 P3V3_AUX    VDD @T6G_MB_LIB.T6G(SCH_1):P3V3_AUX
   2 P12V_HSC_TEMP_D+     D+ @T6G_MB_LIB.T6G(SCH_1):P12V_HSC_TEMP_D+
   3 P12V_HSC_TEMP_D-     D- @T6G_MB_LIB.T6G(SCH_1):P12V_HSC_TEMP_D-
   4 P12V_HSC_T_CRIT_N T_CRIT# @T6G_MB_LIB.T6G(SCH_1):P12V_HSC_T_CRIT_N
   5    GND    GND @T6G_MB_LIB.T6G(SCH_1):GND
   6 P12V_HSC_TEMP_ALERT_N ALERT# @T6G_MB_LIB.T6G(SCH_1):P12V_HSC_TEMP_ALERT_N
   7 SMB_P12V_HSC_TEMP_SDA    SDA @T6G_MB_LIB.T6G(SCH_1):SMB_P12V_HSC_TEMP_SDA
   8 SMB_P12V_HSC_TEMP_SCL    SCL @T6G_MB_LIB.T6G(SCH_1):SMB_P12V_HSC_TEMP_SCL

Q_RES_0402LF-0,5%,1/16W,CHIP,CS00002JB13  I10  R2628
   1 P12V_HSC_TEMP_ALERT_N      A @T6G_MB_LIB.T6G(SCH_1):P12V_HSC_TEMP_ALERT_N
   2 P12V_HSC_TEMP_ALERT_R_N      B @T6G_MB_LIB.T6G(SCH_1):P12V_HSC_TEMP_ALERT_R_N

Q_CAP_0402-0.1UF,25V,10%,X7R,CH4104K1B00  I28  PC1789
   1 P12V_AUX      A @T6G_MB_LIB.T6G(SCH_1):P12V_AUX
   2    GND      B @T6G_MB_LIB.T6G(SCH_1):GND

Q_RES_0402LF-0,5%,1/16W,CHIP,CS00002JB13  I39  R2627
   1 SMB_P12V_HSC_TEMP_SDA      A @T6G_MB_LIB.T6G(SCH_1):SMB_P12V_HSC_TEMP_SDA
   2 SMB_P12V_HSC_SDA      B @T6G_MB_LIB.T6G(SCH_1):SMB_P12V_HSC_SDA

Q_RES_0402LF-0,5%,1/16W,CHIP,CS00002JB13  I40  R2626
   1 SMB_P12V_HSC_TEMP_SCL      A @T6G_MB_LIB.T6G(SCH_1):SMB_P12V_HSC_TEMP_SCL
   2 SMB_P12V_HSC_SCL      B @T6G_MB_LIB.T6G(SCH_1):SMB_P12V_HSC_SCL

SCONN21_9193031121LF-SCONN21_91930-31121LF,SMLF,IOA  I42  PJ38
   1 P12V_PSU      1 @T6G_MB_LIB.T6G(SCH_1):P12V_PSU
   3 P12V_HSC_SENSE1_N      3 @T6G_MB_LIB.T6G(SCH_1):P12V_HSC_SENSE1_N
   4 P12V_HSC_SENSE2_P      4 @T6G_MB_LIB.T6G(SCH_1):P12V_HSC_SENSE2_P
   5 P12V_HSC_SENSE2_N      5 @T6G_MB_LIB.T6G(SCH_1):P12V_HSC_SENSE2_N
   2 P12V_HSC_SENSE1_P      2 @T6G_MB_LIB.T6G(SCH_1):P12V_HSC_SENSE1_P
  G1    GND     G1 @T6G_MB_LIB.T6G(SCH_1):GND
  G2    GND     G2 @T6G_MB_LIB.T6G(SCH_1):GND
   6 P12V_HSC_ADC_N      6 @T6G_MB_LIB.T6G(SCH_1):P12V_HSC_ADC_N
   7 P12V_HSC_ADC_P      7 @T6G_MB_LIB.T6G(SCH_1):P12V_HSC_ADC_P
   8 P12V_HSC_GATE1      8 @T6G_MB_LIB.T6G(SCH_1):P12V_HSC_GATE1
   9 P12V_HSC_GATE2      9 @T6G_MB_LIB.T6G(SCH_1):P12V_HSC_GATE2
  10 P12V_AUX     10 @T6G_MB_LIB.T6G(SCH_1):P12V_AUX
  11    GND     11 @T6G_MB_LIB.T6G(SCH_1):GND
  12 P3V3_AUX     12 @T6G_MB_LIB.T6G(SCH_1):P3V3_AUX
  13 IRQ_HSC_FAULT_N     13 @T6G_MB_LIB.T6G(SCH_1):IRQ_HSC_FAULT_N
  14 HSC_EN     14 @T6G_MB_LIB.T6G(SCH_1):HSC_EN
  15 MB0_P12V_STBY_PWRGD     15 @T6G_MB_LIB.T6G(SCH_1):MB0_P12V_STBY_PWRGD
  16 HSC_CSOUT     16 @T6G_MB_LIB.T6G(SCH_1):HSC_CSOUT
  17 HSC_TYPE_ADC     17 @T6G_MB_LIB.T6G(SCH_1):HSC_TYPE_ADC
  18 SMB_SML1_PMBUS_HSC_R1_SCL     18 @T6G_MB_LIB.T6G(SCH_1):SMB_SML1_PMBUS_HSC_R1_SCL
  19 SMB_SML1_PMBUS_HSC_R1_SDA     19 @T6G_MB_LIB.T6G(SCH_1):SMB_SML1_PMBUS_HSC_R1_SDA
  20 IRQ_SML1_PMBUS_ALERT_N     20 @T6G_MB_LIB.T6G(SCH_1):IRQ_SML1_PMBUS_ALERT_N
  21    GND     21 @T6G_MB_LIB.T6G(SCH_1):GND

Q_RES_0402LF-2.2K,5%,1/16W,CHIP,CS22202JB07  I45  R6230
   1 P3V3_AUX      A @T6G_MB_LIB.T6G(SCH_1):P3V3_AUX
   2 SMB_P12V_HSC_SDA      B @T6G_MB_LIB.T6G(SCH_1):SMB_P12V_HSC_SDA

Q_RES_0402LF-2.2K,5%,1/16W,CHIP,CS22202JB07  I46  R6231
   1 P3V3_AUX      A @T6G_MB_LIB.T6G(SCH_1):P3V3_AUX
   2 SMB_P12V_HSC_SCL      B @T6G_MB_LIB.T6G(SCH_1):SMB_P12V_HSC_SCL

LT6700CS61TRPBF-LT6700CS6-1#TRPBF,SMLF,EMPTY,AL006A  I50  U142
   5 U142_VS     VS @T6G_MB_LIB.T6G(SCH_1):U142_VS
   4 A_HSC_HIGH   INB- @T6G_MB_LIB.T6G(SCH_1):A_HSC_HIGH
   2    GND    GND @T6G_MB_LIB.T6G(SCH_1):GND
   1 A_HSC_LOW_GATE   OUTA @T6G_MB_LIB.T6G(SCH_1):A_HSC_LOW_GATE
   3 A_HSC_LOW   INA+ @T6G_MB_LIB.T6G(SCH_1):A_HSC_LOW
   6 HSC_D_OC   OUTB @T6G_MB_LIB.T6G(SCH_1):HSC_D_OC

Q_RES_0402LF-160K,1%,1/16W,EMPTY,CS41602FB05  I55  R6234
   1 HSC_CSOUT      A @T6G_MB_LIB.T6G(SCH_1):HSC_CSOUT
   2 A_HSC_HIGH      B @T6G_MB_LIB.T6G(SCH_1):A_HSC_HIGH

Q_RES_0402LF-160K,1%,1/16W,EMPTY,CS41602FB05  I56  R6232
   1 HSC_CSOUT      A @T6G_MB_LIB.T6G(SCH_1):HSC_CSOUT
   2 A_HSC_LOW      B @T6G_MB_LIB.T6G(SCH_1):A_HSC_LOW

Q_RES_0402LF-10K,1%,1/16W,EMPTY,CS31002FB08  I57  R6233
   1 A_HSC_LOW      A @T6G_MB_LIB.T6G(SCH_1):A_HSC_LOW
   2    GND      B @T6G_MB_LIB.T6G(SCH_1):GND

Q_RES_0402LF-10K,1%,1/16W,EMPTY,CS31002FB08  I58  R6235
   1 A_HSC_HIGH      A @T6G_MB_LIB.T6G(SCH_1):A_HSC_HIGH
   2    GND      B @T6G_MB_LIB.T6G(SCH_1):GND

Q_RES_0402LF-10K,1%,1/16W,EMPTY,CS31002FB08  I63  R6236
   1 P3V3_AUX      A @T6G_MB_LIB.T6G(SCH_1):P3V3_AUX
   2 A_HSC_LOW_GATE      B @T6G_MB_LIB.T6G(SCH_1):A_HSC_LOW_GATE

Q_RES_0402LF-0,5%,1/16W,EMPTY,CS00002JB13  I66  R6237
   1 A_HSC_LOW_GATE      A @T6G_MB_LIB.T6G(SCH_1):A_HSC_LOW_GATE
   2    GND      B @T6G_MB_LIB.T6G(SCH_1):GND

MOSFET_NCH_GDS_ESD_PROTECTED-2N7002K,SMLF,EMPTY,BAA  I68  U6004
   D A_HSC_LOW_DRAIN      D @T6G_MB_LIB.T6G(SCH_1):A_HSC_LOW_DRAIN
   G A_HSC_LOW_GATE      G @T6G_MB_LIB.T6G(SCH_1):A_HSC_LOW_GATE
   S    GND      S @T6G_MB_LIB.T6G(SCH_1):GND

Q_RES_0402LF-10K,1%,1/16W,CHIP,CS31002FB08  I70  R6239
   1 P3V3_AUX      A @T6G_MB_LIB.T6G(SCH_1):P3V3_AUX
   2 HSC_D_OC      B @T6G_MB_LIB.T6G(SCH_1):HSC_D_OC

Q_RES_0402LF-0,5%,1/16W,EMPTY,CS00002JB13  I72  R6238
   1 A_HSC_LOW_DRAIN      A @T6G_MB_LIB.T6G(SCH_1):A_HSC_LOW_DRAIN
   2 HSC_D_OC      B @T6G_MB_LIB.T6G(SCH_1):HSC_D_OC

Q_RES_0402LF-0,5%,1/16W,CHIP,CS00002JB13  I73  R6210
   1 HSC_CSOUT      A @T6G_MB_LIB.T6G(SCH_1):HSC_CSOUT
   2 HSC_D_OC      B @T6G_MB_LIB.T6G(SCH_1):HSC_D_OC

Q_RES_0402LF-0,5%,1/16W,CHIP,CS00002JB13  I74  R353
   1 P12V_HSC_T_CRIT_N      A @T6G_MB_LIB.T6G(SCH_1):P12V_HSC_T_CRIT_N
   2 P12V_HSC_T_CRIT_R_N      B @T6G_MB_LIB.T6G(SCH_1):P12V_HSC_T_CRIT_R_N

Q_RES_0402LF-10.5K,1%,1/16W,CHIP,CS31052FB03  I76  R354
   1 P3V3_AUX      A @T6G_MB_LIB.T6G(SCH_1):P3V3_AUX
   2 P12V_HSC_T_CRIT_R_N      B @T6G_MB_LIB.T6G(SCH_1):P12V_HSC_T_CRIT_R_N

Q_RES_0402LF-10.5K,1%,1/16W,CHIP,CS31052FB03  I79  R355
   1 P3V3_AUX      A @T6G_MB_LIB.T6G(SCH_1):P3V3_AUX
   2 P12V_HSC_TEMP_ALERT_R_N      B @T6G_MB_LIB.T6G(SCH_1):P12V_HSC_TEMP_ALERT_R_N

Q_RES_0402LF-10K,1%,1/16W,EMPTY,CS31002FB08  I81  R8107
   1 P3V3_AUX      A @T6G_MB_LIB.T6G(SCH_1):P3V3_AUX
   2 OC_P2V5_COMP      B @T6G_MB_LIB.T6G(SCH_1):OC_P2V5_COMP

Q_RES_0402LF-10K,1%,1/16W,EMPTY,CS31002FB08  I82  R8109
   1 HSC_OC_VOL      A @T6G_MB_LIB.T6G(SCH_1):HSC_OC_VOL
   2    GND      B @T6G_MB_LIB.T6G(SCH_1):GND

Q_RES_0402LF-160K,1%,1/16W,EMPTY,CS41602FB05  I84  R8108
   1 HSC_CSOUT      A @T6G_MB_LIB.T6G(SCH_1):HSC_CSOUT
   2 HSC_OC_VOL      B @T6G_MB_LIB.T6G(SCH_1):HSC_OC_VOL

Q_CAP_C0402-100NF,50V,10%,EMPTY,CH4106K1B01  I87  C8014
   1 OC_P2V5_COMP      A @T6G_MB_LIB.T6G(SCH_1):OC_P2V5_COMP
   2    GND      B @T6G_MB_LIB.T6G(SCH_1):GND

Q_CAP_C0402-100NF,50V,10%,EMPTY,CH4106K1B01  I89  C8015
   1 HSC_OC_VOL      A @T6G_MB_LIB.T6G(SCH_1):HSC_OC_VOL
   2    GND      B @T6G_MB_LIB.T6G(SCH_1):GND

Q_CAP_C0402-100NF,50V,10%,EMPTY,CH4106K1B01  I95  C8016
   1 P12V_AUX      A @T6G_MB_LIB.T6G(SCH_1):P12V_AUX
   2    GND      B @T6G_MB_LIB.T6G(SCH_1):GND

Q_RES_0402LF-33.2,1%,1/16W,EMPTY,CS03322FB03  I96  R8110
   1 HSC_D_OC_R2      A @T6G_MB_LIB.T6G(SCH_1):HSC_D_OC_R2
   2 A_HSC_LOW_GATE      B @T6G_MB_LIB.T6G(SCH_1):A_HSC_LOW_GATE

Q_RES_0402LF-10K,1%,1/16W,EMPTY,CS31002FB08  I98  R8111
   1 P3V3_AUX      A @T6G_MB_LIB.T6G(SCH_1):P3V3_AUX
   2 A_HSC_LOW_GATE      B @T6G_MB_LIB.T6G(SCH_1):A_HSC_LOW_GATE

LM4040AIM3X25NOPB-LM4040AIM3X-2.5/NOPB,SMLF,EMPTY,A  I101  U8005
   1 OC_P2V5_COMP     1+ @T6G_MB_LIB.T6G(SCH_1):OC_P2V5_COMP
   2    GND     2- @T6G_MB_LIB.T6G(SCH_1):GND
   3     NC      3     NC

Q_RES_0402LF-1M,1%,1/16W,EMPTY,CS51002FB05  I103  R8112
   1 HSC_OC_VOL      A @T6G_MB_LIB.T6G(SCH_1):HSC_OC_VOL
   2 HSC_D_OC_R2      B @T6G_MB_LIB.T6G(SCH_1):HSC_D_OC_R2

AP331AWG7-AP331AWG-7,SMLF,EMPTY,AL000331011  I104  U8006
   3 HSC_OC_VOL    IN+ @T6G_MB_LIB.T6G(SCH_1):HSC_OC_VOL
   1 OC_P2V5_COMP    IN- @T6G_MB_LIB.T6G(SCH_1):OC_P2V5_COMP
   4 HSC_D_OC_R2 OUTPUT @T6G_MB_LIB.T6G(SCH_1):HSC_D_OC_R2
   5 P12V_AUX    VCC @T6G_MB_LIB.T6G(SCH_1):P12V_AUX
   2    GND    GND @T6G_MB_LIB.T6G(SCH_1):GND

Q_CAP_0402-0.1UF,25V,10%,EMPTY,CH4104K1B00  I107  C6084
   1 U142_VS      A @T6G_MB_LIB.T6G(SCH_1):U142_VS
   2    GND      B @T6G_MB_LIB.T6G(SCH_1):GND

Q_RES_0402LF-1K,1%,1/16W,EMPTY,CS21002FB06  I108  R9020
   1 P3V3_AUX      A @T6G_MB_LIB.T6G(SCH_1):P3V3_AUX
   2 U142_VS      B @T6G_MB_LIB.T6G(SCH_1):U142_VS

Q_CAP_C0402-1UF,25V,10%,EMPTY,CH5104KEB02  I110  C9003
   1 U142_VS      A @T6G_MB_LIB.T6G(SCH_1):U142_VS
   2    GND      B @T6G_MB_LIB.T6G(SCH_1):GND

Q_RES_0402LF-54.9K,1%,1/16W,CHIP,CS35492FB03  I113  R9024
   1 P3V3_AUX      A @T6G_MB_LIB.T6G(SCH_1):P3V3_AUX
   2 IRQ_HSC_FAULT_N      B @T6G_MB_LIB.T6G(SCH_1):IRQ_HSC_FAULT_N


DRAWING: @T6G_MB_LIB.T6G(SCH_1):PAGE264 

Q_RES_0402LF-33,5%,1/16W,CHIP,CS03302JB10  I5  R1459
   1 PWRGD_P12V_MEM_CPU1      A @T6G_MB_LIB.T6G(SCH_1):PWRGD_P12V_MEM_CPU1
   2 PWRGD_P12V_MEM_CPU1_R      B @T6G_MB_LIB.T6G(SCH_1):PWRGD_P12V_MEM_CPU1_R

Q_RES_0402LF-33,5%,1/16W,CHIP,CS03302JB10  I6  R1458
   1 PWRGD_P12V_MEM_CPU0      A @T6G_MB_LIB.T6G(SCH_1):PWRGD_P12V_MEM_CPU0
   2 PWRGD_P12V_MEM_CPU0_R      B @T6G_MB_LIB.T6G(SCH_1):PWRGD_P12V_MEM_CPU0_R

SN74LVC1G11DCKR-SN74LVC1G11DCKR,SMLF,IC,ALLVC1G1000  I8  U38
   1 PWRGD_P12V_MEM_CPU0_R      A @T6G_MB_LIB.T6G(SCH_1):PWRGD_P12V_MEM_CPU0_R
   3 PWRGD_P12V_MEM_CPU1_R      B @T6G_MB_LIB.T6G(SCH_1):PWRGD_P12V_MEM_CPU1_R
   6 PU_U38_6      C @T6G_MB_LIB.T6G(SCH_1):PU_U38_6
   5 P1V8_AUX    VCC @T6G_MB_LIB.T6G(SCH_1):P1V8_AUX
   4 PWRGD_P12V_MEM      Y @T6G_MB_LIB.T6G(SCH_1):PWRGD_P12V_MEM
   2    GND    GND @T6G_MB_LIB.T6G(SCH_1):GND

Q_RES_0402LF-33,5%,1/16W,CHIP,CS03302JB10  I17  R1363
   1 PWRGD_P12V_MEM      A @T6G_MB_LIB.T6G(SCH_1):PWRGD_P12V_MEM
   2 PWRGD_P12V_MEM_R      B @T6G_MB_LIB.T6G(SCH_1):PWRGD_P12V_MEM_R

Q_RES_0402LF-16.9K,1%,1/16W,CHIP,CS31692FB03  I24  R1441
   1 PWRGD_P12V_MEM_CPU1_EN      A @T6G_MB_LIB.T6G(SCH_1):PWRGD_P12V_MEM_CPU1_EN
   2    GND      B @T6G_MB_LIB.T6G(SCH_1):GND

Q_RES_0402LF-100K,1%,1/16W,CHIP,CS41002FB09  I25  R1440
   1 P12V_MEM_CPU1      A @T6G_MB_LIB.T6G(SCH_1):P12V_MEM_CPU1
   2 PWRGD_P12V_MEM_CPU1_EN      B @T6G_MB_LIB.T6G(SCH_1):PWRGD_P12V_MEM_CPU1_EN

Q_RES_0402LF-10K,5%,1/16W,CHIP,CS31002JB08  I26  R1449
   1 P3V3_AUX      A @T6G_MB_LIB.T6G(SCH_1):P3V3_AUX
   2 PWRGD_P12V_MEM_CPU1_EN_N      B @T6G_MB_LIB.T6G(SCH_1):PWRGD_P12V_MEM_CPU1_EN_N

Q_RES_0402LF-16.9K,1%,1/16W,CHIP,CS31692FB03  I27  R1443
   1 PWRGD_P12V_MEM_CPU0_EN      A @T6G_MB_LIB.T6G(SCH_1):PWRGD_P12V_MEM_CPU0_EN
   2    GND      B @T6G_MB_LIB.T6G(SCH_1):GND

Q_RES_0402LF-100K,1%,1/16W,CHIP,CS41002FB09  I30  R1442
   1 P12V_MEM_CPU0      A @T6G_MB_LIB.T6G(SCH_1):P12V_MEM_CPU0
   2 PWRGD_P12V_MEM_CPU0_EN      B @T6G_MB_LIB.T6G(SCH_1):PWRGD_P12V_MEM_CPU0_EN

BSS138DW7F-BSS138DW-7-F,SMLF,IC,BAM01380032  I33  Q19
   2 PWRGD_P12V_MEM_CPU1_EN     G1 @T6G_MB_LIB.T6G(SCH_1):PWRGD_P12V_MEM_CPU1_EN
   5 PWRGD_P12V_MEM_CPU1_EN_N     G2 @T6G_MB_LIB.T6G(SCH_1):PWRGD_P12V_MEM_CPU1_EN_N
   1    GND     S1 @T6G_MB_LIB.T6G(SCH_1):GND
   4    GND     S2 @T6G_MB_LIB.T6G(SCH_1):GND
   6 PWRGD_P12V_MEM_CPU1_EN_N     D1 @T6G_MB_LIB.T6G(SCH_1):PWRGD_P12V_MEM_CPU1_EN_N
   3 PWRGD_P12V_MEM_CPU1     D2 @T6G_MB_LIB.T6G(SCH_1):PWRGD_P12V_MEM_CPU1

BSS138DW7F-BSS138DW-7-F,SMLF,IC,BAM01380032  I36  Q18
   2 PWRGD_P12V_MEM_CPU0_EN     G1 @T6G_MB_LIB.T6G(SCH_1):PWRGD_P12V_MEM_CPU0_EN
   5 PWRGD_P12V_MEM_CPU0_EN_N     G2 @T6G_MB_LIB.T6G(SCH_1):PWRGD_P12V_MEM_CPU0_EN_N
   1    GND     S1 @T6G_MB_LIB.T6G(SCH_1):GND
   4    GND     S2 @T6G_MB_LIB.T6G(SCH_1):GND
   6 PWRGD_P12V_MEM_CPU0_EN_N     D1 @T6G_MB_LIB.T6G(SCH_1):PWRGD_P12V_MEM_CPU0_EN_N
   3 PWRGD_P12V_MEM_CPU0     D2 @T6G_MB_LIB.T6G(SCH_1):PWRGD_P12V_MEM_CPU0

Q_RES_0402LF-10K,5%,1/16W,CHIP,CS31002JB08  I39  R1450
   1 P3V3_AUX      A @T6G_MB_LIB.T6G(SCH_1):P3V3_AUX
   2 PWRGD_P12V_MEM_CPU0_EN_N      B @T6G_MB_LIB.T6G(SCH_1):PWRGD_P12V_MEM_CPU0_EN_N

Q_RES_0402LF-10K,5%,1/16W,CHIP,CS31002JB08  I41  R1457
   1 P1V8_AUX      A @T6G_MB_LIB.T6G(SCH_1):P1V8_AUX
   2 PWRGD_P12V_MEM_CPU0      B @T6G_MB_LIB.T6G(SCH_1):PWRGD_P12V_MEM_CPU0

Q_RES_0402LF-10K,5%,1/16W,CHIP,CS31002JB08  I43  R1452
   1 P1V8_AUX      A @T6G_MB_LIB.T6G(SCH_1):P1V8_AUX
   2 PWRGD_P12V_MEM_CPU1      B @T6G_MB_LIB.T6G(SCH_1):PWRGD_P12V_MEM_CPU1

Q_CAP_0402-0.1UF,25V,10%,X7R,CH4104K1B00  I47  C347
   1 P1V8_AUX      A @T6G_MB_LIB.T6G(SCH_1):P1V8_AUX
   2    GND      B @T6G_MB_LIB.T6G(SCH_1):GND

Q_CAP_0402-1000PF,50V,5%,X7R,TMP_QCH21006JB10  I49  C5014
   1 PWRGD_P12V_MEM_R      A @T6G_MB_LIB.T6G(SCH_1):PWRGD_P12V_MEM_R
   2    GND      B @T6G_MB_LIB.T6G(SCH_1):GND

Q_RES_0402LF-10K,1%,1/16W,CHIP,CS31002FB08  I51  R6504
   1 P1V8_AUX      A @T6G_MB_LIB.T6G(SCH_1):P1V8_AUX
   2 PU_U38_6      B @T6G_MB_LIB.T6G(SCH_1):PU_U38_6

Q_RES_4P_12-0.001,1%,3W,SMLF,CHIP,SP_CS+001DFR10  I54  R1837
   1 P12V_AUX      1 @T6G_MB_LIB.T6G(SCH_1):P12V_AUX
   2 P12V_MEM_CPU1      2 @T6G_MB_LIB.T6G(SCH_1):P12V_MEM_CPU1
   3 TP_P12V_AUX_CPU1_DIMM_ISEN_P      3 @T6G_MB_LIB.T6G(SCH_1):TP_P12V_AUX_CPU1_DIMM_ISEN_P
   4 TP_P12V_AUX_CPU1_DIMM_ISEN_N      4 @T6G_MB_LIB.T6G(SCH_1):TP_P12V_AUX_CPU1_DIMM_ISEN_N

Q_RES_4P_12-0.001,1%,3W,SMLF,CHIP,SP_CS+001DFR10  I58  R1838
   1 P12V_AUX      1 @T6G_MB_LIB.T6G(SCH_1):P12V_AUX
   2 P12V_MEM_CPU0      2 @T6G_MB_LIB.T6G(SCH_1):P12V_MEM_CPU0
   3 TP_P12V_AUX_CPU0_DIMM_ISEN_P      3 @T6G_MB_LIB.T6G(SCH_1):TP_P12V_AUX_CPU0_DIMM_ISEN_P
   4 TP_P12V_AUX_CPU0_DIMM_ISEN_N      4 @T6G_MB_LIB.T6G(SCH_1):TP_P12V_AUX_CPU0_DIMM_ISEN_N


DRAWING: @T6G_MB_LIB.T6G(SCH_1):PAGE265 

TDR_3P_TH2-EMPTY,N_A  I2  DB6
   1 T1_GND    GND @T6G_MB_LIB.T6G(SCH_1):T1_GND
   2 TDR_SE_45_OHM_BOT    IO1 @T6G_MB_LIB.T6G(SCH_1):TDR_SE_45_OHM_BOT
   3 TDR_SE_45_OHM_BOT    IO2 @T6G_MB_LIB.T6G(SCH_1):TDR_SE_45_OHM_BOT

TDR_3P_TH2-EMPTY,N_A  I5  DB14
   1 T1_GND    GND @T6G_MB_LIB.T6G(SCH_1):T1_GND
   2 TDR_SE_45_OHM_IN6    IO1 @T6G_MB_LIB.T6G(SCH_1):TDR_SE_45_OHM_IN6
   3 TDR_SE_45_OHM_IN6    IO2 @T6G_MB_LIB.T6G(SCH_1):TDR_SE_45_OHM_IN6

TDR_3P_TH2-EMPTY,N_A  I8  DB13
   1 T1_GND    GND @T6G_MB_LIB.T6G(SCH_1):T1_GND
   2 TDR_SE_45_OHM_IN5    IO1 @T6G_MB_LIB.T6G(SCH_1):TDR_SE_45_OHM_IN5
   3 TDR_SE_45_OHM_IN5    IO2 @T6G_MB_LIB.T6G(SCH_1):TDR_SE_45_OHM_IN5

TDR_3P_TH2-EMPTY,N_A  I9  DB5
   1 T1_GND    GND @T6G_MB_LIB.T6G(SCH_1):T1_GND
   2 TDR_SE_45_OHM_IN4    IO1 @T6G_MB_LIB.T6G(SCH_1):TDR_SE_45_OHM_IN4
   3 TDR_SE_45_OHM_IN4    IO2 @T6G_MB_LIB.T6G(SCH_1):TDR_SE_45_OHM_IN4

TDR_3P_TH2-EMPTY,N_A  I12  DB4
   1 T1_GND    GND @T6G_MB_LIB.T6G(SCH_1):T1_GND
   2 TDR_SE_45_OHM_IN3    IO1 @T6G_MB_LIB.T6G(SCH_1):TDR_SE_45_OHM_IN3
   3 TDR_SE_45_OHM_IN3    IO2 @T6G_MB_LIB.T6G(SCH_1):TDR_SE_45_OHM_IN3

TDR_3P_TH2-EMPTY,N_A  I13  DB3
   1 T1_GND    GND @T6G_MB_LIB.T6G(SCH_1):T1_GND
   2 TDR_SE_45_OHM_IN2    IO1 @T6G_MB_LIB.T6G(SCH_1):TDR_SE_45_OHM_IN2
   3 TDR_SE_45_OHM_IN2    IO2 @T6G_MB_LIB.T6G(SCH_1):TDR_SE_45_OHM_IN2

TDR_3P_TH2-EMPTY,N_A  I15  DB2
   1 T1_GND    GND @T6G_MB_LIB.T6G(SCH_1):T1_GND
   2 TDR_SE_45_OHM_IN1    IO1 @T6G_MB_LIB.T6G(SCH_1):TDR_SE_45_OHM_IN1
   3 TDR_SE_45_OHM_IN1    IO2 @T6G_MB_LIB.T6G(SCH_1):TDR_SE_45_OHM_IN1

TDR_3P_TH2-EMPTY,N_A  I16  DB1
   1 T1_GND    GND @T6G_MB_LIB.T6G(SCH_1):T1_GND
   2 TDR_SE_45_OHM_TOP    IO1 @T6G_MB_LIB.T6G(SCH_1):TDR_SE_45_OHM_TOP
   3 TDR_SE_45_OHM_TOP    IO2 @T6G_MB_LIB.T6G(SCH_1):TDR_SE_45_OHM_TOP

TDR_3P_TH2-EMPTY,N_A  I18  DB12
   1 T1_GND    GND @T6G_MB_LIB.T6G(SCH_1):T1_GND
   2 TDR_SE_50_OHM_BOT    IO1 @T6G_MB_LIB.T6G(SCH_1):TDR_SE_50_OHM_BOT
   3 TDR_SE_50_OHM_BOT    IO2 @T6G_MB_LIB.T6G(SCH_1):TDR_SE_50_OHM_BOT

TDR_3P_TH2-EMPTY,N_A  I20  DB16
   1 T1_GND    GND @T6G_MB_LIB.T6G(SCH_1):T1_GND
   2 TDR_SE_50_OHM_IN6    IO1 @T6G_MB_LIB.T6G(SCH_1):TDR_SE_50_OHM_IN6
   3 TDR_SE_50_OHM_IN6    IO2 @T6G_MB_LIB.T6G(SCH_1):TDR_SE_50_OHM_IN6

TDR_3P_TH2-EMPTY,N_A  I22  DB15
   1 T1_GND    GND @T6G_MB_LIB.T6G(SCH_1):T1_GND
   2 TDR_SE_50_OHM_IN5    IO1 @T6G_MB_LIB.T6G(SCH_1):TDR_SE_50_OHM_IN5
   3 TDR_SE_50_OHM_IN5    IO2 @T6G_MB_LIB.T6G(SCH_1):TDR_SE_50_OHM_IN5

TDR_3P_TH2-EMPTY,N_A  I25  DB11
   1 T1_GND    GND @T6G_MB_LIB.T6G(SCH_1):T1_GND
   2 TDR_SE_50_OHM_IN4    IO1 @T6G_MB_LIB.T6G(SCH_1):TDR_SE_50_OHM_IN4
   3 TDR_SE_50_OHM_IN4    IO2 @T6G_MB_LIB.T6G(SCH_1):TDR_SE_50_OHM_IN4

TP_TDR_4P_FTS_TH-TP_TDR_4P_DIP,EMPTY,TP15  I29  X6
   2 T1_GND     P1 @T6G_MB_LIB.T6G(SCH_1):T1_GND
   3 T1_GND     P2 @T6G_MB_LIB.T6G(SCH_1):T1_GND
   1 TDR_DIFF_80_BOT_DP     S1 @T6G_MB_LIB.T6G(SCH_1):TDR_DIFF_80_BOT_DP
   4 TDR_DIFF_80_BOT_DN     S2 @T6G_MB_LIB.T6G(SCH_1):TDR_DIFF_80_BOT_DN

TP_TDR_4P_FTS_TH-TP_TDR_4P_DIP,EMPTY,TP15  I30  X26
   2 T1_GND     P1 @T6G_MB_LIB.T6G(SCH_1):T1_GND
   3 T1_GND     P2 @T6G_MB_LIB.T6G(SCH_1):T1_GND
   1 TDR_DIFF_80_IN6_DP     S1 @T6G_MB_LIB.T6G(SCH_1):TDR_DIFF_80_IN6_DP
   4 TDR_DIFF_80_IN6_DN     S2 @T6G_MB_LIB.T6G(SCH_1):TDR_DIFF_80_IN6_DN

TP_TDR_4P_FTS_TH-TP_TDR_4P_DIP,EMPTY,TP15  I31  X25
   2 T1_GND     P1 @T6G_MB_LIB.T6G(SCH_1):T1_GND
   3 T1_GND     P2 @T6G_MB_LIB.T6G(SCH_1):T1_GND
   1 TDR_DIFF_80_IN5_DP     S1 @T6G_MB_LIB.T6G(SCH_1):TDR_DIFF_80_IN5_DP
   4 TDR_DIFF_80_IN5_DN     S2 @T6G_MB_LIB.T6G(SCH_1):TDR_DIFF_80_IN5_DN

TP_TDR_4P_FTS_TH-TP_TDR_4P_DIP,EMPTY,TP15  I35  X5
   2 T1_GND     P1 @T6G_MB_LIB.T6G(SCH_1):T1_GND
   3 T1_GND     P2 @T6G_MB_LIB.T6G(SCH_1):T1_GND
   1 TDR_DIFF_80_IN4_DP     S1 @T6G_MB_LIB.T6G(SCH_1):TDR_DIFF_80_IN4_DP
   4 TDR_DIFF_80_IN4_DN     S2 @T6G_MB_LIB.T6G(SCH_1):TDR_DIFF_80_IN4_DN

TP_TDR_4P_FTS_TH-TP_TDR_4P_DIP,EMPTY,TP15  I36  X4
   2 T1_GND     P1 @T6G_MB_LIB.T6G(SCH_1):T1_GND
   3 T1_GND     P2 @T6G_MB_LIB.T6G(SCH_1):T1_GND
   1 TDR_DIFF_80_IN3_DP     S1 @T6G_MB_LIB.T6G(SCH_1):TDR_DIFF_80_IN3_DP
   4 TDR_DIFF_80_IN3_DN     S2 @T6G_MB_LIB.T6G(SCH_1):TDR_DIFF_80_IN3_DN

TP_TDR_4P_FTS_TH-TP_TDR_4P_DIP,EMPTY,TP15  I37  X3
   2 T1_GND     P1 @T6G_MB_LIB.T6G(SCH_1):T1_GND
   3 T1_GND     P2 @T6G_MB_LIB.T6G(SCH_1):T1_GND
   1 TDR_DIFF_80_IN2_DP     S1 @T6G_MB_LIB.T6G(SCH_1):TDR_DIFF_80_IN2_DP
   4 TDR_DIFF_80_IN2_DN     S2 @T6G_MB_LIB.T6G(SCH_1):TDR_DIFF_80_IN2_DN

TDR_3P_TH2-EMPTY,N_A  I38  DB10
   1 T1_GND    GND @T6G_MB_LIB.T6G(SCH_1):T1_GND
   2 TDR_SE_50_OHM_IN3    IO1 @T6G_MB_LIB.T6G(SCH_1):TDR_SE_50_OHM_IN3
   3 TDR_SE_50_OHM_IN3    IO2 @T6G_MB_LIB.T6G(SCH_1):TDR_SE_50_OHM_IN3

TDR_3P_TH2-EMPTY,N_A  I40  DB9
   1 T1_GND    GND @T6G_MB_LIB.T6G(SCH_1):T1_GND
   2 TDR_SE_50_OHM_IN2    IO1 @T6G_MB_LIB.T6G(SCH_1):TDR_SE_50_OHM_IN2
   3 TDR_SE_50_OHM_IN2    IO2 @T6G_MB_LIB.T6G(SCH_1):TDR_SE_50_OHM_IN2

TDR_3P_TH2-EMPTY,N_A  I42  DB8
   1 T1_GND    GND @T6G_MB_LIB.T6G(SCH_1):T1_GND
   2 TDR_SE_50_OHM_IN1    IO1 @T6G_MB_LIB.T6G(SCH_1):TDR_SE_50_OHM_IN1
   3 TDR_SE_50_OHM_IN1    IO2 @T6G_MB_LIB.T6G(SCH_1):TDR_SE_50_OHM_IN1

TDR_3P_TH2-EMPTY,N_A  I44  DB7
   1 T1_GND    GND @T6G_MB_LIB.T6G(SCH_1):T1_GND
   2 TDR_SE_50_OHM_TOP    IO1 @T6G_MB_LIB.T6G(SCH_1):TDR_SE_50_OHM_TOP
   3 TDR_SE_50_OHM_TOP    IO2 @T6G_MB_LIB.T6G(SCH_1):TDR_SE_50_OHM_TOP

TP_TDR_4P_FTS_TH-TP_TDR_4P_DIP,EMPTY,TP15  I47  X2
   2 T1_GND     P1 @T6G_MB_LIB.T6G(SCH_1):T1_GND
   3 T1_GND     P2 @T6G_MB_LIB.T6G(SCH_1):T1_GND
   1 TDR_DIFF_80_IN1_DP     S1 @T6G_MB_LIB.T6G(SCH_1):TDR_DIFF_80_IN1_DP
   4 TDR_DIFF_80_IN1_DN     S2 @T6G_MB_LIB.T6G(SCH_1):TDR_DIFF_80_IN1_DN

TP_TDR_4P_FTS_TH-TP_TDR_4P_DIP,EMPTY,TP15  I48  X1
   2 T1_GND     P1 @T6G_MB_LIB.T6G(SCH_1):T1_GND
   3 T1_GND     P2 @T6G_MB_LIB.T6G(SCH_1):T1_GND
   1 TDR_DIFF_80_TOP_DP     S1 @T6G_MB_LIB.T6G(SCH_1):TDR_DIFF_80_TOP_DP
   4 TDR_DIFF_80_TOP_DN     S2 @T6G_MB_LIB.T6G(SCH_1):TDR_DIFF_80_TOP_DN

TP_TDR_4P_FTS_TH-TP_TDR_4P_DIP,EMPTY,TP15  I49  X12
   2 T1_GND     P1 @T6G_MB_LIB.T6G(SCH_1):T1_GND
   3 T1_GND     P2 @T6G_MB_LIB.T6G(SCH_1):T1_GND
   1 TDR_DIFF_80_BOT_DN     S1 @T6G_MB_LIB.T6G(SCH_1):TDR_DIFF_80_BOT_DN
   4 TDR_DIFF_80_BOT_DP     S2 @T6G_MB_LIB.T6G(SCH_1):TDR_DIFF_80_BOT_DP

TP_TDR_4P_FTS_TH-TP_TDR_4P_DIP,EMPTY,TP15  I52  X28
   2 T1_GND     P1 @T6G_MB_LIB.T6G(SCH_1):T1_GND
   3 T1_GND     P2 @T6G_MB_LIB.T6G(SCH_1):T1_GND
   1 TDR_DIFF_80_IN6_DN     S1 @T6G_MB_LIB.T6G(SCH_1):TDR_DIFF_80_IN6_DN
   4 TDR_DIFF_80_IN6_DP     S2 @T6G_MB_LIB.T6G(SCH_1):TDR_DIFF_80_IN6_DP

TP_TDR_4P_FTS_TH-TP_TDR_4P_DIP,EMPTY,TP15  I53  X27
   2 T1_GND     P1 @T6G_MB_LIB.T6G(SCH_1):T1_GND
   3 T1_GND     P2 @T6G_MB_LIB.T6G(SCH_1):T1_GND
   1 TDR_DIFF_80_IN5_DN     S1 @T6G_MB_LIB.T6G(SCH_1):TDR_DIFF_80_IN5_DN
   4 TDR_DIFF_80_IN5_DP     S2 @T6G_MB_LIB.T6G(SCH_1):TDR_DIFF_80_IN5_DP

TP_TDR_4P_FTS_TH-TP_TDR_4P_DIP,EMPTY,TP15  I56  X8006
   2 T1_GND     P1 @T6G_MB_LIB.T6G(SCH_1):T1_GND
   3 T1_GND     P2 @T6G_MB_LIB.T6G(SCH_1):T1_GND
   1 TDR_DIFF_85_BOT_DP     S1 @T6G_MB_LIB.T6G(SCH_1):TDR_DIFF_85_BOT_DP
   4 TDR_DIFF_85_BOT_DN     S2 @T6G_MB_LIB.T6G(SCH_1):TDR_DIFF_85_BOT_DN

TP_TDR_4P_FTS_TH-TP_TDR_4P_DIP,EMPTY,TP15  I58  X8026
   2 T1_GND     P1 @T6G_MB_LIB.T6G(SCH_1):T1_GND
   3 T1_GND     P2 @T6G_MB_LIB.T6G(SCH_1):T1_GND
   1 TDR_DIFF_85_IN6_DP     S1 @T6G_MB_LIB.T6G(SCH_1):TDR_DIFF_85_IN6_DP
   4 TDR_DIFF_85_IN6_DN     S2 @T6G_MB_LIB.T6G(SCH_1):TDR_DIFF_85_IN6_DN

TP_TDR_4P_FTS_TH-TP_TDR_4P_DIP,EMPTY,TP15  I60  X8025
   2 T1_GND     P1 @T6G_MB_LIB.T6G(SCH_1):T1_GND
   3 T1_GND     P2 @T6G_MB_LIB.T6G(SCH_1):T1_GND
   1 TDR_DIFF_85_IN5_DP     S1 @T6G_MB_LIB.T6G(SCH_1):TDR_DIFF_85_IN5_DP
   4 TDR_DIFF_85_IN5_DN     S2 @T6G_MB_LIB.T6G(SCH_1):TDR_DIFF_85_IN5_DN

TP_TDR_4P_FTS_TH-TP_TDR_4P_DIP,EMPTY,TP15  I61  X10
   2 T1_GND     P1 @T6G_MB_LIB.T6G(SCH_1):T1_GND
   3 T1_GND     P2 @T6G_MB_LIB.T6G(SCH_1):T1_GND
   1 TDR_DIFF_80_IN3_DN     S1 @T6G_MB_LIB.T6G(SCH_1):TDR_DIFF_80_IN3_DN
   4 TDR_DIFF_80_IN3_DP     S2 @T6G_MB_LIB.T6G(SCH_1):TDR_DIFF_80_IN3_DP

TP_TDR_4P_FTS_TH-TP_TDR_4P_DIP,EMPTY,TP15  I62  X9
   2 T1_GND     P1 @T6G_MB_LIB.T6G(SCH_1):T1_GND
   3 T1_GND     P2 @T6G_MB_LIB.T6G(SCH_1):T1_GND
   1 TDR_DIFF_80_IN2_DN     S1 @T6G_MB_LIB.T6G(SCH_1):TDR_DIFF_80_IN2_DN
   4 TDR_DIFF_80_IN2_DP     S2 @T6G_MB_LIB.T6G(SCH_1):TDR_DIFF_80_IN2_DP

TP_TDR_4P_FTS_TH-TP_TDR_4P_DIP,EMPTY,TP15  I66  X8005
   2 T1_GND     P1 @T6G_MB_LIB.T6G(SCH_1):T1_GND
   3 T1_GND     P2 @T6G_MB_LIB.T6G(SCH_1):T1_GND
   1 TDR_DIFF_85_IN4_DP     S1 @T6G_MB_LIB.T6G(SCH_1):TDR_DIFF_85_IN4_DP
   4 TDR_DIFF_85_IN4_DN     S2 @T6G_MB_LIB.T6G(SCH_1):TDR_DIFF_85_IN4_DN

TP_TDR_4P_FTS_TH-TP_TDR_4P_DIP,EMPTY,TP15  I68  X8004
   2 T1_GND     P1 @T6G_MB_LIB.T6G(SCH_1):T1_GND
   3 T1_GND     P2 @T6G_MB_LIB.T6G(SCH_1):T1_GND
   1 TDR_DIFF_85_IN3_DP     S1 @T6G_MB_LIB.T6G(SCH_1):TDR_DIFF_85_IN3_DP
   4 TDR_DIFF_85_IN3_DN     S2 @T6G_MB_LIB.T6G(SCH_1):TDR_DIFF_85_IN3_DN

TP_TDR_4P_FTS_TH-TP_TDR_4P_DIP,EMPTY,TP15  I70  X8003
   2 T1_GND     P1 @T6G_MB_LIB.T6G(SCH_1):T1_GND
   3 T1_GND     P2 @T6G_MB_LIB.T6G(SCH_1):T1_GND
   1 TDR_DIFF_85_IN2_DP     S1 @T6G_MB_LIB.T6G(SCH_1):TDR_DIFF_85_IN2_DP
   4 TDR_DIFF_85_IN2_DN     S2 @T6G_MB_LIB.T6G(SCH_1):TDR_DIFF_85_IN2_DN

TP_TDR_4P_FTS_TH-TP_TDR_4P_DIP,EMPTY,TP15  I73  X8028
   2 T1_GND     P1 @T6G_MB_LIB.T6G(SCH_1):T1_GND
   3 T1_GND     P2 @T6G_MB_LIB.T6G(SCH_1):T1_GND
   1 TDR_DIFF_85_IN6_DN     S1 @T6G_MB_LIB.T6G(SCH_1):TDR_DIFF_85_IN6_DN
   4 TDR_DIFF_85_IN6_DP     S2 @T6G_MB_LIB.T6G(SCH_1):TDR_DIFF_85_IN6_DP

TP_TDR_4P_FTS_TH-TP_TDR_4P_DIP,EMPTY,TP15  I74  X8027
   2 T1_GND     P1 @T6G_MB_LIB.T6G(SCH_1):T1_GND
   3 T1_GND     P2 @T6G_MB_LIB.T6G(SCH_1):T1_GND
   1 TDR_DIFF_85_IN5_DN     S1 @T6G_MB_LIB.T6G(SCH_1):TDR_DIFF_85_IN5_DN
   4 TDR_DIFF_85_IN5_DP     S2 @T6G_MB_LIB.T6G(SCH_1):TDR_DIFF_85_IN5_DP

TP_TDR_4P_FTS_TH-TP_TDR_4P_DIP,EMPTY,TP15  I76  X8011
   2 T1_GND     P1 @T6G_MB_LIB.T6G(SCH_1):T1_GND
   3 T1_GND     P2 @T6G_MB_LIB.T6G(SCH_1):T1_GND
   1 TDR_DIFF_85_IN4_DN     S1 @T6G_MB_LIB.T6G(SCH_1):TDR_DIFF_85_IN4_DN
   4 TDR_DIFF_85_IN4_DP     S2 @T6G_MB_LIB.T6G(SCH_1):TDR_DIFF_85_IN4_DP

TP_TDR_4P_FTS_TH-TP_TDR_4P_DIP,EMPTY,TP15  I78  X8010
   2 T1_GND     P1 @T6G_MB_LIB.T6G(SCH_1):T1_GND
   3 T1_GND     P2 @T6G_MB_LIB.T6G(SCH_1):T1_GND
   1 TDR_DIFF_85_IN3_DN     S1 @T6G_MB_LIB.T6G(SCH_1):TDR_DIFF_85_IN3_DN
   4 TDR_DIFF_85_IN3_DP     S2 @T6G_MB_LIB.T6G(SCH_1):TDR_DIFF_85_IN3_DP

TP_TDR_4P_FTS_TH-TP_TDR_4P_DIP,EMPTY,TP15  I79  X8009
   2 T1_GND     P1 @T6G_MB_LIB.T6G(SCH_1):T1_GND
   3 T1_GND     P2 @T6G_MB_LIB.T6G(SCH_1):T1_GND
   1 TDR_DIFF_85_IN2_DN     S1 @T6G_MB_LIB.T6G(SCH_1):TDR_DIFF_85_IN2_DN
   4 TDR_DIFF_85_IN2_DP     S2 @T6G_MB_LIB.T6G(SCH_1):TDR_DIFF_85_IN2_DP

TP_TDR_4P_FTS_TH-TP_TDR_4P_DIP,EMPTY,TP15  I82  X8
   2 T1_GND     P1 @T6G_MB_LIB.T6G(SCH_1):T1_GND
   3 T1_GND     P2 @T6G_MB_LIB.T6G(SCH_1):T1_GND
   1 TDR_DIFF_80_IN1_DN     S1 @T6G_MB_LIB.T6G(SCH_1):TDR_DIFF_80_IN1_DN
   4 TDR_DIFF_80_IN1_DP     S2 @T6G_MB_LIB.T6G(SCH_1):TDR_DIFF_80_IN1_DP

TP_TDR_4P_FTS_TH-TP_TDR_4P_DIP,EMPTY,TP15  I84  X7
   2 T1_GND     P1 @T6G_MB_LIB.T6G(SCH_1):T1_GND
   3 T1_GND     P2 @T6G_MB_LIB.T6G(SCH_1):T1_GND
   1 TDR_DIFF_80_TOP_DN     S1 @T6G_MB_LIB.T6G(SCH_1):TDR_DIFF_80_TOP_DN
   4 TDR_DIFF_80_TOP_DP     S2 @T6G_MB_LIB.T6G(SCH_1):TDR_DIFF_80_TOP_DP

TP_TDR_4P_FTS_TH-TP_TDR_4P_DIP,EMPTY,TP15  I87  X8002
   2 T1_GND     P1 @T6G_MB_LIB.T6G(SCH_1):T1_GND
   3 T1_GND     P2 @T6G_MB_LIB.T6G(SCH_1):T1_GND
   1 TDR_DIFF_85_IN1_DP     S1 @T6G_MB_LIB.T6G(SCH_1):TDR_DIFF_85_IN1_DP
   4 TDR_DIFF_85_IN1_DN     S2 @T6G_MB_LIB.T6G(SCH_1):TDR_DIFF_85_IN1_DN

TP_TDR_4P_FTS_TH-TP_TDR_4P_DIP,EMPTY,TP15  I89  X8001
   2 T1_GND     P1 @T6G_MB_LIB.T6G(SCH_1):T1_GND
   3 T1_GND     P2 @T6G_MB_LIB.T6G(SCH_1):T1_GND
   1 TDR_DIFF_85_TOP_DP     S1 @T6G_MB_LIB.T6G(SCH_1):TDR_DIFF_85_TOP_DP
   4 TDR_DIFF_85_TOP_DN     S2 @T6G_MB_LIB.T6G(SCH_1):TDR_DIFF_85_TOP_DN

TP_TDR_4P_FTS_TH-TP_TDR_4P_DIP,EMPTY,TP15  I90  X8008
   2 T1_GND     P1 @T6G_MB_LIB.T6G(SCH_1):T1_GND
   3 T1_GND     P2 @T6G_MB_LIB.T6G(SCH_1):T1_GND
   1 TDR_DIFF_85_IN1_DN     S1 @T6G_MB_LIB.T6G(SCH_1):TDR_DIFF_85_IN1_DN
   4 TDR_DIFF_85_IN1_DP     S2 @T6G_MB_LIB.T6G(SCH_1):TDR_DIFF_85_IN1_DP

TP_TDR_4P_FTS_TH-TP_TDR_4P_DIP,EMPTY,TP15  I92  X8007
   2 T1_GND     P1 @T6G_MB_LIB.T6G(SCH_1):T1_GND
   3 T1_GND     P2 @T6G_MB_LIB.T6G(SCH_1):T1_GND
   1 TDR_DIFF_85_TOP_DN     S1 @T6G_MB_LIB.T6G(SCH_1):TDR_DIFF_85_TOP_DN
   4 TDR_DIFF_85_TOP_DP     S2 @T6G_MB_LIB.T6G(SCH_1):TDR_DIFF_85_TOP_DP

TP_TDR_4P_FTS_TH-TP_TDR_4P_DIP,EMPTY,TP15  I94  X8012
   2 T1_GND     P1 @T6G_MB_LIB.T6G(SCH_1):T1_GND
   3 T1_GND     P2 @T6G_MB_LIB.T6G(SCH_1):T1_GND
   1 TDR_DIFF_85_BOT_DN     S1 @T6G_MB_LIB.T6G(SCH_1):TDR_DIFF_85_BOT_DN
   4 TDR_DIFF_85_BOT_DP     S2 @T6G_MB_LIB.T6G(SCH_1):TDR_DIFF_85_BOT_DP

TP_TDR_4P_FTS_TH-TP_TDR_4P_DIP,EMPTY,TP15  I96  X11
   2 T1_GND     P1 @T6G_MB_LIB.T6G(SCH_1):T1_GND
   3 T1_GND     P2 @T6G_MB_LIB.T6G(SCH_1):T1_GND
   1 TDR_DIFF_80_IN4_DN     S1 @T6G_MB_LIB.T6G(SCH_1):TDR_DIFF_80_IN4_DN
   4 TDR_DIFF_80_IN4_DP     S2 @T6G_MB_LIB.T6G(SCH_1):TDR_DIFF_80_IN4_DP


DRAWING: @T6G_MB_LIB.T6G(SCH_1):PAGE266 

TP_TDR_4P_FTS_TH-TP_TDR_4P_DIP,EMPTY,TP15  I2  X9026
   2 T1_GND     P1 @T6G_MB_LIB.T6G(SCH_1):T1_GND
   3 T1_GND     P2 @T6G_MB_LIB.T6G(SCH_1):T1_GND
   1 TDR_DIFF_85_NECK_IN6_DP     S1 @T6G_MB_LIB.T6G(SCH_1):TDR_DIFF_85_NECK_IN6_DP
   4 TDR_DIFF_85_NECK_IN6_DN     S2 @T6G_MB_LIB.T6G(SCH_1):TDR_DIFF_85_NECK_IN6_DN

TP_TDR_4P_FTS_TH-TP_TDR_4P_DIP,EMPTY,TP15  I4  X9025
   2 T1_GND     P1 @T6G_MB_LIB.T6G(SCH_1):T1_GND
   3 T1_GND     P2 @T6G_MB_LIB.T6G(SCH_1):T1_GND
   1 TDR_DIFF_85_NECK_IN5_DP     S1 @T6G_MB_LIB.T6G(SCH_1):TDR_DIFF_85_NECK_IN5_DP
   4 TDR_DIFF_85_NECK_IN5_DN     S2 @T6G_MB_LIB.T6G(SCH_1):TDR_DIFF_85_NECK_IN5_DN

TP_TDR_4P_FTS_TH-TP_TDR_4P_DIP,EMPTY,TP15  I7  X9005
   2 T1_GND     P1 @T6G_MB_LIB.T6G(SCH_1):T1_GND
   3 T1_GND     P2 @T6G_MB_LIB.T6G(SCH_1):T1_GND
   1 TDR_DIFF_85_NECK_IN4_DP     S1 @T6G_MB_LIB.T6G(SCH_1):TDR_DIFF_85_NECK_IN4_DP
   4 TDR_DIFF_85_NECK_IN4_DN     S2 @T6G_MB_LIB.T6G(SCH_1):TDR_DIFF_85_NECK_IN4_DN

TP_TDR_4P_FTS_TH-TP_TDR_4P_DIP,EMPTY,TP15  I8  X9004
   2 T1_GND     P1 @T6G_MB_LIB.T6G(SCH_1):T1_GND
   3 T1_GND     P2 @T6G_MB_LIB.T6G(SCH_1):T1_GND
   1 TDR_DIFF_85_NECK_IN3_DP     S1 @T6G_MB_LIB.T6G(SCH_1):TDR_DIFF_85_NECK_IN3_DP
   4 TDR_DIFF_85_NECK_IN3_DN     S2 @T6G_MB_LIB.T6G(SCH_1):TDR_DIFF_85_NECK_IN3_DN

TP_TDR_4P_FTS_TH-TP_TDR_4P_DIP,EMPTY,TP15  I10  X9003
   2 T1_GND     P1 @T6G_MB_LIB.T6G(SCH_1):T1_GND
   3 T1_GND     P2 @T6G_MB_LIB.T6G(SCH_1):T1_GND
   1 TDR_DIFF_85_NECK_IN2_DP     S1 @T6G_MB_LIB.T6G(SCH_1):TDR_DIFF_85_NECK_IN2_DP
   4 TDR_DIFF_85_NECK_IN2_DN     S2 @T6G_MB_LIB.T6G(SCH_1):TDR_DIFF_85_NECK_IN2_DN

TP_TDR_4P_FTS_TH-TP_TDR_4P_DIP,EMPTY,TP15  I12  X9002
   2 T1_GND     P1 @T6G_MB_LIB.T6G(SCH_1):T1_GND
   3 T1_GND     P2 @T6G_MB_LIB.T6G(SCH_1):T1_GND
   1 TDR_DIFF_85_NECK_IN1_DP     S1 @T6G_MB_LIB.T6G(SCH_1):TDR_DIFF_85_NECK_IN1_DP
   4 TDR_DIFF_85_NECK_IN1_DN     S2 @T6G_MB_LIB.T6G(SCH_1):TDR_DIFF_85_NECK_IN1_DN

TP_TDR_4P_FTS_TH-TP_TDR_4P_DIP,EMPTY,TP15  I13  X9028
   2 T1_GND     P1 @T6G_MB_LIB.T6G(SCH_1):T1_GND
   3 T1_GND     P2 @T6G_MB_LIB.T6G(SCH_1):T1_GND
   1 TDR_DIFF_85_NECK_IN6_DN     S1 @T6G_MB_LIB.T6G(SCH_1):TDR_DIFF_85_NECK_IN6_DN
   4 TDR_DIFF_85_NECK_IN6_DP     S2 @T6G_MB_LIB.T6G(SCH_1):TDR_DIFF_85_NECK_IN6_DP

TP_TDR_4P_FTS_TH-TP_TDR_4P_DIP,EMPTY,TP15  I15  X9027
   2 T1_GND     P1 @T6G_MB_LIB.T6G(SCH_1):T1_GND
   3 T1_GND     P2 @T6G_MB_LIB.T6G(SCH_1):T1_GND
   1 TDR_DIFF_85_NECK_IN5_DN     S1 @T6G_MB_LIB.T6G(SCH_1):TDR_DIFF_85_NECK_IN5_DN
   4 TDR_DIFF_85_NECK_IN5_DP     S2 @T6G_MB_LIB.T6G(SCH_1):TDR_DIFF_85_NECK_IN5_DP

TP_TDR_4P_FTS_TH-TP_TDR_4P_DIP,EMPTY,TP15  I16  X9010
   2 T1_GND     P1 @T6G_MB_LIB.T6G(SCH_1):T1_GND
   3 T1_GND     P2 @T6G_MB_LIB.T6G(SCH_1):T1_GND
   1 TDR_DIFF_85_NECK_IN3_DN     S1 @T6G_MB_LIB.T6G(SCH_1):TDR_DIFF_85_NECK_IN3_DN
   4 TDR_DIFF_85_NECK_IN3_DP     S2 @T6G_MB_LIB.T6G(SCH_1):TDR_DIFF_85_NECK_IN3_DP

TP_TDR_4P_FTS_TH-TP_TDR_4P_DIP,EMPTY,TP15  I17  X9011
   2 T1_GND     P1 @T6G_MB_LIB.T6G(SCH_1):T1_GND
   3 T1_GND     P2 @T6G_MB_LIB.T6G(SCH_1):T1_GND
   1 TDR_DIFF_85_NECK_IN4_DN     S1 @T6G_MB_LIB.T6G(SCH_1):TDR_DIFF_85_NECK_IN4_DN
   4 TDR_DIFF_85_NECK_IN4_DP     S2 @T6G_MB_LIB.T6G(SCH_1):TDR_DIFF_85_NECK_IN4_DP

TP_TDR_4P_FTS_TH-TP_TDR_4P_DIP,EMPTY,TP15  I37  X9009
   2 T1_GND     P1 @T6G_MB_LIB.T6G(SCH_1):T1_GND
   3 T1_GND     P2 @T6G_MB_LIB.T6G(SCH_1):T1_GND
   1 TDR_DIFF_85_NECK_IN2_DN     S1 @T6G_MB_LIB.T6G(SCH_1):TDR_DIFF_85_NECK_IN2_DN
   4 TDR_DIFF_85_NECK_IN2_DP     S2 @T6G_MB_LIB.T6G(SCH_1):TDR_DIFF_85_NECK_IN2_DP

TP_TDR_4P_FTS_TH-TP_TDR_4P_DIP,EMPTY,TP15  I38  X9008
   2 T1_GND     P1 @T6G_MB_LIB.T6G(SCH_1):T1_GND
   3 T1_GND     P2 @T6G_MB_LIB.T6G(SCH_1):T1_GND
   1 TDR_DIFF_85_NECK_IN1_DN     S1 @T6G_MB_LIB.T6G(SCH_1):TDR_DIFF_85_NECK_IN1_DN
   4 TDR_DIFF_85_NECK_IN1_DP     S2 @T6G_MB_LIB.T6G(SCH_1):TDR_DIFF_85_NECK_IN1_DP


DRAWING: @T6G_MB_LIB.T6G(SCH_1):PAGE153 

CYUSB330468LTXI-CYUSB3304-68LTXI,SMLF,IC,AJ0330400A  I1  U6001
  60 USB2_CPU0_P0_HUB1_R_DP DS1_DP @T6G_MB_LIB.T6G(SCH_1):USB2_CPU0_P0_HUB1_R_DP
  59 USB2_CPU0_P0_HUB1_R_DN DS1_DM @T6G_MB_LIB.T6G(SCH_1):USB2_CPU0_P0_HUB1_R_DN
  51 USB3_CPU0_BMC_RX_C1_DP DS1_RXP @T6G_MB_LIB.T6G(SCH_1):USB3_CPU0_BMC_RX_C1_DP
  50 USB3_CPU0_BMC_RX_C1_DN DS1_RXM @T6G_MB_LIB.T6G(SCH_1):USB3_CPU0_BMC_RX_C1_DN
  47 USB3_CPU0_BMC_HUB1_TX_DP DS1_TXP @T6G_MB_LIB.T6G(SCH_1):USB3_CPU0_BMC_HUB1_TX_DP
  48 USB3_CPU0_BMC_HUB1_TX_DN DS1_TXM @T6G_MB_LIB.T6G(SCH_1):USB3_CPU0_BMC_HUB1_TX_DN
  62     NC DS2_DP     NC
  63     NC DS2_DM     NC
  45     NC DS2_RXP     NC
  44     NC DS2_RXM     NC
  41     NC DS2_TXP     NC
  42     NC DS2_TXM     NC
  65     NC DS3_DP     NC
  64     NC DS3_DM     NC
  35     NC DS3_RXP     NC
  36     NC DS3_RXM     NC
  38     NC DS3_TXP     NC
  39     NC DS3_TXM     NC
  67     NC DS4_DP     NC
  68     NC DS4_DM     NC
  15     NC DS4_RXP     NC
  14     NC DS4_RXM     NC
  11     NC DS4_TXP     NC
  12     NC DS4_TXM     NC
  18 USB_CPU0_HUB1_VBUS_DS VBUS_DS @T6G_MB_LIB.T6G(SCH_1):USB_CPU0_HUB1_VBUS_DS
  32 SMB_USB_CPU0_HUB1_SCL I2C_CLK @T6G_MB_LIB.T6G(SCH_1):SMB_USB_CPU0_HUB1_SCL
  33 SMB_USB_CPU0_HUB1_SDA I2C_DATA @T6G_MB_LIB.T6G(SCH_1):SMB_USB_CPU0_HUB1_SDA
  20 TP_CPU0_USB_HUB1_SUSPEND SUSPEND @T6G_MB_LIB.T6G(SCH_1):TP_CPU0_USB_HUB1_SUSPEND
  55 XTAL_USB_CPU0_HUB1_XIN XTL_IN @T6G_MB_LIB.T6G(SCH_1):XTAL_USB_CPU0_HUB1_XIN
  54 XTAL_USB_CPU0_HUB1_XOUT XTL_OUT @T6G_MB_LIB.T6G(SCH_1):XTAL_USB_CPU0_HUB1_XOUT
  23 USB_CPU0_HUB1_MODE_SEL0 MODE_SEL0 @T6G_MB_LIB.T6G(SCH_1):USB_CPU0_HUB1_MODE_SEL0
  24 USB_CPU0_HUB1_MODE_SEL1 MODE_SEL1 @T6G_MB_LIB.T6G(SCH_1):USB_CPU0_HUB1_MODE_SEL1
  40    GND    GND @T6G_MB_LIB.T6G(SCH_1):GND
  17 USB_CPU0_HUB1_VBUS_US VBUS_US @T6G_MB_LIB.T6G(SCH_1):USB_CPU0_HUB1_VBUS_US
  57 USB2_CPU0_P0_R1_DP  US_DP @T6G_MB_LIB.T6G(SCH_1):USB2_CPU0_P0_R1_DP
  58 USB2_CPU0_P0_R1_DN  US_DM @T6G_MB_LIB.T6G(SCH_1):USB2_CPU0_P0_R1_DN
   9 USB3_CPU0_BMC_TX_C1_DP US_RXP @T6G_MB_LIB.T6G(SCH_1):USB3_CPU0_BMC_TX_C1_DP
   8 USB3_CPU0_BMC_TX_C1_DN US_RXM @T6G_MB_LIB.T6G(SCH_1):USB3_CPU0_BMC_TX_C1_DN
   6 USB3_CPU0_BMC_RX_HUB1_DP US_TXP @T6G_MB_LIB.T6G(SCH_1):USB3_CPU0_BMC_RX_HUB1_DP
   5 USB3_CPU0_BMC_RX_HUB1_DN US_TXM @T6G_MB_LIB.T6G(SCH_1):USB3_CPU0_BMC_RX_HUB1_DN
  26 USB_CPU0_HUB1_RREF_SS RREF_SS @T6G_MB_LIB.T6G(SCH_1):USB_CPU0_HUB1_RREF_SS
   2 USB_CPU0_HUB1_RREF_USB2 RREF_USB2 @T6G_MB_LIB.T6G(SCH_1):USB_CPU0_HUB1_RREF_USB2
  25     NC  NC_25     NC
  29 PU_CPU0_USB_HUB_PWR_EN PWR_EN @T6G_MB_LIB.T6G(SCH_1):PU_CPU0_USB_HUB_PWR_EN
  30 PU_CPU0_USB_HUB_OVRCURR OVRCURR @T6G_MB_LIB.T6G(SCH_1):PU_CPU0_USB_HUB_OVRCURR
  31 RST_USB_CPU0_HUB1_R_N RESET# @T6G_MB_LIB.T6G(SCH_1):RST_USB_CPU0_HUB1_R_N
  22 PU_CPU0_USB_HUB_RESERVED2 RESERVED2 @T6G_MB_LIB.T6G(SCH_1):PU_CPU0_USB_HUB_RESERVED2
  21 PU_CPU0_USB_HUB_RESERVED1 RESERVED1 @T6G_MB_LIB.T6G(SCH_1):PU_CPU0_USB_HUB_RESERVED1
  TH    GND   EPAD @T6G_MB_LIB.T6G(SCH_1):GND

Q_XTAL_4P_13BI_24GND-26MHZ,SMLF,MISC,BG626000049  I14  Y9
   1 XTAL_USB_CPU0_HUB1_XIN     X1 @T6G_MB_LIB.T6G(SCH_1):XTAL_USB_CPU0_HUB1_XIN
   2    GND     G1 @T6G_MB_LIB.T6G(SCH_1):GND
   4    GND     G2 @T6G_MB_LIB.T6G(SCH_1):GND
   3 XTAL_USB_CPU0_HUB1_XOUT     X2 @T6G_MB_LIB.T6G(SCH_1):XTAL_USB_CPU0_HUB1_XOUT

Q_RES_0402LF-33.2,1%,1/16W,CHIP,CS03322FB03  I20  R4451
   1 RST_USB_HUB_N      A @T6G_MB_LIB.T6G(SCH_1):RST_USB_HUB_N
   2 RST_USB_CPU0_HUB1_R_N      B @T6G_MB_LIB.T6G(SCH_1):RST_USB_CPU0_HUB1_R_N

Q_RES_0402LF-47K,0.1%,1/16W,EMPTY,CS34702BB05  I23  R4453
   1 RST_USB_CPU0_HUB1_R_N      A @T6G_MB_LIB.T6G(SCH_1):RST_USB_CPU0_HUB1_R_N
   2    GND      B @T6G_MB_LIB.T6G(SCH_1):GND

Q_CAP_C0402-1UF,25V,10%,X6S,CH5104KEB02  I25  C2317
   1 RST_USB_CPU0_HUB1_R_N      A @T6G_MB_LIB.T6G(SCH_1):RST_USB_CPU0_HUB1_R_N
   2    GND      B @T6G_MB_LIB.T6G(SCH_1):GND

Q_RES_0402LF-0,5%,1/16W,CHIP,CS00002JB13  I27  R4450
   1 USB_CPU0_HUB1_VBUS_DS      A @T6G_MB_LIB.T6G(SCH_1):USB_CPU0_HUB1_VBUS_DS
   2 P5V_AUX      B @T6G_MB_LIB.T6G(SCH_1):P5V_AUX

Q_CAP_C0805-22UF,16V,20%,X6S,CH6223MEA00  I28  C6027
   1 P5V_AUX      A @T6G_MB_LIB.T6G(SCH_1):P5V_AUX
   2    GND      B @T6G_MB_LIB.T6G(SCH_1):GND

Q_CAP_0402-470PF,50V,10%,X7R,TMP_QCH14706KB18  I29  C6028
   1 P5V_AUX      A @T6G_MB_LIB.T6G(SCH_1):P5V_AUX
   2    GND      B @T6G_MB_LIB.T6G(SCH_1):GND

Q_RES_0402LF-200,1%,1/16W,CHIP,CS12002FB06  I37  R6202
   1    GND      A @T6G_MB_LIB.T6G(SCH_1):GND
   2 USB_CPU0_HUB1_RREF_SS      B @T6G_MB_LIB.T6G(SCH_1):USB_CPU0_HUB1_RREF_SS

Q_RES_0402LF-6.04K,1%,1/16W,CHIP,CS26042FB04  I39  R6203
   1    GND      A @T6G_MB_LIB.T6G(SCH_1):GND
   2 USB_CPU0_HUB1_RREF_USB2      B @T6G_MB_LIB.T6G(SCH_1):USB_CPU0_HUB1_RREF_USB2

Q_RES_0402LF-10K,1%,1/16W,CHIP,CS31002FB08  I41  R6204
   1 P3V3_AUX      A @T6G_MB_LIB.T6G(SCH_1):P3V3_AUX
   2 PU_CPU0_USB_HUB_PWR_EN      B @T6G_MB_LIB.T6G(SCH_1):PU_CPU0_USB_HUB_PWR_EN

Q_RES_0402LF-10K,1%,1/16W,CHIP,CS31002FB08  I43  R6205
   1 P3V3_AUX      A @T6G_MB_LIB.T6G(SCH_1):P3V3_AUX
   2 PU_CPU0_USB_HUB_OVRCURR      B @T6G_MB_LIB.T6G(SCH_1):PU_CPU0_USB_HUB_OVRCURR

Q_RES_0402LF-10K,1%,1/16W,CHIP,CS31002FB08  I44  R6206
   1 P3V3_AUX      A @T6G_MB_LIB.T6G(SCH_1):P3V3_AUX
   2 PU_CPU0_USB_HUB_RESERVED2      B @T6G_MB_LIB.T6G(SCH_1):PU_CPU0_USB_HUB_RESERVED2

Q_RES_0402LF-10K,1%,1/16W,CHIP,CS31002FB08  I45  R6207
   1 P3V3_AUX      A @T6G_MB_LIB.T6G(SCH_1):P3V3_AUX
   2 PU_CPU0_USB_HUB_RESERVED1      B @T6G_MB_LIB.T6G(SCH_1):PU_CPU0_USB_HUB_RESERVED1

Q_RES_0402LF-10K,1%,1/16W,CHIP,CS31002FB08  I47  R6208
   1 P5V_AUX      A @T6G_MB_LIB.T6G(SCH_1):P5V_AUX
   2 USB_CPU0_HUB1_VBUS_US      B @T6G_MB_LIB.T6G(SCH_1):USB_CPU0_HUB1_VBUS_US

Q_RES_0402LF-10K,1%,1/16W,CHIP,CS31002FB08  I48  R6209
   1 USB_CPU0_HUB1_VBUS_US      A @T6G_MB_LIB.T6G(SCH_1):USB_CPU0_HUB1_VBUS_US
   2    GND      B @T6G_MB_LIB.T6G(SCH_1):GND

M24128BWMN6TP-M24128-BWMN6TP,SMLF,IC,AKE30Z00613  I64  U6003
   8 P3V3_AUX    VCC @T6G_MB_LIB.T6G(SCH_1):P3V3_AUX
   7 PD_USB_CPU0_WP    WC# @T6G_MB_LIB.T6G(SCH_1):PD_USB_CPU0_WP
   6 SMB_USB_CPU0_HUB1_SCL_R2    SCL @T6G_MB_LIB.T6G(SCH_1):SMB_USB_CPU0_HUB1_SCL_R2
   5 SMB_USB_CPU0_HUB1_SDA_R2    SDA @T6G_MB_LIB.T6G(SCH_1):SMB_USB_CPU0_HUB1_SDA_R2
   4    GND    VSS @T6G_MB_LIB.T6G(SCH_1):GND
   3 USB_CPU0_ADD_A2     E2 @T6G_MB_LIB.T6G(SCH_1):USB_CPU0_ADD_A2
   2 USB_CPU0_ADD_A1     E1 @T6G_MB_LIB.T6G(SCH_1):USB_CPU0_ADD_A1
   1 USB_CPU0_ADD_A0     E0 @T6G_MB_LIB.T6G(SCH_1):USB_CPU0_ADD_A0

Q_RES_0402LF-10K,1%,1/16W,CHIP,CS31002FB08  I65  R6222
   1 P3V3_AUX      A @T6G_MB_LIB.T6G(SCH_1):P3V3_AUX
   2 USB_CPU0_ADD_A0      B @T6G_MB_LIB.T6G(SCH_1):USB_CPU0_ADD_A0

Q_RES_0402LF-10K,1%,1/16W,CHIP,CS31002FB08  I66  R6219
   1 USB_CPU0_ADD_A1      A @T6G_MB_LIB.T6G(SCH_1):USB_CPU0_ADD_A1
   2    GND      B @T6G_MB_LIB.T6G(SCH_1):GND

Q_RES_0402LF-10K,1%,1/16W,CHIP,CS31002FB08  I67  R6221
   1 USB_CPU0_ADD_A2      A @T6G_MB_LIB.T6G(SCH_1):USB_CPU0_ADD_A2
   2    GND      B @T6G_MB_LIB.T6G(SCH_1):GND

Q_RES_0402LF-10K,1%,1/16W,EMPTY,CS31002FB08  I68  R6217
   1 USB_CPU0_ADD_A0      A @T6G_MB_LIB.T6G(SCH_1):USB_CPU0_ADD_A0
   2    GND      B @T6G_MB_LIB.T6G(SCH_1):GND

Q_RES_0402LF-10K,1%,1/16W,EMPTY,CS31002FB08  I69  R6218
   1 P3V3_AUX      A @T6G_MB_LIB.T6G(SCH_1):P3V3_AUX
   2 USB_CPU0_ADD_A1      B @T6G_MB_LIB.T6G(SCH_1):USB_CPU0_ADD_A1

Q_RES_0402LF-10K,1%,1/16W,EMPTY,CS31002FB08  I70  R6220
   1 P3V3_AUX      A @T6G_MB_LIB.T6G(SCH_1):P3V3_AUX
   2 USB_CPU0_ADD_A2      B @T6G_MB_LIB.T6G(SCH_1):USB_CPU0_ADD_A2

Q_CAP_0402-0.1UF,25V,10%,X7R,CH4104K1B00  I75  C6083
   1 P3V3_AUX      A @T6G_MB_LIB.T6G(SCH_1):P3V3_AUX
   2    GND      B @T6G_MB_LIB.T6G(SCH_1):GND

Q_RES_0402LF-1K,1%,1/16W,CHIP,CS21002FB06  I77  R6223
   1 PD_USB_CPU0_WP      A @T6G_MB_LIB.T6G(SCH_1):PD_USB_CPU0_WP
   2    GND      B @T6G_MB_LIB.T6G(SCH_1):GND

Q_RES_0402LF-33.2,1%,1/16W,EMPTY,CS03322FB03  I83  R6225
   1 SMB_USB_CPU0_HUB1_SDA      A @T6G_MB_LIB.T6G(SCH_1):SMB_USB_CPU0_HUB1_SDA
   2 SMB_USB_CPU0_HUB1_SDA_R2      B @T6G_MB_LIB.T6G(SCH_1):SMB_USB_CPU0_HUB1_SDA_R2

Q_RES_0402LF-33.2,1%,1/16W,EMPTY,CS03322FB03  I84  R6224
   1 SMB_USB_CPU0_HUB1_SCL      A @T6G_MB_LIB.T6G(SCH_1):SMB_USB_CPU0_HUB1_SCL
   2 SMB_USB_CPU0_HUB1_SCL_R2      B @T6G_MB_LIB.T6G(SCH_1):SMB_USB_CPU0_HUB1_SCL_R2

Q_RES_0402LF-10K,1%,1/16W,EMPTY,CS31002FB08  I85  R6226
   1 P3V3_AUX      A @T6G_MB_LIB.T6G(SCH_1):P3V3_AUX
   2 SMB_USB_CPU0_HUB1_SCL_R2      B @T6G_MB_LIB.T6G(SCH_1):SMB_USB_CPU0_HUB1_SCL_R2

Q_RES_0402LF-10K,1%,1/16W,EMPTY,CS31002FB08  I86  R6227
   1 P3V3_AUX      A @T6G_MB_LIB.T6G(SCH_1):P3V3_AUX
   2 SMB_USB_CPU0_HUB1_SDA_R2      B @T6G_MB_LIB.T6G(SCH_1):SMB_USB_CPU0_HUB1_SDA_R2

Q_RES_0402LF-10K,1%,1/16W,CHIP,CS31002FB08  I87  R6213
   1 P3V3_AUX      A @T6G_MB_LIB.T6G(SCH_1):P3V3_AUX
   2 USB_CPU0_HUB1_MODE_SEL1      B @T6G_MB_LIB.T6G(SCH_1):USB_CPU0_HUB1_MODE_SEL1

Q_RES_0402LF-10K,1%,1/16W,EMPTY,CS31002FB08  I88  R6214
   1 USB_CPU0_HUB1_MODE_SEL1      A @T6G_MB_LIB.T6G(SCH_1):USB_CPU0_HUB1_MODE_SEL1
   2    GND      B @T6G_MB_LIB.T6G(SCH_1):GND

Q_RES_0402LF-10K,1%,1/16W,CHIP,CS31002FB08  I89  R6215
   1 P3V3_AUX      A @T6G_MB_LIB.T6G(SCH_1):P3V3_AUX
   2 USB_CPU0_HUB1_MODE_SEL0      B @T6G_MB_LIB.T6G(SCH_1):USB_CPU0_HUB1_MODE_SEL0

Q_RES_0402LF-10K,1%,1/16W,EMPTY,CS31002FB08  I90  R6216
   1 USB_CPU0_HUB1_MODE_SEL0      A @T6G_MB_LIB.T6G(SCH_1):USB_CPU0_HUB1_MODE_SEL0
   2    GND      B @T6G_MB_LIB.T6G(SCH_1):GND

Q_CAP_C0402-12PF,50V,5%,C0G,CH01206JB05  I92  C91
   1 XTAL_USB_CPU0_HUB1_XIN      A @T6G_MB_LIB.T6G(SCH_1):XTAL_USB_CPU0_HUB1_XIN
   2    GND      B @T6G_MB_LIB.T6G(SCH_1):GND

Q_RES_0402LF-10K,1%,1/16W,EMPTY,CS31002FB08  I93  R4452
   1 P3V3_AUX      A @T6G_MB_LIB.T6G(SCH_1):P3V3_AUX
   2 RST_USB_CPU0_HUB1_R_N      B @T6G_MB_LIB.T6G(SCH_1):RST_USB_CPU0_HUB1_R_N

Q_CAP_0402-15PF,50V,5%,C0G,CH01506JB06  I91  C93
   1 XTAL_USB_CPU0_HUB1_XOUT      A @T6G_MB_LIB.T6G(SCH_1):XTAL_USB_CPU0_HUB1_XOUT
   2    GND      B @T6G_MB_LIB.T6G(SCH_1):GND


DRAWING: @T6G_MB_LIB.T6G(SCH_1):PAGE154 

CYUSB330468LTXI-CYUSB3304-68LTXI,SMLF,IC,AJ0330400A  I1  U6001
   1 P1V2_CPU0_USB_DVDD12 DVDD12_1 @T6G_MB_LIB.T6G(SCH_1):P1V2_CPU0_USB_DVDD12
   3 P1V2_CPU0_USB_DVDD12 DVDD12_2 @T6G_MB_LIB.T6G(SCH_1):P1V2_CPU0_USB_DVDD12
  19 P1V2_CPU0_USB_DVDD12 VDD_EFUSE @T6G_MB_LIB.T6G(SCH_1):P1V2_CPU0_USB_DVDD12
  27 P1V2_CPU0_USB_DVDD12 DVDD12_3 @T6G_MB_LIB.T6G(SCH_1):P1V2_CPU0_USB_DVDD12
  43 P1V2_AUX DVDD12_8 @T6G_MB_LIB.T6G(SCH_1):P1V2_AUX
  49 P1V2_AUX DVDD12_4 @T6G_MB_LIB.T6G(SCH_1):P1V2_AUX
  53 P1V2_AUX AVDD12_6 @T6G_MB_LIB.T6G(SCH_1):P1V2_AUX
   7 P1V2_AUX DVDD12_5 @T6G_MB_LIB.T6G(SCH_1):P1V2_AUX
  13 P1V2_AUX DVDD12_6 @T6G_MB_LIB.T6G(SCH_1):P1V2_AUX
  37 P1V2_AUX DVDD12_7 @T6G_MB_LIB.T6G(SCH_1):P1V2_AUX
   4 P3V3_AUX_CPU0_USB_AVDD33 AVDD33_1 @T6G_MB_LIB.T6G(SCH_1):P3V3_AUX_CPU0_USB_AVDD33
  56 P3V3_AUX AVDD33_2 @T6G_MB_LIB.T6G(SCH_1):P3V3_AUX
  61 P3V3_AUX AVDD33_3 @T6G_MB_LIB.T6G(SCH_1):P3V3_AUX
  66 P3V3_AUX AVDD33_4 @T6G_MB_LIB.T6G(SCH_1):P3V3_AUX
  28 P3V3_AUX VDD_IO @T6G_MB_LIB.T6G(SCH_1):P3V3_AUX
  10 P1V2_AUX AVDD12_1 @T6G_MB_LIB.T6G(SCH_1):P1V2_AUX
  16 P1V2_AUX AVDD12_2 @T6G_MB_LIB.T6G(SCH_1):P1V2_AUX
  34 P1V2_AUX AVDD12_3 @T6G_MB_LIB.T6G(SCH_1):P1V2_AUX
  46 P1V2_AUX AVDD12_4 @T6G_MB_LIB.T6G(SCH_1):P1V2_AUX
  52 P1V2_AUX AVDD12_5 @T6G_MB_LIB.T6G(SCH_1):P1V2_AUX

Q_INDUCTOR_SMLF-BLM21PG221SN1D,IND,CX1PG221001  I3  L6000
   2 P3V3_AUX_CPU0_USB_AVDD33      2 @T6G_MB_LIB.T6G(SCH_1):P3V3_AUX_CPU0_USB_AVDD33
   1 P3V3_AUX      1 @T6G_MB_LIB.T6G(SCH_1):P3V3_AUX

Q_CAP_C0402-0.01UF,50V,10%,X7R,CH31006KB18  I5  C6040
   1 P3V3_AUX      A @T6G_MB_LIB.T6G(SCH_1):P3V3_AUX
   2    GND      B @T6G_MB_LIB.T6G(SCH_1):GND

Q_CAP_0402-0.1UF,25V,10%,X7R,CH4104K1B00  I7  C6041
   1 P3V3_AUX      A @T6G_MB_LIB.T6G(SCH_1):P3V3_AUX
   2    GND      B @T6G_MB_LIB.T6G(SCH_1):GND

Q_CAP_C0603-22UF,6.3V,20%,X6S,CH6221ME900  I9  C6042
   1 P3V3_AUX_CPU0_USB_AVDD33      A @T6G_MB_LIB.T6G(SCH_1):P3V3_AUX_CPU0_USB_AVDD33
   2    GND      B @T6G_MB_LIB.T6G(SCH_1):GND

Q_CAP_C0402-1UF,25V,10%,X6S,CH5104KEB02  I10  C6043
   1 P3V3_AUX_CPU0_USB_AVDD33      A @T6G_MB_LIB.T6G(SCH_1):P3V3_AUX_CPU0_USB_AVDD33
   2    GND      B @T6G_MB_LIB.T6G(SCH_1):GND

Q_CAP_0402-0.1UF,25V,10%,X7R,CH4104K1B00  I12  C6044
   1 P3V3_AUX_CPU0_USB_AVDD33      A @T6G_MB_LIB.T6G(SCH_1):P3V3_AUX_CPU0_USB_AVDD33
   2    GND      B @T6G_MB_LIB.T6G(SCH_1):GND

Q_CAP_C0402-0.01UF,50V,10%,X7R,CH31006KB18  I13  C6045
   1 P3V3_AUX_CPU0_USB_AVDD33      A @T6G_MB_LIB.T6G(SCH_1):P3V3_AUX_CPU0_USB_AVDD33
   2    GND      B @T6G_MB_LIB.T6G(SCH_1):GND

Q_CAP_C0603-22UF,6.3V,20%,X6S,CH6221ME900  I14  C6046
   1 P3V3_AUX      A @T6G_MB_LIB.T6G(SCH_1):P3V3_AUX
   2    GND      B @T6G_MB_LIB.T6G(SCH_1):GND

Q_CAP_C0402-1UF,25V,10%,X6S,CH5104KEB02  I15  C6047
   1 P3V3_AUX      A @T6G_MB_LIB.T6G(SCH_1):P3V3_AUX
   2    GND      B @T6G_MB_LIB.T6G(SCH_1):GND

Q_CAP_0402-0.1UF,25V,10%,X7R,CH4104K1B00  I17  C6048
   1 P3V3_AUX      A @T6G_MB_LIB.T6G(SCH_1):P3V3_AUX
   2    GND      B @T6G_MB_LIB.T6G(SCH_1):GND

Q_CAP_C0402-0.01UF,50V,10%,X7R,CH31006KB18  I19  C6049
   1 P3V3_AUX      A @T6G_MB_LIB.T6G(SCH_1):P3V3_AUX
   2    GND      B @T6G_MB_LIB.T6G(SCH_1):GND

Q_CAP_0402-0.1UF,25V,10%,X7R,CH4104K1B00  I20  C6050
   1 P3V3_AUX      A @T6G_MB_LIB.T6G(SCH_1):P3V3_AUX
   2    GND      B @T6G_MB_LIB.T6G(SCH_1):GND

Q_CAP_C0402-0.01UF,50V,10%,X7R,CH31006KB18  I21  C6051
   1 P3V3_AUX      A @T6G_MB_LIB.T6G(SCH_1):P3V3_AUX
   2    GND      B @T6G_MB_LIB.T6G(SCH_1):GND

Q_CAP_C0402-0.01UF,50V,10%,X7R,CH31006KB18  I22  C6053
   1 P3V3_AUX      A @T6G_MB_LIB.T6G(SCH_1):P3V3_AUX
   2    GND      B @T6G_MB_LIB.T6G(SCH_1):GND

Q_CAP_0402-0.1UF,25V,10%,X7R,CH4104K1B00  I23  C6052
   1 P3V3_AUX      A @T6G_MB_LIB.T6G(SCH_1):P3V3_AUX
   2    GND      B @T6G_MB_LIB.T6G(SCH_1):GND

Q_INDUCTOR_SMLF-BLM21PG221SN1D,IND,CX1PG221001  I26  L6001
   2 P1V2_CPU0_USB_DVDD12      2 @T6G_MB_LIB.T6G(SCH_1):P1V2_CPU0_USB_DVDD12
   1 P1V2_AUX      1 @T6G_MB_LIB.T6G(SCH_1):P1V2_AUX

Q_CAP_C0603-22UF,6.3V,20%,X6S,CH6221ME900  I27  C6030
   1 P1V2_CPU0_USB_DVDD12      A @T6G_MB_LIB.T6G(SCH_1):P1V2_CPU0_USB_DVDD12
   2    GND      B @T6G_MB_LIB.T6G(SCH_1):GND

Q_CAP_C0402-1UF,25V,10%,X6S,CH5104KEB02  I29  C6031
   1 P1V2_CPU0_USB_DVDD12      A @T6G_MB_LIB.T6G(SCH_1):P1V2_CPU0_USB_DVDD12
   2    GND      B @T6G_MB_LIB.T6G(SCH_1):GND

Q_CAP_C0402-0.01UF,50V,10%,X7R,CH31006KB18  I31  C6035
   1 P1V2_CPU0_USB_DVDD12      A @T6G_MB_LIB.T6G(SCH_1):P1V2_CPU0_USB_DVDD12
   2    GND      B @T6G_MB_LIB.T6G(SCH_1):GND

Q_CAP_0402-0.1UF,25V,10%,X7R,CH4104K1B00  I32  C6034
   1 P1V2_CPU0_USB_DVDD12      A @T6G_MB_LIB.T6G(SCH_1):P1V2_CPU0_USB_DVDD12
   2    GND      B @T6G_MB_LIB.T6G(SCH_1):GND

Q_CAP_C0402-0.01UF,50V,10%,X7R,CH31006KB18  I34  C6033
   1 P1V2_CPU0_USB_DVDD12      A @T6G_MB_LIB.T6G(SCH_1):P1V2_CPU0_USB_DVDD12
   2    GND      B @T6G_MB_LIB.T6G(SCH_1):GND

Q_CAP_0402-0.1UF,25V,10%,X7R,CH4104K1B00  I35  C6032
   1 P1V2_CPU0_USB_DVDD12      A @T6G_MB_LIB.T6G(SCH_1):P1V2_CPU0_USB_DVDD12
   2    GND      B @T6G_MB_LIB.T6G(SCH_1):GND

Q_CAP_0402-0.1UF,25V,10%,X7R,CH4104K1B00  I37  C6036
   1 P1V2_CPU0_USB_DVDD12      A @T6G_MB_LIB.T6G(SCH_1):P1V2_CPU0_USB_DVDD12
   2    GND      B @T6G_MB_LIB.T6G(SCH_1):GND

Q_CAP_C0402-0.01UF,50V,10%,X7R,CH31006KB18  I38  C6037
   1 P1V2_CPU0_USB_DVDD12      A @T6G_MB_LIB.T6G(SCH_1):P1V2_CPU0_USB_DVDD12
   2    GND      B @T6G_MB_LIB.T6G(SCH_1):GND

Q_CAP_C0402-0.01UF,50V,10%,X7R,CH31006KB18  I40  C6039
   1 P1V2_CPU0_USB_DVDD12      A @T6G_MB_LIB.T6G(SCH_1):P1V2_CPU0_USB_DVDD12
   2    GND      B @T6G_MB_LIB.T6G(SCH_1):GND

Q_CAP_0402-0.1UF,25V,10%,X7R,CH4104K1B00  I41  C6038
   1 P1V2_CPU0_USB_DVDD12      A @T6G_MB_LIB.T6G(SCH_1):P1V2_CPU0_USB_DVDD12
   2    GND      B @T6G_MB_LIB.T6G(SCH_1):GND

Q_CAP_C0402-0.001UF,50V,10%,X7R,CH30106KB19  I43  C6054
   1 P1V2_AUX      A @T6G_MB_LIB.T6G(SCH_1):P1V2_AUX
   2    GND      B @T6G_MB_LIB.T6G(SCH_1):GND

Q_CAP_C0402-0.01UF,50V,10%,X7R,CH31006KB18  I44  C6055
   1 P1V2_AUX      A @T6G_MB_LIB.T6G(SCH_1):P1V2_AUX
   2    GND      B @T6G_MB_LIB.T6G(SCH_1):GND

Q_CAP_C0402-0.001UF,50V,10%,X7R,CH30106KB19  I46  C6056
   1 P1V2_AUX      A @T6G_MB_LIB.T6G(SCH_1):P1V2_AUX
   2    GND      B @T6G_MB_LIB.T6G(SCH_1):GND

Q_CAP_C0402-0.01UF,50V,10%,X7R,CH31006KB18  I47  C6057
   1 P1V2_AUX      A @T6G_MB_LIB.T6G(SCH_1):P1V2_AUX
   2    GND      B @T6G_MB_LIB.T6G(SCH_1):GND

Q_CAP_C0402-0.001UF,50V,10%,X7R,CH30106KB19  I49  C6058
   1 P1V2_AUX      A @T6G_MB_LIB.T6G(SCH_1):P1V2_AUX
   2    GND      B @T6G_MB_LIB.T6G(SCH_1):GND

Q_CAP_C0402-0.01UF,50V,10%,X7R,CH31006KB18  I50  C6059
   1 P1V2_AUX      A @T6G_MB_LIB.T6G(SCH_1):P1V2_AUX
   2    GND      B @T6G_MB_LIB.T6G(SCH_1):GND

Q_CAP_C0402-0.001UF,50V,10%,X7R,CH30106KB19  I52  C6060
   1 P1V2_AUX      A @T6G_MB_LIB.T6G(SCH_1):P1V2_AUX
   2    GND      B @T6G_MB_LIB.T6G(SCH_1):GND

Q_CAP_C0402-0.01UF,50V,10%,X7R,CH31006KB18  I53  C6061
   1 P1V2_AUX      A @T6G_MB_LIB.T6G(SCH_1):P1V2_AUX
   2    GND      B @T6G_MB_LIB.T6G(SCH_1):GND

Q_CAP_C0402-0.001UF,50V,10%,X7R,CH30106KB19  I55  C6062
   1 P1V2_AUX      A @T6G_MB_LIB.T6G(SCH_1):P1V2_AUX
   2    GND      B @T6G_MB_LIB.T6G(SCH_1):GND

Q_CAP_C0402-0.01UF,50V,10%,X7R,CH31006KB18  I56  C6063
   1 P1V2_AUX      A @T6G_MB_LIB.T6G(SCH_1):P1V2_AUX
   2    GND      B @T6G_MB_LIB.T6G(SCH_1):GND

Q_CAP_0402-0.1UF,25V,10%,X7R,CH4104K1B00  I58  C6064
   1 P1V2_AUX      A @T6G_MB_LIB.T6G(SCH_1):P1V2_AUX
   2    GND      B @T6G_MB_LIB.T6G(SCH_1):GND

Q_CAP_C0402-1UF,25V,10%,X6S,CH5104KEB02  I59  C6065
   1 P1V2_AUX      A @T6G_MB_LIB.T6G(SCH_1):P1V2_AUX
   2    GND      B @T6G_MB_LIB.T6G(SCH_1):GND

Q_CAP_C0603-22UF,6.3V,20%,X6S,CH6221ME900  I60  C6066
   1 P1V2_AUX      A @T6G_MB_LIB.T6G(SCH_1):P1V2_AUX
   2    GND      B @T6G_MB_LIB.T6G(SCH_1):GND

Q_CAP_C0402-0.001UF,50V,10%,X7R,CH30106KB19  I63  C6069
   1 P1V2_AUX      A @T6G_MB_LIB.T6G(SCH_1):P1V2_AUX
   2    GND      B @T6G_MB_LIB.T6G(SCH_1):GND

Q_CAP_C0603-22UF,6.3V,20%,X6S,CH6221ME900  I64  C6079
   1 P1V2_AUX      A @T6G_MB_LIB.T6G(SCH_1):P1V2_AUX
   2    GND      B @T6G_MB_LIB.T6G(SCH_1):GND

Q_CAP_C0402-1UF,25V,10%,X6S,CH5104KEB02  I65  C6078
   1 P1V2_AUX      A @T6G_MB_LIB.T6G(SCH_1):P1V2_AUX
   2    GND      B @T6G_MB_LIB.T6G(SCH_1):GND

Q_CAP_0402-0.1UF,25V,10%,X7R,CH4104K1B00  I66  C6077
   1 P1V2_AUX      A @T6G_MB_LIB.T6G(SCH_1):P1V2_AUX
   2    GND      B @T6G_MB_LIB.T6G(SCH_1):GND

Q_CAP_C0402-0.01UF,50V,10%,X7R,CH31006KB18  I68  C6076
   1 P1V2_AUX      A @T6G_MB_LIB.T6G(SCH_1):P1V2_AUX
   2    GND      B @T6G_MB_LIB.T6G(SCH_1):GND

Q_CAP_C0402-0.001UF,50V,10%,X7R,CH30106KB19  I69  C6075
   1 P1V2_AUX      A @T6G_MB_LIB.T6G(SCH_1):P1V2_AUX
   2    GND      B @T6G_MB_LIB.T6G(SCH_1):GND

Q_CAP_C0402-0.01UF,50V,10%,X7R,CH31006KB18  I71  C6074
   1 P1V2_AUX      A @T6G_MB_LIB.T6G(SCH_1):P1V2_AUX
   2    GND      B @T6G_MB_LIB.T6G(SCH_1):GND

Q_CAP_C0402-0.001UF,50V,10%,X7R,CH30106KB19  I73  C6073
   1 P1V2_AUX      A @T6G_MB_LIB.T6G(SCH_1):P1V2_AUX
   2    GND      B @T6G_MB_LIB.T6G(SCH_1):GND

Q_CAP_C0402-0.01UF,50V,10%,X7R,CH31006KB18  I74  C6072
   1 P1V2_AUX      A @T6G_MB_LIB.T6G(SCH_1):P1V2_AUX
   2    GND      B @T6G_MB_LIB.T6G(SCH_1):GND

Q_CAP_C0402-0.001UF,50V,10%,X7R,CH30106KB19  I75  C6071
   1 P1V2_AUX      A @T6G_MB_LIB.T6G(SCH_1):P1V2_AUX
   2    GND      B @T6G_MB_LIB.T6G(SCH_1):GND

Q_CAP_C0402-0.01UF,50V,10%,X7R,CH31006KB18  I76  C6070
   1 P1V2_AUX      A @T6G_MB_LIB.T6G(SCH_1):P1V2_AUX
   2    GND      B @T6G_MB_LIB.T6G(SCH_1):GND

Q_CAP_C0402-0.01UF,50V,10%,X7R,CH31006KB18  I78  C6068
   1 P1V2_AUX      A @T6G_MB_LIB.T6G(SCH_1):P1V2_AUX
   2    GND      B @T6G_MB_LIB.T6G(SCH_1):GND

Q_CAP_C0402-0.001UF,50V,10%,X7R,CH30106KB19  I79  C6067
   1 P1V2_AUX      A @T6G_MB_LIB.T6G(SCH_1):P1V2_AUX
   2    GND      B @T6G_MB_LIB.T6G(SCH_1):GND

Q_CAP_C0402-0.01UF,50V,10%,X7R,CH31006KB18  I81  C6080
   1 P1V2_AUX      A @T6G_MB_LIB.T6G(SCH_1):P1V2_AUX
   2    GND      B @T6G_MB_LIB.T6G(SCH_1):GND

Q_CAP_0402-0.1UF,25V,10%,X7R,CH4104K1B00  I82  C6081
   1 P1V2_AUX      A @T6G_MB_LIB.T6G(SCH_1):P1V2_AUX
   2    GND      B @T6G_MB_LIB.T6G(SCH_1):GND

Q_CAP_C0402-1UF,25V,10%,X6S,CH5104KEB02  I83  C6082
   1 P1V2_AUX      A @T6G_MB_LIB.T6G(SCH_1):P1V2_AUX
   2    GND      B @T6G_MB_LIB.T6G(SCH_1):GND


DRAWING: @T6G_MB_LIB.T6G(SCH_1):PAGE158 

Q_RES_0201LF-0,5%,1/20W,CHIP,CS00001JE10  I3  R6192
   1 USB2_CPU0_P0_DP      A @T6G_MB_LIB.T6G(SCH_1):USB2_CPU0_P0_DP
   2 USB2_CPU0_P0_R2_DP      B @T6G_MB_LIB.T6G(SCH_1):USB2_CPU0_P0_R2_DP

Q_RES_0201LF-0,5%,1/20W,CHIP,CS00001JE10  I4  R6193
   1 USB2_CPU0_P0_DN      A @T6G_MB_LIB.T6G(SCH_1):USB2_CPU0_P0_DN
   2 USB2_CPU0_P0_R2_DN      B @T6G_MB_LIB.T6G(SCH_1):USB2_CPU0_P0_R2_DN

Q_RES_0201LF-0,5%,1/20W,CHIP,CS00001JE10  I5  R6191
   1 USB2_CPU0_P0_DN      A @T6G_MB_LIB.T6G(SCH_1):USB2_CPU0_P0_DN
   2 USB2_CPU0_P0_R1_DN      B @T6G_MB_LIB.T6G(SCH_1):USB2_CPU0_P0_R1_DN

Q_RES_0201LF-0,5%,1/20W,CHIP,CS00001JE10  I6  R6190
   1 USB2_CPU0_P0_DP      A @T6G_MB_LIB.T6G(SCH_1):USB2_CPU0_P0_DP
   2 USB2_CPU0_P0_R1_DP      B @T6G_MB_LIB.T6G(SCH_1):USB2_CPU0_P0_R1_DP

Q_CAP_DIFFBUS_C0402-DIFF BUS_0.33UF,6.3V,10%,X6S,SA  I49  C6015
   1 USB3_CPU0_BMC_RX_HUB1_DP      1 @T6G_MB_LIB.T6G(SCH_1):USB3_CPU0_BMC_RX_HUB1_DP
   2 USB3_CPU0_BMC_RX_HUB_C_DP      2 @T6G_MB_LIB.T6G(SCH_1):USB3_CPU0_BMC_RX_HUB_C_DP

Q_CAP_DIFFBUS_C0402-DIFF BUS_0.33UF,6.3V,10%,X6S,SA  I50  C6016
   1 USB3_CPU0_BMC_RX_HUB1_DN      1 @T6G_MB_LIB.T6G(SCH_1):USB3_CPU0_BMC_RX_HUB1_DN
   2 USB3_CPU0_BMC_RX_HUB_C_DN      2 @T6G_MB_LIB.T6G(SCH_1):USB3_CPU0_BMC_RX_HUB_C_DN

Q_RES_0201LF-0,5%,1/20W,CHIP,CS00001JE10  I71  R6195
   1 USB2_CPU0_P0_HUB1_R_DN      A @T6G_MB_LIB.T6G(SCH_1):USB2_CPU0_P0_HUB1_R_DN
   2 USB2_HUB_EXT_DN      B @T6G_MB_LIB.T6G(SCH_1):USB2_HUB_EXT_DN

Q_RES_0201LF-0,5%,1/20W,CHIP,CS00001JE10  I72  R6194
   1 USB2_CPU0_P0_HUB1_R_DP      A @T6G_MB_LIB.T6G(SCH_1):USB2_CPU0_P0_HUB1_R_DP
   2 USB2_HUB_EXT_DP      B @T6G_MB_LIB.T6G(SCH_1):USB2_HUB_EXT_DP

Q_RES_0201LF-0,5%,1/20W,CHIP,CS00001JE10  I73  R6196
   1 USB2_CPU0_P0_HUB2_R_DP      A @T6G_MB_LIB.T6G(SCH_1):USB2_CPU0_P0_HUB2_R_DP
   2 USB2_HUB_EXT_DP      B @T6G_MB_LIB.T6G(SCH_1):USB2_HUB_EXT_DP

Q_RES_0201LF-0,5%,1/20W,CHIP,CS00001JE10  I74  R6197
   1 USB2_CPU0_P0_HUB2_R_DN      A @T6G_MB_LIB.T6G(SCH_1):USB2_CPU0_P0_HUB2_R_DN
   2 USB2_HUB_EXT_DN      B @T6G_MB_LIB.T6G(SCH_1):USB2_HUB_EXT_DN

Q_CAP_DIFFBUS_C0402-DIFF BUS_0.33UF,6.3V,10%,X6S,SA  I85  C6019
   1 USB3_CPU0_BMC_RX_DP      1 @T6G_MB_LIB.T6G(SCH_1):USB3_CPU0_BMC_RX_DP
   2 USB3_CPU0_BMC_RX_C1_DP      2 @T6G_MB_LIB.T6G(SCH_1):USB3_CPU0_BMC_RX_C1_DP

Q_CAP_DIFFBUS_C0402-DIFF BUS_0.33UF,6.3V,10%,X6S,SA  I86  C6020
   1 USB3_CPU0_BMC_RX_DN      1 @T6G_MB_LIB.T6G(SCH_1):USB3_CPU0_BMC_RX_DN
   2 USB3_CPU0_BMC_RX_C1_DN      2 @T6G_MB_LIB.T6G(SCH_1):USB3_CPU0_BMC_RX_C1_DN

Q_CAP_DIFFBUS_C0402-DIFF BUS_0.33UF,6.3V,10%,X6S,SA  I87  C6021
   1 USB3_CPU0_BMC_RX_DP      1 @T6G_MB_LIB.T6G(SCH_1):USB3_CPU0_BMC_RX_DP
   2 USB3_CPU0_BMC_RX_C2_DP      2 @T6G_MB_LIB.T6G(SCH_1):USB3_CPU0_BMC_RX_C2_DP

Q_CAP_DIFFBUS_C0402-DIFF BUS_0.33UF,6.3V,10%,X6S,SA  I88  C6022
   1 USB3_CPU0_BMC_RX_DN      1 @T6G_MB_LIB.T6G(SCH_1):USB3_CPU0_BMC_RX_DN
   2 USB3_CPU0_BMC_RX_C2_DN      2 @T6G_MB_LIB.T6G(SCH_1):USB3_CPU0_BMC_RX_C2_DN

Q_RES_0201LF-49.9,1%,1/20W,EMPTY,CS04991FE06  I120  R339
   1 USB2_CPU0_P0_DP      A @T6G_MB_LIB.T6G(SCH_1):USB2_CPU0_P0_DP
   2    GND      B @T6G_MB_LIB.T6G(SCH_1):GND

Q_RES_0201LF-49.9,1%,1/20W,EMPTY,CS04991FE06  I121  R340
   1 USB2_CPU0_P0_DN      A @T6G_MB_LIB.T6G(SCH_1):USB2_CPU0_P0_DN
   2    GND      B @T6G_MB_LIB.T6G(SCH_1):GND

Q_RES_0201LF-49.9,1%,1/20W,EMPTY,CS04991FE06  I124  R345
   1 USB2_CPU0_P0_R2_DN      A @T6G_MB_LIB.T6G(SCH_1):USB2_CPU0_P0_R2_DN
   2    GND      B @T6G_MB_LIB.T6G(SCH_1):GND

Q_RES_0201LF-49.9,1%,1/20W,EMPTY,CS04991FE06  I125  R343
   1 USB2_CPU0_P0_R2_DP      A @T6G_MB_LIB.T6G(SCH_1):USB2_CPU0_P0_R2_DP
   2    GND      B @T6G_MB_LIB.T6G(SCH_1):GND

Q_RES_0201LF-49.9,1%,1/20W,EMPTY,CS04991FE06  I126  R346
   1 USB3_CPU0_BMC_TX_C2_DN      A @T6G_MB_LIB.T6G(SCH_1):USB3_CPU0_BMC_TX_C2_DN
   2    GND      B @T6G_MB_LIB.T6G(SCH_1):GND

Q_RES_0201LF-49.9,1%,1/20W,EMPTY,CS04991FE06  I127  R344
   1 USB3_CPU0_BMC_TX_C2_DP      A @T6G_MB_LIB.T6G(SCH_1):USB3_CPU0_BMC_TX_C2_DP
   2    GND      B @T6G_MB_LIB.T6G(SCH_1):GND

Q_CAP_0402-0.1UF,25V,10%,X7R,CH4104K1B00  I137  C6023
   1 USB3_CPU0_BMC_HUB1_TX_DP      A @T6G_MB_LIB.T6G(SCH_1):USB3_CPU0_BMC_HUB1_TX_DP
   2 USB3_CPU0_BMC_TX_BUF_C_DP      B @T6G_MB_LIB.T6G(SCH_1):USB3_CPU0_BMC_TX_BUF_C_DP

Q_CAP_0402-0.1UF,25V,10%,X7R,CH4104K1B00  I138  C6024
   1 USB3_CPU0_BMC_HUB1_TX_DN      A @T6G_MB_LIB.T6G(SCH_1):USB3_CPU0_BMC_HUB1_TX_DN
   2 USB3_CPU0_BMC_TX_BUF_C_DN      B @T6G_MB_LIB.T6G(SCH_1):USB3_CPU0_BMC_TX_BUF_C_DN

Q_CAP_0402-0.1UF,25V,10%,X7R,CH4104K1B00  I139  C6025
   1 USB3_CPU0_BMC_HUB2_TX_DP      A @T6G_MB_LIB.T6G(SCH_1):USB3_CPU0_BMC_HUB2_TX_DP
   2 USB3_CPU0_BMC_TX_BUF_C_DP      B @T6G_MB_LIB.T6G(SCH_1):USB3_CPU0_BMC_TX_BUF_C_DP

Q_CAP_0402-0.1UF,25V,10%,X7R,CH4104K1B00  I140  C6026
   1 USB3_CPU0_BMC_HUB2_TX_DN      A @T6G_MB_LIB.T6G(SCH_1):USB3_CPU0_BMC_HUB2_TX_DN
   2 USB3_CPU0_BMC_TX_BUF_C_DN      B @T6G_MB_LIB.T6G(SCH_1):USB3_CPU0_BMC_TX_BUF_C_DN

Q_CAP_0402-0.1UF,25V,10%,X7R,CH4104K1B00  I141  C6014
   1 USB3_CPU0_BMC_TX_DN      A @T6G_MB_LIB.T6G(SCH_1):USB3_CPU0_BMC_TX_DN
   2 USB3_CPU0_BMC_TX_C2_DN      B @T6G_MB_LIB.T6G(SCH_1):USB3_CPU0_BMC_TX_C2_DN

Q_CAP_0402-0.1UF,25V,10%,X7R,CH4104K1B00  I142  C6013
   1 USB3_CPU0_BMC_TX_DP      A @T6G_MB_LIB.T6G(SCH_1):USB3_CPU0_BMC_TX_DP
   2 USB3_CPU0_BMC_TX_C2_DP      B @T6G_MB_LIB.T6G(SCH_1):USB3_CPU0_BMC_TX_C2_DP

Q_CAP_0402-0.1UF,25V,10%,X7R,CH4104K1B00  I143  C6004
   1 USB3_CPU0_BMC_TX_DN      A @T6G_MB_LIB.T6G(SCH_1):USB3_CPU0_BMC_TX_DN
   2 USB3_CPU0_BMC_TX_C1_DN      B @T6G_MB_LIB.T6G(SCH_1):USB3_CPU0_BMC_TX_C1_DN

Q_CAP_0402-0.1UF,25V,10%,X7R,CH4104K1B00  I144  C6003
   1 USB3_CPU0_BMC_TX_DP      A @T6G_MB_LIB.T6G(SCH_1):USB3_CPU0_BMC_TX_DP
   2 USB3_CPU0_BMC_TX_C1_DP      B @T6G_MB_LIB.T6G(SCH_1):USB3_CPU0_BMC_TX_C1_DP

Q_RES_0402LF-51,5%,1/16W,EMPTY,CS05102JB04  I145  R341
   1 USB3_CPU0_BMC_TX_DP      A @T6G_MB_LIB.T6G(SCH_1):USB3_CPU0_BMC_TX_DP
   2    GND      B @T6G_MB_LIB.T6G(SCH_1):GND

Q_RES_0402LF-51,5%,1/16W,EMPTY,CS05102JB04  I146  R342
   1 USB3_CPU0_BMC_TX_DN      A @T6G_MB_LIB.T6G(SCH_1):USB3_CPU0_BMC_TX_DN
   2    GND      B @T6G_MB_LIB.T6G(SCH_1):GND

Q_CAP_0402-0.1UF,25V,10%,X7R,CH4104K1B00  I147  C6018
   1 USB3_CPU0_BMC_RX_HUB2_DN      A @T6G_MB_LIB.T6G(SCH_1):USB3_CPU0_BMC_RX_HUB2_DN
   2 USB3_CPU0_BMC_RX_HUB_C_DN      B @T6G_MB_LIB.T6G(SCH_1):USB3_CPU0_BMC_RX_HUB_C_DN

Q_CAP_0402-0.1UF,25V,10%,X7R,CH4104K1B00  I148  C6017
   1 USB3_CPU0_BMC_RX_HUB2_DP      A @T6G_MB_LIB.T6G(SCH_1):USB3_CPU0_BMC_RX_HUB2_DP
   2 USB3_CPU0_BMC_RX_HUB_C_DP      B @T6G_MB_LIB.T6G(SCH_1):USB3_CPU0_BMC_RX_HUB_C_DP


DRAWING: @T6G_MB_LIB.T6G(SCH_1):PAGE315 

Q_RES_0402LF-0,5%,1/16W,CHIP,CS00002JB13  I2  R6242
   1 P3V3_AUX      A @T6G_MB_LIB.T6G(SCH_1):P3V3_AUX
   2 P1V8_AUX_VCC      B @T6G_MB_LIB.T6G(SCH_1):P1V8_AUX_VCC

Q_CAP_C0402-100NF,50V,10%,X7R,CH4106K1B01  I5  PC6020
   1 P12V_AUX      A @T6G_MB_LIB.T6G(SCH_1):P12V_AUX
   2    GND      B @T6G_MB_LIB.T6G(SCH_1):GND

Q_INDUCTOR_SMLF-BLM18SN220TN1D/8000MA,IND,CX220TN1A  I7  PL6002
   2 SW_P12V_AUX_P1V8_AUX_FLT      2 @T6G_MB_LIB.T6G(SCH_1):SW_P12V_AUX_P1V8_AUX_FLT
   1 P12V_AUX      1 @T6G_MB_LIB.T6G(SCH_1):P12V_AUX

Q_CAP_C0805-22UF,16V,20%,X6S,CH6223MEA01  I8  PC6012
   1 SW_P12V_AUX_P1V8_AUX_FLT      A @T6G_MB_LIB.T6G(SCH_1):SW_P12V_AUX_P1V8_AUX_FLT
   2    GND      B @T6G_MB_LIB.T6G(SCH_1):GND

Q_CAP_C0805-22UF,16V,20%,X6S,CH6223MEA01  I10  PC6014
   1 SW_P12V_AUX_P1V8_AUX_FLT      A @T6G_MB_LIB.T6G(SCH_1):SW_P12V_AUX_P1V8_AUX_FLT
   2    GND      B @T6G_MB_LIB.T6G(SCH_1):GND

Q_RES_0402LF-10K,1%,1/16W,CHIP,CS31002FB08  I12  PR6003
   1 P1V8_AUX_CS      A @T6G_MB_LIB.T6G(SCH_1):P1V8_AUX_CS
   2    GND      B @T6G_MB_LIB.T6G(SCH_1):GND

Q_CAP_C0402-1UF,25V,10%,X6S,CH5104KEB02  I13  PC6008
   1 P1V8_AUX_VCC      A @T6G_MB_LIB.T6G(SCH_1):P1V8_AUX_VCC
   2    GND      B @T6G_MB_LIB.T6G(SCH_1):GND

Q_RES_0402LF-60.4K,1%,1/16W,CHIP,CS36042FB04  I15  PR6006
   1    GND      A @T6G_MB_LIB.T6G(SCH_1):GND
   2 P1V8_AUX_MODE      B @T6G_MB_LIB.T6G(SCH_1):P1V8_AUX_MODE

MPQ8626GDZ-MPQ8626GD-Z,SMLF,IC,AL008626000  I18  PU6000
   3 SW_P12V_AUX_P1V8_AUX_FLT    VIN @T6G_MB_LIB.T6G(SCH_1):SW_P12V_AUX_P1V8_AUX_FLT
   9 PWRGD_P1V8_AUX  PGOOD @T6G_MB_LIB.T6G(SCH_1):PWRGD_P1V8_AUX
  14    GND  PGND2 @T6G_MB_LIB.T6G(SCH_1):GND
   5 P1V8_AUX_ENABLE     EN @T6G_MB_LIB.T6G(SCH_1):P1V8_AUX_ENABLE
  10 SW_P1V8_AUX_BT    BST @T6G_MB_LIB.T6G(SCH_1):SW_P1V8_AUX_BT
   6 P1V8_AUX_FB     FB @T6G_MB_LIB.T6G(SCH_1):P1V8_AUX_FB
   7    GND   AGND @T6G_MB_LIB.T6G(SCH_1):GND
  13 P1V8_AUX_VCC    VCC @T6G_MB_LIB.T6G(SCH_1):P1V8_AUX_VCC
   1    GND  PGND1 @T6G_MB_LIB.T6G(SCH_1):GND
  11 SW_P1V8_AUX_PH    SW2 @T6G_MB_LIB.T6G(SCH_1):SW_P1V8_AUX_PH
   8 P1V8_AUX_REF TRK_REF @T6G_MB_LIB.T6G(SCH_1):P1V8_AUX_REF
  12 P1V8_AUX_MODE   MODE @T6G_MB_LIB.T6G(SCH_1):P1V8_AUX_MODE
   4 P1V8_AUX_CS     CS @T6G_MB_LIB.T6G(SCH_1):P1V8_AUX_CS
   2 SW_P1V8_AUX_PH    SW1 @T6G_MB_LIB.T6G(SCH_1):SW_P1V8_AUX_PH

Q_CAP_C0402-1UF,25V,10%,X6S,CH5104KEB02  I19  PC6010
   1 SW_P12V_AUX_P1V8_AUX_FLT      A @T6G_MB_LIB.T6G(SCH_1):SW_P12V_AUX_P1V8_AUX_FLT
   2    GND      B @T6G_MB_LIB.T6G(SCH_1):GND

Q_CAP_0402-3300PF,50V,10%,X7R,TMP_QCH2336K1B12  I21  PC384
   1 P1V8_AUX_REF      A @T6G_MB_LIB.T6G(SCH_1):P1V8_AUX_REF
   2    GND      B @T6G_MB_LIB.T6G(SCH_1):GND

Q_RES_0402LF-10K,1%,1/16W,CHIP,CS31002FB08  I23  PR6010
   1 P1V8_AUX_FB      A @T6G_MB_LIB.T6G(SCH_1):P1V8_AUX_FB
   2    GND      B @T6G_MB_LIB.T6G(SCH_1):GND

Q_INDUCTOR_SMLF-3.3UH/6A,IND,CV-3360MZ07  I25  PL6000
   2 P1V8_AUX      2 @T6G_MB_LIB.T6G(SCH_1):P1V8_AUX
   1 SW_P1V8_AUX_PH      1 @T6G_MB_LIB.T6G(SCH_1):SW_P1V8_AUX_PH

Q_CAP_0402-330PF,50V,10%,X7R,CH1336K1B02  I26  PC6019
   1 P1V8_AUX_FB      A @T6G_MB_LIB.T6G(SCH_1):P1V8_AUX_FB
   2 P1V8_AUX      B @T6G_MB_LIB.T6G(SCH_1):P1V8_AUX

Q_CAP_C0402-100NF,50V,10%,X7R,CH4106K1B01  I27  PC6021
   1 P1V8_AUX      A @T6G_MB_LIB.T6G(SCH_1):P1V8_AUX
   2    GND      B @T6G_MB_LIB.T6G(SCH_1):GND

Q_RES_0402LF-20K,1%,1/16W,CHIP,CS32002FB06  I28  PR6007
   1 P1V8_AUX_FB      A @T6G_MB_LIB.T6G(SCH_1):P1V8_AUX_FB
   2 P1V8_AUX      B @T6G_MB_LIB.T6G(SCH_1):P1V8_AUX

Q_CAP_C0805-22UF,4V,20%,X6S,CH622KMEA03  I29  PC865
   1 P1V8_AUX      A @T6G_MB_LIB.T6G(SCH_1):P1V8_AUX
   2    GND      B @T6G_MB_LIB.T6G(SCH_1):GND

Q_CAP_C0402-0.22UF,25V,10%,X7R,CH4224K1B01  I30  PC641
   1 SW_P1V8_AUX_BT_R      A @T6G_MB_LIB.T6G(SCH_1):SW_P1V8_AUX_BT_R
   2 SW_P1V8_AUX_PH      B @T6G_MB_LIB.T6G(SCH_1):SW_P1V8_AUX_PH

Q_RES_0402LF-10K,1%,1/16W,CHIP,CS31002FB08  I32  R6243
   1 P3V3_AUX      A @T6G_MB_LIB.T6G(SCH_1):P3V3_AUX
   2 PWRGD_P1V8_AUX      B @T6G_MB_LIB.T6G(SCH_1):PWRGD_P1V8_AUX

Q_CAP_C0805-22UF,4V,20%,X6S,CH622KMEA03  I34  PC866
   1 P1V8_AUX      A @T6G_MB_LIB.T6G(SCH_1):P1V8_AUX
   2    GND      B @T6G_MB_LIB.T6G(SCH_1):GND

Q_CAP_C0805-22UF,4V,20%,X6S,CH622KMEA03  I36  PC867
   1 P1V8_AUX      A @T6G_MB_LIB.T6G(SCH_1):P1V8_AUX
   2    GND      B @T6G_MB_LIB.T6G(SCH_1):GND

Q_CAP_C0805-22UF,4V,20%,X6S,CH622KMEA03  I37  PC850
   1 P1V8_AUX      A @T6G_MB_LIB.T6G(SCH_1):P1V8_AUX
   2    GND      B @T6G_MB_LIB.T6G(SCH_1):GND

Q_RES_0402LF-0,5%,1/16W,CHIP,CS00002JB13  I40  R6119
   1 PWRGD_P3V3_AUX      A @T6G_MB_LIB.T6G(SCH_1):PWRGD_P3V3_AUX
   2 P1V8_AUX_ENABLE      B @T6G_MB_LIB.T6G(SCH_1):P1V8_AUX_ENABLE

Q_CAP_0402-0.1UF,25V,10%,EMPTY,CH4104K1B00  I41  C345
   1 P1V8_AUX_ENABLE      A @T6G_MB_LIB.T6G(SCH_1):P1V8_AUX_ENABLE
   2    GND      B @T6G_MB_LIB.T6G(SCH_1):GND

Q_RES_0402LF-33,5%,1/16W,CHIP,CS03302JB10  I44  R214
   1 PWRGD_P1V8_AUX      A @T6G_MB_LIB.T6G(SCH_1):PWRGD_P1V8_AUX
   2 PWRGD_P1V8_AUX_R      B @T6G_MB_LIB.T6G(SCH_1):PWRGD_P1V8_AUX_R

Q_RES_0402LF-2.2,1%,1/16W,CHIP,CS-2202FB01  I45  PR8003
   1 SW_P1V8_AUX_BT      A @T6G_MB_LIB.T6G(SCH_1):SW_P1V8_AUX_BT
   2 SW_P1V8_AUX_BT_R      B @T6G_MB_LIB.T6G(SCH_1):SW_P1V8_AUX_BT_R


DRAWING: @T6G_MB_LIB.T6G(SCH_1):PAGE380 

Q_INDUCTOR_SMLF-BLM18SN220TN1D/8000MA,IND,CX220TN1A  I2  PL6003
   2 SW_P12V_AUX_P1V2_AUX_FLT      2 @T6G_MB_LIB.T6G(SCH_1):SW_P12V_AUX_P1V2_AUX_FLT
   1 P12V_AUX      1 @T6G_MB_LIB.T6G(SCH_1):P12V_AUX

Q_CAP_C0805-22UF,16V,20%,X6S,CH6223MEA01  I3  PC6013
   1 SW_P12V_AUX_P1V2_AUX_FLT      A @T6G_MB_LIB.T6G(SCH_1):SW_P12V_AUX_P1V2_AUX_FLT
   2    GND      B @T6G_MB_LIB.T6G(SCH_1):GND

Q_RES_0402LF-11.5K,1%,1/16W,CHIP,CS31152FB03  I6  PR6004
   1 P1V2_AUX_CS      A @T6G_MB_LIB.T6G(SCH_1):P1V2_AUX_CS
   2    GND      B @T6G_MB_LIB.T6G(SCH_1):GND

Q_CAP_C0402-1UF,25V,10%,X6S,CH5104KEB02  I7  PC6009
   1 P1V2_AUX_VCC      A @T6G_MB_LIB.T6G(SCH_1):P1V2_AUX_VCC
   2    GND      B @T6G_MB_LIB.T6G(SCH_1):GND

Q_CAP_C0805-22UF,16V,20%,X6S,CH6223MEA01  I10  PC6015
   1 SW_P12V_AUX_P1V2_AUX_FLT      A @T6G_MB_LIB.T6G(SCH_1):SW_P12V_AUX_P1V2_AUX_FLT
   2    GND      B @T6G_MB_LIB.T6G(SCH_1):GND

Q_RES_0402LF-60.4K,1%,1/16W,CHIP,CS36042FB04  I11  PR6005
   1    GND      A @T6G_MB_LIB.T6G(SCH_1):GND
   2 P1V2_AUX_MODE      B @T6G_MB_LIB.T6G(SCH_1):P1V2_AUX_MODE

Q_CAP_C0402-1UF,25V,10%,X6S,CH5104KEB02  I12  PC6011
   1 SW_P12V_AUX_P1V2_AUX_FLT      A @T6G_MB_LIB.T6G(SCH_1):SW_P12V_AUX_P1V2_AUX_FLT
   2    GND      B @T6G_MB_LIB.T6G(SCH_1):GND

MPQ8626GDZ-MPQ8626GD-Z,SMLF,IC,AL008626000  I16  PU6001
   3 SW_P12V_AUX_P1V2_AUX_FLT    VIN @T6G_MB_LIB.T6G(SCH_1):SW_P12V_AUX_P1V2_AUX_FLT
   9 PWRGD_P1V2_AUX  PGOOD @T6G_MB_LIB.T6G(SCH_1):PWRGD_P1V2_AUX
  14    GND  PGND2 @T6G_MB_LIB.T6G(SCH_1):GND
   5 P1V2_AUX_ENABLE     EN @T6G_MB_LIB.T6G(SCH_1):P1V2_AUX_ENABLE
  10 SW_P1V2_AUX_BT    BST @T6G_MB_LIB.T6G(SCH_1):SW_P1V2_AUX_BT
   6 P1V2_AUX_FB     FB @T6G_MB_LIB.T6G(SCH_1):P1V2_AUX_FB
   7    GND   AGND @T6G_MB_LIB.T6G(SCH_1):GND
  13 P1V2_AUX_VCC    VCC @T6G_MB_LIB.T6G(SCH_1):P1V2_AUX_VCC
   1    GND  PGND1 @T6G_MB_LIB.T6G(SCH_1):GND
  11 SW_P1V2_AUX_PH    SW2 @T6G_MB_LIB.T6G(SCH_1):SW_P1V2_AUX_PH
   8 P1V2_AUX_REF TRK_REF @T6G_MB_LIB.T6G(SCH_1):P1V2_AUX_REF
  12 P1V2_AUX_MODE   MODE @T6G_MB_LIB.T6G(SCH_1):P1V2_AUX_MODE
   4 P1V2_AUX_CS     CS @T6G_MB_LIB.T6G(SCH_1):P1V2_AUX_CS
   2 SW_P1V2_AUX_PH    SW1 @T6G_MB_LIB.T6G(SCH_1):SW_P1V2_AUX_PH

Q_CAP_0402-3300PF,50V,10%,X7R,TMP_QCH2336K1B12  I17  PC6016
   1 P1V2_AUX_REF      A @T6G_MB_LIB.T6G(SCH_1):P1V2_AUX_REF
   2    GND      B @T6G_MB_LIB.T6G(SCH_1):GND

Q_CAP_C0402-0.22UF,25V,10%,X7R,CH4224K1B01  I18  PC6017
   1 SW_P1V2_AUX_BT_R      A @T6G_MB_LIB.T6G(SCH_1):SW_P1V2_AUX_BT_R
   2 SW_P1V2_AUX_PH      B @T6G_MB_LIB.T6G(SCH_1):SW_P1V2_AUX_PH

Q_RES_0402LF-10K,1%,1/16W,CHIP,CS31002FB08  I19  R6244
   1 P3V3_AUX      A @T6G_MB_LIB.T6G(SCH_1):P3V3_AUX
   2 PWRGD_P1V2_AUX      B @T6G_MB_LIB.T6G(SCH_1):PWRGD_P1V2_AUX

Q_RES_0402LF-10K,1%,1/16W,CHIP,CS31002FB08  I21  PR6011
   1 P1V2_AUX_FB      A @T6G_MB_LIB.T6G(SCH_1):P1V2_AUX_FB
   2    GND      B @T6G_MB_LIB.T6G(SCH_1):GND

Q_CAP_C0402-100NF,50V,10%,X7R,CH4106K1B01  I23  PC6022
   1 P1V2_AUX      A @T6G_MB_LIB.T6G(SCH_1):P1V2_AUX
   2    GND      B @T6G_MB_LIB.T6G(SCH_1):GND

Q_INDUCTOR_SMLF-2.2UH,IND,CV-2280MZ15  I24  PL6001
   2 P1V2_AUX      2 @T6G_MB_LIB.T6G(SCH_1):P1V2_AUX
   1 SW_P1V2_AUX_PH      1 @T6G_MB_LIB.T6G(SCH_1):SW_P1V2_AUX_PH

Q_CAP_0402-330PF,50V,10%,X7R,CH1336K1B02  I26  PC852
   1 P1V2_AUX_FB      A @T6G_MB_LIB.T6G(SCH_1):P1V2_AUX_FB
   2 P1V2_AUX      B @T6G_MB_LIB.T6G(SCH_1):P1V2_AUX

Q_RES_0402LF-10K,1%,1/16W,CHIP,CS31002FB08  I27  PR6008
   1 P1V2_AUX_FB      A @T6G_MB_LIB.T6G(SCH_1):P1V2_AUX_FB
   2 P1V2_AUX      B @T6G_MB_LIB.T6G(SCH_1):P1V2_AUX

Q_CAP_C0805-22UF,4V,20%,X6S,CH622KMEA03  I28  PC6024
   1 P1V2_AUX      A @T6G_MB_LIB.T6G(SCH_1):P1V2_AUX
   2    GND      B @T6G_MB_LIB.T6G(SCH_1):GND

Q_CAP_C0805-22UF,4V,20%,X6S,CH622KMEA03  I29  PC6025
   1 P1V2_AUX      A @T6G_MB_LIB.T6G(SCH_1):P1V2_AUX
   2    GND      B @T6G_MB_LIB.T6G(SCH_1):GND

Q_CAP_C0805-22UF,4V,20%,X6S,CH622KMEA03  I32  PC6026
   1 P1V2_AUX      A @T6G_MB_LIB.T6G(SCH_1):P1V2_AUX
   2    GND      B @T6G_MB_LIB.T6G(SCH_1):GND

Q_CAP_C0805-22UF,4V,20%,X6S,CH622KMEA03  I33  PC6018
   1 P1V2_AUX      A @T6G_MB_LIB.T6G(SCH_1):P1V2_AUX
   2    GND      B @T6G_MB_LIB.T6G(SCH_1):GND

Q_CAP_C0402-100NF,50V,10%,X7R,CH4106K1B01  I35  PC6023
   1 P12V_AUX      A @T6G_MB_LIB.T6G(SCH_1):P12V_AUX
   2    GND      B @T6G_MB_LIB.T6G(SCH_1):GND

Q_RES_0402LF-0,5%,1/16W,CHIP,CS00002JB13  I38  R6245
   1 P3V3_AUX      A @T6G_MB_LIB.T6G(SCH_1):P3V3_AUX
   2 P1V2_AUX_VCC      B @T6G_MB_LIB.T6G(SCH_1):P1V2_AUX_VCC

Q_RES_0402LF-0,5%,1/16W,CHIP,CS00002JB13  I40  R6240
   1 PWRGD_P1V8_AUX_R      A @T6G_MB_LIB.T6G(SCH_1):PWRGD_P1V8_AUX_R
   2 P1V2_AUX_ENABLE      B @T6G_MB_LIB.T6G(SCH_1):P1V2_AUX_ENABLE

Q_CAP_0402-0.1UF,25V,10%,EMPTY,CH4104K1B00  I41  C6085
   1 PWRGD_P1V8_AUX_R      A @T6G_MB_LIB.T6G(SCH_1):PWRGD_P1V8_AUX_R
   2    GND      B @T6G_MB_LIB.T6G(SCH_1):GND

Q_RES_0402LF-0,5%,1/16W,CHIP,CS00002JB13  I44  R6241
   1 PWRGD_P1V2_AUX      A @T6G_MB_LIB.T6G(SCH_1):PWRGD_P1V2_AUX
   2 PWRGD_P1V2_AUX_R      B @T6G_MB_LIB.T6G(SCH_1):PWRGD_P1V2_AUX_R

Q_RES_0402LF-2.2,1%,1/16W,CHIP,CS-2202FB01  I45  PR8004
   1 SW_P1V2_AUX_BT      A @T6G_MB_LIB.T6G(SCH_1):SW_P1V2_AUX_BT
   2 SW_P1V2_AUX_BT_R      B @T6G_MB_LIB.T6G(SCH_1):SW_P1V2_AUX_BT_R


DRAWING: @T6G_MB_LIB.T6G(SCH_1):PAGE157 

Q_INDUCTOR_SMLF-BLM21PG221SN1D,IND,CX1PG221001  I17  L6003
   2 P3V3_AUX_CPU0_USB2_AVDD33      2 @T6G_MB_LIB.T6G(SCH_1):P3V3_AUX_CPU0_USB2_AVDD33
   1 P3V3_AUX      1 @T6G_MB_LIB.T6G(SCH_1):P3V3_AUX

Q_INDUCTOR_SMLF-BLM21PG221SN1D,IND,CX1PG221001  I20  L6004
   2 P1V2_CPU0_USB2_DVDD12      2 @T6G_MB_LIB.T6G(SCH_1):P1V2_CPU0_USB2_DVDD12
   1 P1V2_AUX      1 @T6G_MB_LIB.T6G(SCH_1):P1V2_AUX

Q_CAP_C0402-1UF,25V,10%,X6S,CH5104KEB02  I21  C6092
   1 P3V3_AUX_CPU0_USB2_AVDD33      A @T6G_MB_LIB.T6G(SCH_1):P3V3_AUX_CPU0_USB2_AVDD33
   2    GND      B @T6G_MB_LIB.T6G(SCH_1):GND

Q_CAP_C0402-0.01UF,50V,10%,X7R,CH31006KB18  I22  C6094
   1 P3V3_AUX_CPU0_USB2_AVDD33      A @T6G_MB_LIB.T6G(SCH_1):P3V3_AUX_CPU0_USB2_AVDD33
   2    GND      B @T6G_MB_LIB.T6G(SCH_1):GND

Q_CAP_0402-0.1UF,25V,10%,X7R,CH4104K1B00  I23  C6095
   1 P3V3_AUX_CPU0_USB2_AVDD33      A @T6G_MB_LIB.T6G(SCH_1):P3V3_AUX_CPU0_USB2_AVDD33
   2    GND      B @T6G_MB_LIB.T6G(SCH_1):GND

Q_CAP_C0402-1PF,50V,0.05P,COG,CH-106T0B00  I24  C6093
   1 P3V3_AUX_CPU0_USB2_AVDD33      A @T6G_MB_LIB.T6G(SCH_1):P3V3_AUX_CPU0_USB2_AVDD33
   2    GND      B @T6G_MB_LIB.T6G(SCH_1):GND

Q_CAP_0402-0.1UF,25V,10%,X7R,CH4104K1B00  I25  C6098
   1 P3V3_AUX_CPU0_USB2_AVDD33      A @T6G_MB_LIB.T6G(SCH_1):P3V3_AUX_CPU0_USB2_AVDD33
   2    GND      B @T6G_MB_LIB.T6G(SCH_1):GND

Q_CAP_C0402-0.01UF,50V,10%,X7R,CH31006KB18  I26  C6097
   1 P3V3_AUX_CPU0_USB2_AVDD33      A @T6G_MB_LIB.T6G(SCH_1):P3V3_AUX_CPU0_USB2_AVDD33
   2    GND      B @T6G_MB_LIB.T6G(SCH_1):GND

Q_CAP_C0402-1PF,50V,0.05P,COG,CH-106T0B00  I27  C6096
   1 P3V3_AUX_CPU0_USB2_AVDD33      A @T6G_MB_LIB.T6G(SCH_1):P3V3_AUX_CPU0_USB2_AVDD33
   2    GND      B @T6G_MB_LIB.T6G(SCH_1):GND

Q_CAP_0402-0.1UF,25V,10%,X7R,CH4104K1B00  I28  C6101
   1 P3V3_AUX_CPU0_USB2_AVDD33      A @T6G_MB_LIB.T6G(SCH_1):P3V3_AUX_CPU0_USB2_AVDD33
   2    GND      B @T6G_MB_LIB.T6G(SCH_1):GND

Q_CAP_C0402-0.01UF,50V,10%,X7R,CH31006KB18  I29  C6100
   1 P3V3_AUX_CPU0_USB2_AVDD33      A @T6G_MB_LIB.T6G(SCH_1):P3V3_AUX_CPU0_USB2_AVDD33
   2    GND      B @T6G_MB_LIB.T6G(SCH_1):GND

Q_CAP_C0402-1PF,50V,0.05P,COG,CH-106T0B00  I30  C6099
   1 P3V3_AUX_CPU0_USB2_AVDD33      A @T6G_MB_LIB.T6G(SCH_1):P3V3_AUX_CPU0_USB2_AVDD33
   2    GND      B @T6G_MB_LIB.T6G(SCH_1):GND

Q_CAP_0402-0.1UF,25V,10%,X7R,CH4104K1B00  I31  C6104
   1 P3V3_AUX_CPU0_USB2_AVDD33      A @T6G_MB_LIB.T6G(SCH_1):P3V3_AUX_CPU0_USB2_AVDD33
   2    GND      B @T6G_MB_LIB.T6G(SCH_1):GND

Q_CAP_C0402-0.01UF,50V,10%,X7R,CH31006KB18  I32  C6103
   1 P3V3_AUX_CPU0_USB2_AVDD33      A @T6G_MB_LIB.T6G(SCH_1):P3V3_AUX_CPU0_USB2_AVDD33
   2    GND      B @T6G_MB_LIB.T6G(SCH_1):GND

Q_CAP_C0402-1PF,50V,0.05P,COG,CH-106T0B00  I33  C6102
   1 P3V3_AUX_CPU0_USB2_AVDD33      A @T6G_MB_LIB.T6G(SCH_1):P3V3_AUX_CPU0_USB2_AVDD33
   2    GND      B @T6G_MB_LIB.T6G(SCH_1):GND

Q_CAP_C0805-10UF,25V,10%,X6S,CH6104KEA00  I36  C6105
   1 P1V2_CPU0_USB2_DVDD12      A @T6G_MB_LIB.T6G(SCH_1):P1V2_CPU0_USB2_DVDD12
   2    GND      B @T6G_MB_LIB.T6G(SCH_1):GND

Q_CAP_0402-0.1UF,25V,10%,X7R,CH4104K1B00  I39  C6108
   1 P1V2_CPU0_USB2_DVDD12      A @T6G_MB_LIB.T6G(SCH_1):P1V2_CPU0_USB2_DVDD12
   2    GND      B @T6G_MB_LIB.T6G(SCH_1):GND

Q_CAP_C0402-0.01UF,50V,10%,X7R,CH31006KB18  I40  C6107
   1 P1V2_CPU0_USB2_DVDD12      A @T6G_MB_LIB.T6G(SCH_1):P1V2_CPU0_USB2_DVDD12
   2    GND      B @T6G_MB_LIB.T6G(SCH_1):GND

Q_CAP_C0402-1PF,50V,0.05P,COG,CH-106T0B00  I41  C6106
   1 P1V2_CPU0_USB2_DVDD12      A @T6G_MB_LIB.T6G(SCH_1):P1V2_CPU0_USB2_DVDD12
   2    GND      B @T6G_MB_LIB.T6G(SCH_1):GND

Q_CAP_0402-0.1UF,25V,10%,X7R,CH4104K1B00  I42  C6111
   1 P1V2_CPU0_USB2_DVDD12      A @T6G_MB_LIB.T6G(SCH_1):P1V2_CPU0_USB2_DVDD12
   2    GND      B @T6G_MB_LIB.T6G(SCH_1):GND

Q_CAP_C0402-0.01UF,50V,10%,X7R,CH31006KB18  I43  C6110
   1 P1V2_CPU0_USB2_DVDD12      A @T6G_MB_LIB.T6G(SCH_1):P1V2_CPU0_USB2_DVDD12
   2    GND      B @T6G_MB_LIB.T6G(SCH_1):GND

Q_CAP_C0402-1PF,50V,0.05P,COG,CH-106T0B00  I44  C6109
   1 P1V2_CPU0_USB2_DVDD12      A @T6G_MB_LIB.T6G(SCH_1):P1V2_CPU0_USB2_DVDD12
   2    GND      B @T6G_MB_LIB.T6G(SCH_1):GND

Q_CAP_0402-0.1UF,25V,10%,X7R,CH4104K1B00  I45  C6114
   1 P1V2_CPU0_USB2_DVDD12      A @T6G_MB_LIB.T6G(SCH_1):P1V2_CPU0_USB2_DVDD12
   2    GND      B @T6G_MB_LIB.T6G(SCH_1):GND

Q_CAP_C0402-0.01UF,50V,10%,X7R,CH31006KB18  I46  C6113
   1 P1V2_CPU0_USB2_DVDD12      A @T6G_MB_LIB.T6G(SCH_1):P1V2_CPU0_USB2_DVDD12
   2    GND      B @T6G_MB_LIB.T6G(SCH_1):GND

Q_CAP_C0402-1PF,50V,0.05P,COG,CH-106T0B00  I47  C6112
   1 P1V2_CPU0_USB2_DVDD12      A @T6G_MB_LIB.T6G(SCH_1):P1V2_CPU0_USB2_DVDD12
   2    GND      B @T6G_MB_LIB.T6G(SCH_1):GND

Q_CAP_0402-0.1UF,25V,10%,X7R,CH4104K1B00  I48  C6117
   1 P1V2_CPU0_USB2_DVDD12      A @T6G_MB_LIB.T6G(SCH_1):P1V2_CPU0_USB2_DVDD12
   2    GND      B @T6G_MB_LIB.T6G(SCH_1):GND

Q_CAP_C0402-0.01UF,50V,10%,X7R,CH31006KB18  I49  C6116
   1 P1V2_CPU0_USB2_DVDD12      A @T6G_MB_LIB.T6G(SCH_1):P1V2_CPU0_USB2_DVDD12
   2    GND      B @T6G_MB_LIB.T6G(SCH_1):GND

Q_CAP_C0402-1PF,50V,0.05P,COG,CH-106T0B00  I50  C6115
   1 P1V2_CPU0_USB2_DVDD12      A @T6G_MB_LIB.T6G(SCH_1):P1V2_CPU0_USB2_DVDD12
   2    GND      B @T6G_MB_LIB.T6G(SCH_1):GND

Q_CAP_0402-0.1UF,25V,10%,X7R,CH4104K1B00  I51  C6121
   1 P1V2_CPU0_USB2_DVDD12      A @T6G_MB_LIB.T6G(SCH_1):P1V2_CPU0_USB2_DVDD12
   2    GND      B @T6G_MB_LIB.T6G(SCH_1):GND

Q_CAP_C0402-0.01UF,50V,10%,X7R,CH31006KB18  I52  C6120
   1 P1V2_CPU0_USB2_DVDD12      A @T6G_MB_LIB.T6G(SCH_1):P1V2_CPU0_USB2_DVDD12
   2    GND      B @T6G_MB_LIB.T6G(SCH_1):GND

Q_CAP_C0402-1PF,50V,0.05P,COG,CH-106T0B00  I53  C6119
   1 P1V2_CPU0_USB2_DVDD12      A @T6G_MB_LIB.T6G(SCH_1):P1V2_CPU0_USB2_DVDD12
   2    GND      B @T6G_MB_LIB.T6G(SCH_1):GND

Q_CAP_C0805-10UF,25V,10%,X6S,CH6104KEA00  I54  C6118
   1 P1V2_CPU0_USB2_DVDD12      A @T6G_MB_LIB.T6G(SCH_1):P1V2_CPU0_USB2_DVDD12
   2    GND      B @T6G_MB_LIB.T6G(SCH_1):GND

Q_RES_0402LF-1K,1%,1/16W,EMPTY,CS21002FB06  I63  R6283
   1 P3V3_AUX      A @T6G_MB_LIB.T6G(SCH_1):P3V3_AUX
   2 USB_HUB2_TI_FULLPWRMGMTZ_MRP_PROG_FUNC3      B @T6G_MB_LIB.T6G(SCH_1):USB_HUB2_TI_FULLPWRMGMTZ_MRP_PROG_FUNC3

Q_RES_0402LF-0,5%,1/16W,CHIP,CS00002JB13  I75  R6291
   1 USB_HUB2_TI_GANGED_MRP_I2C_SLV_CFG0      A @T6G_MB_LIB.T6G(SCH_1):USB_HUB2_TI_GANGED_MRP_I2C_SLV_CFG0
   2 USB_HUB2_MRP_I2C_SLV_CFG0      B @T6G_MB_LIB.T6G(SCH_1):USB_HUB2_MRP_I2C_SLV_CFG0

Q_RES_0402LF-0,5%,1/16W,CHIP,CS00002JB13  I76  R6290
   1 USB_HUB2_TI_GANGED_MRP_I2C_SLV_CFG0      A @T6G_MB_LIB.T6G(SCH_1):USB_HUB2_TI_GANGED_MRP_I2C_SLV_CFG0
   2 USB_HUB2_TI_GANGED      B @T6G_MB_LIB.T6G(SCH_1):USB_HUB2_TI_GANGED

Q_RES_0402LF-1K,1%,1/16W,EMPTY,CS21002FB06  I77  R6292
   1 P3V3_AUX      A @T6G_MB_LIB.T6G(SCH_1):P3V3_AUX
   2 USB_HUB2_TI_GANGED      B @T6G_MB_LIB.T6G(SCH_1):USB_HUB2_TI_GANGED

Q_RES_0402LF-4.7K,1%,1/16W,CHIP,CS24702FB06  I79  R6293
   1 USB_HUB2_TI_GANGED      A @T6G_MB_LIB.T6G(SCH_1):USB_HUB2_TI_GANGED
   2    GND      B @T6G_MB_LIB.T6G(SCH_1):GND

Q_RES_0402LF-10K,1%,1/16W,CHIP,CS31002FB08  I81  R6294
   1 P3V3_AUX      A @T6G_MB_LIB.T6G(SCH_1):P3V3_AUX
   2 USB_HUB2_MRP_I2C_SLV_CFG0      B @T6G_MB_LIB.T6G(SCH_1):USB_HUB2_MRP_I2C_SLV_CFG0

TUSB8042AIRGCR-TUSB8042AIRGCR,SMLF,IC,AL008042000  I119  U6002
  13 P1V2_CPU0_USB2_DVDD12 VDD_13 @T6G_MB_LIB.T6G(SCH_1):P1V2_CPU0_USB2_DVDD12
  37 SMB_USB_HUB2_TI_SDA_MRP_PRT_CTL2 SDA||SMBDAT @T6G_MB_LIB.T6G(SCH_1):SMB_USB_HUB2_TI_SDA_MRP_PRT_CTL2
  28 USB_HUB2_TI_VDD_MRP_USB3DN_TXDP4 VDD_28 @T6G_MB_LIB.T6G(SCH_1):USB_HUB2_TI_VDD_MRP_USB3DN_TXDP4
  16 USB_HUB2_TI_VDD33_MRP_PROG_FUNC7 VDD33_16 @T6G_MB_LIB.T6G(SCH_1):USB_HUB2_TI_VDD33_MRP_PROG_FUNC7
  34 USB_HUB2_TI_VDD33_MRP_PRT_CTL4_GANGPWR VDD33_34 @T6G_MB_LIB.T6G(SCH_1):USB_HUB2_TI_VDD33_MRP_PRT_CTL4_GANGPWR
  52 P3V3_AUX_CPU0_USB2_AVDD33 VDD33_52 @T6G_MB_LIB.T6G(SCH_1):P3V3_AUX_CPU0_USB2_AVDD33
  40 USB_HUB2_TI_FULLPWRMGMTZ_MRP_PROG_FUNC3 FULLPWRMGMTZ||FULLAUTOZ||SMBA1||SS_UP @T6G_MB_LIB.T6G(SCH_1):USB_HUB2_TI_FULLPWRMGMTZ_MRP_PROG_FUNC3
  42 USB_HUB2_TI_GANGED_MRP_I2C_SLV_CFG0 GANGED||SMBA2||HS_UP @T6G_MB_LIB.T6G(SCH_1):USB_HUB2_TI_GANGED_MRP_I2C_SLV_CFG0
  38 SMB_USB_HUB2_TI_SCL_MRP_PRT_CTL1 SCL||SMBCLK @T6G_MB_LIB.T6G(SCH_1):SMB_USB_HUB2_TI_SCL_MRP_PRT_CTL1
  39 USB_HUB2_TI_SMBUSZ_MRP_PROG_FUNC2 SMBUSZ||SS_SUSPEND @T6G_MB_LIB.T6G(SCH_1):USB_HUB2_TI_SMBUSZ_MRP_PROG_FUNC2
  63 P3V3_AUX_CPU0_USB2_AVDD33 VDD33_63 @T6G_MB_LIB.T6G(SCH_1):P3V3_AUX_CPU0_USB2_AVDD33
  51 P1V2_CPU0_USB2_DVDD12 VDD_51 @T6G_MB_LIB.T6G(SCH_1):P1V2_CPU0_USB2_DVDD12
  45 USB_HUB2_TI_HS_SUSPEND_MRP_CFG_NON_REM AUTOENZ||HS_SUSPEND @T6G_MB_LIB.T6G(SCH_1):USB_HUB2_TI_HS_SUSPEND_MRP_CFG_NON_REM
   8 USB_HUB2_TI_VDD_MRP_USB3DN_RXDM1  VDD_8 @T6G_MB_LIB.T6G(SCH_1):USB_HUB2_TI_VDD_MRP_USB3DN_RXDM1
   5 USB_HUB2_TI_VDD_MRP_USB3DN_TXDM1  VDD_5 @T6G_MB_LIB.T6G(SCH_1):USB_HUB2_TI_VDD_MRP_USB3DN_TXDM1
  57 P1V2_CPU0_USB2_DVDD12 VDD_57 @T6G_MB_LIB.T6G(SCH_1):P1V2_CPU0_USB2_DVDD12
  21 USB_HUB2_TI_VDD_MRP_USB3DN_TXDP3 VDD_21 @T6G_MB_LIB.T6G(SCH_1):USB_HUB2_TI_VDD_MRP_USB3DN_TXDP3
  31 USB_HUB2_TI_VDD_MRP_USB3DN_RXDP4 VDD_31 @T6G_MB_LIB.T6G(SCH_1):USB_HUB2_TI_VDD_MRP_USB3DN_RXDP4
  61 XTAL_USB_CPU0_HUB2_XOUT     XO @T6G_MB_LIB.T6G(SCH_1):XTAL_USB_CPU0_HUB2_XOUT
  62 XTAL_USB_CPU0_HUB2_XIN     XI @T6G_MB_LIB.T6G(SCH_1):XTAL_USB_CPU0_HUB2_XIN

Q_RES_0402LF-0,5%,1/16W,CHIP,CS00002JB13  I122  R6267
   1 USB_HUB2_TI_VDD_MRP_USB3DN_TXDP4      A @T6G_MB_LIB.T6G(SCH_1):USB_HUB2_TI_VDD_MRP_USB3DN_TXDP4
   2 P1V2_CPU0_USB2_DVDD12      B @T6G_MB_LIB.T6G(SCH_1):P1V2_CPU0_USB2_DVDD12

Q_RES_0402LF-10K,1%,1/16W,EMPTY,CS31002FB08  I124  R6278
   1 USB_HUB2_MRP_PRT_CTL4_GANGPWR      A @T6G_MB_LIB.T6G(SCH_1):USB_HUB2_MRP_PRT_CTL4_GANGPWR
   2    GND      B @T6G_MB_LIB.T6G(SCH_1):GND

Q_RES_0402LF-0,5%,1/16W,CHIP,CS00002JB13  I125  R6276
   1 USB_HUB2_TI_VDD33_MRP_PRT_CTL4_GANGPWR      A @T6G_MB_LIB.T6G(SCH_1):USB_HUB2_TI_VDD33_MRP_PRT_CTL4_GANGPWR
   2 USB_HUB2_MRP_PRT_CTL4_GANGPWR      B @T6G_MB_LIB.T6G(SCH_1):USB_HUB2_MRP_PRT_CTL4_GANGPWR

Q_RES_0402LF-10K,1%,1/16W,EMPTY,CS31002FB08  I130  R6277
   1 P3V3_AUX      A @T6G_MB_LIB.T6G(SCH_1):P3V3_AUX
   2 USB_HUB2_MRP_PRT_CTL4_GANGPWR      B @T6G_MB_LIB.T6G(SCH_1):USB_HUB2_MRP_PRT_CTL4_GANGPWR

Q_RES_0402LF-0,5%,1/16W,CHIP,CS00002JB13  I131  R6275
   1 USB_HUB2_TI_VDD33_MRP_PRT_CTL4_GANGPWR      A @T6G_MB_LIB.T6G(SCH_1):USB_HUB2_TI_VDD33_MRP_PRT_CTL4_GANGPWR
   2 P3V3_AUX_CPU0_USB2_AVDD33      B @T6G_MB_LIB.T6G(SCH_1):P3V3_AUX_CPU0_USB2_AVDD33

Q_RES_0402LF-0,5%,1/16W,CHIP,CS00002JB13  I134  R6262
   1 USB_HUB2_TI_VDD_MRP_USB3DN_RXDM1      A @T6G_MB_LIB.T6G(SCH_1):USB_HUB2_TI_VDD_MRP_USB3DN_RXDM1
   2 P1V2_CPU0_USB2_DVDD12      B @T6G_MB_LIB.T6G(SCH_1):P1V2_CPU0_USB2_DVDD12

Q_RES_0402LF-0,5%,1/16W,CHIP,CS00002JB13  I136  R6269
   1 USB_HUB2_TI_VDD_MRP_USB3DN_RXDP4      A @T6G_MB_LIB.T6G(SCH_1):USB_HUB2_TI_VDD_MRP_USB3DN_RXDP4
   2 P1V2_CPU0_USB2_DVDD12      B @T6G_MB_LIB.T6G(SCH_1):P1V2_CPU0_USB2_DVDD12

Q_RES_0402LF-1K,1%,1/16W,EMPTY,CS21002FB06  I138  R6282
   1 P3V3_AUX      A @T6G_MB_LIB.T6G(SCH_1):P3V3_AUX
   2 USB_HUB2_TI_SMBUSZ_MRP_PROG_FUNC2      B @T6G_MB_LIB.T6G(SCH_1):USB_HUB2_TI_SMBUSZ_MRP_PROG_FUNC2

Q_RES_0402LF-1K,1%,1/16W,EMPTY,CS21002FB06  I139  R6281
   1 USB_HUB2_TI_SMBUSZ_MRP_PROG_FUNC2      A @T6G_MB_LIB.T6G(SCH_1):USB_HUB2_TI_SMBUSZ_MRP_PROG_FUNC2
   2    GND      B @T6G_MB_LIB.T6G(SCH_1):GND

Q_RES_0402LF-0,5%,1/16W,CHIP,CS00002JB13  I142  R6274
   1 USB_HUB2_TI_VDD33_MRP_PROG_FUNC7      A @T6G_MB_LIB.T6G(SCH_1):USB_HUB2_TI_VDD33_MRP_PROG_FUNC7
   2 P3V3_AUX_CPU0_USB2_AVDD33      B @T6G_MB_LIB.T6G(SCH_1):P3V3_AUX_CPU0_USB2_AVDD33

Q_RES_0402LF-0,5%,1/16W,CHIP,CS00002JB13  I145  R6265
   1 USB_HUB2_TI_VDD_MRP_USB3DN_TXDP3      A @T6G_MB_LIB.T6G(SCH_1):USB_HUB2_TI_VDD_MRP_USB3DN_TXDP3
   2 P1V2_CPU0_USB2_DVDD12      B @T6G_MB_LIB.T6G(SCH_1):P1V2_CPU0_USB2_DVDD12

Q_RES_0402LF-0,5%,1/16W,CHIP,CS00002JB13  I146  R6280
   1 SMB_USB_CPU0_HUB1_SCL      A @T6G_MB_LIB.T6G(SCH_1):SMB_USB_CPU0_HUB1_SCL
   2 SMB_USB_HUB2_TI_SCL_MRP_PRT_CTL1      B @T6G_MB_LIB.T6G(SCH_1):SMB_USB_HUB2_TI_SCL_MRP_PRT_CTL1

Q_RES_0402LF-0,5%,1/16W,CHIP,CS00002JB13  I148  R6279
   1 SMB_USB_CPU0_HUB1_SDA      A @T6G_MB_LIB.T6G(SCH_1):SMB_USB_CPU0_HUB1_SDA
   2 SMB_USB_HUB2_TI_SDA_MRP_PRT_CTL2      B @T6G_MB_LIB.T6G(SCH_1):SMB_USB_HUB2_TI_SDA_MRP_PRT_CTL2

Q_RES_0402LF-0,5%,1/16W,CHIP,CS00002JB13  I150  R6305
   1 USB_HUB2_MRP_CFG_NON_REM      A @T6G_MB_LIB.T6G(SCH_1):USB_HUB2_MRP_CFG_NON_REM
   2 USB_HUB2_TI_HS_SUSPEND_MRP_CFG_NON_REM      B @T6G_MB_LIB.T6G(SCH_1):USB_HUB2_TI_HS_SUSPEND_MRP_CFG_NON_REM

Q_RES_0402LF-0,5%,1/16W,CHIP,CS00002JB13  I151  R6304
   1 USB_HUB2_TI_HS_SUSPEND      A @T6G_MB_LIB.T6G(SCH_1):USB_HUB2_TI_HS_SUSPEND
   2 USB_HUB2_TI_HS_SUSPEND_MRP_CFG_NON_REM      B @T6G_MB_LIB.T6G(SCH_1):USB_HUB2_TI_HS_SUSPEND_MRP_CFG_NON_REM

Q_RES_0402LF-200K,1%,1/16W,EMPTY,CS42002FB05  I153  R6308
   1 P3V3_AUX      A @T6G_MB_LIB.T6G(SCH_1):P3V3_AUX
   2 USB_HUB2_MRP_CFG_NON_REM      B @T6G_MB_LIB.T6G(SCH_1):USB_HUB2_MRP_CFG_NON_REM

Q_RES_0402LF-4.7K,1%,1/16W,CHIP,CS24702FB06  I155  R6306
   1 P3V3_AUX      A @T6G_MB_LIB.T6G(SCH_1):P3V3_AUX
   2 USB_HUB2_TI_HS_SUSPEND      B @T6G_MB_LIB.T6G(SCH_1):USB_HUB2_TI_HS_SUSPEND

Q_RES_0402LF-4.7K,1%,1/16W,EMPTY,CS24702FB06  I156  R6307
   1 USB_HUB2_TI_HS_SUSPEND      A @T6G_MB_LIB.T6G(SCH_1):USB_HUB2_TI_HS_SUSPEND
   2    GND      B @T6G_MB_LIB.T6G(SCH_1):GND

Q_RES_0402LF-200K,1%,1/16W,CHIP,CS42002FB05  I158  R6309
   1 USB_HUB2_MRP_CFG_NON_REM      A @T6G_MB_LIB.T6G(SCH_1):USB_HUB2_MRP_CFG_NON_REM
   2    GND      B @T6G_MB_LIB.T6G(SCH_1):GND

Q_RES_0402LF-1M,1%,1/16W,CHIP,CS51002FB05  I160  R6257
   1 XTAL_USB_CPU0_HUB2_XOUT      A @T6G_MB_LIB.T6G(SCH_1):XTAL_USB_CPU0_HUB2_XOUT
   2 XTAL_USB_CPU0_HUB2_XIN      B @T6G_MB_LIB.T6G(SCH_1):XTAL_USB_CPU0_HUB2_XIN

Q_XTAL_4P_13BI_24GND-24MHZ,SMLF,MISC,BG624000101  I164  Y6000
   1 XTAL_USB_CPU0_HUB2_XIN     X1 @T6G_MB_LIB.T6G(SCH_1):XTAL_USB_CPU0_HUB2_XIN
   2    GND     G1 @T6G_MB_LIB.T6G(SCH_1):GND
   4    GND     G2 @T6G_MB_LIB.T6G(SCH_1):GND
   3 XTAL_USB_CPU0_HUB2_XOUT     X2 @T6G_MB_LIB.T6G(SCH_1):XTAL_USB_CPU0_HUB2_XOUT

Q_RES_0402LF-0,5%,1/16W,CHIP,CS00002JB13  I170  R6260
   1 USB_HUB2_TI_VDD_MRP_USB3DN_TXDM1      A @T6G_MB_LIB.T6G(SCH_1):USB_HUB2_TI_VDD_MRP_USB3DN_TXDM1
   2 P1V2_CPU0_USB2_DVDD12      B @T6G_MB_LIB.T6G(SCH_1):P1V2_CPU0_USB2_DVDD12

Q_RES_0402LF-10,1%,1/16W,CHIP,CS01002FB07  I171  R6284
   1 USB_HUB2_TI_FULLPWRMGMTZ_MRP_PROG_FUNC3      A @T6G_MB_LIB.T6G(SCH_1):USB_HUB2_TI_FULLPWRMGMTZ_MRP_PROG_FUNC3
   2    GND      B @T6G_MB_LIB.T6G(SCH_1):GND

Q_CAP_0402-27PF,50V,5%,NPO,CH02706JB06  I174  C6090
   1 XTAL_USB_CPU0_HUB2_XOUT      A @T6G_MB_LIB.T6G(SCH_1):XTAL_USB_CPU0_HUB2_XOUT
   2    GND      B @T6G_MB_LIB.T6G(SCH_1):GND

Q_CAP_0402-27PF,50V,5%,NPO,CH02706JB06  I175  C6091
   1 XTAL_USB_CPU0_HUB2_XIN      A @T6G_MB_LIB.T6G(SCH_1):XTAL_USB_CPU0_HUB2_XIN
   2    GND      B @T6G_MB_LIB.T6G(SCH_1):GND


DRAWING: @T6G_MB_LIB.T6G(SCH_1):PAGE271 

Q_RES_0402LF-33.2,1%,1/16W,CHIP,CS03322FB03  I9  R6252
   1 SMB_LM75_0_3V3AUX_SCL      A @T6G_MB_LIB.T6G(SCH_1):SMB_LM75_0_3V3AUX_SCL
   2 SMB_HSC_TYPE_ADC_SCL      B @T6G_MB_LIB.T6G(SCH_1):SMB_HSC_TYPE_ADC_SCL

Q_RES_0402LF-33.2,1%,1/16W,CHIP,CS03322FB03  I10  R6253
   1 SMB_LM75_0_3V3AUX_SDA      A @T6G_MB_LIB.T6G(SCH_1):SMB_LM75_0_3V3AUX_SDA
   2 SMB_HSC_TYPE_ADC_SDA      B @T6G_MB_LIB.T6G(SCH_1):SMB_HSC_TYPE_ADC_SDA

Q_CAP_0402-0.1UF,25V,10%,X7R,CH4104K1B00  I11  C6086
   1 HSC_TYPE_ADC      A @T6G_MB_LIB.T6G(SCH_1):HSC_TYPE_ADC
   2    GND      B @T6G_MB_LIB.T6G(SCH_1):GND

Q_RES_0402LF-4.7K,1%,1/16W,EMPTY,CS24702FB06  I14  R6251
   1    GND      A @T6G_MB_LIB.T6G(SCH_1):GND
   2 HSC_TYPE_ADC_A0      B @T6G_MB_LIB.T6G(SCH_1):HSC_TYPE_ADC_A0

Q_CAP_0402-0.1UF,25V,10%,X7R,CH4104K1B00  I22  C6087
   1 P3V3_AUX      A @T6G_MB_LIB.T6G(SCH_1):P3V3_AUX
   2    GND      B @T6G_MB_LIB.T6G(SCH_1):GND

Q_RES_0402LF-4.7K,1%,1/16W,CHIP,CS24702FB06  I25  R6247
   1 P3V3_AUX      A @T6G_MB_LIB.T6G(SCH_1):P3V3_AUX
   2 HSC_TYPE_ADC_ALERT      B @T6G_MB_LIB.T6G(SCH_1):HSC_TYPE_ADC_ALERT

ISL28022FRZT-ISL28022FRZ-T,SMLF,IC,AL028022003  I28  U6005
   9 P3V3_AUX    VCC @T6G_MB_LIB.T6G(SCH_1):P3V3_AUX
   1 HSC_TYPE_ADC_A1     A1 @T6G_MB_LIB.T6G(SCH_1):HSC_TYPE_ADC_A1
   2 HSC_TYPE_ADC_A0     A0 @T6G_MB_LIB.T6G(SCH_1):HSC_TYPE_ADC_A0
   5 SMB_HSC_TYPE_ADC_SCL SCL|||SMBCLK @T6G_MB_LIB.T6G(SCH_1):SMB_HSC_TYPE_ADC_SCL
   4 SMB_HSC_TYPE_ADC_SDA SDA||SMBDAT @T6G_MB_LIB.T6G(SCH_1):SMB_HSC_TYPE_ADC_SDA
  11 HSC_TYPE_ADC   VBUS @T6G_MB_LIB.T6G(SCH_1):HSC_TYPE_ADC
  13 NC_HSC_TYPE_VINP   VINP @T6G_MB_LIB.T6G(SCH_1):NC_HSC_TYPE_VINP
  12 NC_HSC_TYPE_VINM   VINM @T6G_MB_LIB.T6G(SCH_1):NC_HSC_TYPE_VINM
   3 HSC_TYPE_ADC_ALERT EXT_CLK||INT @T6G_MB_LIB.T6G(SCH_1):HSC_TYPE_ADC_ALERT
   6 NC_HSC_TYPE_NC0    NC0 @T6G_MB_LIB.T6G(SCH_1):NC_HSC_TYPE_NC0
   7 NC_HSC_TYPE_NC1    NC1 @T6G_MB_LIB.T6G(SCH_1):NC_HSC_TYPE_NC1
   8 NC_HSC_TYPE_NC2    NC2 @T6G_MB_LIB.T6G(SCH_1):NC_HSC_TYPE_NC2
  14 NC_HSC_TYPE_NC3    NC3 @T6G_MB_LIB.T6G(SCH_1):NC_HSC_TYPE_NC3
  15 NC_HSC_TYPE_NC4    NC4 @T6G_MB_LIB.T6G(SCH_1):NC_HSC_TYPE_NC4
  16 NC_HSC_TYPE_NC5    NC5 @T6G_MB_LIB.T6G(SCH_1):NC_HSC_TYPE_NC5
  10    GND    GND @T6G_MB_LIB.T6G(SCH_1):GND
  TH    GND TH_GND @T6G_MB_LIB.T6G(SCH_1):GND

Q_RES_0402LF-0,5%,1/16W,CHIP,CS00002JB13  I29  R6254
   1 HSC_TYPE_ADC_A0      A @T6G_MB_LIB.T6G(SCH_1):HSC_TYPE_ADC_A0
   2 SMB_HSC_TYPE_ADC_SDA      B @T6G_MB_LIB.T6G(SCH_1):SMB_HSC_TYPE_ADC_SDA

Q_RES_0402LF-4.7K,1%,1/16W,CHIP,CS24702FB06  I30  R6250
   1    GND      A @T6G_MB_LIB.T6G(SCH_1):GND
   2 HSC_TYPE_ADC_A1      B @T6G_MB_LIB.T6G(SCH_1):HSC_TYPE_ADC_A1


DRAWING: @T6G_MB_LIB.T6G(SCH_1):PAGE155 

Q_RES_0402LF-4.7K,1%,1/16W,CHIP,CS24702FB06  I89  R6326
   1 USB_HUB2_MRP_PROG_FUNC6      A @T6G_MB_LIB.T6G(SCH_1):USB_HUB2_MRP_PROG_FUNC6
   2    GND      B @T6G_MB_LIB.T6G(SCH_1):GND

Q_RES_0402LF-4.7K,1%,1/16W,EMPTY,CS24702FB06  I91  R6327
   1 P3V3_AUX      A @T6G_MB_LIB.T6G(SCH_1):P3V3_AUX
   2 USB_HUB2_MRP_PROG_FUNC6      B @T6G_MB_LIB.T6G(SCH_1):USB_HUB2_MRP_PROG_FUNC6

TUSB8042AIRGCR-TUSB8042AIRGCR,SMLF,IC,AL008042000  I101  U6002
  59 USB3_CPU0_BMC_TX_C2_DN USB_SSRXM_UP @T6G_MB_LIB.T6G(SCH_1):USB3_CPU0_BMC_TX_C2_DN
  15 USB3_CPU0_BMC_RX_C2_DN USB_SSRXM_DN2 @T6G_MB_LIB.T6G(SCH_1):USB3_CPU0_BMC_RX_C2_DN
  14 USB3_CPU0_BMC_RX_C2_DP USB_SSRXP_DN2 @T6G_MB_LIB.T6G(SCH_1):USB3_CPU0_BMC_RX_C2_DP
  11 USB3_CPU0_BMC_HUB2_TX_DP USB_SSTXP_DN2 @T6G_MB_LIB.T6G(SCH_1):USB3_CPU0_BMC_HUB2_TX_DP
  12 USB3_CPU0_BMC_HUB2_TX_DN USB_SSTXM_DN2 @T6G_MB_LIB.T6G(SCH_1):USB3_CPU0_BMC_HUB2_TX_DN
  18 USB_HUB2_TI_USB_DM_DN3_MRP_VDD33 USB_DM_DN3 @T6G_MB_LIB.T6G(SCH_1):USB_HUB2_TI_USB_DM_DN3_MRP_VDD33
  20     NC USB_SSTXM_DN3     NC
  55 USB3_CPU0_BMC_RX_HUB2_DP USB_SSTXP_UP @T6G_MB_LIB.T6G(SCH_1):USB3_CPU0_BMC_RX_HUB2_DP
  54 USB2_CPU0_P0_R2_DN USB_DM_UP @T6G_MB_LIB.T6G(SCH_1):USB2_CPU0_P0_R2_DN
  23 USB_HUB2_TI_USB_SSRXM_DN3_MRP_VDD12 USB_SSRXM_DN3 @T6G_MB_LIB.T6G(SCH_1):USB_HUB2_TI_USB_SSRXM_DN3_MRP_VDD12
  24     NC USB_DP_DN4     NC
  17 USB_HUB2_TI_USB_DP_DN3_MRP_VDD12 USB_DP_DN3 @T6G_MB_LIB.T6G(SCH_1):USB_HUB2_TI_USB_DP_DN3_MRP_VDD12
  58 USB3_CPU0_BMC_TX_C2_DP USB_SSRXP_UP @T6G_MB_LIB.T6G(SCH_1):USB3_CPU0_BMC_TX_C2_DP
   9 USB2_CPU0_P0_HUB2_R_DP USB_DP_DN2 @T6G_MB_LIB.T6G(SCH_1):USB2_CPU0_P0_HUB2_R_DP
   6 USB_HUB2_TI_USB_SSRXP_DN1_MRP_VDD12 USB_SSRXP_DN1 @T6G_MB_LIB.T6G(SCH_1):USB_HUB2_TI_USB_SSRXP_DN1_MRP_VDD12
  26     NC USB_SSTXP_DN4     NC
   2     NC USB_DM_DN1     NC
  25     NC USB_DM_DN4     NC
  29     NC USB_SSRXP_DN4     NC
  30 USB_HUB2_TI_USB_SSRXM_DN4_MRP_VDD12 USB_SSRXM_DN4 @T6G_MB_LIB.T6G(SCH_1):USB_HUB2_TI_USB_SSRXM_DN4_MRP_VDD12
  22     NC USB_SSRXP_DN3     NC
  TH    GND TH_VSS @T6G_MB_LIB.T6G(SCH_1):GND
  53 USB2_CPU0_P0_R2_DP USB_DP_UP @T6G_MB_LIB.T6G(SCH_1):USB2_CPU0_P0_R2_DP
  56 USB3_CPU0_BMC_RX_HUB2_DN USB_SSTXM_UP @T6G_MB_LIB.T6G(SCH_1):USB3_CPU0_BMC_RX_HUB2_DN
   1 USB_HUB2_TI_USB_DP_DN1_MRP_CFG_STRAP USB_DP_DN1 @T6G_MB_LIB.T6G(SCH_1):USB_HUB2_TI_USB_DP_DN1_MRP_CFG_STRAP
   7     NC USB_SSRXM_DN1     NC
   3     NC USB_SSTXP_DN1     NC
   4     NC USB_SSTXM_DN1     NC
  10 USB2_CPU0_P0_HUB2_R_DN USB_DM_DN2 @T6G_MB_LIB.T6G(SCH_1):USB2_CPU0_P0_HUB2_R_DN
  19     NC USB_SSTXP_DN3     NC
  27     NC USB_SSTXM_DN4     NC
  48 USB_HUB2_TI_USB_VBUS_MRP_RESET_N USB_VBUS @T6G_MB_LIB.T6G(SCH_1):USB_HUB2_TI_USB_VBUS_MRP_RESET_N
  36     NC PWRCTL1||BATEN1     NC
  35 USB_HUB2_TI_PWRCTL2_MRP_VDD12 PWRCTL2||BATEN2 @T6G_MB_LIB.T6G(SCH_1):USB_HUB2_TI_PWRCTL2_MRP_VDD12
  33 USB_HUB2_TI_PWRCTL3_MRP_VDD33 PWRCTL3||BATEN3 @T6G_MB_LIB.T6G(SCH_1):USB_HUB2_TI_PWRCTL3_MRP_VDD33
  32     NC PWRCTL4||BATEN4     NC
  41 USB_HUB2_TI_PWRCTL_POL_MRP_VBUS_DET PWRCTL_POL @T6G_MB_LIB.T6G(SCH_1):USB_HUB2_TI_PWRCTL_POL_MRP_VBUS_DET
  50 USB_HUB2_TI_GRSTZ_MRP_PROG_FUNC1  GRSTZ @T6G_MB_LIB.T6G(SCH_1):USB_HUB2_TI_GRSTZ_MRP_PROG_FUNC1
  46 USB_HUB2_TI_OVERCUR1_MRP_PROG_FUNC4 OVERCUR1Z @T6G_MB_LIB.T6G(SCH_1):USB_HUB2_TI_OVERCUR1_MRP_PROG_FUNC4
  47 USB_HUB2_TI_OVERCUR2_MRP_PROG_FUNC5 OVERCUR2Z @T6G_MB_LIB.T6G(SCH_1):USB_HUB2_TI_OVERCUR2_MRP_PROG_FUNC5
  44 USB_HUB2_TI_OVERCUR3_MRP_CFG_BC_EN OVERCUR3Z @T6G_MB_LIB.T6G(SCH_1):USB_HUB2_TI_OVERCUR3_MRP_CFG_BC_EN
  43 USB_HUB2_TI_OVERCUR4_MRP_I2C_SLV_CFG1 OVERCUR4Z @T6G_MB_LIB.T6G(SCH_1):USB_HUB2_TI_OVERCUR4_MRP_I2C_SLV_CFG1
  49 USB_HUB2_TI_TEST_MRP_PROG_FUNC6   TEST @T6G_MB_LIB.T6G(SCH_1):USB_HUB2_TI_TEST_MRP_PROG_FUNC6
  64 USB_HUB2_TI_USB_R1_MRP_RBIAS USB_R1 @T6G_MB_LIB.T6G(SCH_1):USB_HUB2_TI_USB_R1_MRP_RBIAS
  60 USB_HUB2_TI_NC_MRP_ATEST   NC_1 @T6G_MB_LIB.T6G(SCH_1):USB_HUB2_TI_NC_MRP_ATEST

Q_RES_0402LF-0,5%,1/16W,CHIP,CS00002JB13  I102  R6271
   1 USB_HUB2_TI_USB_DP_DN1_MRP_CFG_STRAP      A @T6G_MB_LIB.T6G(SCH_1):USB_HUB2_TI_USB_DP_DN1_MRP_CFG_STRAP
   2 USB_HUB2_MRP_CFG_STRAP      B @T6G_MB_LIB.T6G(SCH_1):USB_HUB2_MRP_CFG_STRAP

Q_RES_0402LF-200K,1%,1/16W,EMPTY,CS42002FB05  I104  R6273
   1 P3V3_AUX      A @T6G_MB_LIB.T6G(SCH_1):P3V3_AUX
   2 USB_HUB2_MRP_CFG_STRAP      B @T6G_MB_LIB.T6G(SCH_1):USB_HUB2_MRP_CFG_STRAP

Q_RES_0402LF-200K,1%,1/16W,CHIP,CS42002FB05  I105  R6272
   1 USB_HUB2_MRP_CFG_STRAP      A @T6G_MB_LIB.T6G(SCH_1):USB_HUB2_MRP_CFG_STRAP
   2    GND      B @T6G_MB_LIB.T6G(SCH_1):GND

Q_RES_0402LF-47K,0.1%,1/16W,EMPTY,CS34702BB05  I111  R6333
   1 USB_HUB2_TI_GRSTZ_MRP_PROG_FUNC1      A @T6G_MB_LIB.T6G(SCH_1):USB_HUB2_TI_GRSTZ_MRP_PROG_FUNC1
   2    GND      B @T6G_MB_LIB.T6G(SCH_1):GND

Q_RES_0402LF-0,5%,1/16W,CHIP,CS00002JB13  I114  R6328
   1 RST_USB_HUB_N      A @T6G_MB_LIB.T6G(SCH_1):RST_USB_HUB_N
   2 USB_HUB2_TI_GRSTZ_MRP_PROG_FUNC1      B @T6G_MB_LIB.T6G(SCH_1):USB_HUB2_TI_GRSTZ_MRP_PROG_FUNC1

Q_RES_0402LF-0,5%,1/16W,CHIP,CS00002JB13  I115  R6323
   1 USB_HUB2_TI_TEST      A @T6G_MB_LIB.T6G(SCH_1):USB_HUB2_TI_TEST
   2 USB_HUB2_TI_TEST_MRP_PROG_FUNC6      B @T6G_MB_LIB.T6G(SCH_1):USB_HUB2_TI_TEST_MRP_PROG_FUNC6

Q_RES_0402LF-10K,1%,1/16W,CHIP,CS31002FB08  I116  R6325
   1 USB_HUB2_TI_TEST      A @T6G_MB_LIB.T6G(SCH_1):USB_HUB2_TI_TEST
   2    GND      B @T6G_MB_LIB.T6G(SCH_1):GND

Q_RES_0402LF-0,5%,1/16W,CHIP,CS00002JB13  I118  R6324
   1 USB_HUB2_MRP_PROG_FUNC6      A @T6G_MB_LIB.T6G(SCH_1):USB_HUB2_MRP_PROG_FUNC6
   2 USB_HUB2_TI_TEST_MRP_PROG_FUNC6      B @T6G_MB_LIB.T6G(SCH_1):USB_HUB2_TI_TEST_MRP_PROG_FUNC6

Q_RES_0402LF-0,5%,1/16W,CHIP,CS00002JB13  I119  R6316
   1 USB_HUB2_TI_USB_VBUS      A @T6G_MB_LIB.T6G(SCH_1):USB_HUB2_TI_USB_VBUS
   2 USB_HUB2_TI_USB_VBUS_MRP_RESET_N      B @T6G_MB_LIB.T6G(SCH_1):USB_HUB2_TI_USB_VBUS_MRP_RESET_N

Q_RES_0402LF-10K,1%,1/16W,CHIP,CS31002FB08  I121  R6319
   1 USB_HUB2_TI_USB_VBUS      A @T6G_MB_LIB.T6G(SCH_1):USB_HUB2_TI_USB_VBUS
   2    GND      B @T6G_MB_LIB.T6G(SCH_1):GND

Q_RES_0402LF-90.9K,1%,1/16W,CHIP,CS39092FB04  I123  R6318
   1 P5V_AUX      A @T6G_MB_LIB.T6G(SCH_1):P5V_AUX
   2 USB_HUB2_TI_USB_VBUS      B @T6G_MB_LIB.T6G(SCH_1):USB_HUB2_TI_USB_VBUS

Q_RES_0402LF-0,5%,1/16W,CHIP,CS00002JB13  I124  R6317
   1 USB_HUB2_MRP_RESET_N      A @T6G_MB_LIB.T6G(SCH_1):USB_HUB2_MRP_RESET_N
   2 USB_HUB2_TI_USB_VBUS_MRP_RESET_N      B @T6G_MB_LIB.T6G(SCH_1):USB_HUB2_TI_USB_VBUS_MRP_RESET_N

Q_CAP_C0805-10UF,16V,10%,X6S,CH6103KEA00  I127  C6088
   1 USB_HUB2_MRP_RESET_N      A @T6G_MB_LIB.T6G(SCH_1):USB_HUB2_MRP_RESET_N
   2    GND      B @T6G_MB_LIB.T6G(SCH_1):GND

Q_RES_0402LF-47K,0.1%,1/16W,EMPTY,CS34702BB05  I129  R6321
   1 USB_HUB2_MRP_RESET_N      A @T6G_MB_LIB.T6G(SCH_1):USB_HUB2_MRP_RESET_N
   2    GND      B @T6G_MB_LIB.T6G(SCH_1):GND

Q_RES_0402LF-0,5%,1/16W,CHIP,CS00002JB13  I131  R6322
   1 RST_USB_HUB_N      A @T6G_MB_LIB.T6G(SCH_1):RST_USB_HUB_N
   2 USB_HUB2_MRP_RESET_N      B @T6G_MB_LIB.T6G(SCH_1):USB_HUB2_MRP_RESET_N

Q_RES_0402LF-0,5%,1/16W,CHIP,CS00002JB13  I134  R6261
   1 USB_HUB2_TI_USB_SSRXP_DN1_MRP_VDD12      A @T6G_MB_LIB.T6G(SCH_1):USB_HUB2_TI_USB_SSRXP_DN1_MRP_VDD12
   2 P1V2_CPU0_USB2_DVDD12      B @T6G_MB_LIB.T6G(SCH_1):P1V2_CPU0_USB2_DVDD12

Q_RES_0402LF-0,5%,1/16W,CHIP,CS00002JB13  I136  R6266
   1 USB_HUB2_TI_USB_SSRXM_DN3_MRP_VDD12      A @T6G_MB_LIB.T6G(SCH_1):USB_HUB2_TI_USB_SSRXM_DN3_MRP_VDD12
   2 P1V2_CPU0_USB2_DVDD12      B @T6G_MB_LIB.T6G(SCH_1):P1V2_CPU0_USB2_DVDD12

Q_RES_0402LF-0,5%,1/16W,CHIP,CS00002JB13  I137  R6314
   1 SMB_USB_CPU0_HUB1_SCL      A @T6G_MB_LIB.T6G(SCH_1):SMB_USB_CPU0_HUB1_SCL
   2 USB_HUB2_TI_OVERCUR2_MRP_PROG_FUNC5      B @T6G_MB_LIB.T6G(SCH_1):USB_HUB2_TI_OVERCUR2_MRP_PROG_FUNC5

Q_RES_0402LF-0,5%,1/16W,CHIP,CS00002JB13  I138  R6313
   1 USB_HUB2_TI_OVERCUR2      A @T6G_MB_LIB.T6G(SCH_1):USB_HUB2_TI_OVERCUR2
   2 USB_HUB2_TI_OVERCUR2_MRP_PROG_FUNC5      B @T6G_MB_LIB.T6G(SCH_1):USB_HUB2_TI_OVERCUR2_MRP_PROG_FUNC5

Q_RES_0402LF-10K,1%,1/16W,CHIP,CS31002FB08  I140  R6315
   1 P3V3_AUX      A @T6G_MB_LIB.T6G(SCH_1):P3V3_AUX
   2 USB_HUB2_TI_OVERCUR2      B @T6G_MB_LIB.T6G(SCH_1):USB_HUB2_TI_OVERCUR2

Q_RES_0402LF-0,5%,1/16W,CHIP,CS00002JB13  I143  R6270
   1 P3V3_AUX_CPU0_USB2_AVDD33      A @T6G_MB_LIB.T6G(SCH_1):P3V3_AUX_CPU0_USB2_AVDD33
   2 USB_HUB2_TI_PWRCTL3_MRP_VDD33      B @T6G_MB_LIB.T6G(SCH_1):USB_HUB2_TI_PWRCTL3_MRP_VDD33

Q_CAP_C0402-1UF,25V,10%,X6S,CH5104KEB02  I145  C6089
   1 USB_HUB2_TI_GRSTZ_MRP_PROG_FUNC1      A @T6G_MB_LIB.T6G(SCH_1):USB_HUB2_TI_GRSTZ_MRP_PROG_FUNC1
   2    GND      B @T6G_MB_LIB.T6G(SCH_1):GND

Q_RES_0402LF-0,5%,1/16W,CHIP,CS00002JB13  I149  R6268
   1 USB_HUB2_TI_USB_SSRXM_DN4_MRP_VDD12      A @T6G_MB_LIB.T6G(SCH_1):USB_HUB2_TI_USB_SSRXM_DN4_MRP_VDD12
   2 P1V2_CPU0_USB2_DVDD12      B @T6G_MB_LIB.T6G(SCH_1):P1V2_CPU0_USB2_DVDD12

Q_RES_0402LF-0,5%,1/16W,CHIP,CS00002JB13  I151  R6264
   1 USB_HUB2_TI_USB_DM_DN3_MRP_VDD33      A @T6G_MB_LIB.T6G(SCH_1):USB_HUB2_TI_USB_DM_DN3_MRP_VDD33
   2 P3V3_AUX_CPU0_USB2_AVDD33      B @T6G_MB_LIB.T6G(SCH_1):P3V3_AUX_CPU0_USB2_AVDD33

Q_RES_0402LF-0,5%,1/16W,CHIP,CS00002JB13  I155  R6263
   1 USB_HUB2_TI_USB_DP_DN3_MRP_VDD12      A @T6G_MB_LIB.T6G(SCH_1):USB_HUB2_TI_USB_DP_DN3_MRP_VDD12
   2 P1V2_CPU0_USB2_DVDD12      B @T6G_MB_LIB.T6G(SCH_1):P1V2_CPU0_USB2_DVDD12

Q_RES_0402LF-4.7K,5%,1/16W,EMPTY,CS24702JB10  I164  R6258
   1 P3V3_AUX      A @T6G_MB_LIB.T6G(SCH_1):P3V3_AUX
   2 USB_HUB2_TI_PWRCTL2_MRP_VDD12      B @T6G_MB_LIB.T6G(SCH_1):USB_HUB2_TI_PWRCTL2_MRP_VDD12

Q_RES_0402LF-0,5%,1/16W,CHIP,CS00002JB13  I166  R6259
   1 P1V2_CPU0_USB2_DVDD12      A @T6G_MB_LIB.T6G(SCH_1):P1V2_CPU0_USB2_DVDD12
   2 USB_HUB2_TI_PWRCTL2_MRP_VDD12      B @T6G_MB_LIB.T6G(SCH_1):USB_HUB2_TI_PWRCTL2_MRP_VDD12

Q_RES_0402LF-200K,1%,1/16W,EMPTY,CS42002FB05  I169  R6303
   1 P3V3_AUX      A @T6G_MB_LIB.T6G(SCH_1):P3V3_AUX
   2 USB_HUB2_MRP_CFG_BC_EN      B @T6G_MB_LIB.T6G(SCH_1):USB_HUB2_MRP_CFG_BC_EN

Q_RES_0402LF-200K,1%,1/16W,CHIP,CS42002FB05  I175  R6302
   1 USB_HUB2_MRP_CFG_BC_EN      A @T6G_MB_LIB.T6G(SCH_1):USB_HUB2_MRP_CFG_BC_EN
   2    GND      B @T6G_MB_LIB.T6G(SCH_1):GND

Q_RES_0402LF-10K,1%,1/16W,CHIP,CS31002FB08  I179  R6301
   1 P3V3_AUX      A @T6G_MB_LIB.T6G(SCH_1):P3V3_AUX
   2 USB_HUB2_TI_OVERCUR3      B @T6G_MB_LIB.T6G(SCH_1):USB_HUB2_TI_OVERCUR3

Q_RES_0402LF-0,5%,1/16W,CHIP,CS00002JB13  I180  R6299
   1 USB_HUB2_TI_OVERCUR3      A @T6G_MB_LIB.T6G(SCH_1):USB_HUB2_TI_OVERCUR3
   2 USB_HUB2_TI_OVERCUR3_MRP_CFG_BC_EN      B @T6G_MB_LIB.T6G(SCH_1):USB_HUB2_TI_OVERCUR3_MRP_CFG_BC_EN

Q_RES_0402LF-0,5%,1/16W,CHIP,CS00002JB13  I181  R6300
   1 USB_HUB2_MRP_CFG_BC_EN      A @T6G_MB_LIB.T6G(SCH_1):USB_HUB2_MRP_CFG_BC_EN
   2 USB_HUB2_TI_OVERCUR3_MRP_CFG_BC_EN      B @T6G_MB_LIB.T6G(SCH_1):USB_HUB2_TI_OVERCUR3_MRP_CFG_BC_EN

Q_RES_0402LF-0,5%,1/16W,CHIP,CS00002JB13  I182  R6295
   1 USB_HUB2_TI_OVERCCUR4      A @T6G_MB_LIB.T6G(SCH_1):USB_HUB2_TI_OVERCCUR4
   2 USB_HUB2_TI_OVERCUR4_MRP_I2C_SLV_CFG1      B @T6G_MB_LIB.T6G(SCH_1):USB_HUB2_TI_OVERCUR4_MRP_I2C_SLV_CFG1

Q_RES_0402LF-0,5%,1/16W,CHIP,CS00002JB13  I183  R6296
   1 USB_HUB2_MRP_I2C_SLV_CFG1      A @T6G_MB_LIB.T6G(SCH_1):USB_HUB2_MRP_I2C_SLV_CFG1
   2 USB_HUB2_TI_OVERCUR4_MRP_I2C_SLV_CFG1      B @T6G_MB_LIB.T6G(SCH_1):USB_HUB2_TI_OVERCUR4_MRP_I2C_SLV_CFG1

Q_RES_0402LF-10K,1%,1/16W,CHIP,CS31002FB08  I185  R6297
   1 P3V3_AUX      A @T6G_MB_LIB.T6G(SCH_1):P3V3_AUX
   2 USB_HUB2_TI_OVERCCUR4      B @T6G_MB_LIB.T6G(SCH_1):USB_HUB2_TI_OVERCCUR4

Q_RES_0402LF-10K,1%,1/16W,CHIP,CS31002FB08  I187  R6298
   1 P3V3_AUX      A @T6G_MB_LIB.T6G(SCH_1):P3V3_AUX
   2 USB_HUB2_MRP_I2C_SLV_CFG1      B @T6G_MB_LIB.T6G(SCH_1):USB_HUB2_MRP_I2C_SLV_CFG1

Q_RES_0402LF-4.7K,1%,1/16W,CHIP,CS24702FB06  I188  R6330
   1    GND      A @T6G_MB_LIB.T6G(SCH_1):GND
   2 USB_HUB2_TI_NC_MRP_ATEST      B @T6G_MB_LIB.T6G(SCH_1):USB_HUB2_TI_NC_MRP_ATEST

Q_RES_0402LF-0,5%,1/16W,CHIP,CS00002JB13  I192  R6285
   1 USB_HUB2_TI_PWRCTL_POL      A @T6G_MB_LIB.T6G(SCH_1):USB_HUB2_TI_PWRCTL_POL
   2 USB_HUB2_TI_PWRCTL_POL_MRP_VBUS_DET      B @T6G_MB_LIB.T6G(SCH_1):USB_HUB2_TI_PWRCTL_POL_MRP_VBUS_DET

Q_RES_0402LF-0,5%,1/16W,CHIP,CS00002JB13  I193  R6286
   1 USB_HUB2_MRP_VBUS_DET      A @T6G_MB_LIB.T6G(SCH_1):USB_HUB2_MRP_VBUS_DET
   2 USB_HUB2_TI_PWRCTL_POL_MRP_VBUS_DET      B @T6G_MB_LIB.T6G(SCH_1):USB_HUB2_TI_PWRCTL_POL_MRP_VBUS_DET

Q_RES_0402LF-10K,1%,1/16W,CHIP,CS31002FB08  I195  R6289
   1 P3V3_AUX      A @T6G_MB_LIB.T6G(SCH_1):P3V3_AUX
   2 USB_HUB2_MRP_VBUS_DET      B @T6G_MB_LIB.T6G(SCH_1):USB_HUB2_MRP_VBUS_DET

Q_RES_0402LF-1K,1%,1/16W,CHIP,CS21002FB06  I197  R6287
   1 P3V3_AUX      A @T6G_MB_LIB.T6G(SCH_1):P3V3_AUX
   2 USB_HUB2_TI_PWRCTL_POL      B @T6G_MB_LIB.T6G(SCH_1):USB_HUB2_TI_PWRCTL_POL

Q_RES_0402LF-1K,1%,1/16W,EMPTY,CS21002FB06  I198  R6288
   1 USB_HUB2_TI_PWRCTL_POL      A @T6G_MB_LIB.T6G(SCH_1):USB_HUB2_TI_PWRCTL_POL
   2    GND      B @T6G_MB_LIB.T6G(SCH_1):GND

Q_RES_0402LF-0,5%,1/16W,CHIP,CS00002JB13  I200  R6311
   1 SMB_USB_CPU0_HUB1_SDA      A @T6G_MB_LIB.T6G(SCH_1):SMB_USB_CPU0_HUB1_SDA
   2 USB_HUB2_TI_OVERCUR1_MRP_PROG_FUNC4      B @T6G_MB_LIB.T6G(SCH_1):USB_HUB2_TI_OVERCUR1_MRP_PROG_FUNC4

Q_RES_0402LF-0,5%,1/16W,CHIP,CS00002JB13  I202  R6310
   1 USB_HUB2_TI_OVERCUR1      A @T6G_MB_LIB.T6G(SCH_1):USB_HUB2_TI_OVERCUR1
   2 USB_HUB2_TI_OVERCUR1_MRP_PROG_FUNC4      B @T6G_MB_LIB.T6G(SCH_1):USB_HUB2_TI_OVERCUR1_MRP_PROG_FUNC4

Q_RES_0402LF-10K,1%,1/16W,CHIP,CS31002FB08  I205  R6312
   1 P3V3_AUX      A @T6G_MB_LIB.T6G(SCH_1):P3V3_AUX
   2 USB_HUB2_TI_OVERCUR1      B @T6G_MB_LIB.T6G(SCH_1):USB_HUB2_TI_OVERCUR1

Q_RES_0402LF-9.53K,1%,1/16W,CHIP,CS29532FB06  I207  R6331
   1 USB_HUB2_TI_USB_R1_MRP_RBIAS      A @T6G_MB_LIB.T6G(SCH_1):USB_HUB2_TI_USB_R1_MRP_RBIAS
   2    GND      B @T6G_MB_LIB.T6G(SCH_1):GND

Q_RES_0402LF-12K,1%,1/16W,CHIP,CS31202FB04  I208  R6332
   1 USB_HUB2_TI_USB_R1_MRP_RBIAS      A @T6G_MB_LIB.T6G(SCH_1):USB_HUB2_TI_USB_R1_MRP_RBIAS
   2    GND      B @T6G_MB_LIB.T6G(SCH_1):GND

Q_RES_0402LF-10K,1%,1/16W,EMPTY,CS31002FB08  I212  R6320
   1 P3V3_AUX      A @T6G_MB_LIB.T6G(SCH_1):P3V3_AUX
   2 USB_HUB2_MRP_RESET_N      B @T6G_MB_LIB.T6G(SCH_1):USB_HUB2_MRP_RESET_N

Q_RES_0402LF-10K,1%,1/16W,EMPTY,CS31002FB08  I213  R6329
   1 P3V3_AUX      A @T6G_MB_LIB.T6G(SCH_1):P3V3_AUX
   2 USB_HUB2_TI_GRSTZ_MRP_PROG_FUNC1      B @T6G_MB_LIB.T6G(SCH_1):USB_HUB2_TI_GRSTZ_MRP_PROG_FUNC1


DRAWING: @T6G_MB_LIB.T6G(SCH_1):PAGE130 

NC7SB3157P6X-NC7SB3157P6X,SMLF,IC,ALSB3157000  I1  U8000
   1 ESPI_CPU0_ALERT_R1_N     B1 @T6G_MB_LIB.T6G(SCH_1):ESPI_CPU0_ALERT_R1_N
   2    GND    GND @T6G_MB_LIB.T6G(SCH_1):GND
   3 ESPI_CPU0_ALERT_PLD_N     B0 @T6G_MB_LIB.T6G(SCH_1):ESPI_CPU0_ALERT_PLD_N
   6 FM_ESPI_CPU0_ALERT_R_SEL      S @T6G_MB_LIB.T6G(SCH_1):FM_ESPI_CPU0_ALERT_R_SEL
   5 P1V8_AUX    VCC @T6G_MB_LIB.T6G(SCH_1):P1V8_AUX
   4 ESPI_CPU0_ALERT_P0_N      A @T6G_MB_LIB.T6G(SCH_1):ESPI_CPU0_ALERT_P0_N

Q_CAP_0402-0.1UF,25V,10%,X7R,CH4104K1B00  I4  C8007
   1 P1V8_AUX      A @T6G_MB_LIB.T6G(SCH_1):P1V8_AUX
   2    GND      B @T6G_MB_LIB.T6G(SCH_1):GND

Q_RES_0402LF-4.7K,5%,1/16W,EMPTY,CS24702JB10  I11  R8035
   1 P1V8_AUX      A @T6G_MB_LIB.T6G(SCH_1):P1V8_AUX
   2 ESPI_CPU0_ALERT_N      B @T6G_MB_LIB.T6G(SCH_1):ESPI_CPU0_ALERT_N

Q_RES_0402LF-4.7K,5%,1/16W,EMPTY,CS24702JB10  I12  R8036
   1 PVDD18_S5_P0      A @T6G_MB_LIB.T6G(SCH_1):PVDD18_S5_P0
   2 ESPI_CPU0_ALERT_PLD_N      B @T6G_MB_LIB.T6G(SCH_1):ESPI_CPU0_ALERT_PLD_N

Q_RES_0402LF-0,5%,1/16W,CHIP,CS00002JB13  I23  R8034
   1 ESPI_CPU0_ALERT_R1_N      A @T6G_MB_LIB.T6G(SCH_1):ESPI_CPU0_ALERT_R1_N
   2 ESPI_CPU0_ALERT_N      B @T6G_MB_LIB.T6G(SCH_1):ESPI_CPU0_ALERT_N

Q_RES_0402LF-0,5%,1/16W,EMPTY,CS00002JB13  I24  R1197
   1 ESPI_CPU0_ALERT_P0_N      A @T6G_MB_LIB.T6G(SCH_1):ESPI_CPU0_ALERT_P0_N
   2 ESPI_CPU0_ALERT_N      B @T6G_MB_LIB.T6G(SCH_1):ESPI_CPU0_ALERT_N


DRAWING: @T6G_MB_LIB.T6G(SCH_1):PAGE381 

PT5161LRS-PT5161LRS,SMLF,IC,AJ051610U03  I3  U6010
 N34 P5E_CPU0_P0_TX_C_DN<15> B_PERP0 @T6G_MB_LIB.T6G(SCH_1):P5E_CPU0_P0_TX_C_DN(15)
 R35 P5E_CPU0_P0_TX_C_DP<15> B_PERN0 @T6G_MB_LIB.T6G(SCH_1):P5E_CPU0_P0_TX_C_DP(15)
 Y34 P5E_CPU0_P0_TX_C_DN<14> B_PERP1 @T6G_MB_LIB.T6G(SCH_1):P5E_CPU0_P0_TX_C_DN(14)
AB35 P5E_CPU0_P0_TX_C_DP<14> B_PERN1 @T6G_MB_LIB.T6G(SCH_1):P5E_CPU0_P0_TX_C_DP(14)
AG34 P5E_CPU0_P0_TX_C_DP<13> B_PERP2 @T6G_MB_LIB.T6G(SCH_1):P5E_CPU0_P0_TX_C_DP(13)
AJ35 P5E_CPU0_P0_TX_C_DN<13> B_PERN2 @T6G_MB_LIB.T6G(SCH_1):P5E_CPU0_P0_TX_C_DN(13)
AP34 P5E_CPU0_P0_TX_C_DN<12> B_PERP3 @T6G_MB_LIB.T6G(SCH_1):P5E_CPU0_P0_TX_C_DN(12)
AT35 P5E_CPU0_P0_TX_C_DP<12> B_PERN3 @T6G_MB_LIB.T6G(SCH_1):P5E_CPU0_P0_TX_C_DP(12)
BA34 P5E_CPU0_P0_TX_C_DN<11> B_PERP4 @T6G_MB_LIB.T6G(SCH_1):P5E_CPU0_P0_TX_C_DN(11)
BC35 P5E_CPU0_P0_TX_C_DP<11> B_PERN4 @T6G_MB_LIB.T6G(SCH_1):P5E_CPU0_P0_TX_C_DP(11)
BH34 P5E_CPU0_P0_TX_C_DN<10> B_PERP5 @T6G_MB_LIB.T6G(SCH_1):P5E_CPU0_P0_TX_C_DN(10)
BK35 P5E_CPU0_P0_TX_C_DP<10> B_PERN5 @T6G_MB_LIB.T6G(SCH_1):P5E_CPU0_P0_TX_C_DP(10)
BR34 P5E_CPU0_P0_TX_C_DN<9> B_PERP6 @T6G_MB_LIB.T6G(SCH_1):P5E_CPU0_P0_TX_C_DN(9)
BU35 P5E_CPU0_P0_TX_C_DP<9> B_PERN6 @T6G_MB_LIB.T6G(SCH_1):P5E_CPU0_P0_TX_C_DP(9)
CB34 P5E_CPU0_P0_TX_C_DN<8> B_PERP7 @T6G_MB_LIB.T6G(SCH_1):P5E_CPU0_P0_TX_C_DN(8)
CD35 P5E_CPU0_P0_TX_C_DP<8> B_PERN7 @T6G_MB_LIB.T6G(SCH_1):P5E_CPU0_P0_TX_C_DP(8)

PT5161LRS-PT5161LRS,SMLF,IC,AJ051610U03  I4  U6010
CJ34 P5E_CPU0_P0_TX_C_DN<7> B_PERP8 @T6G_MB_LIB.T6G(SCH_1):P5E_CPU0_P0_TX_C_DN(7)
CL35 P5E_CPU0_P0_TX_C_DP<7> B_PERN8 @T6G_MB_LIB.T6G(SCH_1):P5E_CPU0_P0_TX_C_DP(7)
CT34 P5E_CPU0_P0_TX_C_DN<6> B_PERP9 @T6G_MB_LIB.T6G(SCH_1):P5E_CPU0_P0_TX_C_DN(6)
CV35 P5E_CPU0_P0_TX_C_DP<6> B_PERN9 @T6G_MB_LIB.T6G(SCH_1):P5E_CPU0_P0_TX_C_DP(6)
DC34 P5E_CPU0_P0_TX_C_DN<5> B_PERP10 @T6G_MB_LIB.T6G(SCH_1):P5E_CPU0_P0_TX_C_DN(5)
DE35 P5E_CPU0_P0_TX_C_DP<5> B_PERN10 @T6G_MB_LIB.T6G(SCH_1):P5E_CPU0_P0_TX_C_DP(5)
DK34 P5E_CPU0_P0_TX_C_DN<4> B_PERP11 @T6G_MB_LIB.T6G(SCH_1):P5E_CPU0_P0_TX_C_DN(4)
DM35 P5E_CPU0_P0_TX_C_DP<4> B_PERN11 @T6G_MB_LIB.T6G(SCH_1):P5E_CPU0_P0_TX_C_DP(4)
DU34 P5E_CPU0_P0_TX_C_DN<3> B_PERP12 @T6G_MB_LIB.T6G(SCH_1):P5E_CPU0_P0_TX_C_DN(3)
DW35 P5E_CPU0_P0_TX_C_DP<3> B_PERN12 @T6G_MB_LIB.T6G(SCH_1):P5E_CPU0_P0_TX_C_DP(3)
ED34 P5E_CPU0_P0_TX_C_DN<2> B_PERP13 @T6G_MB_LIB.T6G(SCH_1):P5E_CPU0_P0_TX_C_DN(2)
EF35 P5E_CPU0_P0_TX_C_DP<2> B_PERN13 @T6G_MB_LIB.T6G(SCH_1):P5E_CPU0_P0_TX_C_DP(2)
EL34 P5E_CPU0_P0_TX_C_DP<1> B_PERP14 @T6G_MB_LIB.T6G(SCH_1):P5E_CPU0_P0_TX_C_DP(1)
EN35 P5E_CPU0_P0_TX_C_DN<1> B_PERN14 @T6G_MB_LIB.T6G(SCH_1):P5E_CPU0_P0_TX_C_DN(1)
EV34 P5E_CPU0_P0_TX_C_DN<0> B_PERP15 @T6G_MB_LIB.T6G(SCH_1):P5E_CPU0_P0_TX_C_DN(0)
EY35 P5E_CPU0_P0_TX_C_DP<0> B_PERN15 @T6G_MB_LIB.T6G(SCH_1):P5E_CPU0_P0_TX_C_DP(0)


DRAWING: @T6G_MB_LIB.T6G(SCH_1):PAGE382 

PT5161LRS-PT5161LRS,SMLF,IC,AJ051610U03  I2  U6010
 M26 P5E_CPU0_P0_RX_DP<15> A_PETP0 @T6G_MB_LIB.T6G(SCH_1):P5E_CPU0_P0_RX_DP(15)
 P29 P5E_CPU0_P0_RX_DN<15> A_PETN0 @T6G_MB_LIB.T6G(SCH_1):P5E_CPU0_P0_RX_DN(15)
 W26 P5E_CPU0_P0_RX_DP<14> A_PETP1 @T6G_MB_LIB.T6G(SCH_1):P5E_CPU0_P0_RX_DP(14)
AA29 P5E_CPU0_P0_RX_DN<14> A_PETN1 @T6G_MB_LIB.T6G(SCH_1):P5E_CPU0_P0_RX_DN(14)
AF26 P5E_CPU0_P0_RX_DP<13> A_PETP2 @T6G_MB_LIB.T6G(SCH_1):P5E_CPU0_P0_RX_DP(13)
AH29 P5E_CPU0_P0_RX_DN<13> A_PETN2 @T6G_MB_LIB.T6G(SCH_1):P5E_CPU0_P0_RX_DN(13)
AN26 P5E_CPU0_P0_RX_DP<12> A_PETP3 @T6G_MB_LIB.T6G(SCH_1):P5E_CPU0_P0_RX_DP(12)
AR29 P5E_CPU0_P0_RX_DN<12> A_PETN3 @T6G_MB_LIB.T6G(SCH_1):P5E_CPU0_P0_RX_DN(12)
AY26 P5E_CPU0_P0_RX_DP<11> A_PETP4 @T6G_MB_LIB.T6G(SCH_1):P5E_CPU0_P0_RX_DP(11)
BB29 P5E_CPU0_P0_RX_DN<11> A_PETN4 @T6G_MB_LIB.T6G(SCH_1):P5E_CPU0_P0_RX_DN(11)
BG26 P5E_CPU0_P0_RX_DP<10> A_PETP5 @T6G_MB_LIB.T6G(SCH_1):P5E_CPU0_P0_RX_DP(10)
BJ29 P5E_CPU0_P0_RX_DN<10> A_PETN5 @T6G_MB_LIB.T6G(SCH_1):P5E_CPU0_P0_RX_DN(10)
BP26 P5E_CPU0_P0_RX_DP<9> A_PETP6 @T6G_MB_LIB.T6G(SCH_1):P5E_CPU0_P0_RX_DP(9)
BT29 P5E_CPU0_P0_RX_DN<9> A_PETN6 @T6G_MB_LIB.T6G(SCH_1):P5E_CPU0_P0_RX_DN(9)
CA26 P5E_CPU0_P0_RX_DP<8> A_PETP7 @T6G_MB_LIB.T6G(SCH_1):P5E_CPU0_P0_RX_DP(8)
CC29 P5E_CPU0_P0_RX_DN<8> A_PETN7 @T6G_MB_LIB.T6G(SCH_1):P5E_CPU0_P0_RX_DN(8)

PT5161LRS-PT5161LRS,SMLF,IC,AJ051610U03  I3  U6010
CH26 P5E_CPU0_P0_RX_DP<7> A_PETP8 @T6G_MB_LIB.T6G(SCH_1):P5E_CPU0_P0_RX_DP(7)
CK29 P5E_CPU0_P0_RX_DN<7> A_PETN8 @T6G_MB_LIB.T6G(SCH_1):P5E_CPU0_P0_RX_DN(7)
CR26 P5E_CPU0_P0_RX_DP<6> A_PETP9 @T6G_MB_LIB.T6G(SCH_1):P5E_CPU0_P0_RX_DP(6)
CU29 P5E_CPU0_P0_RX_DN<6> A_PETN9 @T6G_MB_LIB.T6G(SCH_1):P5E_CPU0_P0_RX_DN(6)
DB26 P5E_CPU0_P0_RX_DP<5> A_PETP10 @T6G_MB_LIB.T6G(SCH_1):P5E_CPU0_P0_RX_DP(5)
DD29 P5E_CPU0_P0_RX_DN<5> A_PETN10 @T6G_MB_LIB.T6G(SCH_1):P5E_CPU0_P0_RX_DN(5)
DJ26 P5E_CPU0_P0_RX_DP<4> A_PETP11 @T6G_MB_LIB.T6G(SCH_1):P5E_CPU0_P0_RX_DP(4)
DL29 P5E_CPU0_P0_RX_DN<4> A_PETN11 @T6G_MB_LIB.T6G(SCH_1):P5E_CPU0_P0_RX_DN(4)
DT26 P5E_CPU0_P0_RX_DP<3> A_PETP12 @T6G_MB_LIB.T6G(SCH_1):P5E_CPU0_P0_RX_DP(3)
DV29 P5E_CPU0_P0_RX_DN<3> A_PETN12 @T6G_MB_LIB.T6G(SCH_1):P5E_CPU0_P0_RX_DN(3)
EC26 P5E_CPU0_P0_RX_DP<2> A_PETP13 @T6G_MB_LIB.T6G(SCH_1):P5E_CPU0_P0_RX_DP(2)
EE29 P5E_CPU0_P0_RX_DN<2> A_PETN13 @T6G_MB_LIB.T6G(SCH_1):P5E_CPU0_P0_RX_DN(2)
EK26 P5E_CPU0_P0_RX_DP<1> A_PETP14 @T6G_MB_LIB.T6G(SCH_1):P5E_CPU0_P0_RX_DP(1)
EM29 P5E_CPU0_P0_RX_DN<1> A_PETN14 @T6G_MB_LIB.T6G(SCH_1):P5E_CPU0_P0_RX_DN(1)
EU26 P5E_CPU0_P0_RX_DP<0> A_PETP15 @T6G_MB_LIB.T6G(SCH_1):P5E_CPU0_P0_RX_DP(0)
EW29 P5E_CPU0_P0_RX_DN<0> A_PETN15 @T6G_MB_LIB.T6G(SCH_1):P5E_CPU0_P0_RX_DN(0)


DRAWING: @T6G_MB_LIB.T6G(SCH_1):PAGE383 

PT5161LRS-PT5161LRS,SMLF,IC,AJ051610U03  I3  U6010
 CL1 P5E_CPU0_P0_RX_BUF_DP<7> A_PERP8 @T6G_MB_LIB.T6G(SCH_1):P5E_CPU0_P0_RX_BUF_DP(7)
 CJ2 P5E_CPU0_P0_RX_BUF_DN<7> A_PERN8 @T6G_MB_LIB.T6G(SCH_1):P5E_CPU0_P0_RX_BUF_DN(7)
 CV1 P5E_CPU0_P0_RX_BUF_DP<6> A_PERP9 @T6G_MB_LIB.T6G(SCH_1):P5E_CPU0_P0_RX_BUF_DP(6)
 CT2 P5E_CPU0_P0_RX_BUF_DN<6> A_PERN9 @T6G_MB_LIB.T6G(SCH_1):P5E_CPU0_P0_RX_BUF_DN(6)
 DE1 P5E_CPU0_P0_RX_BUF_DP<5> A_PERP10 @T6G_MB_LIB.T6G(SCH_1):P5E_CPU0_P0_RX_BUF_DP(5)
 DC2 P5E_CPU0_P0_RX_BUF_DN<5> A_PERN10 @T6G_MB_LIB.T6G(SCH_1):P5E_CPU0_P0_RX_BUF_DN(5)
 DM1 P5E_CPU0_P0_RX_BUF_DP<4> A_PERP11 @T6G_MB_LIB.T6G(SCH_1):P5E_CPU0_P0_RX_BUF_DP(4)
 DK2 P5E_CPU0_P0_RX_BUF_DN<4> A_PERN11 @T6G_MB_LIB.T6G(SCH_1):P5E_CPU0_P0_RX_BUF_DN(4)
 DW1 P5E_CPU0_P0_RX_BUF_DP<3> A_PERP12 @T6G_MB_LIB.T6G(SCH_1):P5E_CPU0_P0_RX_BUF_DP(3)
 DU2 P5E_CPU0_P0_RX_BUF_DN<3> A_PERN12 @T6G_MB_LIB.T6G(SCH_1):P5E_CPU0_P0_RX_BUF_DN(3)
 EF1 P5E_CPU0_P0_RX_BUF_DP<2> A_PERP13 @T6G_MB_LIB.T6G(SCH_1):P5E_CPU0_P0_RX_BUF_DP(2)
 ED2 P5E_CPU0_P0_RX_BUF_DN<2> A_PERN13 @T6G_MB_LIB.T6G(SCH_1):P5E_CPU0_P0_RX_BUF_DN(2)
 EN1 P5E_CPU0_P0_RX_BUF_DP<1> A_PERP14 @T6G_MB_LIB.T6G(SCH_1):P5E_CPU0_P0_RX_BUF_DP(1)
 EL2 P5E_CPU0_P0_RX_BUF_DN<1> A_PERN14 @T6G_MB_LIB.T6G(SCH_1):P5E_CPU0_P0_RX_BUF_DN(1)
 EY1 P5E_CPU0_P0_RX_BUF_DP<0> A_PERP15 @T6G_MB_LIB.T6G(SCH_1):P5E_CPU0_P0_RX_BUF_DP(0)
 EV2 P5E_CPU0_P0_RX_BUF_DN<0> A_PERN15 @T6G_MB_LIB.T6G(SCH_1):P5E_CPU0_P0_RX_BUF_DN(0)

PT5161LRS-PT5161LRS,SMLF,IC,AJ051610U03  I4  U6010
  R1 P5E_CPU0_P0_RX_BUF_DP<15> A_PERP0 @T6G_MB_LIB.T6G(SCH_1):P5E_CPU0_P0_RX_BUF_DP(15)
  N2 P5E_CPU0_P0_RX_BUF_DN<15> A_PERN0 @T6G_MB_LIB.T6G(SCH_1):P5E_CPU0_P0_RX_BUF_DN(15)
 AB1 P5E_CPU0_P0_RX_BUF_DP<14> A_PERP1 @T6G_MB_LIB.T6G(SCH_1):P5E_CPU0_P0_RX_BUF_DP(14)
  Y2 P5E_CPU0_P0_RX_BUF_DN<14> A_PERN1 @T6G_MB_LIB.T6G(SCH_1):P5E_CPU0_P0_RX_BUF_DN(14)
 AJ1 P5E_CPU0_P0_RX_BUF_DP<13> A_PERP2 @T6G_MB_LIB.T6G(SCH_1):P5E_CPU0_P0_RX_BUF_DP(13)
 AG2 P5E_CPU0_P0_RX_BUF_DN<13> A_PERN2 @T6G_MB_LIB.T6G(SCH_1):P5E_CPU0_P0_RX_BUF_DN(13)
 AT1 P5E_CPU0_P0_RX_BUF_DP<12> A_PERP3 @T6G_MB_LIB.T6G(SCH_1):P5E_CPU0_P0_RX_BUF_DP(12)
 AP2 P5E_CPU0_P0_RX_BUF_DN<12> A_PERN3 @T6G_MB_LIB.T6G(SCH_1):P5E_CPU0_P0_RX_BUF_DN(12)
 BC1 P5E_CPU0_P0_RX_BUF_DP<11> A_PERP4 @T6G_MB_LIB.T6G(SCH_1):P5E_CPU0_P0_RX_BUF_DP(11)
 BA2 P5E_CPU0_P0_RX_BUF_DN<11> A_PERN4 @T6G_MB_LIB.T6G(SCH_1):P5E_CPU0_P0_RX_BUF_DN(11)
 BK1 P5E_CPU0_P0_RX_BUF_DP<10> A_PERP5 @T6G_MB_LIB.T6G(SCH_1):P5E_CPU0_P0_RX_BUF_DP(10)
 BH2 P5E_CPU0_P0_RX_BUF_DN<10> A_PERN5 @T6G_MB_LIB.T6G(SCH_1):P5E_CPU0_P0_RX_BUF_DN(10)
 BU1 P5E_CPU0_P0_RX_BUF_DP<9> A_PERP6 @T6G_MB_LIB.T6G(SCH_1):P5E_CPU0_P0_RX_BUF_DP(9)
 BR2 P5E_CPU0_P0_RX_BUF_DN<9> A_PERN6 @T6G_MB_LIB.T6G(SCH_1):P5E_CPU0_P0_RX_BUF_DN(9)
 CD1 P5E_CPU0_P0_RX_BUF_DP<8> A_PERP7 @T6G_MB_LIB.T6G(SCH_1):P5E_CPU0_P0_RX_BUF_DP(8)
 CB2 P5E_CPU0_P0_RX_BUF_DN<8> A_PERN7 @T6G_MB_LIB.T6G(SCH_1):P5E_CPU0_P0_RX_BUF_DN(8)


DRAWING: @T6G_MB_LIB.T6G(SCH_1):PAGE384 

PT5161LRS-PT5161LRS,SMLF,IC,AJ051610U03  I1  U6010
  M7 P5E_CPU0_P0_TX_BUF_DP<15> B_PETP0 @T6G_MB_LIB.T6G(SCH_1):P5E_CPU0_P0_TX_BUF_DP(15)
 P10 P5E_CPU0_P0_TX_BUF_DN<15> B_PETN0 @T6G_MB_LIB.T6G(SCH_1):P5E_CPU0_P0_TX_BUF_DN(15)
  W7 P5E_CPU0_P0_TX_BUF_DP<14> B_PETP1 @T6G_MB_LIB.T6G(SCH_1):P5E_CPU0_P0_TX_BUF_DP(14)
AA10 P5E_CPU0_P0_TX_BUF_DN<14> B_PETN1 @T6G_MB_LIB.T6G(SCH_1):P5E_CPU0_P0_TX_BUF_DN(14)
 AF7 P5E_CPU0_P0_TX_BUF_DP<13> B_PETP2 @T6G_MB_LIB.T6G(SCH_1):P5E_CPU0_P0_TX_BUF_DP(13)
AH10 P5E_CPU0_P0_TX_BUF_DN<13> B_PETN2 @T6G_MB_LIB.T6G(SCH_1):P5E_CPU0_P0_TX_BUF_DN(13)
 AN7 P5E_CPU0_P0_TX_BUF_DP<12> B_PETP3 @T6G_MB_LIB.T6G(SCH_1):P5E_CPU0_P0_TX_BUF_DP(12)
AR10 P5E_CPU0_P0_TX_BUF_DN<12> B_PETN3 @T6G_MB_LIB.T6G(SCH_1):P5E_CPU0_P0_TX_BUF_DN(12)
 AY7 P5E_CPU0_P0_TX_BUF_DP<11> B_PETP4 @T6G_MB_LIB.T6G(SCH_1):P5E_CPU0_P0_TX_BUF_DP(11)
BB10 P5E_CPU0_P0_TX_BUF_DN<11> B_PETN4 @T6G_MB_LIB.T6G(SCH_1):P5E_CPU0_P0_TX_BUF_DN(11)
 BG7 P5E_CPU0_P0_TX_BUF_DP<10> B_PETP5 @T6G_MB_LIB.T6G(SCH_1):P5E_CPU0_P0_TX_BUF_DP(10)
BJ10 P5E_CPU0_P0_TX_BUF_DN<10> B_PETN5 @T6G_MB_LIB.T6G(SCH_1):P5E_CPU0_P0_TX_BUF_DN(10)
 BP7 P5E_CPU0_P0_TX_BUF_DP<9> B_PETP6 @T6G_MB_LIB.T6G(SCH_1):P5E_CPU0_P0_TX_BUF_DP(9)
BT10 P5E_CPU0_P0_TX_BUF_DN<9> B_PETN6 @T6G_MB_LIB.T6G(SCH_1):P5E_CPU0_P0_TX_BUF_DN(9)
 CA7 P5E_CPU0_P0_TX_BUF_DP<8> B_PETP7 @T6G_MB_LIB.T6G(SCH_1):P5E_CPU0_P0_TX_BUF_DP(8)
CC10 P5E_CPU0_P0_TX_BUF_DN<8> B_PETN7 @T6G_MB_LIB.T6G(SCH_1):P5E_CPU0_P0_TX_BUF_DN(8)

PT5161LRS-PT5161LRS,SMLF,IC,AJ051610U03  I2  U6010
 CH7 P5E_CPU0_P0_TX_BUF_DP<7> B_PETP8 @T6G_MB_LIB.T6G(SCH_1):P5E_CPU0_P0_TX_BUF_DP(7)
CK10 P5E_CPU0_P0_TX_BUF_DN<7> B_PETN8 @T6G_MB_LIB.T6G(SCH_1):P5E_CPU0_P0_TX_BUF_DN(7)
 CR7 P5E_CPU0_P0_TX_BUF_DP<6> B_PETP9 @T6G_MB_LIB.T6G(SCH_1):P5E_CPU0_P0_TX_BUF_DP(6)
CU10 P5E_CPU0_P0_TX_BUF_DN<6> B_PETN9 @T6G_MB_LIB.T6G(SCH_1):P5E_CPU0_P0_TX_BUF_DN(6)
 DB7 P5E_CPU0_P0_TX_BUF_DP<5> B_PETP10 @T6G_MB_LIB.T6G(SCH_1):P5E_CPU0_P0_TX_BUF_DP(5)
DD10 P5E_CPU0_P0_TX_BUF_DN<5> B_PETN10 @T6G_MB_LIB.T6G(SCH_1):P5E_CPU0_P0_TX_BUF_DN(5)
 DJ7 P5E_CPU0_P0_TX_BUF_DP<4> B_PETP11 @T6G_MB_LIB.T6G(SCH_1):P5E_CPU0_P0_TX_BUF_DP(4)
DL10 P5E_CPU0_P0_TX_BUF_DN<4> B_PETN11 @T6G_MB_LIB.T6G(SCH_1):P5E_CPU0_P0_TX_BUF_DN(4)
 DT7 P5E_CPU0_P0_TX_BUF_DP<3> B_PETP12 @T6G_MB_LIB.T6G(SCH_1):P5E_CPU0_P0_TX_BUF_DP(3)
DV10 P5E_CPU0_P0_TX_BUF_DN<3> B_PETN12 @T6G_MB_LIB.T6G(SCH_1):P5E_CPU0_P0_TX_BUF_DN(3)
 EC7 P5E_CPU0_P0_TX_BUF_DP<2> B_PETP13 @T6G_MB_LIB.T6G(SCH_1):P5E_CPU0_P0_TX_BUF_DP(2)
EE10 P5E_CPU0_P0_TX_BUF_DN<2> B_PETN13 @T6G_MB_LIB.T6G(SCH_1):P5E_CPU0_P0_TX_BUF_DN(2)
 EK7 P5E_CPU0_P0_TX_BUF_DP<1> B_PETP14 @T6G_MB_LIB.T6G(SCH_1):P5E_CPU0_P0_TX_BUF_DP(1)
EM10 P5E_CPU0_P0_TX_BUF_DN<1> B_PETN14 @T6G_MB_LIB.T6G(SCH_1):P5E_CPU0_P0_TX_BUF_DN(1)
 EU7 P5E_CPU0_P0_TX_BUF_DP<0> B_PETP15 @T6G_MB_LIB.T6G(SCH_1):P5E_CPU0_P0_TX_BUF_DP(0)
EW10 P5E_CPU0_P0_TX_BUF_DN<0> B_PETN15 @T6G_MB_LIB.T6G(SCH_1):P5E_CPU0_P0_TX_BUF_DN(0)

Q_CAP_DIFFBUS_C0201-DIFF BUS_0.22UF,6.3V,20%,X6S,SA  I59  C6516
   1 P5E_CPU0_P0_TX_BUF_C_DN<7>      1 @T6G_MB_LIB.T6G(SCH_1):P5E_CPU0_P0_TX_BUF_C_DN(7)
   2 P5E_CPU0_P0_TX_BUF_DN<7>      2 @T6G_MB_LIB.T6G(SCH_1):P5E_CPU0_P0_TX_BUF_DN(7)

Q_CAP_DIFFBUS_C0201-DIFF BUS_0.22UF,6.3V,20%,X6S,SA  I60  C6513
   1 P5E_CPU0_P0_TX_BUF_C_DP<6>      1 @T6G_MB_LIB.T6G(SCH_1):P5E_CPU0_P0_TX_BUF_C_DP(6)
   2 P5E_CPU0_P0_TX_BUF_DP<6>      2 @T6G_MB_LIB.T6G(SCH_1):P5E_CPU0_P0_TX_BUF_DP(6)

Q_CAP_DIFFBUS_C0201-DIFF BUS_0.22UF,6.3V,20%,X6S,SA  I61  C6514
   1 P5E_CPU0_P0_TX_BUF_C_DN<6>      1 @T6G_MB_LIB.T6G(SCH_1):P5E_CPU0_P0_TX_BUF_C_DN(6)
   2 P5E_CPU0_P0_TX_BUF_DN<6>      2 @T6G_MB_LIB.T6G(SCH_1):P5E_CPU0_P0_TX_BUF_DN(6)

Q_CAP_DIFFBUS_C0201-DIFF BUS_0.22UF,6.3V,20%,X6S,SA  I62  C6515
   1 P5E_CPU0_P0_TX_BUF_C_DP<7>      1 @T6G_MB_LIB.T6G(SCH_1):P5E_CPU0_P0_TX_BUF_C_DP(7)
   2 P5E_CPU0_P0_TX_BUF_DP<7>      2 @T6G_MB_LIB.T6G(SCH_1):P5E_CPU0_P0_TX_BUF_DP(7)

Q_CAP_DIFFBUS_C0201-DIFF BUS_0.22UF,6.3V,20%,X6S,SA  I63  C6511
   1 P5E_CPU0_P0_TX_BUF_C_DP<5>      1 @T6G_MB_LIB.T6G(SCH_1):P5E_CPU0_P0_TX_BUF_C_DP(5)
   2 P5E_CPU0_P0_TX_BUF_DP<5>      2 @T6G_MB_LIB.T6G(SCH_1):P5E_CPU0_P0_TX_BUF_DP(5)

Q_CAP_DIFFBUS_C0201-DIFF BUS_0.22UF,6.3V,20%,X6S,SA  I64  C6512
   1 P5E_CPU0_P0_TX_BUF_C_DN<5>      1 @T6G_MB_LIB.T6G(SCH_1):P5E_CPU0_P0_TX_BUF_C_DN(5)
   2 P5E_CPU0_P0_TX_BUF_DN<5>      2 @T6G_MB_LIB.T6G(SCH_1):P5E_CPU0_P0_TX_BUF_DN(5)

Q_CAP_DIFFBUS_C0201-DIFF BUS_0.22UF,6.3V,20%,X6S,SA  I65  C6509
   1 P5E_CPU0_P0_TX_BUF_C_DP<4>      1 @T6G_MB_LIB.T6G(SCH_1):P5E_CPU0_P0_TX_BUF_C_DP(4)
   2 P5E_CPU0_P0_TX_BUF_DP<4>      2 @T6G_MB_LIB.T6G(SCH_1):P5E_CPU0_P0_TX_BUF_DP(4)

Q_CAP_DIFFBUS_C0201-DIFF BUS_0.22UF,6.3V,20%,X6S,SA  I66  C6510
   1 P5E_CPU0_P0_TX_BUF_C_DN<4>      1 @T6G_MB_LIB.T6G(SCH_1):P5E_CPU0_P0_TX_BUF_C_DN(4)
   2 P5E_CPU0_P0_TX_BUF_DN<4>      2 @T6G_MB_LIB.T6G(SCH_1):P5E_CPU0_P0_TX_BUF_DN(4)

Q_CAP_DIFFBUS_C0201-DIFF BUS_0.22UF,6.3V,20%,X6S,SA  I71  C6508
   1 P5E_CPU0_P0_TX_BUF_C_DN<3>      1 @T6G_MB_LIB.T6G(SCH_1):P5E_CPU0_P0_TX_BUF_C_DN(3)
   2 P5E_CPU0_P0_TX_BUF_DN<3>      2 @T6G_MB_LIB.T6G(SCH_1):P5E_CPU0_P0_TX_BUF_DN(3)

Q_CAP_DIFFBUS_C0201-DIFF BUS_0.22UF,6.3V,20%,X6S,SA  I72  C6506
   1 P5E_CPU0_P0_TX_BUF_C_DN<2>      1 @T6G_MB_LIB.T6G(SCH_1):P5E_CPU0_P0_TX_BUF_C_DN(2)
   2 P5E_CPU0_P0_TX_BUF_DN<2>      2 @T6G_MB_LIB.T6G(SCH_1):P5E_CPU0_P0_TX_BUF_DN(2)

Q_CAP_DIFFBUS_C0201-DIFF BUS_0.22UF,6.3V,20%,X6S,SA  I73  C6507
   1 P5E_CPU0_P0_TX_BUF_C_DP<3>      1 @T6G_MB_LIB.T6G(SCH_1):P5E_CPU0_P0_TX_BUF_C_DP(3)
   2 P5E_CPU0_P0_TX_BUF_DP<3>      2 @T6G_MB_LIB.T6G(SCH_1):P5E_CPU0_P0_TX_BUF_DP(3)

Q_CAP_DIFFBUS_C0201-DIFF BUS_0.22UF,6.3V,20%,X6S,SA  I74  C6505
   1 P5E_CPU0_P0_TX_BUF_C_DP<2>      1 @T6G_MB_LIB.T6G(SCH_1):P5E_CPU0_P0_TX_BUF_C_DP(2)
   2 P5E_CPU0_P0_TX_BUF_DP<2>      2 @T6G_MB_LIB.T6G(SCH_1):P5E_CPU0_P0_TX_BUF_DP(2)

Q_CAP_DIFFBUS_C0201-DIFF BUS_0.22UF,6.3V,20%,X6S,SA  I75  C6503
   1 P5E_CPU0_P0_TX_BUF_C_DP<1>      1 @T6G_MB_LIB.T6G(SCH_1):P5E_CPU0_P0_TX_BUF_C_DP(1)
   2 P5E_CPU0_P0_TX_BUF_DP<1>      2 @T6G_MB_LIB.T6G(SCH_1):P5E_CPU0_P0_TX_BUF_DP(1)

Q_CAP_DIFFBUS_C0201-DIFF BUS_0.22UF,6.3V,20%,X6S,SA  I76  C6504
   1 P5E_CPU0_P0_TX_BUF_C_DN<1>      1 @T6G_MB_LIB.T6G(SCH_1):P5E_CPU0_P0_TX_BUF_C_DN(1)
   2 P5E_CPU0_P0_TX_BUF_DN<1>      2 @T6G_MB_LIB.T6G(SCH_1):P5E_CPU0_P0_TX_BUF_DN(1)

Q_CAP_DIFFBUS_C0201-DIFF BUS_0.22UF,6.3V,20%,X6S,SA  I77  C6501
   1 P5E_CPU0_P0_TX_BUF_C_DP<0>      1 @T6G_MB_LIB.T6G(SCH_1):P5E_CPU0_P0_TX_BUF_C_DP(0)
   2 P5E_CPU0_P0_TX_BUF_DP<0>      2 @T6G_MB_LIB.T6G(SCH_1):P5E_CPU0_P0_TX_BUF_DP(0)

Q_CAP_DIFFBUS_C0201-DIFF BUS_0.22UF,6.3V,20%,X6S,SA  I78  C6502
   1 P5E_CPU0_P0_TX_BUF_C_DN<0>      1 @T6G_MB_LIB.T6G(SCH_1):P5E_CPU0_P0_TX_BUF_C_DN(0)
   2 P5E_CPU0_P0_TX_BUF_DN<0>      2 @T6G_MB_LIB.T6G(SCH_1):P5E_CPU0_P0_TX_BUF_DN(0)

Q_CAP_DIFFBUS_C0201-DIFF BUS_0.22UF,6.3V,20%,X6S,SA  I99  C6517
   1 P5E_CPU0_P0_TX_BUF_C_DP<8>      1 @T6G_MB_LIB.T6G(SCH_1):P5E_CPU0_P0_TX_BUF_C_DP(8)
   2 P5E_CPU0_P0_TX_BUF_DP<8>      2 @T6G_MB_LIB.T6G(SCH_1):P5E_CPU0_P0_TX_BUF_DP(8)

Q_CAP_DIFFBUS_C0201-DIFF BUS_0.22UF,6.3V,20%,X6S,SA  I100  C6518
   1 P5E_CPU0_P0_TX_BUF_C_DN<8>      1 @T6G_MB_LIB.T6G(SCH_1):P5E_CPU0_P0_TX_BUF_C_DN(8)
   2 P5E_CPU0_P0_TX_BUF_DN<8>      2 @T6G_MB_LIB.T6G(SCH_1):P5E_CPU0_P0_TX_BUF_DN(8)

Q_CAP_DIFFBUS_C0201-DIFF BUS_0.22UF,6.3V,20%,X6S,SA  I101  C6520
   1 P5E_CPU0_P0_TX_BUF_C_DN<9>      1 @T6G_MB_LIB.T6G(SCH_1):P5E_CPU0_P0_TX_BUF_C_DN(9)
   2 P5E_CPU0_P0_TX_BUF_DN<9>      2 @T6G_MB_LIB.T6G(SCH_1):P5E_CPU0_P0_TX_BUF_DN(9)

Q_CAP_DIFFBUS_C0201-DIFF BUS_0.22UF,6.3V,20%,X6S,SA  I102  C6519
   1 P5E_CPU0_P0_TX_BUF_C_DP<9>      1 @T6G_MB_LIB.T6G(SCH_1):P5E_CPU0_P0_TX_BUF_C_DP(9)
   2 P5E_CPU0_P0_TX_BUF_DP<9>      2 @T6G_MB_LIB.T6G(SCH_1):P5E_CPU0_P0_TX_BUF_DP(9)

Q_CAP_DIFFBUS_C0201-DIFF BUS_0.22UF,6.3V,20%,X6S,SA  I118  C6522
   1 P5E_CPU0_P0_TX_BUF_C_DN<10>      1 @T6G_MB_LIB.T6G(SCH_1):P5E_CPU0_P0_TX_BUF_C_DN(10)
   2 P5E_CPU0_P0_TX_BUF_DN<10>      2 @T6G_MB_LIB.T6G(SCH_1):P5E_CPU0_P0_TX_BUF_DN(10)

Q_CAP_DIFFBUS_C0201-DIFF BUS_0.22UF,6.3V,20%,X6S,SA  I119  C6521
   1 P5E_CPU0_P0_TX_BUF_C_DP<10>      1 @T6G_MB_LIB.T6G(SCH_1):P5E_CPU0_P0_TX_BUF_C_DP(10)
   2 P5E_CPU0_P0_TX_BUF_DP<10>      2 @T6G_MB_LIB.T6G(SCH_1):P5E_CPU0_P0_TX_BUF_DP(10)

Q_CAP_DIFFBUS_C0201-DIFF BUS_0.22UF,6.3V,20%,X6S,SA  I120  C6523
   1 P5E_CPU0_P0_TX_BUF_C_DP<11>      1 @T6G_MB_LIB.T6G(SCH_1):P5E_CPU0_P0_TX_BUF_C_DP(11)
   2 P5E_CPU0_P0_TX_BUF_DP<11>      2 @T6G_MB_LIB.T6G(SCH_1):P5E_CPU0_P0_TX_BUF_DP(11)

Q_CAP_DIFFBUS_C0201-DIFF BUS_0.22UF,6.3V,20%,X6S,SA  I121  C6524
   1 P5E_CPU0_P0_TX_BUF_C_DN<11>      1 @T6G_MB_LIB.T6G(SCH_1):P5E_CPU0_P0_TX_BUF_C_DN(11)
   2 P5E_CPU0_P0_TX_BUF_DN<11>      2 @T6G_MB_LIB.T6G(SCH_1):P5E_CPU0_P0_TX_BUF_DN(11)

Q_CAP_DIFFBUS_C0201-DIFF BUS_0.22UF,6.3V,20%,X6S,SA  I122  C6526
   1 P5E_CPU0_P0_TX_BUF_C_DN<12>      1 @T6G_MB_LIB.T6G(SCH_1):P5E_CPU0_P0_TX_BUF_C_DN(12)
   2 P5E_CPU0_P0_TX_BUF_DN<12>      2 @T6G_MB_LIB.T6G(SCH_1):P5E_CPU0_P0_TX_BUF_DN(12)

Q_CAP_DIFFBUS_C0201-DIFF BUS_0.22UF,6.3V,20%,X6S,SA  I123  C6525
   1 P5E_CPU0_P0_TX_BUF_C_DP<12>      1 @T6G_MB_LIB.T6G(SCH_1):P5E_CPU0_P0_TX_BUF_C_DP(12)
   2 P5E_CPU0_P0_TX_BUF_DP<12>      2 @T6G_MB_LIB.T6G(SCH_1):P5E_CPU0_P0_TX_BUF_DP(12)

Q_CAP_DIFFBUS_C0201-DIFF BUS_0.22UF,6.3V,20%,X6S,SA  I124  C6527
   1 P5E_CPU0_P0_TX_BUF_C_DP<13>      1 @T6G_MB_LIB.T6G(SCH_1):P5E_CPU0_P0_TX_BUF_C_DP(13)
   2 P5E_CPU0_P0_TX_BUF_DP<13>      2 @T6G_MB_LIB.T6G(SCH_1):P5E_CPU0_P0_TX_BUF_DP(13)

Q_CAP_DIFFBUS_C0201-DIFF BUS_0.22UF,6.3V,20%,X6S,SA  I125  C6528
   1 P5E_CPU0_P0_TX_BUF_C_DN<13>      1 @T6G_MB_LIB.T6G(SCH_1):P5E_CPU0_P0_TX_BUF_C_DN(13)
   2 P5E_CPU0_P0_TX_BUF_DN<13>      2 @T6G_MB_LIB.T6G(SCH_1):P5E_CPU0_P0_TX_BUF_DN(13)

Q_CAP_DIFFBUS_C0201-DIFF BUS_0.22UF,6.3V,20%,X6S,SA  I126  C6529
   1 P5E_CPU0_P0_TX_BUF_C_DP<14>      1 @T6G_MB_LIB.T6G(SCH_1):P5E_CPU0_P0_TX_BUF_C_DP(14)
   2 P5E_CPU0_P0_TX_BUF_DP<14>      2 @T6G_MB_LIB.T6G(SCH_1):P5E_CPU0_P0_TX_BUF_DP(14)

Q_CAP_DIFFBUS_C0201-DIFF BUS_0.22UF,6.3V,20%,X6S,SA  I127  C6530
   1 P5E_CPU0_P0_TX_BUF_C_DN<14>      1 @T6G_MB_LIB.T6G(SCH_1):P5E_CPU0_P0_TX_BUF_C_DN(14)
   2 P5E_CPU0_P0_TX_BUF_DN<14>      2 @T6G_MB_LIB.T6G(SCH_1):P5E_CPU0_P0_TX_BUF_DN(14)

Q_CAP_DIFFBUS_C0201-DIFF BUS_0.22UF,6.3V,20%,X6S,SA  I129  C6531
   1 P5E_CPU0_P0_TX_BUF_C_DP<15>      1 @T6G_MB_LIB.T6G(SCH_1):P5E_CPU0_P0_TX_BUF_C_DP(15)
   2 P5E_CPU0_P0_TX_BUF_DP<15>      2 @T6G_MB_LIB.T6G(SCH_1):P5E_CPU0_P0_TX_BUF_DP(15)

Q_CAP_DIFFBUS_C0201-DIFF BUS_0.22UF,6.3V,20%,X6S,SA  I130  C6532
   1 P5E_CPU0_P0_TX_BUF_C_DN<15>      1 @T6G_MB_LIB.T6G(SCH_1):P5E_CPU0_P0_TX_BUF_C_DN(15)
   2 P5E_CPU0_P0_TX_BUF_DN<15>      2 @T6G_MB_LIB.T6G(SCH_1):P5E_CPU0_P0_TX_BUF_DN(15)


DRAWING: @T6G_MB_LIB.T6G(SCH_1):PAGE393 

Q_CAP_DIFFBUS_C0201-DIFF BUS_0.22UF,6.3V,20%,X6S,SA  I17  C6676
   1 P5E_CPU1_P1_TX_BUF_C_DN<7>      1 @T6G_MB_LIB.T6G(SCH_1):P5E_CPU1_P1_TX_BUF_C_DN(7)
   2 P5E_CPU1_P1_TX_BUF_DN<7>      2 @T6G_MB_LIB.T6G(SCH_1):P5E_CPU1_P1_TX_BUF_DN(7)

Q_CAP_DIFFBUS_C0201-DIFF BUS_0.22UF,6.3V,20%,X6S,SA  I18  C6675
   1 P5E_CPU1_P1_TX_BUF_C_DP<7>      1 @T6G_MB_LIB.T6G(SCH_1):P5E_CPU1_P1_TX_BUF_C_DP(7)
   2 P5E_CPU1_P1_TX_BUF_DP<7>      2 @T6G_MB_LIB.T6G(SCH_1):P5E_CPU1_P1_TX_BUF_DP(7)

Q_CAP_DIFFBUS_C0201-DIFF BUS_0.22UF,6.3V,20%,X6S,SA  I19  C6674
   1 P5E_CPU1_P1_TX_BUF_C_DN<6>      1 @T6G_MB_LIB.T6G(SCH_1):P5E_CPU1_P1_TX_BUF_C_DN(6)
   2 P5E_CPU1_P1_TX_BUF_DN<6>      2 @T6G_MB_LIB.T6G(SCH_1):P5E_CPU1_P1_TX_BUF_DN(6)

Q_CAP_DIFFBUS_C0201-DIFF BUS_0.22UF,6.3V,20%,X6S,SA  I20  C6673
   1 P5E_CPU1_P1_TX_BUF_C_DP<6>      1 @T6G_MB_LIB.T6G(SCH_1):P5E_CPU1_P1_TX_BUF_C_DP(6)
   2 P5E_CPU1_P1_TX_BUF_DP<6>      2 @T6G_MB_LIB.T6G(SCH_1):P5E_CPU1_P1_TX_BUF_DP(6)

Q_CAP_DIFFBUS_C0201-DIFF BUS_0.22UF,6.3V,20%,X6S,SA  I23  C6672
   1 P5E_CPU1_P1_TX_BUF_C_DN<5>      1 @T6G_MB_LIB.T6G(SCH_1):P5E_CPU1_P1_TX_BUF_C_DN(5)
   2 P5E_CPU1_P1_TX_BUF_DN<5>      2 @T6G_MB_LIB.T6G(SCH_1):P5E_CPU1_P1_TX_BUF_DN(5)

Q_CAP_DIFFBUS_C0201-DIFF BUS_0.22UF,6.3V,20%,X6S,SA  I24  C6671
   1 P5E_CPU1_P1_TX_BUF_C_DP<5>      1 @T6G_MB_LIB.T6G(SCH_1):P5E_CPU1_P1_TX_BUF_C_DP(5)
   2 P5E_CPU1_P1_TX_BUF_DP<5>      2 @T6G_MB_LIB.T6G(SCH_1):P5E_CPU1_P1_TX_BUF_DP(5)

Q_CAP_DIFFBUS_C0201-DIFF BUS_0.22UF,6.3V,20%,X6S,SA  I25  C6670
   1 P5E_CPU1_P1_TX_BUF_C_DN<4>      1 @T6G_MB_LIB.T6G(SCH_1):P5E_CPU1_P1_TX_BUF_C_DN(4)
   2 P5E_CPU1_P1_TX_BUF_DN<4>      2 @T6G_MB_LIB.T6G(SCH_1):P5E_CPU1_P1_TX_BUF_DN(4)

Q_CAP_DIFFBUS_C0201-DIFF BUS_0.22UF,6.3V,20%,X6S,SA  I26  C6669
   1 P5E_CPU1_P1_TX_BUF_C_DP<4>      1 @T6G_MB_LIB.T6G(SCH_1):P5E_CPU1_P1_TX_BUF_C_DP(4)
   2 P5E_CPU1_P1_TX_BUF_DP<4>      2 @T6G_MB_LIB.T6G(SCH_1):P5E_CPU1_P1_TX_BUF_DP(4)

Q_CAP_DIFFBUS_C0201-DIFF BUS_0.22UF,6.3V,20%,X6S,SA  I27  C6667
   1 P5E_CPU1_P1_TX_BUF_C_DP<3>      1 @T6G_MB_LIB.T6G(SCH_1):P5E_CPU1_P1_TX_BUF_C_DP(3)
   2 P5E_CPU1_P1_TX_BUF_DP<3>      2 @T6G_MB_LIB.T6G(SCH_1):P5E_CPU1_P1_TX_BUF_DP(3)

Q_CAP_DIFFBUS_C0201-DIFF BUS_0.22UF,6.3V,20%,X6S,SA  I28  C6668
   1 P5E_CPU1_P1_TX_BUF_C_DN<3>      1 @T6G_MB_LIB.T6G(SCH_1):P5E_CPU1_P1_TX_BUF_C_DN(3)
   2 P5E_CPU1_P1_TX_BUF_DN<3>      2 @T6G_MB_LIB.T6G(SCH_1):P5E_CPU1_P1_TX_BUF_DN(3)

Q_CAP_DIFFBUS_C0201-DIFF BUS_0.22UF,6.3V,20%,X6S,SA  I29  C6666
   1 P5E_CPU1_P1_TX_BUF_C_DN<2>      1 @T6G_MB_LIB.T6G(SCH_1):P5E_CPU1_P1_TX_BUF_C_DN(2)
   2 P5E_CPU1_P1_TX_BUF_DN<2>      2 @T6G_MB_LIB.T6G(SCH_1):P5E_CPU1_P1_TX_BUF_DN(2)

Q_CAP_DIFFBUS_C0201-DIFF BUS_0.22UF,6.3V,20%,X6S,SA  I30  C6665
   1 P5E_CPU1_P1_TX_BUF_C_DP<2>      1 @T6G_MB_LIB.T6G(SCH_1):P5E_CPU1_P1_TX_BUF_C_DP(2)
   2 P5E_CPU1_P1_TX_BUF_DP<2>      2 @T6G_MB_LIB.T6G(SCH_1):P5E_CPU1_P1_TX_BUF_DP(2)

Q_CAP_DIFFBUS_C0201-DIFF BUS_0.22UF,6.3V,20%,X6S,SA  I31  C6663
   1 P5E_CPU1_P1_TX_BUF_C_DP<1>      1 @T6G_MB_LIB.T6G(SCH_1):P5E_CPU1_P1_TX_BUF_C_DP(1)
   2 P5E_CPU1_P1_TX_BUF_DP<1>      2 @T6G_MB_LIB.T6G(SCH_1):P5E_CPU1_P1_TX_BUF_DP(1)

Q_CAP_DIFFBUS_C0201-DIFF BUS_0.22UF,6.3V,20%,X6S,SA  I32  C6664
   1 P5E_CPU1_P1_TX_BUF_C_DN<1>      1 @T6G_MB_LIB.T6G(SCH_1):P5E_CPU1_P1_TX_BUF_C_DN(1)
   2 P5E_CPU1_P1_TX_BUF_DN<1>      2 @T6G_MB_LIB.T6G(SCH_1):P5E_CPU1_P1_TX_BUF_DN(1)

Q_CAP_DIFFBUS_C0201-DIFF BUS_0.22UF,6.3V,20%,X6S,SA  I33  C6662
   1 P5E_CPU1_P1_TX_BUF_C_DN<0>      1 @T6G_MB_LIB.T6G(SCH_1):P5E_CPU1_P1_TX_BUF_C_DN(0)
   2 P5E_CPU1_P1_TX_BUF_DN<0>      2 @T6G_MB_LIB.T6G(SCH_1):P5E_CPU1_P1_TX_BUF_DN(0)

PT5161LRS-PT5161LRS,SMLF,IC,AJ051610U03  I41  U6015
  M7 P5E_CPU1_P1_TX_BUF_DP<15> B_PETP0 @T6G_MB_LIB.T6G(SCH_1):P5E_CPU1_P1_TX_BUF_DP(15)
 P10 P5E_CPU1_P1_TX_BUF_DN<15> B_PETN0 @T6G_MB_LIB.T6G(SCH_1):P5E_CPU1_P1_TX_BUF_DN(15)
  W7 P5E_CPU1_P1_TX_BUF_DP<14> B_PETP1 @T6G_MB_LIB.T6G(SCH_1):P5E_CPU1_P1_TX_BUF_DP(14)
AA10 P5E_CPU1_P1_TX_BUF_DN<14> B_PETN1 @T6G_MB_LIB.T6G(SCH_1):P5E_CPU1_P1_TX_BUF_DN(14)
 AF7 P5E_CPU1_P1_TX_BUF_DP<13> B_PETP2 @T6G_MB_LIB.T6G(SCH_1):P5E_CPU1_P1_TX_BUF_DP(13)
AH10 P5E_CPU1_P1_TX_BUF_DN<13> B_PETN2 @T6G_MB_LIB.T6G(SCH_1):P5E_CPU1_P1_TX_BUF_DN(13)
 AN7 P5E_CPU1_P1_TX_BUF_DP<12> B_PETP3 @T6G_MB_LIB.T6G(SCH_1):P5E_CPU1_P1_TX_BUF_DP(12)
AR10 P5E_CPU1_P1_TX_BUF_DN<12> B_PETN3 @T6G_MB_LIB.T6G(SCH_1):P5E_CPU1_P1_TX_BUF_DN(12)
 AY7 P5E_CPU1_P1_TX_BUF_DP<11> B_PETP4 @T6G_MB_LIB.T6G(SCH_1):P5E_CPU1_P1_TX_BUF_DP(11)
BB10 P5E_CPU1_P1_TX_BUF_DN<11> B_PETN4 @T6G_MB_LIB.T6G(SCH_1):P5E_CPU1_P1_TX_BUF_DN(11)
 BG7 P5E_CPU1_P1_TX_BUF_DP<10> B_PETP5 @T6G_MB_LIB.T6G(SCH_1):P5E_CPU1_P1_TX_BUF_DP(10)
BJ10 P5E_CPU1_P1_TX_BUF_DN<10> B_PETN5 @T6G_MB_LIB.T6G(SCH_1):P5E_CPU1_P1_TX_BUF_DN(10)
 BP7 P5E_CPU1_P1_TX_BUF_DP<9> B_PETP6 @T6G_MB_LIB.T6G(SCH_1):P5E_CPU1_P1_TX_BUF_DP(9)
BT10 P5E_CPU1_P1_TX_BUF_DN<9> B_PETN6 @T6G_MB_LIB.T6G(SCH_1):P5E_CPU1_P1_TX_BUF_DN(9)
 CA7 P5E_CPU1_P1_TX_BUF_DP<8> B_PETP7 @T6G_MB_LIB.T6G(SCH_1):P5E_CPU1_P1_TX_BUF_DP(8)
CC10 P5E_CPU1_P1_TX_BUF_DN<8> B_PETN7 @T6G_MB_LIB.T6G(SCH_1):P5E_CPU1_P1_TX_BUF_DN(8)

Q_CAP_DIFFBUS_C0201-DIFF BUS_0.22UF,6.3V,20%,X6S,SA  I42  C6661
   1 P5E_CPU1_P1_TX_BUF_C_DP<0>      1 @T6G_MB_LIB.T6G(SCH_1):P5E_CPU1_P1_TX_BUF_C_DP(0)
   2 P5E_CPU1_P1_TX_BUF_DP<0>      2 @T6G_MB_LIB.T6G(SCH_1):P5E_CPU1_P1_TX_BUF_DP(0)

Q_CAP_DIFFBUS_C0201-DIFF BUS_0.22UF,6.3V,20%,X6S,SA  I84  C6692
   1 P5E_CPU1_P1_TX_BUF_C_DN<15>      1 @T6G_MB_LIB.T6G(SCH_1):P5E_CPU1_P1_TX_BUF_C_DN(15)
   2 P5E_CPU1_P1_TX_BUF_DN<15>      2 @T6G_MB_LIB.T6G(SCH_1):P5E_CPU1_P1_TX_BUF_DN(15)

Q_CAP_DIFFBUS_C0201-DIFF BUS_0.22UF,6.3V,20%,X6S,SA  I85  C6691
   1 P5E_CPU1_P1_TX_BUF_C_DP<15>      1 @T6G_MB_LIB.T6G(SCH_1):P5E_CPU1_P1_TX_BUF_C_DP(15)
   2 P5E_CPU1_P1_TX_BUF_DP<15>      2 @T6G_MB_LIB.T6G(SCH_1):P5E_CPU1_P1_TX_BUF_DP(15)

Q_CAP_DIFFBUS_C0201-DIFF BUS_0.22UF,6.3V,20%,X6S,SA  I86  C6690
   1 P5E_CPU1_P1_TX_BUF_C_DN<14>      1 @T6G_MB_LIB.T6G(SCH_1):P5E_CPU1_P1_TX_BUF_C_DN(14)
   2 P5E_CPU1_P1_TX_BUF_DN<14>      2 @T6G_MB_LIB.T6G(SCH_1):P5E_CPU1_P1_TX_BUF_DN(14)

Q_CAP_DIFFBUS_C0201-DIFF BUS_0.22UF,6.3V,20%,X6S,SA  I87  C6689
   1 P5E_CPU1_P1_TX_BUF_C_DP<14>      1 @T6G_MB_LIB.T6G(SCH_1):P5E_CPU1_P1_TX_BUF_C_DP(14)
   2 P5E_CPU1_P1_TX_BUF_DP<14>      2 @T6G_MB_LIB.T6G(SCH_1):P5E_CPU1_P1_TX_BUF_DP(14)

Q_CAP_DIFFBUS_C0201-DIFF BUS_0.22UF,6.3V,20%,X6S,SA  I88  C6688
   1 P5E_CPU1_P1_TX_BUF_C_DN<13>      1 @T6G_MB_LIB.T6G(SCH_1):P5E_CPU1_P1_TX_BUF_C_DN(13)
   2 P5E_CPU1_P1_TX_BUF_DN<13>      2 @T6G_MB_LIB.T6G(SCH_1):P5E_CPU1_P1_TX_BUF_DN(13)

Q_CAP_DIFFBUS_C0201-DIFF BUS_0.22UF,6.3V,20%,X6S,SA  I89  C6687
   1 P5E_CPU1_P1_TX_BUF_C_DP<13>      1 @T6G_MB_LIB.T6G(SCH_1):P5E_CPU1_P1_TX_BUF_C_DP(13)
   2 P5E_CPU1_P1_TX_BUF_DP<13>      2 @T6G_MB_LIB.T6G(SCH_1):P5E_CPU1_P1_TX_BUF_DP(13)

Q_CAP_DIFFBUS_C0201-DIFF BUS_0.22UF,6.3V,20%,X6S,SA  I95  C6686
   1 P5E_CPU1_P1_TX_BUF_C_DN<12>      1 @T6G_MB_LIB.T6G(SCH_1):P5E_CPU1_P1_TX_BUF_C_DN(12)
   2 P5E_CPU1_P1_TX_BUF_DN<12>      2 @T6G_MB_LIB.T6G(SCH_1):P5E_CPU1_P1_TX_BUF_DN(12)

Q_CAP_DIFFBUS_C0201-DIFF BUS_0.22UF,6.3V,20%,X6S,SA  I96  C6685
   1 P5E_CPU1_P1_TX_BUF_C_DP<12>      1 @T6G_MB_LIB.T6G(SCH_1):P5E_CPU1_P1_TX_BUF_C_DP(12)
   2 P5E_CPU1_P1_TX_BUF_DP<12>      2 @T6G_MB_LIB.T6G(SCH_1):P5E_CPU1_P1_TX_BUF_DP(12)

Q_CAP_DIFFBUS_C0201-DIFF BUS_0.22UF,6.3V,20%,X6S,SA  I97  C6684
   1 P5E_CPU1_P1_TX_BUF_C_DN<11>      1 @T6G_MB_LIB.T6G(SCH_1):P5E_CPU1_P1_TX_BUF_C_DN(11)
   2 P5E_CPU1_P1_TX_BUF_DN<11>      2 @T6G_MB_LIB.T6G(SCH_1):P5E_CPU1_P1_TX_BUF_DN(11)

Q_CAP_DIFFBUS_C0201-DIFF BUS_0.22UF,6.3V,20%,X6S,SA  I98  C6683
   1 P5E_CPU1_P1_TX_BUF_C_DP<11>      1 @T6G_MB_LIB.T6G(SCH_1):P5E_CPU1_P1_TX_BUF_C_DP(11)
   2 P5E_CPU1_P1_TX_BUF_DP<11>      2 @T6G_MB_LIB.T6G(SCH_1):P5E_CPU1_P1_TX_BUF_DP(11)

Q_CAP_DIFFBUS_C0201-DIFF BUS_0.22UF,6.3V,20%,X6S,SA  I99  C6681
   1 P5E_CPU1_P1_TX_BUF_C_DP<10>      1 @T6G_MB_LIB.T6G(SCH_1):P5E_CPU1_P1_TX_BUF_C_DP(10)
   2 P5E_CPU1_P1_TX_BUF_DP<10>      2 @T6G_MB_LIB.T6G(SCH_1):P5E_CPU1_P1_TX_BUF_DP(10)

Q_CAP_DIFFBUS_C0201-DIFF BUS_0.22UF,6.3V,20%,X6S,SA  I100  C6682
   1 P5E_CPU1_P1_TX_BUF_C_DN<10>      1 @T6G_MB_LIB.T6G(SCH_1):P5E_CPU1_P1_TX_BUF_C_DN(10)
   2 P5E_CPU1_P1_TX_BUF_DN<10>      2 @T6G_MB_LIB.T6G(SCH_1):P5E_CPU1_P1_TX_BUF_DN(10)

Q_CAP_DIFFBUS_C0201-DIFF BUS_0.22UF,6.3V,20%,X6S,SA  I101  C6679
   1 P5E_CPU1_P1_TX_BUF_C_DP<9>      1 @T6G_MB_LIB.T6G(SCH_1):P5E_CPU1_P1_TX_BUF_C_DP(9)
   2 P5E_CPU1_P1_TX_BUF_DP<9>      2 @T6G_MB_LIB.T6G(SCH_1):P5E_CPU1_P1_TX_BUF_DP(9)

Q_CAP_DIFFBUS_C0201-DIFF BUS_0.22UF,6.3V,20%,X6S,SA  I102  C6680
   1 P5E_CPU1_P1_TX_BUF_C_DN<9>      1 @T6G_MB_LIB.T6G(SCH_1):P5E_CPU1_P1_TX_BUF_C_DN(9)
   2 P5E_CPU1_P1_TX_BUF_DN<9>      2 @T6G_MB_LIB.T6G(SCH_1):P5E_CPU1_P1_TX_BUF_DN(9)

Q_CAP_DIFFBUS_C0201-DIFF BUS_0.22UF,6.3V,20%,X6S,SA  I103  C6678
   1 P5E_CPU1_P1_TX_BUF_C_DN<8>      1 @T6G_MB_LIB.T6G(SCH_1):P5E_CPU1_P1_TX_BUF_C_DN(8)
   2 P5E_CPU1_P1_TX_BUF_DN<8>      2 @T6G_MB_LIB.T6G(SCH_1):P5E_CPU1_P1_TX_BUF_DN(8)

Q_CAP_DIFFBUS_C0201-DIFF BUS_0.22UF,6.3V,20%,X6S,SA  I104  C6677
   1 P5E_CPU1_P1_TX_BUF_C_DP<8>      1 @T6G_MB_LIB.T6G(SCH_1):P5E_CPU1_P1_TX_BUF_C_DP(8)
   2 P5E_CPU1_P1_TX_BUF_DP<8>      2 @T6G_MB_LIB.T6G(SCH_1):P5E_CPU1_P1_TX_BUF_DP(8)

PT5161LRS-PT5161LRS,SMLF,IC,AJ051610U03  I142  U6015
 CH7 P5E_CPU1_P1_TX_BUF_DP<7> B_PETP8 @T6G_MB_LIB.T6G(SCH_1):P5E_CPU1_P1_TX_BUF_DP(7)
CK10 P5E_CPU1_P1_TX_BUF_DN<7> B_PETN8 @T6G_MB_LIB.T6G(SCH_1):P5E_CPU1_P1_TX_BUF_DN(7)
 CR7 P5E_CPU1_P1_TX_BUF_DP<6> B_PETP9 @T6G_MB_LIB.T6G(SCH_1):P5E_CPU1_P1_TX_BUF_DP(6)
CU10 P5E_CPU1_P1_TX_BUF_DN<6> B_PETN9 @T6G_MB_LIB.T6G(SCH_1):P5E_CPU1_P1_TX_BUF_DN(6)
 DB7 P5E_CPU1_P1_TX_BUF_DP<5> B_PETP10 @T6G_MB_LIB.T6G(SCH_1):P5E_CPU1_P1_TX_BUF_DP(5)
DD10 P5E_CPU1_P1_TX_BUF_DN<5> B_PETN10 @T6G_MB_LIB.T6G(SCH_1):P5E_CPU1_P1_TX_BUF_DN(5)
 DJ7 P5E_CPU1_P1_TX_BUF_DP<4> B_PETP11 @T6G_MB_LIB.T6G(SCH_1):P5E_CPU1_P1_TX_BUF_DP(4)
DL10 P5E_CPU1_P1_TX_BUF_DN<4> B_PETN11 @T6G_MB_LIB.T6G(SCH_1):P5E_CPU1_P1_TX_BUF_DN(4)
 DT7 P5E_CPU1_P1_TX_BUF_DP<3> B_PETP12 @T6G_MB_LIB.T6G(SCH_1):P5E_CPU1_P1_TX_BUF_DP(3)
DV10 P5E_CPU1_P1_TX_BUF_DN<3> B_PETN12 @T6G_MB_LIB.T6G(SCH_1):P5E_CPU1_P1_TX_BUF_DN(3)
 EC7 P5E_CPU1_P1_TX_BUF_DP<2> B_PETP13 @T6G_MB_LIB.T6G(SCH_1):P5E_CPU1_P1_TX_BUF_DP(2)
EE10 P5E_CPU1_P1_TX_BUF_DN<2> B_PETN13 @T6G_MB_LIB.T6G(SCH_1):P5E_CPU1_P1_TX_BUF_DN(2)
 EK7 P5E_CPU1_P1_TX_BUF_DP<1> B_PETP14 @T6G_MB_LIB.T6G(SCH_1):P5E_CPU1_P1_TX_BUF_DP(1)
EM10 P5E_CPU1_P1_TX_BUF_DN<1> B_PETN14 @T6G_MB_LIB.T6G(SCH_1):P5E_CPU1_P1_TX_BUF_DN(1)
 EU7 P5E_CPU1_P1_TX_BUF_DP<0> B_PETP15 @T6G_MB_LIB.T6G(SCH_1):P5E_CPU1_P1_TX_BUF_DP(0)
EW10 P5E_CPU1_P1_TX_BUF_DN<0> B_PETN15 @T6G_MB_LIB.T6G(SCH_1):P5E_CPU1_P1_TX_BUF_DN(0)


DRAWING: @T6G_MB_LIB.T6G(SCH_1):PAGE394 

PT5161LRS-PT5161LRS,SMLF,IC,AJ051610U03  I1  U6015
  R1 P5E_CPU1_P1_RX_BUF_DP<15> A_PERP0 @T6G_MB_LIB.T6G(SCH_1):P5E_CPU1_P1_RX_BUF_DP(15)
  N2 P5E_CPU1_P1_RX_BUF_DN<15> A_PERN0 @T6G_MB_LIB.T6G(SCH_1):P5E_CPU1_P1_RX_BUF_DN(15)
 AB1 P5E_CPU1_P1_RX_BUF_DP<14> A_PERP1 @T6G_MB_LIB.T6G(SCH_1):P5E_CPU1_P1_RX_BUF_DP(14)
  Y2 P5E_CPU1_P1_RX_BUF_DN<14> A_PERN1 @T6G_MB_LIB.T6G(SCH_1):P5E_CPU1_P1_RX_BUF_DN(14)
 AJ1 P5E_CPU1_P1_RX_BUF_DP<13> A_PERP2 @T6G_MB_LIB.T6G(SCH_1):P5E_CPU1_P1_RX_BUF_DP(13)
 AG2 P5E_CPU1_P1_RX_BUF_DN<13> A_PERN2 @T6G_MB_LIB.T6G(SCH_1):P5E_CPU1_P1_RX_BUF_DN(13)
 AT1 P5E_CPU1_P1_RX_BUF_DP<12> A_PERP3 @T6G_MB_LIB.T6G(SCH_1):P5E_CPU1_P1_RX_BUF_DP(12)
 AP2 P5E_CPU1_P1_RX_BUF_DN<12> A_PERN3 @T6G_MB_LIB.T6G(SCH_1):P5E_CPU1_P1_RX_BUF_DN(12)
 BC1 P5E_CPU1_P1_RX_BUF_DP<11> A_PERP4 @T6G_MB_LIB.T6G(SCH_1):P5E_CPU1_P1_RX_BUF_DP(11)
 BA2 P5E_CPU1_P1_RX_BUF_DN<11> A_PERN4 @T6G_MB_LIB.T6G(SCH_1):P5E_CPU1_P1_RX_BUF_DN(11)
 BK1 P5E_CPU1_P1_RX_BUF_DP<10> A_PERP5 @T6G_MB_LIB.T6G(SCH_1):P5E_CPU1_P1_RX_BUF_DP(10)
 BH2 P5E_CPU1_P1_RX_BUF_DN<10> A_PERN5 @T6G_MB_LIB.T6G(SCH_1):P5E_CPU1_P1_RX_BUF_DN(10)
 BU1 P5E_CPU1_P1_RX_BUF_DP<9> A_PERP6 @T6G_MB_LIB.T6G(SCH_1):P5E_CPU1_P1_RX_BUF_DP(9)
 BR2 P5E_CPU1_P1_RX_BUF_DN<9> A_PERN6 @T6G_MB_LIB.T6G(SCH_1):P5E_CPU1_P1_RX_BUF_DN(9)
 CD1 P5E_CPU1_P1_RX_BUF_DP<8> A_PERP7 @T6G_MB_LIB.T6G(SCH_1):P5E_CPU1_P1_RX_BUF_DP(8)
 CB2 P5E_CPU1_P1_RX_BUF_DN<8> A_PERN7 @T6G_MB_LIB.T6G(SCH_1):P5E_CPU1_P1_RX_BUF_DN(8)

PT5161LRS-PT5161LRS,SMLF,IC,AJ051610U03  I38  U6015
 CL1 P5E_CPU1_P1_RX_BUF_DP<7> A_PERP8 @T6G_MB_LIB.T6G(SCH_1):P5E_CPU1_P1_RX_BUF_DP(7)
 CJ2 P5E_CPU1_P1_RX_BUF_DN<7> A_PERN8 @T6G_MB_LIB.T6G(SCH_1):P5E_CPU1_P1_RX_BUF_DN(7)
 CV1 P5E_CPU1_P1_RX_BUF_DP<6> A_PERP9 @T6G_MB_LIB.T6G(SCH_1):P5E_CPU1_P1_RX_BUF_DP(6)
 CT2 P5E_CPU1_P1_RX_BUF_DN<6> A_PERN9 @T6G_MB_LIB.T6G(SCH_1):P5E_CPU1_P1_RX_BUF_DN(6)
 DE1 P5E_CPU1_P1_RX_BUF_DP<5> A_PERP10 @T6G_MB_LIB.T6G(SCH_1):P5E_CPU1_P1_RX_BUF_DP(5)
 DC2 P5E_CPU1_P1_RX_BUF_DN<5> A_PERN10 @T6G_MB_LIB.T6G(SCH_1):P5E_CPU1_P1_RX_BUF_DN(5)
 DM1 P5E_CPU1_P1_RX_BUF_DP<4> A_PERP11 @T6G_MB_LIB.T6G(SCH_1):P5E_CPU1_P1_RX_BUF_DP(4)
 DK2 P5E_CPU1_P1_RX_BUF_DN<4> A_PERN11 @T6G_MB_LIB.T6G(SCH_1):P5E_CPU1_P1_RX_BUF_DN(4)
 DW1 P5E_CPU1_P1_RX_BUF_DP<3> A_PERP12 @T6G_MB_LIB.T6G(SCH_1):P5E_CPU1_P1_RX_BUF_DP(3)
 DU2 P5E_CPU1_P1_RX_BUF_DN<3> A_PERN12 @T6G_MB_LIB.T6G(SCH_1):P5E_CPU1_P1_RX_BUF_DN(3)
 EF1 P5E_CPU1_P1_RX_BUF_DP<2> A_PERP13 @T6G_MB_LIB.T6G(SCH_1):P5E_CPU1_P1_RX_BUF_DP(2)
 ED2 P5E_CPU1_P1_RX_BUF_DN<2> A_PERN13 @T6G_MB_LIB.T6G(SCH_1):P5E_CPU1_P1_RX_BUF_DN(2)
 EN1 P5E_CPU1_P1_RX_BUF_DP<1> A_PERP14 @T6G_MB_LIB.T6G(SCH_1):P5E_CPU1_P1_RX_BUF_DP(1)
 EL2 P5E_CPU1_P1_RX_BUF_DN<1> A_PERN14 @T6G_MB_LIB.T6G(SCH_1):P5E_CPU1_P1_RX_BUF_DN(1)
 EY1 P5E_CPU1_P1_RX_BUF_DP<0> A_PERP15 @T6G_MB_LIB.T6G(SCH_1):P5E_CPU1_P1_RX_BUF_DP(0)
 EV2 P5E_CPU1_P1_RX_BUF_DN<0> A_PERN15 @T6G_MB_LIB.T6G(SCH_1):P5E_CPU1_P1_RX_BUF_DN(0)


DRAWING: @T6G_MB_LIB.T6G(SCH_1):PAGE395 

PT5161LRS-PT5161LRS,SMLF,IC,AJ051610U03  I1  U6015
 M26 P5E_CPU1_P1_RX_DP<15> A_PETP0 @T6G_MB_LIB.T6G(SCH_1):P5E_CPU1_P1_RX_DP(15)
 P29 P5E_CPU1_P1_RX_DN<15> A_PETN0 @T6G_MB_LIB.T6G(SCH_1):P5E_CPU1_P1_RX_DN(15)
 W26 P5E_CPU1_P1_RX_DP<14> A_PETP1 @T6G_MB_LIB.T6G(SCH_1):P5E_CPU1_P1_RX_DP(14)
AA29 P5E_CPU1_P1_RX_DN<14> A_PETN1 @T6G_MB_LIB.T6G(SCH_1):P5E_CPU1_P1_RX_DN(14)
AF26 P5E_CPU1_P1_RX_DP<13> A_PETP2 @T6G_MB_LIB.T6G(SCH_1):P5E_CPU1_P1_RX_DP(13)
AH29 P5E_CPU1_P1_RX_DN<13> A_PETN2 @T6G_MB_LIB.T6G(SCH_1):P5E_CPU1_P1_RX_DN(13)
AN26 P5E_CPU1_P1_RX_DP<12> A_PETP3 @T6G_MB_LIB.T6G(SCH_1):P5E_CPU1_P1_RX_DP(12)
AR29 P5E_CPU1_P1_RX_DN<12> A_PETN3 @T6G_MB_LIB.T6G(SCH_1):P5E_CPU1_P1_RX_DN(12)
AY26 P5E_CPU1_P1_RX_DP<11> A_PETP4 @T6G_MB_LIB.T6G(SCH_1):P5E_CPU1_P1_RX_DP(11)
BB29 P5E_CPU1_P1_RX_DN<11> A_PETN4 @T6G_MB_LIB.T6G(SCH_1):P5E_CPU1_P1_RX_DN(11)
BG26 P5E_CPU1_P1_RX_DP<10> A_PETP5 @T6G_MB_LIB.T6G(SCH_1):P5E_CPU1_P1_RX_DP(10)
BJ29 P5E_CPU1_P1_RX_DN<10> A_PETN5 @T6G_MB_LIB.T6G(SCH_1):P5E_CPU1_P1_RX_DN(10)
BP26 P5E_CPU1_P1_RX_DP<9> A_PETP6 @T6G_MB_LIB.T6G(SCH_1):P5E_CPU1_P1_RX_DP(9)
BT29 P5E_CPU1_P1_RX_DN<9> A_PETN6 @T6G_MB_LIB.T6G(SCH_1):P5E_CPU1_P1_RX_DN(9)
CA26 P5E_CPU1_P1_RX_DP<8> A_PETP7 @T6G_MB_LIB.T6G(SCH_1):P5E_CPU1_P1_RX_DP(8)
CC29 P5E_CPU1_P1_RX_DN<8> A_PETN7 @T6G_MB_LIB.T6G(SCH_1):P5E_CPU1_P1_RX_DN(8)

PT5161LRS-PT5161LRS,SMLF,IC,AJ051610U03  I38  U6015
CH26 P5E_CPU1_P1_RX_DP<7> A_PETP8 @T6G_MB_LIB.T6G(SCH_1):P5E_CPU1_P1_RX_DP(7)
CK29 P5E_CPU1_P1_RX_DN<7> A_PETN8 @T6G_MB_LIB.T6G(SCH_1):P5E_CPU1_P1_RX_DN(7)
CR26 P5E_CPU1_P1_RX_DP<6> A_PETP9 @T6G_MB_LIB.T6G(SCH_1):P5E_CPU1_P1_RX_DP(6)
CU29 P5E_CPU1_P1_RX_DN<6> A_PETN9 @T6G_MB_LIB.T6G(SCH_1):P5E_CPU1_P1_RX_DN(6)
DB26 P5E_CPU1_P1_RX_DP<5> A_PETP10 @T6G_MB_LIB.T6G(SCH_1):P5E_CPU1_P1_RX_DP(5)
DD29 P5E_CPU1_P1_RX_DN<5> A_PETN10 @T6G_MB_LIB.T6G(SCH_1):P5E_CPU1_P1_RX_DN(5)
DJ26 P5E_CPU1_P1_RX_DP<4> A_PETP11 @T6G_MB_LIB.T6G(SCH_1):P5E_CPU1_P1_RX_DP(4)
DL29 P5E_CPU1_P1_RX_DN<4> A_PETN11 @T6G_MB_LIB.T6G(SCH_1):P5E_CPU1_P1_RX_DN(4)
DT26 P5E_CPU1_P1_RX_DP<3> A_PETP12 @T6G_MB_LIB.T6G(SCH_1):P5E_CPU1_P1_RX_DP(3)
DV29 P5E_CPU1_P1_RX_DN<3> A_PETN12 @T6G_MB_LIB.T6G(SCH_1):P5E_CPU1_P1_RX_DN(3)
EC26 P5E_CPU1_P1_RX_DP<2> A_PETP13 @T6G_MB_LIB.T6G(SCH_1):P5E_CPU1_P1_RX_DP(2)
EE29 P5E_CPU1_P1_RX_DN<2> A_PETN13 @T6G_MB_LIB.T6G(SCH_1):P5E_CPU1_P1_RX_DN(2)
EK26 P5E_CPU1_P1_RX_DP<1> A_PETP14 @T6G_MB_LIB.T6G(SCH_1):P5E_CPU1_P1_RX_DP(1)
EM29 P5E_CPU1_P1_RX_DN<1> A_PETN14 @T6G_MB_LIB.T6G(SCH_1):P5E_CPU1_P1_RX_DN(1)
EU26 P5E_CPU1_P1_RX_DP<0> A_PETP15 @T6G_MB_LIB.T6G(SCH_1):P5E_CPU1_P1_RX_DP(0)
EW29 P5E_CPU1_P1_RX_DN<0> A_PETN15 @T6G_MB_LIB.T6G(SCH_1):P5E_CPU1_P1_RX_DN(0)


DRAWING: @T6G_MB_LIB.T6G(SCH_1):PAGE396 

PT5161LRS-PT5161LRS,SMLF,IC,AJ051610U03  I1  U6015
 N34 P5E_CPU1_P1_TX_C_DN<15> B_PERP0 @T6G_MB_LIB.T6G(SCH_1):P5E_CPU1_P1_TX_C_DN(15)
 R35 P5E_CPU1_P1_TX_C_DP<15> B_PERN0 @T6G_MB_LIB.T6G(SCH_1):P5E_CPU1_P1_TX_C_DP(15)
 Y34 P5E_CPU1_P1_TX_C_DP<14> B_PERP1 @T6G_MB_LIB.T6G(SCH_1):P5E_CPU1_P1_TX_C_DP(14)
AB35 P5E_CPU1_P1_TX_C_DN<14> B_PERN1 @T6G_MB_LIB.T6G(SCH_1):P5E_CPU1_P1_TX_C_DN(14)
AG34 P5E_CPU1_P1_TX_C_DN<13> B_PERP2 @T6G_MB_LIB.T6G(SCH_1):P5E_CPU1_P1_TX_C_DN(13)
AJ35 P5E_CPU1_P1_TX_C_DP<13> B_PERN2 @T6G_MB_LIB.T6G(SCH_1):P5E_CPU1_P1_TX_C_DP(13)
AP34 P5E_CPU1_P1_TX_C_DN<12> B_PERP3 @T6G_MB_LIB.T6G(SCH_1):P5E_CPU1_P1_TX_C_DN(12)
AT35 P5E_CPU1_P1_TX_C_DP<12> B_PERN3 @T6G_MB_LIB.T6G(SCH_1):P5E_CPU1_P1_TX_C_DP(12)
BA34 P5E_CPU1_P1_TX_C_DN<11> B_PERP4 @T6G_MB_LIB.T6G(SCH_1):P5E_CPU1_P1_TX_C_DN(11)
BC35 P5E_CPU1_P1_TX_C_DP<11> B_PERN4 @T6G_MB_LIB.T6G(SCH_1):P5E_CPU1_P1_TX_C_DP(11)
BH34 P5E_CPU1_P1_TX_C_DN<10> B_PERP5 @T6G_MB_LIB.T6G(SCH_1):P5E_CPU1_P1_TX_C_DN(10)
BK35 P5E_CPU1_P1_TX_C_DP<10> B_PERN5 @T6G_MB_LIB.T6G(SCH_1):P5E_CPU1_P1_TX_C_DP(10)
BR34 P5E_CPU1_P1_TX_C_DN<9> B_PERP6 @T6G_MB_LIB.T6G(SCH_1):P5E_CPU1_P1_TX_C_DN(9)
BU35 P5E_CPU1_P1_TX_C_DP<9> B_PERN6 @T6G_MB_LIB.T6G(SCH_1):P5E_CPU1_P1_TX_C_DP(9)
CB34 P5E_CPU1_P1_TX_C_DN<8> B_PERP7 @T6G_MB_LIB.T6G(SCH_1):P5E_CPU1_P1_TX_C_DN(8)
CD35 P5E_CPU1_P1_TX_C_DP<8> B_PERN7 @T6G_MB_LIB.T6G(SCH_1):P5E_CPU1_P1_TX_C_DP(8)

PT5161LRS-PT5161LRS,SMLF,IC,AJ051610U03  I38  U6015
CJ34 P5E_CPU1_P1_TX_C_DN<7> B_PERP8 @T6G_MB_LIB.T6G(SCH_1):P5E_CPU1_P1_TX_C_DN(7)
CL35 P5E_CPU1_P1_TX_C_DP<7> B_PERN8 @T6G_MB_LIB.T6G(SCH_1):P5E_CPU1_P1_TX_C_DP(7)
CT34 P5E_CPU1_P1_TX_C_DN<6> B_PERP9 @T6G_MB_LIB.T6G(SCH_1):P5E_CPU1_P1_TX_C_DN(6)
CV35 P5E_CPU1_P1_TX_C_DP<6> B_PERN9 @T6G_MB_LIB.T6G(SCH_1):P5E_CPU1_P1_TX_C_DP(6)
DC34 P5E_CPU1_P1_TX_C_DN<5> B_PERP10 @T6G_MB_LIB.T6G(SCH_1):P5E_CPU1_P1_TX_C_DN(5)
DE35 P5E_CPU1_P1_TX_C_DP<5> B_PERN10 @T6G_MB_LIB.T6G(SCH_1):P5E_CPU1_P1_TX_C_DP(5)
DK34 P5E_CPU1_P1_TX_C_DN<4> B_PERP11 @T6G_MB_LIB.T6G(SCH_1):P5E_CPU1_P1_TX_C_DN(4)
DM35 P5E_CPU1_P1_TX_C_DP<4> B_PERN11 @T6G_MB_LIB.T6G(SCH_1):P5E_CPU1_P1_TX_C_DP(4)
DU34 P5E_CPU1_P1_TX_C_DN<3> B_PERP12 @T6G_MB_LIB.T6G(SCH_1):P5E_CPU1_P1_TX_C_DN(3)
DW35 P5E_CPU1_P1_TX_C_DP<3> B_PERN12 @T6G_MB_LIB.T6G(SCH_1):P5E_CPU1_P1_TX_C_DP(3)
ED34 P5E_CPU1_P1_TX_C_DN<2> B_PERP13 @T6G_MB_LIB.T6G(SCH_1):P5E_CPU1_P1_TX_C_DN(2)
EF35 P5E_CPU1_P1_TX_C_DP<2> B_PERN13 @T6G_MB_LIB.T6G(SCH_1):P5E_CPU1_P1_TX_C_DP(2)
EL34 P5E_CPU1_P1_TX_C_DP<1> B_PERP14 @T6G_MB_LIB.T6G(SCH_1):P5E_CPU1_P1_TX_C_DP(1)
EN35 P5E_CPU1_P1_TX_C_DN<1> B_PERN14 @T6G_MB_LIB.T6G(SCH_1):P5E_CPU1_P1_TX_C_DN(1)
EV34 P5E_CPU1_P1_TX_C_DN<0> B_PERP15 @T6G_MB_LIB.T6G(SCH_1):P5E_CPU1_P1_TX_C_DN(0)
EY35 P5E_CPU1_P1_TX_C_DP<0> B_PERN15 @T6G_MB_LIB.T6G(SCH_1):P5E_CPU1_P1_TX_C_DP(0)


DRAWING: @T6G_MB_LIB.T6G(SCH_1):PAGE400 

PT5161LRS-PT5161LRS,SMLF,IC,AJ051610U03  I1  U6014
  G1 RT_CPU1_P0_VQPS   VQPS @T6G_MB_LIB.T6G(SCH_1):RT_CPU1_P0_VQPS
BV20 P1V8_CPU1_RT0_1A PWR_1A_1 @T6G_MB_LIB.T6G(SCH_1):P1V8_CPU1_RT0_1A
CE17 P1V8_CPU1_RT0_1A PWR_1A_2 @T6G_MB_LIB.T6G(SCH_1):P1V8_CPU1_RT0_1A
CE20 P1V8_CPU1_RT0_1A PWR_1A_3 @T6G_MB_LIB.T6G(SCH_1):P1V8_CPU1_RT0_1A
CM17 P1V8_CPU1_RT0_1A PWR_1A_4 @T6G_MB_LIB.T6G(SCH_1):P1V8_CPU1_RT0_1A
CM20 P1V8_CPU1_RT0_1A PWR_1A_5 @T6G_MB_LIB.T6G(SCH_1):P1V8_CPU1_RT0_1A
BL17 P0V9_CPU1_RT_2D PWR_2D_1 @T6G_MB_LIB.T6G(SCH_1):P0V9_CPU1_RT_2D
BL20 P0V9_CPU1_RT_2D PWR_2D_2 @T6G_MB_LIB.T6G(SCH_1):P0V9_CPU1_RT_2D
CW17 P0V9_CPU1_RT_2D PWR_2D_3 @T6G_MB_LIB.T6G(SCH_1):P0V9_CPU1_RT_2D
CW20 P0V9_CPU1_RT_2D PWR_2D_4 @T6G_MB_LIB.T6G(SCH_1):P0V9_CPU1_RT_2D
BV17 P1V8_CPU1_RT0_1A_1D PWR_1D @T6G_MB_LIB.T6G(SCH_1):P1V8_CPU1_RT0_1A_1D
AC17 P0V9_CPU1_RT0_2A PWR_2A_1 @T6G_MB_LIB.T6G(SCH_1):P0V9_CPU1_RT0_2A
AC20 P0V9_CPU1_RT0_2A PWR_2A_2 @T6G_MB_LIB.T6G(SCH_1):P0V9_CPU1_RT0_2A
AK17 P0V9_CPU1_RT0_2A PWR_2A_3 @T6G_MB_LIB.T6G(SCH_1):P0V9_CPU1_RT0_2A
AK20 P0V9_CPU1_RT0_2A PWR_2A_4 @T6G_MB_LIB.T6G(SCH_1):P0V9_CPU1_RT0_2A
AU17 P0V9_CPU1_RT0_2A PWR_2A_5 @T6G_MB_LIB.T6G(SCH_1):P0V9_CPU1_RT0_2A
AU20 P0V9_CPU1_RT0_2A PWR_2A_6 @T6G_MB_LIB.T6G(SCH_1):P0V9_CPU1_RT0_2A
BD17 P0V9_CPU1_RT0_2A_2D PWR_2A_7 @T6G_MB_LIB.T6G(SCH_1):P0V9_CPU1_RT0_2A_2D
BD20 P0V9_CPU1_RT0_2A_2D PWR_2A_8 @T6G_MB_LIB.T6G(SCH_1):P0V9_CPU1_RT0_2A_2D
DF17 P0V9_CPU1_RT0_2A_2D PWR_2A_9 @T6G_MB_LIB.T6G(SCH_1):P0V9_CPU1_RT0_2A_2D
DF20 P0V9_CPU1_RT0_2A_2D PWR_2A_10 @T6G_MB_LIB.T6G(SCH_1):P0V9_CPU1_RT0_2A_2D
DN17 P0V9_CPU1_RT0_2A PWR_2A_11 @T6G_MB_LIB.T6G(SCH_1):P0V9_CPU1_RT0_2A
DN20 P0V9_CPU1_RT0_2A PWR_2A_12 @T6G_MB_LIB.T6G(SCH_1):P0V9_CPU1_RT0_2A
DY17 P0V9_CPU1_RT0_2A PWR_2A_13 @T6G_MB_LIB.T6G(SCH_1):P0V9_CPU1_RT0_2A
DY20 P0V9_CPU1_RT0_2A PWR_2A_14 @T6G_MB_LIB.T6G(SCH_1):P0V9_CPU1_RT0_2A
EG17 P0V9_CPU1_RT0_2A PWR_2A_15 @T6G_MB_LIB.T6G(SCH_1):P0V9_CPU1_RT0_2A
EG20 P0V9_CPU1_RT0_2A PWR_2A_16 @T6G_MB_LIB.T6G(SCH_1):P0V9_CPU1_RT0_2A
EP17 P0V9_CPU1_RT0_2A PWR_2A_17 @T6G_MB_LIB.T6G(SCH_1):P0V9_CPU1_RT0_2A
EP20 P0V9_CPU1_RT0_2A PWR_2A_18 @T6G_MB_LIB.T6G(SCH_1):P0V9_CPU1_RT0_2A
 T17 P0V9_CPU1_RT0_2A PWR_2A_19 @T6G_MB_LIB.T6G(SCH_1):P0V9_CPU1_RT0_2A
 T20 P0V9_CPU1_RT0_2A PWR_2A_20 @T6G_MB_LIB.T6G(SCH_1):P0V9_CPU1_RT0_2A

PT5161LRS-PT5161LRS,SMLF,IC,AJ051610U03  I2  U6014
AC13    GND   GND1 @T6G_MB_LIB.T6G(SCH_1):GND
AC22    GND   GND2 @T6G_MB_LIB.T6G(SCH_1):GND
AC32    GND   GND3 @T6G_MB_LIB.T6G(SCH_1):GND
 AC4    GND   GND4 @T6G_MB_LIB.T6G(SCH_1):GND
 AD2    GND   GND5 @T6G_MB_LIB.T6G(SCH_1):GND
AD34    GND   GND6 @T6G_MB_LIB.T6G(SCH_1):GND
 AE1    GND   GND7 @T6G_MB_LIB.T6G(SCH_1):GND
AE35    GND   GND8 @T6G_MB_LIB.T6G(SCH_1):GND
AK13    GND   GND9 @T6G_MB_LIB.T6G(SCH_1):GND
AK22    GND  GND10 @T6G_MB_LIB.T6G(SCH_1):GND
AK32    GND  GND11 @T6G_MB_LIB.T6G(SCH_1):GND
 AK4    GND  GND12 @T6G_MB_LIB.T6G(SCH_1):GND
 AL2    GND  GND13 @T6G_MB_LIB.T6G(SCH_1):GND
AL34    GND  GND14 @T6G_MB_LIB.T6G(SCH_1):GND
 AM1    GND  GND15 @T6G_MB_LIB.T6G(SCH_1):GND
AM35    GND  GND16 @T6G_MB_LIB.T6G(SCH_1):GND
AU13    GND  GND17 @T6G_MB_LIB.T6G(SCH_1):GND
AU22    GND  GND18 @T6G_MB_LIB.T6G(SCH_1):GND
AU32    GND  GND19 @T6G_MB_LIB.T6G(SCH_1):GND
 AU4    GND  GND20 @T6G_MB_LIB.T6G(SCH_1):GND
 AV2    GND  GND21 @T6G_MB_LIB.T6G(SCH_1):GND
AV34    GND  GND22 @T6G_MB_LIB.T6G(SCH_1):GND
 AW1    GND  GND23 @T6G_MB_LIB.T6G(SCH_1):GND
AW35    GND  GND24 @T6G_MB_LIB.T6G(SCH_1):GND
 B19    GND  GND25 @T6G_MB_LIB.T6G(SCH_1):GND
BD13    GND  GND26 @T6G_MB_LIB.T6G(SCH_1):GND
BD22    GND  GND27 @T6G_MB_LIB.T6G(SCH_1):GND
BD32    GND  GND28 @T6G_MB_LIB.T6G(SCH_1):GND
 BD4    GND  GND29 @T6G_MB_LIB.T6G(SCH_1):GND
 BE2    GND  GND30 @T6G_MB_LIB.T6G(SCH_1):GND
BE34    GND  GND31 @T6G_MB_LIB.T6G(SCH_1):GND
 BF1    GND  GND32 @T6G_MB_LIB.T6G(SCH_1):GND
BF35    GND  GND33 @T6G_MB_LIB.T6G(SCH_1):GND
BL13    GND  GND34 @T6G_MB_LIB.T6G(SCH_1):GND
BL22    GND  GND35 @T6G_MB_LIB.T6G(SCH_1):GND
BL32    GND  GND36 @T6G_MB_LIB.T6G(SCH_1):GND
 BL4    GND  GND37 @T6G_MB_LIB.T6G(SCH_1):GND
 BM2    GND  GND38 @T6G_MB_LIB.T6G(SCH_1):GND
BM34    GND  GND39 @T6G_MB_LIB.T6G(SCH_1):GND
 BN1    GND  GND40 @T6G_MB_LIB.T6G(SCH_1):GND
BN35    GND  GND41 @T6G_MB_LIB.T6G(SCH_1):GND
BV13    GND  GND42 @T6G_MB_LIB.T6G(SCH_1):GND
BV22    GND  GND43 @T6G_MB_LIB.T6G(SCH_1):GND
BV32    GND  GND44 @T6G_MB_LIB.T6G(SCH_1):GND
 BV4    GND  GND45 @T6G_MB_LIB.T6G(SCH_1):GND
 BW2    GND  GND46 @T6G_MB_LIB.T6G(SCH_1):GND
BW34    GND  GND47 @T6G_MB_LIB.T6G(SCH_1):GND
 BY1    GND  GND48 @T6G_MB_LIB.T6G(SCH_1):GND
BY35    GND  GND49 @T6G_MB_LIB.T6G(SCH_1):GND
CE13    GND  GND50 @T6G_MB_LIB.T6G(SCH_1):GND
CE22    GND  GND51 @T6G_MB_LIB.T6G(SCH_1):GND
CE32    GND  GND52 @T6G_MB_LIB.T6G(SCH_1):GND
 CE4    GND  GND53 @T6G_MB_LIB.T6G(SCH_1):GND
 CF2    GND  GND54 @T6G_MB_LIB.T6G(SCH_1):GND
CF34    GND  GND55 @T6G_MB_LIB.T6G(SCH_1):GND
 CG1    GND  GND56 @T6G_MB_LIB.T6G(SCH_1):GND
CG35    GND  GND57 @T6G_MB_LIB.T6G(SCH_1):GND
CM13    GND  GND58 @T6G_MB_LIB.T6G(SCH_1):GND
CM22    GND  GND59 @T6G_MB_LIB.T6G(SCH_1):GND
CM32    GND  GND60 @T6G_MB_LIB.T6G(SCH_1):GND
 CM4    GND  GND61 @T6G_MB_LIB.T6G(SCH_1):GND
 CN2    GND  GND62 @T6G_MB_LIB.T6G(SCH_1):GND
CN34    GND  GND63 @T6G_MB_LIB.T6G(SCH_1):GND
 CP1    GND  GND64 @T6G_MB_LIB.T6G(SCH_1):GND
CP35    GND  GND65 @T6G_MB_LIB.T6G(SCH_1):GND
CW13    GND  GND66 @T6G_MB_LIB.T6G(SCH_1):GND
CW22    GND  GND67 @T6G_MB_LIB.T6G(SCH_1):GND
CW32    GND  GND68 @T6G_MB_LIB.T6G(SCH_1):GND
 CW4    GND  GND69 @T6G_MB_LIB.T6G(SCH_1):GND
 CY2    GND  GND70 @T6G_MB_LIB.T6G(SCH_1):GND
CY34    GND  GND71 @T6G_MB_LIB.T6G(SCH_1):GND
 DA1    GND  GND72 @T6G_MB_LIB.T6G(SCH_1):GND
DA35    GND  GND73 @T6G_MB_LIB.T6G(SCH_1):GND
DF13    GND  GND74 @T6G_MB_LIB.T6G(SCH_1):GND
DF22    GND  GND75 @T6G_MB_LIB.T6G(SCH_1):GND
DF32    GND  GND76 @T6G_MB_LIB.T6G(SCH_1):GND
 DF4    GND  GND77 @T6G_MB_LIB.T6G(SCH_1):GND
 DG2    GND  GND78 @T6G_MB_LIB.T6G(SCH_1):GND
DG34    GND  GND79 @T6G_MB_LIB.T6G(SCH_1):GND
 DH1    GND  GND80 @T6G_MB_LIB.T6G(SCH_1):GND
DH35    GND  GND81 @T6G_MB_LIB.T6G(SCH_1):GND
DN13    GND  GND82 @T6G_MB_LIB.T6G(SCH_1):GND
  A1 NCF_A1_CPU1_P0_GND NCF_GND1 @T6G_MB_LIB.T6G(SCH_1):NCF_A1_CPU1_P0_GND
 A35 NCF_CPU1_P0_GND NCF_GND2 @T6G_MB_LIB.T6G(SCH_1):NCF_CPU1_P0_GND
  C2 NCF_CPU1_P0_GND NCF_GND3 @T6G_MB_LIB.T6G(SCH_1):NCF_CPU1_P0_GND
 C34 NCF_CPU1_P0_GND NCF_GND4 @T6G_MB_LIB.T6G(SCH_1):NCF_CPU1_P0_GND
  D1 NCF_CPU1_P0_GND NCF_GND5 @T6G_MB_LIB.T6G(SCH_1):NCF_CPU1_P0_GND
 D35 NCF_CPU1_P0_GND NCF_GND6 @T6G_MB_LIB.T6G(SCH_1):NCF_CPU1_P0_GND
 FE2 NCF_CPU1_P0_GND NCF_GND7 @T6G_MB_LIB.T6G(SCH_1):NCF_CPU1_P0_GND
FE34 NCF_CPU1_P0_GND NCF_GND8 @T6G_MB_LIB.T6G(SCH_1):NCF_CPU1_P0_GND
 FG1 NCF_CPU1_P0_GND NCF_GND9 @T6G_MB_LIB.T6G(SCH_1):NCF_CPU1_P0_GND
FG35 NCF_CPU1_P0_GND NCF_GND10 @T6G_MB_LIB.T6G(SCH_1):NCF_CPU1_P0_GND
 FH2 NCF_CPU1_P0_GND NCF_GND11 @T6G_MB_LIB.T6G(SCH_1):NCF_CPU1_P0_GND
FH34 NCF_CPU1_P0_GND NCF_GND12 @T6G_MB_LIB.T6G(SCH_1):NCF_CPU1_P0_GND
DN22    GND  GND83 @T6G_MB_LIB.T6G(SCH_1):GND
DN32    GND  GND84 @T6G_MB_LIB.T6G(SCH_1):GND
 DN4    GND  GND85 @T6G_MB_LIB.T6G(SCH_1):GND
 DP2    GND  GND86 @T6G_MB_LIB.T6G(SCH_1):GND
DP34    GND  GND87 @T6G_MB_LIB.T6G(SCH_1):GND
 DR1    GND  GND88 @T6G_MB_LIB.T6G(SCH_1):GND
DR35    GND  GND89 @T6G_MB_LIB.T6G(SCH_1):GND
DY13    GND  GND90 @T6G_MB_LIB.T6G(SCH_1):GND
DY22    GND  GND91 @T6G_MB_LIB.T6G(SCH_1):GND
DY32    GND  GND92 @T6G_MB_LIB.T6G(SCH_1):GND
 DY4    GND  GND93 @T6G_MB_LIB.T6G(SCH_1):GND
 E14    GND  GND94 @T6G_MB_LIB.T6G(SCH_1):GND
 E27    GND  GND95 @T6G_MB_LIB.T6G(SCH_1):GND
 E33    GND  GND96 @T6G_MB_LIB.T6G(SCH_1):GND
 EA2    GND  GND97 @T6G_MB_LIB.T6G(SCH_1):GND
EA34    GND  GND98 @T6G_MB_LIB.T6G(SCH_1):GND
 EB1    GND  GND99 @T6G_MB_LIB.T6G(SCH_1):GND
EB35    GND GND100 @T6G_MB_LIB.T6G(SCH_1):GND
EG13    GND GND101 @T6G_MB_LIB.T6G(SCH_1):GND
EG22    GND GND102 @T6G_MB_LIB.T6G(SCH_1):GND
EG32    GND GND103 @T6G_MB_LIB.T6G(SCH_1):GND
 EG4    GND GND104 @T6G_MB_LIB.T6G(SCH_1):GND
 EH2    GND GND105 @T6G_MB_LIB.T6G(SCH_1):GND
EH34    GND GND106 @T6G_MB_LIB.T6G(SCH_1):GND
 EJ1    GND GND107 @T6G_MB_LIB.T6G(SCH_1):GND
EJ35    GND GND108 @T6G_MB_LIB.T6G(SCH_1):GND
EP13    GND GND109 @T6G_MB_LIB.T6G(SCH_1):GND
EP22    GND GND110 @T6G_MB_LIB.T6G(SCH_1):GND
EP32    GND GND111 @T6G_MB_LIB.T6G(SCH_1):GND
 EP4    GND GND112 @T6G_MB_LIB.T6G(SCH_1):GND
 ER2    GND GND113 @T6G_MB_LIB.T6G(SCH_1):GND
ER34    GND GND114 @T6G_MB_LIB.T6G(SCH_1):GND
 ET1    GND GND115 @T6G_MB_LIB.T6G(SCH_1):GND
ET35    GND GND116 @T6G_MB_LIB.T6G(SCH_1):GND
FA15    GND GND117 @T6G_MB_LIB.T6G(SCH_1):GND
FA32    GND GND118 @T6G_MB_LIB.T6G(SCH_1):GND
 FB2    GND GND119 @T6G_MB_LIB.T6G(SCH_1):GND
FB34    GND GND120 @T6G_MB_LIB.T6G(SCH_1):GND
FC19    GND GND121 @T6G_MB_LIB.T6G(SCH_1):GND
FC23    GND GND122 @T6G_MB_LIB.T6G(SCH_1):GND
FC25    GND GND123 @T6G_MB_LIB.T6G(SCH_1):GND
FC28    GND GND124 @T6G_MB_LIB.T6G(SCH_1):GND
 FC3    GND GND125 @T6G_MB_LIB.T6G(SCH_1):GND
 FC6    GND GND126 @T6G_MB_LIB.T6G(SCH_1):GND
 FC9    GND GND127 @T6G_MB_LIB.T6G(SCH_1):GND
 FD1    GND GND128 @T6G_MB_LIB.T6G(SCH_1):GND
FD35    GND GND129 @T6G_MB_LIB.T6G(SCH_1):GND
FF14    GND GND130 @T6G_MB_LIB.T6G(SCH_1):GND
FF21    GND GND131 @T6G_MB_LIB.T6G(SCH_1):GND
FJ12    GND GND132 @T6G_MB_LIB.T6G(SCH_1):GND
FJ19    GND GND133 @T6G_MB_LIB.T6G(SCH_1):GND
 H12    GND GND134 @T6G_MB_LIB.T6G(SCH_1):GND
 H16    GND GND135 @T6G_MB_LIB.T6G(SCH_1):GND
 H19    GND GND136 @T6G_MB_LIB.T6G(SCH_1):GND
 H31    GND GND137 @T6G_MB_LIB.T6G(SCH_1):GND
 J22    GND GND138 @T6G_MB_LIB.T6G(SCH_1):GND
  J4    GND GND139 @T6G_MB_LIB.T6G(SCH_1):GND
  K2    GND GND140 @T6G_MB_LIB.T6G(SCH_1):GND
 K34    GND GND141 @T6G_MB_LIB.T6G(SCH_1):GND
  L1    GND GND142 @T6G_MB_LIB.T6G(SCH_1):GND
 L35    GND GND143 @T6G_MB_LIB.T6G(SCH_1):GND
 T13    GND GND144 @T6G_MB_LIB.T6G(SCH_1):GND
 T22    GND GND145 @T6G_MB_LIB.T6G(SCH_1):GND
 T32    GND GND146 @T6G_MB_LIB.T6G(SCH_1):GND
  T4    GND GND147 @T6G_MB_LIB.T6G(SCH_1):GND
  U2    GND GND148 @T6G_MB_LIB.T6G(SCH_1):GND
 U34    GND GND149 @T6G_MB_LIB.T6G(SCH_1):GND
  V1    GND GND150 @T6G_MB_LIB.T6G(SCH_1):GND
 V35    GND GND151 @T6G_MB_LIB.T6G(SCH_1):GND

Q_RES_0201LF-0,5%,1/20W,CHIP,CS00001JE10  I102  R711
   1 NCF_A1_CPU1_P0_GND      A @T6G_MB_LIB.T6G(SCH_1):NCF_A1_CPU1_P0_GND
   2    GND      B @T6G_MB_LIB.T6G(SCH_1):GND

Q_RES_0201LF-0,5%,1/20W,CHIP,CS00001JE10  I103  R709
   1 NCF_CPU1_P0_GND      A @T6G_MB_LIB.T6G(SCH_1):NCF_CPU1_P0_GND
   2    GND      B @T6G_MB_LIB.T6G(SCH_1):GND

Q_RES_0201LF-200,1%,1/20W,CHIP,CS12001FE12  I105  R701
   1 RT_CPU1_P0_VQPS      A @T6G_MB_LIB.T6G(SCH_1):RT_CPU1_P0_VQPS
   2    GND      B @T6G_MB_LIB.T6G(SCH_1):GND

Q_RES_0201LF-1K,1%,1/20W,EMPTY,CS21001FE07  I106  R699
   1 P1V8_CPU1_RT_1D      A @T6G_MB_LIB.T6G(SCH_1):P1V8_CPU1_RT_1D
   2 RT_CPU1_P0_VQPS      B @T6G_MB_LIB.T6G(SCH_1):RT_CPU1_P0_VQPS


DRAWING: @T6G_MB_LIB.T6G(SCH_1):PAGE401 

PT5161LRS-PT5161LRS,SMLF,IC,AJ051610U03  I1  U6014
 FJ6     NC  GPIO0     NC
FJ23     NC  GPIO1     NC
FJ25 GPIO2_RT_CPU1_P0  GPIO2 @T6G_MB_LIB.T6G(SCH_1):GPIO2_RT_CPU1_P0
FJ28 GPIO3_RT_CPU1_P0  GPIO3 @T6G_MB_LIB.T6G(SCH_1):GPIO3_RT_CPU1_P0
FJ31     NC  INT_N     NC
  B3 JTAG_TCK_RT_CPU1_P0 JTAG_TCK @T6G_MB_LIB.T6G(SCH_1):JTAG_TCK_RT_CPU1_P0
  B6 JTAG_TDI_RT_CPU1_P0 JTAG_TDI @T6G_MB_LIB.T6G(SCH_1):JTAG_TDI_RT_CPU1_P0
  B9 JTAG_TDO_RT_CPU1_P0 JTAG_TDO @T6G_MB_LIB.T6G(SCH_1):JTAG_TDO_RT_CPU1_P0
 FF8 JTAG_TEST_MODE_RT_CPU1_P0 JTAG_TEST_MODE @T6G_MB_LIB.T6G(SCH_1):JTAG_TEST_MODE_RT_CPU1_P0
 B12 JTAG_TMS_RT_CPU1_P0 JTAG_TMS @T6G_MB_LIB.T6G(SCH_1):JTAG_TMS_RT_CPU1_P0
  E8 JTAG_TRST_RT_CPU1_P0_N JTAG_TRST_N @T6G_MB_LIB.T6G(SCH_1):JTAG_TRST_RT_CPU1_P0_N
 FJ9 MODE_RT_CPU1_P0   MODE @T6G_MB_LIB.T6G(SCH_1):MODE_RT_CPU1_P0
  F2 RST_RT_CPU1_P0_PERST_N PERST_N @T6G_MB_LIB.T6G(SCH_1):RST_RT_CPU1_P0_PERST_N
 E18     NC REFCLK_OUTN     NC
 B16     NC REFCLK_OUTP     NC
FF18 CLK_100M_RETIMER_CPU1_P0_DN REFCLKN @T6G_MB_LIB.T6G(SCH_1):CLK_100M_RETIMER_CPU1_P0_DN
FJ16 CLK_100M_RETIMER_CPU1_P0_DP REFCLKP @T6G_MB_LIB.T6G(SCH_1):CLK_100M_RETIMER_CPU1_P0_DP
FF11 RST_RT_CPU1_P0_RESET_N RESET_N @T6G_MB_LIB.T6G(SCH_1):RST_RT_CPU1_P0_RESET_N
 E11 RXDET_BYP_RT_CPU1_P0 RXDET_BYP @T6G_MB_LIB.T6G(SCH_1):RXDET_BYP_RT_CPU1_P0
FF33 RT_CPU1_P0_SCAN_MODE SCAN_MODE @T6G_MB_LIB.T6G(SCH_1):RT_CPU1_P0_SCAN_MODE
 F34 RT_CPU1_P0_ADDR1 SMB_ADDR1 @T6G_MB_LIB.T6G(SCH_1):RT_CPU1_P0_ADDR1
 B23 RT_CPU1_P0_ADDR2 SMB_ADDR2 @T6G_MB_LIB.T6G(SCH_1):RT_CPU1_P0_ADDR2
 B25 RT_CPU1_P0_ADDR3 SMB_ADDR3 @T6G_MB_LIB.T6G(SCH_1):RT_CPU1_P0_ADDR3
 B31 SMB_RT_CPU1_P0_R2_SCL SMBCLK @T6G_MB_LIB.T6G(SCH_1):SMB_RT_CPU1_P0_R2_SCL
 B28 SMB_RT_CPU1_P0_R2_SDA SMBDAT @T6G_MB_LIB.T6G(SCH_1):SMB_RT_CPU1_P0_R2_SDA
 E30    GND T_SENSE @T6G_MB_LIB.T6G(SCH_1):GND
FF24 TEST0_RT_CPU1_P0  TEST0 @T6G_MB_LIB.T6G(SCH_1):TEST0_RT_CPU1_P0
FF27 TEST1_RT_CPU1_P0  TEST1 @T6G_MB_LIB.T6G(SCH_1):TEST1_RT_CPU1_P0
FF30 TEST2_RT_CPU1_P0  TEST2 @T6G_MB_LIB.T6G(SCH_1):TEST2_RT_CPU1_P0
 G35 CLKREQ_RT_CPU1_P0_N CLKREQ_N @T6G_MB_LIB.T6G(SCH_1):CLKREQ_RT_CPU1_P0_N
 FF5 SMB_RT_CPU1_P0_ROM_MUX_1D_R_SCL EE_CLK @T6G_MB_LIB.T6G(SCH_1):SMB_RT_CPU1_P0_ROM_MUX_1D_R_SCL
 FJ3 SMB_RT_CPU1_P0_ROM_MUX_1D_R_SDA EE_DAT @T6G_MB_LIB.T6G(SCH_1):SMB_RT_CPU1_P0_ROM_MUX_1D_R_SDA

Q_RES_0201LF-0,5%,1/20W,CHIP,CS00001JE10  I8  R609
   1 CLK_100M_RETIMER_CPU1_P0_R_DN      A @T6G_MB_LIB.T6G(SCH_1):CLK_100M_RETIMER_CPU1_P0_R_DN
   2 CLK_100M_RETIMER_CPU1_P0_DN      B @T6G_MB_LIB.T6G(SCH_1):CLK_100M_RETIMER_CPU1_P0_DN

Q_RES_0201LF-0,5%,1/20W,CHIP,CS00001JE10  I9  R599
   1 CLK_100M_RETIMER_CPU1_P0_R_DP      A @T6G_MB_LIB.T6G(SCH_1):CLK_100M_RETIMER_CPU1_P0_R_DP
   2 CLK_100M_RETIMER_CPU1_P0_DP      B @T6G_MB_LIB.T6G(SCH_1):CLK_100M_RETIMER_CPU1_P0_DP

Q_RES_0201LF-49.9,1%,1/20W,CHIP,CS04991FE06  I13  R675
   1 SMB_RT_CPU1_P0_ROM_MUX_1D_SDA      A @T6G_MB_LIB.T6G(SCH_1):SMB_RT_CPU1_P0_ROM_MUX_1D_SDA
   2 SMB_RT_CPU1_P0_ROM_MUX_1D_R_SDA      B @T6G_MB_LIB.T6G(SCH_1):SMB_RT_CPU1_P0_ROM_MUX_1D_R_SDA

Q_RES_0201LF-0,5%,1/20W,CHIP,CS00001JE10  I19  R6812
   1 SMB_RT_CPU1_P0_R_SCL      A @T6G_MB_LIB.T6G(SCH_1):SMB_RT_CPU1_P0_R_SCL
   2 SMB_RT_CPU1_P0_R2_SCL      B @T6G_MB_LIB.T6G(SCH_1):SMB_RT_CPU1_P0_R2_SCL

Q_RES_0201LF-0,5%,1/20W,CHIP,CS00001JE10  I20  R6813
   1 SMB_RT_CPU1_P0_R_SDA      A @T6G_MB_LIB.T6G(SCH_1):SMB_RT_CPU1_P0_R_SDA
   2 SMB_RT_CPU1_P0_R2_SDA      B @T6G_MB_LIB.T6G(SCH_1):SMB_RT_CPU1_P0_R2_SDA

Q_RES_0201LF-51.1,1%,1/20W,EMPTY,CS05111FE00  I23  R627
   1 CLK_100M_RETIMER_CPU1_P0_DN      A @T6G_MB_LIB.T6G(SCH_1):CLK_100M_RETIMER_CPU1_P0_DN
   2    GND      B @T6G_MB_LIB.T6G(SCH_1):GND

Q_RES_0201LF-51.1,1%,1/20W,EMPTY,CS05111FE00  I24  R628
   1 CLK_100M_RETIMER_CPU1_P0_DP      A @T6G_MB_LIB.T6G(SCH_1):CLK_100M_RETIMER_CPU1_P0_DP
   2    GND      B @T6G_MB_LIB.T6G(SCH_1):GND

Q_RES_0201LF-4.7K,5%,1/20W,EMPTY,CS24701JE04  I25  R724
   1 P1V8_CPU1_RT_1D      A @T6G_MB_LIB.T6G(SCH_1):P1V8_CPU1_RT_1D
   2 TEST2_RT_CPU1_P0      B @T6G_MB_LIB.T6G(SCH_1):TEST2_RT_CPU1_P0

Q_RES_0201LF-4.7K,5%,1/20W,EMPTY,CS24701JE04  I26  R720
   1 P1V8_CPU1_RT_1D      A @T6G_MB_LIB.T6G(SCH_1):P1V8_CPU1_RT_1D
   2 TEST1_RT_CPU1_P0      B @T6G_MB_LIB.T6G(SCH_1):TEST1_RT_CPU1_P0

Q_RES_0201LF-4.7K,5%,1/20W,EMPTY,CS24701JE04  I27  R716
   1 P1V8_CPU1_RT_1D      A @T6G_MB_LIB.T6G(SCH_1):P1V8_CPU1_RT_1D
   2 TEST0_RT_CPU1_P0      B @T6G_MB_LIB.T6G(SCH_1):TEST0_RT_CPU1_P0

Q_RES_0201LF-4.7K,5%,1/20W,EMPTY,CS24701JE04  I29  R706
   1 P1V8_CPU1_RT_1D      A @T6G_MB_LIB.T6G(SCH_1):P1V8_CPU1_RT_1D
   2 GPIO2_RT_CPU1_P0      B @T6G_MB_LIB.T6G(SCH_1):GPIO2_RT_CPU1_P0

Q_RES_0201LF-4.7K,5%,1/20W,CHIP,CS24701JE04  I32  R725
   1 TEST2_RT_CPU1_P0      A @T6G_MB_LIB.T6G(SCH_1):TEST2_RT_CPU1_P0
   2    GND      B @T6G_MB_LIB.T6G(SCH_1):GND

Q_RES_0201LF-4.7K,5%,1/20W,CHIP,CS24701JE04  I33  R723
   1 TEST1_RT_CPU1_P0      A @T6G_MB_LIB.T6G(SCH_1):TEST1_RT_CPU1_P0
   2    GND      B @T6G_MB_LIB.T6G(SCH_1):GND

Q_RES_0201LF-4.7K,5%,1/20W,CHIP,CS24701JE04  I34  R719
   1 TEST0_RT_CPU1_P0      A @T6G_MB_LIB.T6G(SCH_1):TEST0_RT_CPU1_P0
   2    GND      B @T6G_MB_LIB.T6G(SCH_1):GND

Q_RES_0201LF-10K,1%,1/20W,CHIP,CS31001FE17  I35  R715
   1 GPIO3_RT_CPU1_P0      A @T6G_MB_LIB.T6G(SCH_1):GPIO3_RT_CPU1_P0
   2    GND      B @T6G_MB_LIB.T6G(SCH_1):GND

Q_RES_0201LF-10K,1%,1/20W,CHIP,CS31001FE17  I36  R707
   1 GPIO2_RT_CPU1_P0      A @T6G_MB_LIB.T6G(SCH_1):GPIO2_RT_CPU1_P0
   2    GND      B @T6G_MB_LIB.T6G(SCH_1):GND

Q_RES_0201LF-4.7K,5%,1/20W,CHIP,CS24701JE04  I54  R727
   1 P1V8_CPU1_RT_1D      A @T6G_MB_LIB.T6G(SCH_1):P1V8_CPU1_RT_1D
   2 MODE_RT_CPU1_P0      B @T6G_MB_LIB.T6G(SCH_1):MODE_RT_CPU1_P0

Q_RES_0201LF-4.7K,5%,1/20W,EMPTY,CS24701JE04  I55  R728
   1 MODE_RT_CPU1_P0      A @T6G_MB_LIB.T6G(SCH_1):MODE_RT_CPU1_P0
   2    GND      B @T6G_MB_LIB.T6G(SCH_1):GND

Q_RES_0201LF-0,5%,1/20W,CHIP,CS00001JE10  I62  R6708
   1 RST_RT_CPU1_P0_PERST_N      A @T6G_MB_LIB.T6G(SCH_1):RST_RT_CPU1_P0_PERST_N
   2 RST_RT_CPU1_P0_PERST_R_N      B @T6G_MB_LIB.T6G(SCH_1):RST_RT_CPU1_P0_PERST_R_N

Q_RES_0201LF-0,5%,1/20W,CHIP,CS00001JE10  I65  R6709
   1 RST_RT_CPU1_P0_RESET_N      A @T6G_MB_LIB.T6G(SCH_1):RST_RT_CPU1_P0_RESET_N
   2 RST_RT_CPU1_P0_RESET_R_N      B @T6G_MB_LIB.T6G(SCH_1):RST_RT_CPU1_P0_RESET_R_N

Q_RES_0201LF-4.7K,5%,1/20W,EMPTY,CS24701JE04  I85  R6722
   1 P1V8_CPU1_RT_1D      A @T6G_MB_LIB.T6G(SCH_1):P1V8_CPU1_RT_1D
   2 RT_CPU1_P0_SCAN_MODE      B @T6G_MB_LIB.T6G(SCH_1):RT_CPU1_P0_SCAN_MODE

Q_RES_0201LF-4.7K,5%,1/20W,CHIP,CS24701JE04  I90  R726
   1 JTAG_TEST_MODE_RT_CPU1_P0      A @T6G_MB_LIB.T6G(SCH_1):JTAG_TEST_MODE_RT_CPU1_P0
   2    GND      B @T6G_MB_LIB.T6G(SCH_1):GND

Q_RES_0201LF-4.7K,5%,1/20W,EMPTY,CS24701JE04  I91  R6725
   1 P1V8_CPU1_RT_1D      A @T6G_MB_LIB.T6G(SCH_1):P1V8_CPU1_RT_1D
   2 JTAG_TEST_MODE_RT_CPU1_P0      B @T6G_MB_LIB.T6G(SCH_1):JTAG_TEST_MODE_RT_CPU1_P0

Q_RES_0201LF-10K,1%,1/20W,CHIP,CS31001FE17  I96  R6721
   1 RST_RT_CPU1_P0_RESET_R_N      A @T6G_MB_LIB.T6G(SCH_1):RST_RT_CPU1_P0_RESET_R_N
   2    GND      B @T6G_MB_LIB.T6G(SCH_1):GND

Q_RES_0201LF-10K,1%,1/20W,CHIP,CS31001FE17  I97  R6720
   1 RST_RT_CPU1_P0_PERST_R_N      A @T6G_MB_LIB.T6G(SCH_1):RST_RT_CPU1_P0_PERST_R_N
   2    GND      B @T6G_MB_LIB.T6G(SCH_1):GND

Q_RES_0201LF-4.7K,5%,1/20W,EMPTY,CS24701JE04  I101  R6724
   1 P1V8_CPU1_RT_1D      A @T6G_MB_LIB.T6G(SCH_1):P1V8_CPU1_RT_1D
   2 RST_RT_CPU1_P0_RESET_R_N      B @T6G_MB_LIB.T6G(SCH_1):RST_RT_CPU1_P0_RESET_R_N

Q_RES_0201LF-1K,1%,1/20W,CHIP,CS21001FE07  I102  R6712
   1 P1V8_CPU1_RT_1D      A @T6G_MB_LIB.T6G(SCH_1):P1V8_CPU1_RT_1D
   2 RT_CPU1_P0_ADDR3      B @T6G_MB_LIB.T6G(SCH_1):RT_CPU1_P0_ADDR3

Q_RES_0201LF-1K,1%,1/20W,EMPTY,CS21001FE07  I103  R6713
   1 RT_CPU1_P0_ADDR3      A @T6G_MB_LIB.T6G(SCH_1):RT_CPU1_P0_ADDR3
   2    GND      B @T6G_MB_LIB.T6G(SCH_1):GND

Q_RES_0201LF-1K,1%,1/20W,EMPTY,CS21001FE07  I104  R6714
   1 P1V8_CPU1_RT_1D      A @T6G_MB_LIB.T6G(SCH_1):P1V8_CPU1_RT_1D
   2 RT_CPU1_P0_ADDR2      B @T6G_MB_LIB.T6G(SCH_1):RT_CPU1_P0_ADDR2

Q_RES_0201LF-20K,1%,1/20W,CHIP,CS32001FE00  I105  R6715
   1 RT_CPU1_P0_ADDR2      A @T6G_MB_LIB.T6G(SCH_1):RT_CPU1_P0_ADDR2
   2    GND      B @T6G_MB_LIB.T6G(SCH_1):GND

Q_RES_0201LF-1K,1%,1/20W,CHIP,CS21001FE07  I106  R6717
   1 RT_CPU1_P0_ADDR1      A @T6G_MB_LIB.T6G(SCH_1):RT_CPU1_P0_ADDR1
   2    GND      B @T6G_MB_LIB.T6G(SCH_1):GND

Q_RES_0201LF-1K,1%,1/20W,EMPTY,CS21001FE07  I107  R6716
   1 P1V8_CPU1_RT_1D      A @T6G_MB_LIB.T6G(SCH_1):P1V8_CPU1_RT_1D
   2 RT_CPU1_P0_ADDR1      B @T6G_MB_LIB.T6G(SCH_1):RT_CPU1_P0_ADDR1

Q_RES_0201LF-4.7K,5%,1/20W,CHIP,CS24701JE04  I108  R1387
   1 CLKREQ_RT_CPU1_P0_N      A @T6G_MB_LIB.T6G(SCH_1):CLKREQ_RT_CPU1_P0_N
   2    GND      B @T6G_MB_LIB.T6G(SCH_1):GND

Q_RES_0201LF-1K,1%,1/20W,CHIP,CS21001FE07  I112  R1380
   1 JTAG_TRST_RT_CPU1_P0_N      A @T6G_MB_LIB.T6G(SCH_1):JTAG_TRST_RT_CPU1_P0_N
   2    GND      B @T6G_MB_LIB.T6G(SCH_1):GND

Q_RES_0201LF-10K,1%,1/20W,CHIP,CS31001FE17  I124  R1389
   1 RXDET_BYP_RT_CPU1_P0      A @T6G_MB_LIB.T6G(SCH_1):RXDET_BYP_RT_CPU1_P0
   2    GND      B @T6G_MB_LIB.T6G(SCH_1):GND

Q_RES_0201LF-1K,1%,1/20W,EMPTY,CS21001FE07  I125  R1388
   1 P1V8_CPU1_RT_1D      A @T6G_MB_LIB.T6G(SCH_1):P1V8_CPU1_RT_1D
   2 RXDET_BYP_RT_CPU1_P0      B @T6G_MB_LIB.T6G(SCH_1):RXDET_BYP_RT_CPU1_P0

Q_RES_0201LF-200,1%,1/20W,CHIP,CS12001FE12  I128  R6723
   1 RT_CPU1_P0_SCAN_MODE      A @T6G_MB_LIB.T6G(SCH_1):RT_CPU1_P0_SCAN_MODE
   2    GND      B @T6G_MB_LIB.T6G(SCH_1):GND

Q_RES_0201LF-4.7K,5%,1/20W,CHIP,CS24701JE04  I144  R1381
   1 JTAG_TCK_RT_CPU1_P0      A @T6G_MB_LIB.T6G(SCH_1):JTAG_TCK_RT_CPU1_P0
   2    GND      B @T6G_MB_LIB.T6G(SCH_1):GND

Q_RES_0201LF-4.7K,5%,1/20W,EMPTY,CS24701JE04  I145  R1465
   1 P1V8_CPU1_RT_1D      A @T6G_MB_LIB.T6G(SCH_1):P1V8_CPU1_RT_1D
   2 JTAG_TMS_RT_CPU1_P0      B @T6G_MB_LIB.T6G(SCH_1):JTAG_TMS_RT_CPU1_P0

Q_RES_0201LF-1K,1%,1/20W,EMPTY,CS21001FE07  I146  R1466
   1 P1V8_CPU1_RT_1D      A @T6G_MB_LIB.T6G(SCH_1):P1V8_CPU1_RT_1D
   2 JTAG_TDO_RT_CPU1_P0      B @T6G_MB_LIB.T6G(SCH_1):JTAG_TDO_RT_CPU1_P0

Q_RES_0201LF-4.7K,5%,1/20W,EMPTY,CS24701JE04  I147  R1467
   1 P1V8_CPU1_RT_1D      A @T6G_MB_LIB.T6G(SCH_1):P1V8_CPU1_RT_1D
   2 JTAG_TCK_RT_CPU1_P0      B @T6G_MB_LIB.T6G(SCH_1):JTAG_TCK_RT_CPU1_P0

Q_RES_0201LF-4.7K,5%,1/20W,EMPTY,CS24701JE04  I149  R1464
   1 P1V8_CPU1_RT_1D      A @T6G_MB_LIB.T6G(SCH_1):P1V8_CPU1_RT_1D
   2 JTAG_TDI_RT_CPU1_P0      B @T6G_MB_LIB.T6G(SCH_1):JTAG_TDI_RT_CPU1_P0

Q_RES_0201LF-22,1%,1/20W,CHIP,CS02201FE11  I155  R674
   1 SMB_RT_CPU1_P0_ROM_MUX_1D_SCL      A @T6G_MB_LIB.T6G(SCH_1):SMB_RT_CPU1_P0_ROM_MUX_1D_SCL
   2 SMB_RT_CPU1_P0_ROM_MUX_1D_R_SCL      B @T6G_MB_LIB.T6G(SCH_1):SMB_RT_CPU1_P0_ROM_MUX_1D_R_SCL


DRAWING: @T6G_MB_LIB.T6G(SCH_1):PAGE402 

PT5161LRS-PT5161LRS,SMLF,IC,AJ051610U03  I1  U6014
  R1 P5E_CPU1_P0_RX_BUF_DP<15> A_PERP0 @T6G_MB_LIB.T6G(SCH_1):P5E_CPU1_P0_RX_BUF_DP(15)
  N2 P5E_CPU1_P0_RX_BUF_DN<15> A_PERN0 @T6G_MB_LIB.T6G(SCH_1):P5E_CPU1_P0_RX_BUF_DN(15)
 AB1 P5E_CPU1_P0_RX_BUF_DP<14> A_PERP1 @T6G_MB_LIB.T6G(SCH_1):P5E_CPU1_P0_RX_BUF_DP(14)
  Y2 P5E_CPU1_P0_RX_BUF_DN<14> A_PERN1 @T6G_MB_LIB.T6G(SCH_1):P5E_CPU1_P0_RX_BUF_DN(14)
 AJ1 P5E_CPU1_P0_RX_BUF_DP<13> A_PERP2 @T6G_MB_LIB.T6G(SCH_1):P5E_CPU1_P0_RX_BUF_DP(13)
 AG2 P5E_CPU1_P0_RX_BUF_DN<13> A_PERN2 @T6G_MB_LIB.T6G(SCH_1):P5E_CPU1_P0_RX_BUF_DN(13)
 AT1 P5E_CPU1_P0_RX_BUF_DP<12> A_PERP3 @T6G_MB_LIB.T6G(SCH_1):P5E_CPU1_P0_RX_BUF_DP(12)
 AP2 P5E_CPU1_P0_RX_BUF_DN<12> A_PERN3 @T6G_MB_LIB.T6G(SCH_1):P5E_CPU1_P0_RX_BUF_DN(12)
 BC1 P5E_CPU1_P0_RX_BUF_DP<11> A_PERP4 @T6G_MB_LIB.T6G(SCH_1):P5E_CPU1_P0_RX_BUF_DP(11)
 BA2 P5E_CPU1_P0_RX_BUF_DN<11> A_PERN4 @T6G_MB_LIB.T6G(SCH_1):P5E_CPU1_P0_RX_BUF_DN(11)
 BK1 P5E_CPU1_P0_RX_BUF_DP<10> A_PERP5 @T6G_MB_LIB.T6G(SCH_1):P5E_CPU1_P0_RX_BUF_DP(10)
 BH2 P5E_CPU1_P0_RX_BUF_DN<10> A_PERN5 @T6G_MB_LIB.T6G(SCH_1):P5E_CPU1_P0_RX_BUF_DN(10)
 BU1 P5E_CPU1_P0_RX_BUF_DP<9> A_PERP6 @T6G_MB_LIB.T6G(SCH_1):P5E_CPU1_P0_RX_BUF_DP(9)
 BR2 P5E_CPU1_P0_RX_BUF_DN<9> A_PERN6 @T6G_MB_LIB.T6G(SCH_1):P5E_CPU1_P0_RX_BUF_DN(9)
 CD1 P5E_CPU1_P0_RX_BUF_DP<8> A_PERP7 @T6G_MB_LIB.T6G(SCH_1):P5E_CPU1_P0_RX_BUF_DP(8)
 CB2 P5E_CPU1_P0_RX_BUF_DN<8> A_PERN7 @T6G_MB_LIB.T6G(SCH_1):P5E_CPU1_P0_RX_BUF_DN(8)

PT5161LRS-PT5161LRS,SMLF,IC,AJ051610U03  I38  U6014
 CL1 P5E_CPU1_P0_RX_BUF_DP<7> A_PERP8 @T6G_MB_LIB.T6G(SCH_1):P5E_CPU1_P0_RX_BUF_DP(7)
 CJ2 P5E_CPU1_P0_RX_BUF_DN<7> A_PERN8 @T6G_MB_LIB.T6G(SCH_1):P5E_CPU1_P0_RX_BUF_DN(7)
 CV1 P5E_CPU1_P0_RX_BUF_DP<6> A_PERP9 @T6G_MB_LIB.T6G(SCH_1):P5E_CPU1_P0_RX_BUF_DP(6)
 CT2 P5E_CPU1_P0_RX_BUF_DN<6> A_PERN9 @T6G_MB_LIB.T6G(SCH_1):P5E_CPU1_P0_RX_BUF_DN(6)
 DE1 P5E_CPU1_P0_RX_BUF_DP<5> A_PERP10 @T6G_MB_LIB.T6G(SCH_1):P5E_CPU1_P0_RX_BUF_DP(5)
 DC2 P5E_CPU1_P0_RX_BUF_DN<5> A_PERN10 @T6G_MB_LIB.T6G(SCH_1):P5E_CPU1_P0_RX_BUF_DN(5)
 DM1 P5E_CPU1_P0_RX_BUF_DP<4> A_PERP11 @T6G_MB_LIB.T6G(SCH_1):P5E_CPU1_P0_RX_BUF_DP(4)
 DK2 P5E_CPU1_P0_RX_BUF_DN<4> A_PERN11 @T6G_MB_LIB.T6G(SCH_1):P5E_CPU1_P0_RX_BUF_DN(4)
 DW1 P5E_CPU1_P0_RX_BUF_DP<3> A_PERP12 @T6G_MB_LIB.T6G(SCH_1):P5E_CPU1_P0_RX_BUF_DP(3)
 DU2 P5E_CPU1_P0_RX_BUF_DN<3> A_PERN12 @T6G_MB_LIB.T6G(SCH_1):P5E_CPU1_P0_RX_BUF_DN(3)
 EF1 P5E_CPU1_P0_RX_BUF_DP<2> A_PERP13 @T6G_MB_LIB.T6G(SCH_1):P5E_CPU1_P0_RX_BUF_DP(2)
 ED2 P5E_CPU1_P0_RX_BUF_DN<2> A_PERN13 @T6G_MB_LIB.T6G(SCH_1):P5E_CPU1_P0_RX_BUF_DN(2)
 EN1 P5E_CPU1_P0_RX_BUF_DP<1> A_PERP14 @T6G_MB_LIB.T6G(SCH_1):P5E_CPU1_P0_RX_BUF_DP(1)
 EL2 P5E_CPU1_P0_RX_BUF_DN<1> A_PERN14 @T6G_MB_LIB.T6G(SCH_1):P5E_CPU1_P0_RX_BUF_DN(1)
 EY1 P5E_CPU1_P0_RX_BUF_DP<0> A_PERP15 @T6G_MB_LIB.T6G(SCH_1):P5E_CPU1_P0_RX_BUF_DP(0)
 EV2 P5E_CPU1_P0_RX_BUF_DN<0> A_PERN15 @T6G_MB_LIB.T6G(SCH_1):P5E_CPU1_P0_RX_BUF_DN(0)


DRAWING: @T6G_MB_LIB.T6G(SCH_1):PAGE404 

PT5161LRS-PT5161LRS,SMLF,IC,AJ051610U03  I1  U6011
 N34 P5E_CPU0_P1_TX_C_DN<15> B_PERP0 @T6G_MB_LIB.T6G(SCH_1):P5E_CPU0_P1_TX_C_DN(15)
 R35 P5E_CPU0_P1_TX_C_DP<15> B_PERN0 @T6G_MB_LIB.T6G(SCH_1):P5E_CPU0_P1_TX_C_DP(15)
 Y34 P5E_CPU0_P1_TX_C_DP<14> B_PERP1 @T6G_MB_LIB.T6G(SCH_1):P5E_CPU0_P1_TX_C_DP(14)
AB35 P5E_CPU0_P1_TX_C_DN<14> B_PERN1 @T6G_MB_LIB.T6G(SCH_1):P5E_CPU0_P1_TX_C_DN(14)
AG34 P5E_CPU0_P1_TX_C_DN<13> B_PERP2 @T6G_MB_LIB.T6G(SCH_1):P5E_CPU0_P1_TX_C_DN(13)
AJ35 P5E_CPU0_P1_TX_C_DP<13> B_PERN2 @T6G_MB_LIB.T6G(SCH_1):P5E_CPU0_P1_TX_C_DP(13)
AP34 P5E_CPU0_P1_TX_C_DN<12> B_PERP3 @T6G_MB_LIB.T6G(SCH_1):P5E_CPU0_P1_TX_C_DN(12)
AT35 P5E_CPU0_P1_TX_C_DP<12> B_PERN3 @T6G_MB_LIB.T6G(SCH_1):P5E_CPU0_P1_TX_C_DP(12)
BA34 P5E_CPU0_P1_TX_C_DN<11> B_PERP4 @T6G_MB_LIB.T6G(SCH_1):P5E_CPU0_P1_TX_C_DN(11)
BC35 P5E_CPU0_P1_TX_C_DP<11> B_PERN4 @T6G_MB_LIB.T6G(SCH_1):P5E_CPU0_P1_TX_C_DP(11)
BH34 P5E_CPU0_P1_TX_C_DN<10> B_PERP5 @T6G_MB_LIB.T6G(SCH_1):P5E_CPU0_P1_TX_C_DN(10)
BK35 P5E_CPU0_P1_TX_C_DP<10> B_PERN5 @T6G_MB_LIB.T6G(SCH_1):P5E_CPU0_P1_TX_C_DP(10)
BR34 P5E_CPU0_P1_TX_C_DN<9> B_PERP6 @T6G_MB_LIB.T6G(SCH_1):P5E_CPU0_P1_TX_C_DN(9)
BU35 P5E_CPU0_P1_TX_C_DP<9> B_PERN6 @T6G_MB_LIB.T6G(SCH_1):P5E_CPU0_P1_TX_C_DP(9)
CB34 P5E_CPU0_P1_TX_C_DN<8> B_PERP7 @T6G_MB_LIB.T6G(SCH_1):P5E_CPU0_P1_TX_C_DN(8)
CD35 P5E_CPU0_P1_TX_C_DP<8> B_PERN7 @T6G_MB_LIB.T6G(SCH_1):P5E_CPU0_P1_TX_C_DP(8)

PT5161LRS-PT5161LRS,SMLF,IC,AJ051610U03  I38  U6011
CJ34 P5E_CPU0_P1_TX_C_DN<7> B_PERP8 @T6G_MB_LIB.T6G(SCH_1):P5E_CPU0_P1_TX_C_DN(7)
CL35 P5E_CPU0_P1_TX_C_DP<7> B_PERN8 @T6G_MB_LIB.T6G(SCH_1):P5E_CPU0_P1_TX_C_DP(7)
CT34 P5E_CPU0_P1_TX_C_DN<6> B_PERP9 @T6G_MB_LIB.T6G(SCH_1):P5E_CPU0_P1_TX_C_DN(6)
CV35 P5E_CPU0_P1_TX_C_DP<6> B_PERN9 @T6G_MB_LIB.T6G(SCH_1):P5E_CPU0_P1_TX_C_DP(6)
DC34 P5E_CPU0_P1_TX_C_DN<5> B_PERP10 @T6G_MB_LIB.T6G(SCH_1):P5E_CPU0_P1_TX_C_DN(5)
DE35 P5E_CPU0_P1_TX_C_DP<5> B_PERN10 @T6G_MB_LIB.T6G(SCH_1):P5E_CPU0_P1_TX_C_DP(5)
DK34 P5E_CPU0_P1_TX_C_DN<4> B_PERP11 @T6G_MB_LIB.T6G(SCH_1):P5E_CPU0_P1_TX_C_DN(4)
DM35 P5E_CPU0_P1_TX_C_DP<4> B_PERN11 @T6G_MB_LIB.T6G(SCH_1):P5E_CPU0_P1_TX_C_DP(4)
DU34 P5E_CPU0_P1_TX_C_DN<3> B_PERP12 @T6G_MB_LIB.T6G(SCH_1):P5E_CPU0_P1_TX_C_DN(3)
DW35 P5E_CPU0_P1_TX_C_DP<3> B_PERN12 @T6G_MB_LIB.T6G(SCH_1):P5E_CPU0_P1_TX_C_DP(3)
ED34 P5E_CPU0_P1_TX_C_DN<2> B_PERP13 @T6G_MB_LIB.T6G(SCH_1):P5E_CPU0_P1_TX_C_DN(2)
EF35 P5E_CPU0_P1_TX_C_DP<2> B_PERN13 @T6G_MB_LIB.T6G(SCH_1):P5E_CPU0_P1_TX_C_DP(2)
EL34 P5E_CPU0_P1_TX_C_DP<1> B_PERP14 @T6G_MB_LIB.T6G(SCH_1):P5E_CPU0_P1_TX_C_DP(1)
EN35 P5E_CPU0_P1_TX_C_DN<1> B_PERN14 @T6G_MB_LIB.T6G(SCH_1):P5E_CPU0_P1_TX_C_DN(1)
EV34 P5E_CPU0_P1_TX_C_DN<0> B_PERP15 @T6G_MB_LIB.T6G(SCH_1):P5E_CPU0_P1_TX_C_DN(0)
EY35 P5E_CPU0_P1_TX_C_DP<0> B_PERN15 @T6G_MB_LIB.T6G(SCH_1):P5E_CPU0_P1_TX_C_DP(0)


DRAWING: @T6G_MB_LIB.T6G(SCH_1):PAGE405 

PT5161LRS-PT5161LRS,SMLF,IC,AJ051610U03  I1  U6011
 M26 P5E_CPU0_P1_RX_DP<15> A_PETP0 @T6G_MB_LIB.T6G(SCH_1):P5E_CPU0_P1_RX_DP(15)
 P29 P5E_CPU0_P1_RX_DN<15> A_PETN0 @T6G_MB_LIB.T6G(SCH_1):P5E_CPU0_P1_RX_DN(15)
 W26 P5E_CPU0_P1_RX_DP<14> A_PETP1 @T6G_MB_LIB.T6G(SCH_1):P5E_CPU0_P1_RX_DP(14)
AA29 P5E_CPU0_P1_RX_DN<14> A_PETN1 @T6G_MB_LIB.T6G(SCH_1):P5E_CPU0_P1_RX_DN(14)
AF26 P5E_CPU0_P1_RX_DP<13> A_PETP2 @T6G_MB_LIB.T6G(SCH_1):P5E_CPU0_P1_RX_DP(13)
AH29 P5E_CPU0_P1_RX_DN<13> A_PETN2 @T6G_MB_LIB.T6G(SCH_1):P5E_CPU0_P1_RX_DN(13)
AN26 P5E_CPU0_P1_RX_DP<12> A_PETP3 @T6G_MB_LIB.T6G(SCH_1):P5E_CPU0_P1_RX_DP(12)
AR29 P5E_CPU0_P1_RX_DN<12> A_PETN3 @T6G_MB_LIB.T6G(SCH_1):P5E_CPU0_P1_RX_DN(12)
AY26 P5E_CPU0_P1_RX_DP<11> A_PETP4 @T6G_MB_LIB.T6G(SCH_1):P5E_CPU0_P1_RX_DP(11)
BB29 P5E_CPU0_P1_RX_DN<11> A_PETN4 @T6G_MB_LIB.T6G(SCH_1):P5E_CPU0_P1_RX_DN(11)
BG26 P5E_CPU0_P1_RX_DP<10> A_PETP5 @T6G_MB_LIB.T6G(SCH_1):P5E_CPU0_P1_RX_DP(10)
BJ29 P5E_CPU0_P1_RX_DN<10> A_PETN5 @T6G_MB_LIB.T6G(SCH_1):P5E_CPU0_P1_RX_DN(10)
BP26 P5E_CPU0_P1_RX_DP<9> A_PETP6 @T6G_MB_LIB.T6G(SCH_1):P5E_CPU0_P1_RX_DP(9)
BT29 P5E_CPU0_P1_RX_DN<9> A_PETN6 @T6G_MB_LIB.T6G(SCH_1):P5E_CPU0_P1_RX_DN(9)
CA26 P5E_CPU0_P1_RX_DP<8> A_PETP7 @T6G_MB_LIB.T6G(SCH_1):P5E_CPU0_P1_RX_DP(8)
CC29 P5E_CPU0_P1_RX_DN<8> A_PETN7 @T6G_MB_LIB.T6G(SCH_1):P5E_CPU0_P1_RX_DN(8)

PT5161LRS-PT5161LRS,SMLF,IC,AJ051610U03  I38  U6011
CH26 P5E_CPU0_P1_RX_DP<7> A_PETP8 @T6G_MB_LIB.T6G(SCH_1):P5E_CPU0_P1_RX_DP(7)
CK29 P5E_CPU0_P1_RX_DN<7> A_PETN8 @T6G_MB_LIB.T6G(SCH_1):P5E_CPU0_P1_RX_DN(7)
CR26 P5E_CPU0_P1_RX_DP<6> A_PETP9 @T6G_MB_LIB.T6G(SCH_1):P5E_CPU0_P1_RX_DP(6)
CU29 P5E_CPU0_P1_RX_DN<6> A_PETN9 @T6G_MB_LIB.T6G(SCH_1):P5E_CPU0_P1_RX_DN(6)
DB26 P5E_CPU0_P1_RX_DP<5> A_PETP10 @T6G_MB_LIB.T6G(SCH_1):P5E_CPU0_P1_RX_DP(5)
DD29 P5E_CPU0_P1_RX_DN<5> A_PETN10 @T6G_MB_LIB.T6G(SCH_1):P5E_CPU0_P1_RX_DN(5)
DJ26 P5E_CPU0_P1_RX_DP<4> A_PETP11 @T6G_MB_LIB.T6G(SCH_1):P5E_CPU0_P1_RX_DP(4)
DL29 P5E_CPU0_P1_RX_DN<4> A_PETN11 @T6G_MB_LIB.T6G(SCH_1):P5E_CPU0_P1_RX_DN(4)
DT26 P5E_CPU0_P1_RX_DP<3> A_PETP12 @T6G_MB_LIB.T6G(SCH_1):P5E_CPU0_P1_RX_DP(3)
DV29 P5E_CPU0_P1_RX_DN<3> A_PETN12 @T6G_MB_LIB.T6G(SCH_1):P5E_CPU0_P1_RX_DN(3)
EC26 P5E_CPU0_P1_RX_DP<2> A_PETP13 @T6G_MB_LIB.T6G(SCH_1):P5E_CPU0_P1_RX_DP(2)
EE29 P5E_CPU0_P1_RX_DN<2> A_PETN13 @T6G_MB_LIB.T6G(SCH_1):P5E_CPU0_P1_RX_DN(2)
EK26 P5E_CPU0_P1_RX_DP<1> A_PETP14 @T6G_MB_LIB.T6G(SCH_1):P5E_CPU0_P1_RX_DP(1)
EM29 P5E_CPU0_P1_RX_DN<1> A_PETN14 @T6G_MB_LIB.T6G(SCH_1):P5E_CPU0_P1_RX_DN(1)
EU26 P5E_CPU0_P1_RX_DP<0> A_PETP15 @T6G_MB_LIB.T6G(SCH_1):P5E_CPU0_P1_RX_DP(0)
EW29 P5E_CPU0_P1_RX_DN<0> A_PETN15 @T6G_MB_LIB.T6G(SCH_1):P5E_CPU0_P1_RX_DN(0)


DRAWING: @T6G_MB_LIB.T6G(SCH_1):PAGE406 

PT5161LRS-PT5161LRS,SMLF,IC,AJ051610U03  I1  U6011
  R1 P5E_CPU0_P1_RX_BUF_DP<15> A_PERP0 @T6G_MB_LIB.T6G(SCH_1):P5E_CPU0_P1_RX_BUF_DP(15)
  N2 P5E_CPU0_P1_RX_BUF_DN<15> A_PERN0 @T6G_MB_LIB.T6G(SCH_1):P5E_CPU0_P1_RX_BUF_DN(15)
 AB1 P5E_CPU0_P1_RX_BUF_DP<14> A_PERP1 @T6G_MB_LIB.T6G(SCH_1):P5E_CPU0_P1_RX_BUF_DP(14)
  Y2 P5E_CPU0_P1_RX_BUF_DN<14> A_PERN1 @T6G_MB_LIB.T6G(SCH_1):P5E_CPU0_P1_RX_BUF_DN(14)
 AJ1 P5E_CPU0_P1_RX_BUF_DP<13> A_PERP2 @T6G_MB_LIB.T6G(SCH_1):P5E_CPU0_P1_RX_BUF_DP(13)
 AG2 P5E_CPU0_P1_RX_BUF_DN<13> A_PERN2 @T6G_MB_LIB.T6G(SCH_1):P5E_CPU0_P1_RX_BUF_DN(13)
 AT1 P5E_CPU0_P1_RX_BUF_DP<12> A_PERP3 @T6G_MB_LIB.T6G(SCH_1):P5E_CPU0_P1_RX_BUF_DP(12)
 AP2 P5E_CPU0_P1_RX_BUF_DN<12> A_PERN3 @T6G_MB_LIB.T6G(SCH_1):P5E_CPU0_P1_RX_BUF_DN(12)
 BC1 P5E_CPU0_P1_RX_BUF_DP<11> A_PERP4 @T6G_MB_LIB.T6G(SCH_1):P5E_CPU0_P1_RX_BUF_DP(11)
 BA2 P5E_CPU0_P1_RX_BUF_DN<11> A_PERN4 @T6G_MB_LIB.T6G(SCH_1):P5E_CPU0_P1_RX_BUF_DN(11)
 BK1 P5E_CPU0_P1_RX_BUF_DP<10> A_PERP5 @T6G_MB_LIB.T6G(SCH_1):P5E_CPU0_P1_RX_BUF_DP(10)
 BH2 P5E_CPU0_P1_RX_BUF_DN<10> A_PERN5 @T6G_MB_LIB.T6G(SCH_1):P5E_CPU0_P1_RX_BUF_DN(10)
 BU1 P5E_CPU0_P1_RX_BUF_DP<9> A_PERP6 @T6G_MB_LIB.T6G(SCH_1):P5E_CPU0_P1_RX_BUF_DP(9)
 BR2 P5E_CPU0_P1_RX_BUF_DN<9> A_PERN6 @T6G_MB_LIB.T6G(SCH_1):P5E_CPU0_P1_RX_BUF_DN(9)
 CD1 P5E_CPU0_P1_RX_BUF_DP<8> A_PERP7 @T6G_MB_LIB.T6G(SCH_1):P5E_CPU0_P1_RX_BUF_DP(8)
 CB2 P5E_CPU0_P1_RX_BUF_DN<8> A_PERN7 @T6G_MB_LIB.T6G(SCH_1):P5E_CPU0_P1_RX_BUF_DN(8)

PT5161LRS-PT5161LRS,SMLF,IC,AJ051610U03  I38  U6011
 CL1 P5E_CPU0_P1_RX_BUF_DP<7> A_PERP8 @T6G_MB_LIB.T6G(SCH_1):P5E_CPU0_P1_RX_BUF_DP(7)
 CJ2 P5E_CPU0_P1_RX_BUF_DN<7> A_PERN8 @T6G_MB_LIB.T6G(SCH_1):P5E_CPU0_P1_RX_BUF_DN(7)
 CV1 P5E_CPU0_P1_RX_BUF_DP<6> A_PERP9 @T6G_MB_LIB.T6G(SCH_1):P5E_CPU0_P1_RX_BUF_DP(6)
 CT2 P5E_CPU0_P1_RX_BUF_DN<6> A_PERN9 @T6G_MB_LIB.T6G(SCH_1):P5E_CPU0_P1_RX_BUF_DN(6)
 DE1 P5E_CPU0_P1_RX_BUF_DP<5> A_PERP10 @T6G_MB_LIB.T6G(SCH_1):P5E_CPU0_P1_RX_BUF_DP(5)
 DC2 P5E_CPU0_P1_RX_BUF_DN<5> A_PERN10 @T6G_MB_LIB.T6G(SCH_1):P5E_CPU0_P1_RX_BUF_DN(5)
 DM1 P5E_CPU0_P1_RX_BUF_DP<4> A_PERP11 @T6G_MB_LIB.T6G(SCH_1):P5E_CPU0_P1_RX_BUF_DP(4)
 DK2 P5E_CPU0_P1_RX_BUF_DN<4> A_PERN11 @T6G_MB_LIB.T6G(SCH_1):P5E_CPU0_P1_RX_BUF_DN(4)
 DW1 P5E_CPU0_P1_RX_BUF_DP<3> A_PERP12 @T6G_MB_LIB.T6G(SCH_1):P5E_CPU0_P1_RX_BUF_DP(3)
 DU2 P5E_CPU0_P1_RX_BUF_DN<3> A_PERN12 @T6G_MB_LIB.T6G(SCH_1):P5E_CPU0_P1_RX_BUF_DN(3)
 EF1 P5E_CPU0_P1_RX_BUF_DP<2> A_PERP13 @T6G_MB_LIB.T6G(SCH_1):P5E_CPU0_P1_RX_BUF_DP(2)
 ED2 P5E_CPU0_P1_RX_BUF_DN<2> A_PERN13 @T6G_MB_LIB.T6G(SCH_1):P5E_CPU0_P1_RX_BUF_DN(2)
 EN1 P5E_CPU0_P1_RX_BUF_DP<1> A_PERP14 @T6G_MB_LIB.T6G(SCH_1):P5E_CPU0_P1_RX_BUF_DP(1)
 EL2 P5E_CPU0_P1_RX_BUF_DN<1> A_PERN14 @T6G_MB_LIB.T6G(SCH_1):P5E_CPU0_P1_RX_BUF_DN(1)
 EY1 P5E_CPU0_P1_RX_BUF_DP<0> A_PERP15 @T6G_MB_LIB.T6G(SCH_1):P5E_CPU0_P1_RX_BUF_DP(0)
 EV2 P5E_CPU0_P1_RX_BUF_DN<0> A_PERN15 @T6G_MB_LIB.T6G(SCH_1):P5E_CPU0_P1_RX_BUF_DN(0)


DRAWING: @T6G_MB_LIB.T6G(SCH_1):PAGE407 

Q_CAP_DIFFBUS_C0201-DIFF BUS_0.22UF,6.3V,20%,X6S,SA  I15  C6548
   1 P5E_CPU0_P1_TX_BUF_C_DN<7>      1 @T6G_MB_LIB.T6G(SCH_1):P5E_CPU0_P1_TX_BUF_C_DN(7)
   2 P5E_CPU0_P1_TX_BUF_DN<7>      2 @T6G_MB_LIB.T6G(SCH_1):P5E_CPU0_P1_TX_BUF_DN(7)

Q_CAP_DIFFBUS_C0201-DIFF BUS_0.22UF,6.3V,20%,X6S,SA  I16  C6547
   1 P5E_CPU0_P1_TX_BUF_C_DP<7>      1 @T6G_MB_LIB.T6G(SCH_1):P5E_CPU0_P1_TX_BUF_C_DP(7)
   2 P5E_CPU0_P1_TX_BUF_DP<7>      2 @T6G_MB_LIB.T6G(SCH_1):P5E_CPU0_P1_TX_BUF_DP(7)

Q_CAP_DIFFBUS_C0201-DIFF BUS_0.22UF,6.3V,20%,X6S,SA  I18  C6545
   1 P5E_CPU0_P1_TX_BUF_C_DP<6>      1 @T6G_MB_LIB.T6G(SCH_1):P5E_CPU0_P1_TX_BUF_C_DP(6)
   2 P5E_CPU0_P1_TX_BUF_DP<6>      2 @T6G_MB_LIB.T6G(SCH_1):P5E_CPU0_P1_TX_BUF_DP(6)

Q_CAP_DIFFBUS_C0201-DIFF BUS_0.22UF,6.3V,20%,X6S,SA  I19  C6546
   1 P5E_CPU0_P1_TX_BUF_C_DN<6>      1 @T6G_MB_LIB.T6G(SCH_1):P5E_CPU0_P1_TX_BUF_C_DN(6)
   2 P5E_CPU0_P1_TX_BUF_DN<6>      2 @T6G_MB_LIB.T6G(SCH_1):P5E_CPU0_P1_TX_BUF_DN(6)

Q_CAP_DIFFBUS_C0201-DIFF BUS_0.22UF,6.3V,20%,X6S,SA  I20  C6543
   1 P5E_CPU0_P1_TX_BUF_C_DP<5>      1 @T6G_MB_LIB.T6G(SCH_1):P5E_CPU0_P1_TX_BUF_C_DP(5)
   2 P5E_CPU0_P1_TX_BUF_DP<5>      2 @T6G_MB_LIB.T6G(SCH_1):P5E_CPU0_P1_TX_BUF_DP(5)

Q_CAP_DIFFBUS_C0201-DIFF BUS_0.22UF,6.3V,20%,X6S,SA  I21  C6544
   1 P5E_CPU0_P1_TX_BUF_C_DN<5>      1 @T6G_MB_LIB.T6G(SCH_1):P5E_CPU0_P1_TX_BUF_C_DN(5)
   2 P5E_CPU0_P1_TX_BUF_DN<5>      2 @T6G_MB_LIB.T6G(SCH_1):P5E_CPU0_P1_TX_BUF_DN(5)

Q_CAP_DIFFBUS_C0201-DIFF BUS_0.22UF,6.3V,20%,X6S,SA  I22  C6541
   1 P5E_CPU0_P1_TX_BUF_C_DP<4>      1 @T6G_MB_LIB.T6G(SCH_1):P5E_CPU0_P1_TX_BUF_C_DP(4)
   2 P5E_CPU0_P1_TX_BUF_DP<4>      2 @T6G_MB_LIB.T6G(SCH_1):P5E_CPU0_P1_TX_BUF_DP(4)

Q_CAP_DIFFBUS_C0201-DIFF BUS_0.22UF,6.3V,20%,X6S,SA  I23  C6542
   1 P5E_CPU0_P1_TX_BUF_C_DN<4>      1 @T6G_MB_LIB.T6G(SCH_1):P5E_CPU0_P1_TX_BUF_C_DN(4)
   2 P5E_CPU0_P1_TX_BUF_DN<4>      2 @T6G_MB_LIB.T6G(SCH_1):P5E_CPU0_P1_TX_BUF_DN(4)

Q_CAP_DIFFBUS_C0201-DIFF BUS_0.22UF,6.3V,20%,X6S,SA  I24  C6540
   1 P5E_CPU0_P1_TX_BUF_C_DN<3>      1 @T6G_MB_LIB.T6G(SCH_1):P5E_CPU0_P1_TX_BUF_C_DN(3)
   2 P5E_CPU0_P1_TX_BUF_DN<3>      2 @T6G_MB_LIB.T6G(SCH_1):P5E_CPU0_P1_TX_BUF_DN(3)

Q_CAP_DIFFBUS_C0201-DIFF BUS_0.22UF,6.3V,20%,X6S,SA  I25  C6539
   1 P5E_CPU0_P1_TX_BUF_C_DP<3>      1 @T6G_MB_LIB.T6G(SCH_1):P5E_CPU0_P1_TX_BUF_C_DP(3)
   2 P5E_CPU0_P1_TX_BUF_DP<3>      2 @T6G_MB_LIB.T6G(SCH_1):P5E_CPU0_P1_TX_BUF_DP(3)

Q_CAP_DIFFBUS_C0201-DIFF BUS_0.22UF,6.3V,20%,X6S,SA  I26  C6538
   1 P5E_CPU0_P1_TX_BUF_C_DN<2>      1 @T6G_MB_LIB.T6G(SCH_1):P5E_CPU0_P1_TX_BUF_C_DN(2)
   2 P5E_CPU0_P1_TX_BUF_DN<2>      2 @T6G_MB_LIB.T6G(SCH_1):P5E_CPU0_P1_TX_BUF_DN(2)

Q_CAP_DIFFBUS_C0201-DIFF BUS_0.22UF,6.3V,20%,X6S,SA  I27  C6537
   1 P5E_CPU0_P1_TX_BUF_C_DP<2>      1 @T6G_MB_LIB.T6G(SCH_1):P5E_CPU0_P1_TX_BUF_C_DP(2)
   2 P5E_CPU0_P1_TX_BUF_DP<2>      2 @T6G_MB_LIB.T6G(SCH_1):P5E_CPU0_P1_TX_BUF_DP(2)

PT5161LRS-PT5161LRS,SMLF,IC,AJ051610U03  I43  U6011
  M7 P5E_CPU0_P1_TX_BUF_DP<15> B_PETP0 @T6G_MB_LIB.T6G(SCH_1):P5E_CPU0_P1_TX_BUF_DP(15)
 P10 P5E_CPU0_P1_TX_BUF_DN<15> B_PETN0 @T6G_MB_LIB.T6G(SCH_1):P5E_CPU0_P1_TX_BUF_DN(15)
  W7 P5E_CPU0_P1_TX_BUF_DP<14> B_PETP1 @T6G_MB_LIB.T6G(SCH_1):P5E_CPU0_P1_TX_BUF_DP(14)
AA10 P5E_CPU0_P1_TX_BUF_DN<14> B_PETN1 @T6G_MB_LIB.T6G(SCH_1):P5E_CPU0_P1_TX_BUF_DN(14)
 AF7 P5E_CPU0_P1_TX_BUF_DP<13> B_PETP2 @T6G_MB_LIB.T6G(SCH_1):P5E_CPU0_P1_TX_BUF_DP(13)
AH10 P5E_CPU0_P1_TX_BUF_DN<13> B_PETN2 @T6G_MB_LIB.T6G(SCH_1):P5E_CPU0_P1_TX_BUF_DN(13)
 AN7 P5E_CPU0_P1_TX_BUF_DP<12> B_PETP3 @T6G_MB_LIB.T6G(SCH_1):P5E_CPU0_P1_TX_BUF_DP(12)
AR10 P5E_CPU0_P1_TX_BUF_DN<12> B_PETN3 @T6G_MB_LIB.T6G(SCH_1):P5E_CPU0_P1_TX_BUF_DN(12)
 AY7 P5E_CPU0_P1_TX_BUF_DP<11> B_PETP4 @T6G_MB_LIB.T6G(SCH_1):P5E_CPU0_P1_TX_BUF_DP(11)
BB10 P5E_CPU0_P1_TX_BUF_DN<11> B_PETN4 @T6G_MB_LIB.T6G(SCH_1):P5E_CPU0_P1_TX_BUF_DN(11)
 BG7 P5E_CPU0_P1_TX_BUF_DP<10> B_PETP5 @T6G_MB_LIB.T6G(SCH_1):P5E_CPU0_P1_TX_BUF_DP(10)
BJ10 P5E_CPU0_P1_TX_BUF_DN<10> B_PETN5 @T6G_MB_LIB.T6G(SCH_1):P5E_CPU0_P1_TX_BUF_DN(10)
 BP7 P5E_CPU0_P1_TX_BUF_DP<9> B_PETP6 @T6G_MB_LIB.T6G(SCH_1):P5E_CPU0_P1_TX_BUF_DP(9)
BT10 P5E_CPU0_P1_TX_BUF_DN<9> B_PETN6 @T6G_MB_LIB.T6G(SCH_1):P5E_CPU0_P1_TX_BUF_DN(9)
 CA7 P5E_CPU0_P1_TX_BUF_DP<8> B_PETP7 @T6G_MB_LIB.T6G(SCH_1):P5E_CPU0_P1_TX_BUF_DP(8)
CC10 P5E_CPU0_P1_TX_BUF_DN<8> B_PETN7 @T6G_MB_LIB.T6G(SCH_1):P5E_CPU0_P1_TX_BUF_DN(8)

Q_CAP_DIFFBUS_C0201-DIFF BUS_0.22UF,6.3V,20%,X6S,SA  I44  C6536
   1 P5E_CPU0_P1_TX_BUF_C_DN<1>      1 @T6G_MB_LIB.T6G(SCH_1):P5E_CPU0_P1_TX_BUF_C_DN(1)
   2 P5E_CPU0_P1_TX_BUF_DN<1>      2 @T6G_MB_LIB.T6G(SCH_1):P5E_CPU0_P1_TX_BUF_DN(1)

Q_CAP_DIFFBUS_C0201-DIFF BUS_0.22UF,6.3V,20%,X6S,SA  I45  C6535
   1 P5E_CPU0_P1_TX_BUF_C_DP<1>      1 @T6G_MB_LIB.T6G(SCH_1):P5E_CPU0_P1_TX_BUF_C_DP(1)
   2 P5E_CPU0_P1_TX_BUF_DP<1>      2 @T6G_MB_LIB.T6G(SCH_1):P5E_CPU0_P1_TX_BUF_DP(1)

Q_CAP_DIFFBUS_C0201-DIFF BUS_0.22UF,6.3V,20%,X6S,SA  I46  C6533
   1 P5E_CPU0_P1_TX_BUF_C_DP<0>      1 @T6G_MB_LIB.T6G(SCH_1):P5E_CPU0_P1_TX_BUF_C_DP(0)
   2 P5E_CPU0_P1_TX_BUF_DP<0>      2 @T6G_MB_LIB.T6G(SCH_1):P5E_CPU0_P1_TX_BUF_DP(0)

Q_CAP_DIFFBUS_C0201-DIFF BUS_0.22UF,6.3V,20%,X6S,SA  I47  C6534
   1 P5E_CPU0_P1_TX_BUF_C_DN<0>      1 @T6G_MB_LIB.T6G(SCH_1):P5E_CPU0_P1_TX_BUF_C_DN(0)
   2 P5E_CPU0_P1_TX_BUF_DN<0>      2 @T6G_MB_LIB.T6G(SCH_1):P5E_CPU0_P1_TX_BUF_DN(0)

Q_CAP_DIFFBUS_C0201-DIFF BUS_0.22UF,6.3V,20%,X6S,SA  I86  C6564
   1 P5E_CPU0_P1_TX_BUF_C_DN<15>      1 @T6G_MB_LIB.T6G(SCH_1):P5E_CPU0_P1_TX_BUF_C_DN(15)
   2 P5E_CPU0_P1_TX_BUF_DN<15>      2 @T6G_MB_LIB.T6G(SCH_1):P5E_CPU0_P1_TX_BUF_DN(15)

Q_CAP_DIFFBUS_C0201-DIFF BUS_0.22UF,6.3V,20%,X6S,SA  I87  C6563
   1 P5E_CPU0_P1_TX_BUF_C_DP<15>      1 @T6G_MB_LIB.T6G(SCH_1):P5E_CPU0_P1_TX_BUF_C_DP(15)
   2 P5E_CPU0_P1_TX_BUF_DP<15>      2 @T6G_MB_LIB.T6G(SCH_1):P5E_CPU0_P1_TX_BUF_DP(15)

Q_CAP_DIFFBUS_C0201-DIFF BUS_0.22UF,6.3V,20%,X6S,SA  I88  C6562
   1 P5E_CPU0_P1_TX_BUF_C_DN<14>      1 @T6G_MB_LIB.T6G(SCH_1):P5E_CPU0_P1_TX_BUF_C_DN(14)
   2 P5E_CPU0_P1_TX_BUF_DN<14>      2 @T6G_MB_LIB.T6G(SCH_1):P5E_CPU0_P1_TX_BUF_DN(14)

Q_CAP_DIFFBUS_C0201-DIFF BUS_0.22UF,6.3V,20%,X6S,SA  I89  C6561
   1 P5E_CPU0_P1_TX_BUF_C_DP<14>      1 @T6G_MB_LIB.T6G(SCH_1):P5E_CPU0_P1_TX_BUF_C_DP(14)
   2 P5E_CPU0_P1_TX_BUF_DP<14>      2 @T6G_MB_LIB.T6G(SCH_1):P5E_CPU0_P1_TX_BUF_DP(14)

Q_CAP_DIFFBUS_C0201-DIFF BUS_0.22UF,6.3V,20%,X6S,SA  I90  C6560
   1 P5E_CPU0_P1_TX_BUF_C_DN<13>      1 @T6G_MB_LIB.T6G(SCH_1):P5E_CPU0_P1_TX_BUF_C_DN(13)
   2 P5E_CPU0_P1_TX_BUF_DN<13>      2 @T6G_MB_LIB.T6G(SCH_1):P5E_CPU0_P1_TX_BUF_DN(13)

Q_CAP_DIFFBUS_C0201-DIFF BUS_0.22UF,6.3V,20%,X6S,SA  I91  C6559
   1 P5E_CPU0_P1_TX_BUF_C_DP<13>      1 @T6G_MB_LIB.T6G(SCH_1):P5E_CPU0_P1_TX_BUF_C_DP(13)
   2 P5E_CPU0_P1_TX_BUF_DP<13>      2 @T6G_MB_LIB.T6G(SCH_1):P5E_CPU0_P1_TX_BUF_DP(13)

Q_CAP_DIFFBUS_C0201-DIFF BUS_0.22UF,6.3V,20%,X6S,SA  I92  C6558
   1 P5E_CPU0_P1_TX_BUF_C_DN<12>      1 @T6G_MB_LIB.T6G(SCH_1):P5E_CPU0_P1_TX_BUF_C_DN(12)
   2 P5E_CPU0_P1_TX_BUF_DN<12>      2 @T6G_MB_LIB.T6G(SCH_1):P5E_CPU0_P1_TX_BUF_DN(12)

Q_CAP_DIFFBUS_C0201-DIFF BUS_0.22UF,6.3V,20%,X6S,SA  I93  C6557
   1 P5E_CPU0_P1_TX_BUF_C_DP<12>      1 @T6G_MB_LIB.T6G(SCH_1):P5E_CPU0_P1_TX_BUF_C_DP(12)
   2 P5E_CPU0_P1_TX_BUF_DP<12>      2 @T6G_MB_LIB.T6G(SCH_1):P5E_CPU0_P1_TX_BUF_DP(12)

Q_CAP_DIFFBUS_C0201-DIFF BUS_0.22UF,6.3V,20%,X6S,SA  I94  C6556
   1 P5E_CPU0_P1_TX_BUF_C_DN<11>      1 @T6G_MB_LIB.T6G(SCH_1):P5E_CPU0_P1_TX_BUF_C_DN(11)
   2 P5E_CPU0_P1_TX_BUF_DN<11>      2 @T6G_MB_LIB.T6G(SCH_1):P5E_CPU0_P1_TX_BUF_DN(11)

Q_CAP_DIFFBUS_C0201-DIFF BUS_0.22UF,6.3V,20%,X6S,SA  I95  C6555
   1 P5E_CPU0_P1_TX_BUF_C_DP<11>      1 @T6G_MB_LIB.T6G(SCH_1):P5E_CPU0_P1_TX_BUF_C_DP(11)
   2 P5E_CPU0_P1_TX_BUF_DP<11>      2 @T6G_MB_LIB.T6G(SCH_1):P5E_CPU0_P1_TX_BUF_DP(11)

Q_CAP_DIFFBUS_C0201-DIFF BUS_0.22UF,6.3V,20%,X6S,SA  I96  C6553
   1 P5E_CPU0_P1_TX_BUF_C_DP<10>      1 @T6G_MB_LIB.T6G(SCH_1):P5E_CPU0_P1_TX_BUF_C_DP(10)
   2 P5E_CPU0_P1_TX_BUF_DP<10>      2 @T6G_MB_LIB.T6G(SCH_1):P5E_CPU0_P1_TX_BUF_DP(10)

Q_CAP_DIFFBUS_C0201-DIFF BUS_0.22UF,6.3V,20%,X6S,SA  I97  C6554
   1 P5E_CPU0_P1_TX_BUF_C_DN<10>      1 @T6G_MB_LIB.T6G(SCH_1):P5E_CPU0_P1_TX_BUF_C_DN(10)
   2 P5E_CPU0_P1_TX_BUF_DN<10>      2 @T6G_MB_LIB.T6G(SCH_1):P5E_CPU0_P1_TX_BUF_DN(10)

Q_CAP_DIFFBUS_C0201-DIFF BUS_0.22UF,6.3V,20%,X6S,SA  I102  C6551
   1 P5E_CPU0_P1_TX_BUF_C_DP<9>      1 @T6G_MB_LIB.T6G(SCH_1):P5E_CPU0_P1_TX_BUF_C_DP(9)
   2 P5E_CPU0_P1_TX_BUF_DP<9>      2 @T6G_MB_LIB.T6G(SCH_1):P5E_CPU0_P1_TX_BUF_DP(9)

Q_CAP_DIFFBUS_C0201-DIFF BUS_0.22UF,6.3V,20%,X6S,SA  I103  C6552
   1 P5E_CPU0_P1_TX_BUF_C_DN<9>      1 @T6G_MB_LIB.T6G(SCH_1):P5E_CPU0_P1_TX_BUF_C_DN(9)
   2 P5E_CPU0_P1_TX_BUF_DN<9>      2 @T6G_MB_LIB.T6G(SCH_1):P5E_CPU0_P1_TX_BUF_DN(9)

Q_CAP_DIFFBUS_C0201-DIFF BUS_0.22UF,6.3V,20%,X6S,SA  I104  C6550
   1 P5E_CPU0_P1_TX_BUF_C_DN<8>      1 @T6G_MB_LIB.T6G(SCH_1):P5E_CPU0_P1_TX_BUF_C_DN(8)
   2 P5E_CPU0_P1_TX_BUF_DN<8>      2 @T6G_MB_LIB.T6G(SCH_1):P5E_CPU0_P1_TX_BUF_DN(8)

Q_CAP_DIFFBUS_C0201-DIFF BUS_0.22UF,6.3V,20%,X6S,SA  I105  C6549
   1 P5E_CPU0_P1_TX_BUF_C_DP<8>      1 @T6G_MB_LIB.T6G(SCH_1):P5E_CPU0_P1_TX_BUF_C_DP(8)
   2 P5E_CPU0_P1_TX_BUF_DP<8>      2 @T6G_MB_LIB.T6G(SCH_1):P5E_CPU0_P1_TX_BUF_DP(8)

PT5161LRS-PT5161LRS,SMLF,IC,AJ051610U03  I142  U6011
 CH7 P5E_CPU0_P1_TX_BUF_DP<7> B_PETP8 @T6G_MB_LIB.T6G(SCH_1):P5E_CPU0_P1_TX_BUF_DP(7)
CK10 P5E_CPU0_P1_TX_BUF_DN<7> B_PETN8 @T6G_MB_LIB.T6G(SCH_1):P5E_CPU0_P1_TX_BUF_DN(7)
 CR7 P5E_CPU0_P1_TX_BUF_DP<6> B_PETP9 @T6G_MB_LIB.T6G(SCH_1):P5E_CPU0_P1_TX_BUF_DP(6)
CU10 P5E_CPU0_P1_TX_BUF_DN<6> B_PETN9 @T6G_MB_LIB.T6G(SCH_1):P5E_CPU0_P1_TX_BUF_DN(6)
 DB7 P5E_CPU0_P1_TX_BUF_DP<5> B_PETP10 @T6G_MB_LIB.T6G(SCH_1):P5E_CPU0_P1_TX_BUF_DP(5)
DD10 P5E_CPU0_P1_TX_BUF_DN<5> B_PETN10 @T6G_MB_LIB.T6G(SCH_1):P5E_CPU0_P1_TX_BUF_DN(5)
 DJ7 P5E_CPU0_P1_TX_BUF_DP<4> B_PETP11 @T6G_MB_LIB.T6G(SCH_1):P5E_CPU0_P1_TX_BUF_DP(4)
DL10 P5E_CPU0_P1_TX_BUF_DN<4> B_PETN11 @T6G_MB_LIB.T6G(SCH_1):P5E_CPU0_P1_TX_BUF_DN(4)
 DT7 P5E_CPU0_P1_TX_BUF_DP<3> B_PETP12 @T6G_MB_LIB.T6G(SCH_1):P5E_CPU0_P1_TX_BUF_DP(3)
DV10 P5E_CPU0_P1_TX_BUF_DN<3> B_PETN12 @T6G_MB_LIB.T6G(SCH_1):P5E_CPU0_P1_TX_BUF_DN(3)
 EC7 P5E_CPU0_P1_TX_BUF_DP<2> B_PETP13 @T6G_MB_LIB.T6G(SCH_1):P5E_CPU0_P1_TX_BUF_DP(2)
EE10 P5E_CPU0_P1_TX_BUF_DN<2> B_PETN13 @T6G_MB_LIB.T6G(SCH_1):P5E_CPU0_P1_TX_BUF_DN(2)
 EK7 P5E_CPU0_P1_TX_BUF_DP<1> B_PETP14 @T6G_MB_LIB.T6G(SCH_1):P5E_CPU0_P1_TX_BUF_DP(1)
EM10 P5E_CPU0_P1_TX_BUF_DN<1> B_PETN14 @T6G_MB_LIB.T6G(SCH_1):P5E_CPU0_P1_TX_BUF_DN(1)
 EU7 P5E_CPU0_P1_TX_BUF_DP<0> B_PETP15 @T6G_MB_LIB.T6G(SCH_1):P5E_CPU0_P1_TX_BUF_DP(0)
EW10 P5E_CPU0_P1_TX_BUF_DN<0> B_PETN15 @T6G_MB_LIB.T6G(SCH_1):P5E_CPU0_P1_TX_BUF_DN(0)


DRAWING: @T6G_MB_LIB.T6G(SCH_1):PAGE415 

PT5161LRS-PT5161LRS,SMLF,IC,AJ051610U03  I37  U6012
CJ34 P5E_CPU0_P2_TX_C_DN<7> B_PERP8 @T6G_MB_LIB.T6G(SCH_1):P5E_CPU0_P2_TX_C_DN(7)
CL35 P5E_CPU0_P2_TX_C_DP<7> B_PERN8 @T6G_MB_LIB.T6G(SCH_1):P5E_CPU0_P2_TX_C_DP(7)
CT34 P5E_CPU0_P2_TX_C_DN<6> B_PERP9 @T6G_MB_LIB.T6G(SCH_1):P5E_CPU0_P2_TX_C_DN(6)
CV35 P5E_CPU0_P2_TX_C_DP<6> B_PERN9 @T6G_MB_LIB.T6G(SCH_1):P5E_CPU0_P2_TX_C_DP(6)
DC34 P5E_CPU0_P2_TX_C_DN<5> B_PERP10 @T6G_MB_LIB.T6G(SCH_1):P5E_CPU0_P2_TX_C_DN(5)
DE35 P5E_CPU0_P2_TX_C_DP<5> B_PERN10 @T6G_MB_LIB.T6G(SCH_1):P5E_CPU0_P2_TX_C_DP(5)
DK34 P5E_CPU0_P2_TX_C_DN<4> B_PERP11 @T6G_MB_LIB.T6G(SCH_1):P5E_CPU0_P2_TX_C_DN(4)
DM35 P5E_CPU0_P2_TX_C_DP<4> B_PERN11 @T6G_MB_LIB.T6G(SCH_1):P5E_CPU0_P2_TX_C_DP(4)
DU34 P5E_CPU0_P2_TX_C_DN<3> B_PERP12 @T6G_MB_LIB.T6G(SCH_1):P5E_CPU0_P2_TX_C_DN(3)
DW35 P5E_CPU0_P2_TX_C_DP<3> B_PERN12 @T6G_MB_LIB.T6G(SCH_1):P5E_CPU0_P2_TX_C_DP(3)
ED34 P5E_CPU0_P2_TX_C_DN<2> B_PERP13 @T6G_MB_LIB.T6G(SCH_1):P5E_CPU0_P2_TX_C_DN(2)
EF35 P5E_CPU0_P2_TX_C_DP<2> B_PERN13 @T6G_MB_LIB.T6G(SCH_1):P5E_CPU0_P2_TX_C_DP(2)
EL34 P5E_CPU0_P2_TX_C_DP<1> B_PERP14 @T6G_MB_LIB.T6G(SCH_1):P5E_CPU0_P2_TX_C_DP(1)
EN35 P5E_CPU0_P2_TX_C_DN<1> B_PERN14 @T6G_MB_LIB.T6G(SCH_1):P5E_CPU0_P2_TX_C_DN(1)
EV34 P5E_CPU0_P2_TX_C_DN<0> B_PERP15 @T6G_MB_LIB.T6G(SCH_1):P5E_CPU0_P2_TX_C_DN(0)
EY35 P5E_CPU0_P2_TX_C_DP<0> B_PERN15 @T6G_MB_LIB.T6G(SCH_1):P5E_CPU0_P2_TX_C_DP(0)

PT5161LRS-PT5161LRS,SMLF,IC,AJ051610U03  I38  U6012
 N34 P5E_CPU0_P2_TX_C_DN<15> B_PERP0 @T6G_MB_LIB.T6G(SCH_1):P5E_CPU0_P2_TX_C_DN(15)
 R35 P5E_CPU0_P2_TX_C_DP<15> B_PERN0 @T6G_MB_LIB.T6G(SCH_1):P5E_CPU0_P2_TX_C_DP(15)
 Y34 P5E_CPU0_P2_TX_C_DN<14> B_PERP1 @T6G_MB_LIB.T6G(SCH_1):P5E_CPU0_P2_TX_C_DN(14)
AB35 P5E_CPU0_P2_TX_C_DP<14> B_PERN1 @T6G_MB_LIB.T6G(SCH_1):P5E_CPU0_P2_TX_C_DP(14)
AG34 P5E_CPU0_P2_TX_C_DN<13> B_PERP2 @T6G_MB_LIB.T6G(SCH_1):P5E_CPU0_P2_TX_C_DN(13)
AJ35 P5E_CPU0_P2_TX_C_DP<13> B_PERN2 @T6G_MB_LIB.T6G(SCH_1):P5E_CPU0_P2_TX_C_DP(13)
AP34 P5E_CPU0_P2_TX_C_DN<12> B_PERP3 @T6G_MB_LIB.T6G(SCH_1):P5E_CPU0_P2_TX_C_DN(12)
AT35 P5E_CPU0_P2_TX_C_DP<12> B_PERN3 @T6G_MB_LIB.T6G(SCH_1):P5E_CPU0_P2_TX_C_DP(12)
BA34 P5E_CPU0_P2_TX_C_DN<11> B_PERP4 @T6G_MB_LIB.T6G(SCH_1):P5E_CPU0_P2_TX_C_DN(11)
BC35 P5E_CPU0_P2_TX_C_DP<11> B_PERN4 @T6G_MB_LIB.T6G(SCH_1):P5E_CPU0_P2_TX_C_DP(11)
BH34 P5E_CPU0_P2_TX_C_DN<10> B_PERP5 @T6G_MB_LIB.T6G(SCH_1):P5E_CPU0_P2_TX_C_DN(10)
BK35 P5E_CPU0_P2_TX_C_DP<10> B_PERN5 @T6G_MB_LIB.T6G(SCH_1):P5E_CPU0_P2_TX_C_DP(10)
BR34 P5E_CPU0_P2_TX_C_DN<9> B_PERP6 @T6G_MB_LIB.T6G(SCH_1):P5E_CPU0_P2_TX_C_DN(9)
BU35 P5E_CPU0_P2_TX_C_DP<9> B_PERN6 @T6G_MB_LIB.T6G(SCH_1):P5E_CPU0_P2_TX_C_DP(9)
CB34 P5E_CPU0_P2_TX_C_DN<8> B_PERP7 @T6G_MB_LIB.T6G(SCH_1):P5E_CPU0_P2_TX_C_DN(8)
CD35 P5E_CPU0_P2_TX_C_DP<8> B_PERN7 @T6G_MB_LIB.T6G(SCH_1):P5E_CPU0_P2_TX_C_DP(8)


DRAWING: @T6G_MB_LIB.T6G(SCH_1):PAGE416 

PT5161LRS-PT5161LRS,SMLF,IC,AJ051610U03  I1  U6012
 M26 P5E_CPU0_P2_RX_DP<15> A_PETP0 @T6G_MB_LIB.T6G(SCH_1):P5E_CPU0_P2_RX_DP(15)
 P29 P5E_CPU0_P2_RX_DN<15> A_PETN0 @T6G_MB_LIB.T6G(SCH_1):P5E_CPU0_P2_RX_DN(15)
 W26 P5E_CPU0_P2_RX_DP<14> A_PETP1 @T6G_MB_LIB.T6G(SCH_1):P5E_CPU0_P2_RX_DP(14)
AA29 P5E_CPU0_P2_RX_DN<14> A_PETN1 @T6G_MB_LIB.T6G(SCH_1):P5E_CPU0_P2_RX_DN(14)
AF26 P5E_CPU0_P2_RX_DP<13> A_PETP2 @T6G_MB_LIB.T6G(SCH_1):P5E_CPU0_P2_RX_DP(13)
AH29 P5E_CPU0_P2_RX_DN<13> A_PETN2 @T6G_MB_LIB.T6G(SCH_1):P5E_CPU0_P2_RX_DN(13)
AN26 P5E_CPU0_P2_RX_DP<12> A_PETP3 @T6G_MB_LIB.T6G(SCH_1):P5E_CPU0_P2_RX_DP(12)
AR29 P5E_CPU0_P2_RX_DN<12> A_PETN3 @T6G_MB_LIB.T6G(SCH_1):P5E_CPU0_P2_RX_DN(12)
AY26 P5E_CPU0_P2_RX_DP<11> A_PETP4 @T6G_MB_LIB.T6G(SCH_1):P5E_CPU0_P2_RX_DP(11)
BB29 P5E_CPU0_P2_RX_DN<11> A_PETN4 @T6G_MB_LIB.T6G(SCH_1):P5E_CPU0_P2_RX_DN(11)
BG26 P5E_CPU0_P2_RX_DP<10> A_PETP5 @T6G_MB_LIB.T6G(SCH_1):P5E_CPU0_P2_RX_DP(10)
BJ29 P5E_CPU0_P2_RX_DN<10> A_PETN5 @T6G_MB_LIB.T6G(SCH_1):P5E_CPU0_P2_RX_DN(10)
BP26 P5E_CPU0_P2_RX_DP<9> A_PETP6 @T6G_MB_LIB.T6G(SCH_1):P5E_CPU0_P2_RX_DP(9)
BT29 P5E_CPU0_P2_RX_DN<9> A_PETN6 @T6G_MB_LIB.T6G(SCH_1):P5E_CPU0_P2_RX_DN(9)
CA26 P5E_CPU0_P2_RX_DP<8> A_PETP7 @T6G_MB_LIB.T6G(SCH_1):P5E_CPU0_P2_RX_DP(8)
CC29 P5E_CPU0_P2_RX_DN<8> A_PETN7 @T6G_MB_LIB.T6G(SCH_1):P5E_CPU0_P2_RX_DN(8)

PT5161LRS-PT5161LRS,SMLF,IC,AJ051610U03  I38  U6012
CH26 P5E_CPU0_P2_RX_DP<7> A_PETP8 @T6G_MB_LIB.T6G(SCH_1):P5E_CPU0_P2_RX_DP(7)
CK29 P5E_CPU0_P2_RX_DN<7> A_PETN8 @T6G_MB_LIB.T6G(SCH_1):P5E_CPU0_P2_RX_DN(7)
CR26 P5E_CPU0_P2_RX_DP<6> A_PETP9 @T6G_MB_LIB.T6G(SCH_1):P5E_CPU0_P2_RX_DP(6)
CU29 P5E_CPU0_P2_RX_DN<6> A_PETN9 @T6G_MB_LIB.T6G(SCH_1):P5E_CPU0_P2_RX_DN(6)
DB26 P5E_CPU0_P2_RX_DP<5> A_PETP10 @T6G_MB_LIB.T6G(SCH_1):P5E_CPU0_P2_RX_DP(5)
DD29 P5E_CPU0_P2_RX_DN<5> A_PETN10 @T6G_MB_LIB.T6G(SCH_1):P5E_CPU0_P2_RX_DN(5)
DJ26 P5E_CPU0_P2_RX_DP<4> A_PETP11 @T6G_MB_LIB.T6G(SCH_1):P5E_CPU0_P2_RX_DP(4)
DL29 P5E_CPU0_P2_RX_DN<4> A_PETN11 @T6G_MB_LIB.T6G(SCH_1):P5E_CPU0_P2_RX_DN(4)
DT26 P5E_CPU0_P2_RX_DP<3> A_PETP12 @T6G_MB_LIB.T6G(SCH_1):P5E_CPU0_P2_RX_DP(3)
DV29 P5E_CPU0_P2_RX_DN<3> A_PETN12 @T6G_MB_LIB.T6G(SCH_1):P5E_CPU0_P2_RX_DN(3)
EC26 P5E_CPU0_P2_RX_DP<2> A_PETP13 @T6G_MB_LIB.T6G(SCH_1):P5E_CPU0_P2_RX_DP(2)
EE29 P5E_CPU0_P2_RX_DN<2> A_PETN13 @T6G_MB_LIB.T6G(SCH_1):P5E_CPU0_P2_RX_DN(2)
EK26 P5E_CPU0_P2_RX_DP<1> A_PETP14 @T6G_MB_LIB.T6G(SCH_1):P5E_CPU0_P2_RX_DP(1)
EM29 P5E_CPU0_P2_RX_DN<1> A_PETN14 @T6G_MB_LIB.T6G(SCH_1):P5E_CPU0_P2_RX_DN(1)
EU26 P5E_CPU0_P2_RX_DP<0> A_PETP15 @T6G_MB_LIB.T6G(SCH_1):P5E_CPU0_P2_RX_DP(0)
EW29 P5E_CPU0_P2_RX_DN<0> A_PETN15 @T6G_MB_LIB.T6G(SCH_1):P5E_CPU0_P2_RX_DN(0)


DRAWING: @T6G_MB_LIB.T6G(SCH_1):PAGE417 

PT5161LRS-PT5161LRS,SMLF,IC,AJ051610U03  I1  U6012
  R1 P5E_CPU0_P2_RX_BUF_DP<15> A_PERP0 @T6G_MB_LIB.T6G(SCH_1):P5E_CPU0_P2_RX_BUF_DP(15)
  N2 P5E_CPU0_P2_RX_BUF_DN<15> A_PERN0 @T6G_MB_LIB.T6G(SCH_1):P5E_CPU0_P2_RX_BUF_DN(15)
 AB1 P5E_CPU0_P2_RX_BUF_DP<14> A_PERP1 @T6G_MB_LIB.T6G(SCH_1):P5E_CPU0_P2_RX_BUF_DP(14)
  Y2 P5E_CPU0_P2_RX_BUF_DN<14> A_PERN1 @T6G_MB_LIB.T6G(SCH_1):P5E_CPU0_P2_RX_BUF_DN(14)
 AJ1 P5E_CPU0_P2_RX_BUF_DP<13> A_PERP2 @T6G_MB_LIB.T6G(SCH_1):P5E_CPU0_P2_RX_BUF_DP(13)
 AG2 P5E_CPU0_P2_RX_BUF_DN<13> A_PERN2 @T6G_MB_LIB.T6G(SCH_1):P5E_CPU0_P2_RX_BUF_DN(13)
 AT1 P5E_CPU0_P2_RX_BUF_DP<12> A_PERP3 @T6G_MB_LIB.T6G(SCH_1):P5E_CPU0_P2_RX_BUF_DP(12)
 AP2 P5E_CPU0_P2_RX_BUF_DN<12> A_PERN3 @T6G_MB_LIB.T6G(SCH_1):P5E_CPU0_P2_RX_BUF_DN(12)
 BC1 P5E_CPU0_P2_RX_BUF_DP<11> A_PERP4 @T6G_MB_LIB.T6G(SCH_1):P5E_CPU0_P2_RX_BUF_DP(11)
 BA2 P5E_CPU0_P2_RX_BUF_DN<11> A_PERN4 @T6G_MB_LIB.T6G(SCH_1):P5E_CPU0_P2_RX_BUF_DN(11)
 BK1 P5E_CPU0_P2_RX_BUF_DP<10> A_PERP5 @T6G_MB_LIB.T6G(SCH_1):P5E_CPU0_P2_RX_BUF_DP(10)
 BH2 P5E_CPU0_P2_RX_BUF_DN<10> A_PERN5 @T6G_MB_LIB.T6G(SCH_1):P5E_CPU0_P2_RX_BUF_DN(10)
 BU1 P5E_CPU0_P2_RX_BUF_DP<9> A_PERP6 @T6G_MB_LIB.T6G(SCH_1):P5E_CPU0_P2_RX_BUF_DP(9)
 BR2 P5E_CPU0_P2_RX_BUF_DN<9> A_PERN6 @T6G_MB_LIB.T6G(SCH_1):P5E_CPU0_P2_RX_BUF_DN(9)
 CD1 P5E_CPU0_P2_RX_BUF_DP<8> A_PERP7 @T6G_MB_LIB.T6G(SCH_1):P5E_CPU0_P2_RX_BUF_DP(8)
 CB2 P5E_CPU0_P2_RX_BUF_DN<8> A_PERN7 @T6G_MB_LIB.T6G(SCH_1):P5E_CPU0_P2_RX_BUF_DN(8)

PT5161LRS-PT5161LRS,SMLF,IC,AJ051610U03  I38  U6012
 CL1 P5E_CPU0_P2_RX_BUF_DP<7> A_PERP8 @T6G_MB_LIB.T6G(SCH_1):P5E_CPU0_P2_RX_BUF_DP(7)
 CJ2 P5E_CPU0_P2_RX_BUF_DN<7> A_PERN8 @T6G_MB_LIB.T6G(SCH_1):P5E_CPU0_P2_RX_BUF_DN(7)
 CV1 P5E_CPU0_P2_RX_BUF_DP<6> A_PERP9 @T6G_MB_LIB.T6G(SCH_1):P5E_CPU0_P2_RX_BUF_DP(6)
 CT2 P5E_CPU0_P2_RX_BUF_DN<6> A_PERN9 @T6G_MB_LIB.T6G(SCH_1):P5E_CPU0_P2_RX_BUF_DN(6)
 DE1 P5E_CPU0_P2_RX_BUF_DP<5> A_PERP10 @T6G_MB_LIB.T6G(SCH_1):P5E_CPU0_P2_RX_BUF_DP(5)
 DC2 P5E_CPU0_P2_RX_BUF_DN<5> A_PERN10 @T6G_MB_LIB.T6G(SCH_1):P5E_CPU0_P2_RX_BUF_DN(5)
 DM1 P5E_CPU0_P2_RX_BUF_DP<4> A_PERP11 @T6G_MB_LIB.T6G(SCH_1):P5E_CPU0_P2_RX_BUF_DP(4)
 DK2 P5E_CPU0_P2_RX_BUF_DN<4> A_PERN11 @T6G_MB_LIB.T6G(SCH_1):P5E_CPU0_P2_RX_BUF_DN(4)
 DW1 P5E_CPU0_P2_RX_BUF_DP<3> A_PERP12 @T6G_MB_LIB.T6G(SCH_1):P5E_CPU0_P2_RX_BUF_DP(3)
 DU2 P5E_CPU0_P2_RX_BUF_DN<3> A_PERN12 @T6G_MB_LIB.T6G(SCH_1):P5E_CPU0_P2_RX_BUF_DN(3)
 EF1 P5E_CPU0_P2_RX_BUF_DP<2> A_PERP13 @T6G_MB_LIB.T6G(SCH_1):P5E_CPU0_P2_RX_BUF_DP(2)
 ED2 P5E_CPU0_P2_RX_BUF_DN<2> A_PERN13 @T6G_MB_LIB.T6G(SCH_1):P5E_CPU0_P2_RX_BUF_DN(2)
 EN1 P5E_CPU0_P2_RX_BUF_DP<1> A_PERP14 @T6G_MB_LIB.T6G(SCH_1):P5E_CPU0_P2_RX_BUF_DP(1)
 EL2 P5E_CPU0_P2_RX_BUF_DN<1> A_PERN14 @T6G_MB_LIB.T6G(SCH_1):P5E_CPU0_P2_RX_BUF_DN(1)
 EY1 P5E_CPU0_P2_RX_BUF_DP<0> A_PERP15 @T6G_MB_LIB.T6G(SCH_1):P5E_CPU0_P2_RX_BUF_DP(0)
 EV2 P5E_CPU0_P2_RX_BUF_DN<0> A_PERN15 @T6G_MB_LIB.T6G(SCH_1):P5E_CPU0_P2_RX_BUF_DN(0)


DRAWING: @T6G_MB_LIB.T6G(SCH_1):PAGE418 

Q_CAP_DIFFBUS_C0201-DIFF BUS_0.22UF,6.3V,20%,X6S,SA  I17  C6580
   1 P5E_CPU0_P2_TX_BUF_C_DN<7>      1 @T6G_MB_LIB.T6G(SCH_1):P5E_CPU0_P2_TX_BUF_C_DN(7)
   2 P5E_CPU0_P2_TX_BUF_DN<7>      2 @T6G_MB_LIB.T6G(SCH_1):P5E_CPU0_P2_TX_BUF_DN(7)

Q_CAP_DIFFBUS_C0201-DIFF BUS_0.22UF,6.3V,20%,X6S,SA  I18  C6579
   1 P5E_CPU0_P2_TX_BUF_C_DP<7>      1 @T6G_MB_LIB.T6G(SCH_1):P5E_CPU0_P2_TX_BUF_C_DP(7)
   2 P5E_CPU0_P2_TX_BUF_DP<7>      2 @T6G_MB_LIB.T6G(SCH_1):P5E_CPU0_P2_TX_BUF_DP(7)

Q_CAP_DIFFBUS_C0201-DIFF BUS_0.22UF,6.3V,20%,X6S,SA  I19  C6577
   1 P5E_CPU0_P2_TX_BUF_C_DP<6>      1 @T6G_MB_LIB.T6G(SCH_1):P5E_CPU0_P2_TX_BUF_C_DP(6)
   2 P5E_CPU0_P2_TX_BUF_DP<6>      2 @T6G_MB_LIB.T6G(SCH_1):P5E_CPU0_P2_TX_BUF_DP(6)

Q_CAP_DIFFBUS_C0201-DIFF BUS_0.22UF,6.3V,20%,X6S,SA  I20  C6578
   1 P5E_CPU0_P2_TX_BUF_C_DN<6>      1 @T6G_MB_LIB.T6G(SCH_1):P5E_CPU0_P2_TX_BUF_C_DN(6)
   2 P5E_CPU0_P2_TX_BUF_DN<6>      2 @T6G_MB_LIB.T6G(SCH_1):P5E_CPU0_P2_TX_BUF_DN(6)

Q_CAP_DIFFBUS_C0201-DIFF BUS_0.22UF,6.3V,20%,X6S,SA  I25  C6575
   1 P5E_CPU0_P2_TX_BUF_C_DP<5>      1 @T6G_MB_LIB.T6G(SCH_1):P5E_CPU0_P2_TX_BUF_C_DP(5)
   2 P5E_CPU0_P2_TX_BUF_DP<5>      2 @T6G_MB_LIB.T6G(SCH_1):P5E_CPU0_P2_TX_BUF_DP(5)

Q_CAP_DIFFBUS_C0201-DIFF BUS_0.22UF,6.3V,20%,X6S,SA  I26  C6576
   1 P5E_CPU0_P2_TX_BUF_C_DN<5>      1 @T6G_MB_LIB.T6G(SCH_1):P5E_CPU0_P2_TX_BUF_C_DN(5)
   2 P5E_CPU0_P2_TX_BUF_DN<5>      2 @T6G_MB_LIB.T6G(SCH_1):P5E_CPU0_P2_TX_BUF_DN(5)

Q_CAP_DIFFBUS_C0201-DIFF BUS_0.22UF,6.3V,20%,X6S,SA  I27  C6573
   1 P5E_CPU0_P2_TX_BUF_C_DP<4>      1 @T6G_MB_LIB.T6G(SCH_1):P5E_CPU0_P2_TX_BUF_C_DP(4)
   2 P5E_CPU0_P2_TX_BUF_DP<4>      2 @T6G_MB_LIB.T6G(SCH_1):P5E_CPU0_P2_TX_BUF_DP(4)

Q_CAP_DIFFBUS_C0201-DIFF BUS_0.22UF,6.3V,20%,X6S,SA  I28  C6574
   1 P5E_CPU0_P2_TX_BUF_C_DN<4>      1 @T6G_MB_LIB.T6G(SCH_1):P5E_CPU0_P2_TX_BUF_C_DN(4)
   2 P5E_CPU0_P2_TX_BUF_DN<4>      2 @T6G_MB_LIB.T6G(SCH_1):P5E_CPU0_P2_TX_BUF_DN(4)

Q_CAP_DIFFBUS_C0201-DIFF BUS_0.22UF,6.3V,20%,X6S,SA  I29  C6572
   1 P5E_CPU0_P2_TX_BUF_C_DN<3>      1 @T6G_MB_LIB.T6G(SCH_1):P5E_CPU0_P2_TX_BUF_C_DN(3)
   2 P5E_CPU0_P2_TX_BUF_DN<3>      2 @T6G_MB_LIB.T6G(SCH_1):P5E_CPU0_P2_TX_BUF_DN(3)

Q_CAP_DIFFBUS_C0201-DIFF BUS_0.22UF,6.3V,20%,X6S,SA  I30  C6571
   1 P5E_CPU0_P2_TX_BUF_C_DP<3>      1 @T6G_MB_LIB.T6G(SCH_1):P5E_CPU0_P2_TX_BUF_C_DP(3)
   2 P5E_CPU0_P2_TX_BUF_DP<3>      2 @T6G_MB_LIB.T6G(SCH_1):P5E_CPU0_P2_TX_BUF_DP(3)

Q_CAP_DIFFBUS_C0201-DIFF BUS_0.22UF,6.3V,20%,X6S,SA  I31  C6570
   1 P5E_CPU0_P2_TX_BUF_C_DN<2>      1 @T6G_MB_LIB.T6G(SCH_1):P5E_CPU0_P2_TX_BUF_C_DN(2)
   2 P5E_CPU0_P2_TX_BUF_DN<2>      2 @T6G_MB_LIB.T6G(SCH_1):P5E_CPU0_P2_TX_BUF_DN(2)

Q_CAP_DIFFBUS_C0201-DIFF BUS_0.22UF,6.3V,20%,X6S,SA  I32  C6567
   1 P5E_CPU0_P2_TX_BUF_C_DP<1>      1 @T6G_MB_LIB.T6G(SCH_1):P5E_CPU0_P2_TX_BUF_C_DP(1)
   2 P5E_CPU0_P2_TX_BUF_DP<1>      2 @T6G_MB_LIB.T6G(SCH_1):P5E_CPU0_P2_TX_BUF_DP(1)

Q_CAP_DIFFBUS_C0201-DIFF BUS_0.22UF,6.3V,20%,X6S,SA  I33  C6568
   1 P5E_CPU0_P2_TX_BUF_C_DN<1>      1 @T6G_MB_LIB.T6G(SCH_1):P5E_CPU0_P2_TX_BUF_C_DN(1)
   2 P5E_CPU0_P2_TX_BUF_DN<1>      2 @T6G_MB_LIB.T6G(SCH_1):P5E_CPU0_P2_TX_BUF_DN(1)

Q_CAP_DIFFBUS_C0201-DIFF BUS_0.22UF,6.3V,20%,X6S,SA  I34  C6569
   1 P5E_CPU0_P2_TX_BUF_C_DP<2>      1 @T6G_MB_LIB.T6G(SCH_1):P5E_CPU0_P2_TX_BUF_C_DP(2)
   2 P5E_CPU0_P2_TX_BUF_DP<2>      2 @T6G_MB_LIB.T6G(SCH_1):P5E_CPU0_P2_TX_BUF_DP(2)

PT5161LRS-PT5161LRS,SMLF,IC,AJ051610U03  I47  U6012
  M7 P5E_CPU0_P2_TX_BUF_DP<15> B_PETP0 @T6G_MB_LIB.T6G(SCH_1):P5E_CPU0_P2_TX_BUF_DP(15)
 P10 P5E_CPU0_P2_TX_BUF_DN<15> B_PETN0 @T6G_MB_LIB.T6G(SCH_1):P5E_CPU0_P2_TX_BUF_DN(15)
  W7 P5E_CPU0_P2_TX_BUF_DP<14> B_PETP1 @T6G_MB_LIB.T6G(SCH_1):P5E_CPU0_P2_TX_BUF_DP(14)
AA10 P5E_CPU0_P2_TX_BUF_DN<14> B_PETN1 @T6G_MB_LIB.T6G(SCH_1):P5E_CPU0_P2_TX_BUF_DN(14)
 AF7 P5E_CPU0_P2_TX_BUF_DP<13> B_PETP2 @T6G_MB_LIB.T6G(SCH_1):P5E_CPU0_P2_TX_BUF_DP(13)
AH10 P5E_CPU0_P2_TX_BUF_DN<13> B_PETN2 @T6G_MB_LIB.T6G(SCH_1):P5E_CPU0_P2_TX_BUF_DN(13)
 AN7 P5E_CPU0_P2_TX_BUF_DP<12> B_PETP3 @T6G_MB_LIB.T6G(SCH_1):P5E_CPU0_P2_TX_BUF_DP(12)
AR10 P5E_CPU0_P2_TX_BUF_DN<12> B_PETN3 @T6G_MB_LIB.T6G(SCH_1):P5E_CPU0_P2_TX_BUF_DN(12)
 AY7 P5E_CPU0_P2_TX_BUF_DP<11> B_PETP4 @T6G_MB_LIB.T6G(SCH_1):P5E_CPU0_P2_TX_BUF_DP(11)
BB10 P5E_CPU0_P2_TX_BUF_DN<11> B_PETN4 @T6G_MB_LIB.T6G(SCH_1):P5E_CPU0_P2_TX_BUF_DN(11)
 BG7 P5E_CPU0_P2_TX_BUF_DP<10> B_PETP5 @T6G_MB_LIB.T6G(SCH_1):P5E_CPU0_P2_TX_BUF_DP(10)
BJ10 P5E_CPU0_P2_TX_BUF_DN<10> B_PETN5 @T6G_MB_LIB.T6G(SCH_1):P5E_CPU0_P2_TX_BUF_DN(10)
 BP7 P5E_CPU0_P2_TX_BUF_DP<9> B_PETP6 @T6G_MB_LIB.T6G(SCH_1):P5E_CPU0_P2_TX_BUF_DP(9)
BT10 P5E_CPU0_P2_TX_BUF_DN<9> B_PETN6 @T6G_MB_LIB.T6G(SCH_1):P5E_CPU0_P2_TX_BUF_DN(9)
 CA7 P5E_CPU0_P2_TX_BUF_DP<8> B_PETP7 @T6G_MB_LIB.T6G(SCH_1):P5E_CPU0_P2_TX_BUF_DP(8)
CC10 P5E_CPU0_P2_TX_BUF_DN<8> B_PETN7 @T6G_MB_LIB.T6G(SCH_1):P5E_CPU0_P2_TX_BUF_DN(8)

Q_CAP_DIFFBUS_C0201-DIFF BUS_0.22UF,6.3V,20%,X6S,SA  I48  C6566
   1 P5E_CPU0_P2_TX_BUF_C_DN<0>      1 @T6G_MB_LIB.T6G(SCH_1):P5E_CPU0_P2_TX_BUF_C_DN(0)
   2 P5E_CPU0_P2_TX_BUF_DN<0>      2 @T6G_MB_LIB.T6G(SCH_1):P5E_CPU0_P2_TX_BUF_DN(0)

Q_CAP_DIFFBUS_C0201-DIFF BUS_0.22UF,6.3V,20%,X6S,SA  I49  C6565
   1 P5E_CPU0_P2_TX_BUF_C_DP<0>      1 @T6G_MB_LIB.T6G(SCH_1):P5E_CPU0_P2_TX_BUF_C_DP(0)
   2 P5E_CPU0_P2_TX_BUF_DP<0>      2 @T6G_MB_LIB.T6G(SCH_1):P5E_CPU0_P2_TX_BUF_DP(0)

Q_CAP_DIFFBUS_C0201-DIFF BUS_0.22UF,6.3V,20%,X6S,SA  I88  C6596
   1 P5E_CPU0_P2_TX_BUF_C_DN<15>      1 @T6G_MB_LIB.T6G(SCH_1):P5E_CPU0_P2_TX_BUF_C_DN(15)
   2 P5E_CPU0_P2_TX_BUF_DN<15>      2 @T6G_MB_LIB.T6G(SCH_1):P5E_CPU0_P2_TX_BUF_DN(15)

Q_CAP_DIFFBUS_C0201-DIFF BUS_0.22UF,6.3V,20%,X6S,SA  I89  C6595
   1 P5E_CPU0_P2_TX_BUF_C_DP<15>      1 @T6G_MB_LIB.T6G(SCH_1):P5E_CPU0_P2_TX_BUF_C_DP(15)
   2 P5E_CPU0_P2_TX_BUF_DP<15>      2 @T6G_MB_LIB.T6G(SCH_1):P5E_CPU0_P2_TX_BUF_DP(15)

Q_CAP_DIFFBUS_C0201-DIFF BUS_0.22UF,6.3V,20%,X6S,SA  I90  C6594
   1 P5E_CPU0_P2_TX_BUF_C_DN<14>      1 @T6G_MB_LIB.T6G(SCH_1):P5E_CPU0_P2_TX_BUF_C_DN(14)
   2 P5E_CPU0_P2_TX_BUF_DN<14>      2 @T6G_MB_LIB.T6G(SCH_1):P5E_CPU0_P2_TX_BUF_DN(14)

Q_CAP_DIFFBUS_C0201-DIFF BUS_0.22UF,6.3V,20%,X6S,SA  I91  C6593
   1 P5E_CPU0_P2_TX_BUF_C_DP<14>      1 @T6G_MB_LIB.T6G(SCH_1):P5E_CPU0_P2_TX_BUF_C_DP(14)
   2 P5E_CPU0_P2_TX_BUF_DP<14>      2 @T6G_MB_LIB.T6G(SCH_1):P5E_CPU0_P2_TX_BUF_DP(14)

Q_CAP_DIFFBUS_C0201-DIFF BUS_0.22UF,6.3V,20%,X6S,SA  I92  C6592
   1 P5E_CPU0_P2_TX_BUF_C_DN<13>      1 @T6G_MB_LIB.T6G(SCH_1):P5E_CPU0_P2_TX_BUF_C_DN(13)
   2 P5E_CPU0_P2_TX_BUF_DN<13>      2 @T6G_MB_LIB.T6G(SCH_1):P5E_CPU0_P2_TX_BUF_DN(13)

Q_CAP_DIFFBUS_C0201-DIFF BUS_0.22UF,6.3V,20%,X6S,SA  I93  C6591
   1 P5E_CPU0_P2_TX_BUF_C_DP<13>      1 @T6G_MB_LIB.T6G(SCH_1):P5E_CPU0_P2_TX_BUF_C_DP(13)
   2 P5E_CPU0_P2_TX_BUF_DP<13>      2 @T6G_MB_LIB.T6G(SCH_1):P5E_CPU0_P2_TX_BUF_DP(13)

Q_CAP_DIFFBUS_C0201-DIFF BUS_0.22UF,6.3V,20%,X6S,SA  I94  C6590
   1 P5E_CPU0_P2_TX_BUF_C_DN<12>      1 @T6G_MB_LIB.T6G(SCH_1):P5E_CPU0_P2_TX_BUF_C_DN(12)
   2 P5E_CPU0_P2_TX_BUF_DN<12>      2 @T6G_MB_LIB.T6G(SCH_1):P5E_CPU0_P2_TX_BUF_DN(12)

Q_CAP_DIFFBUS_C0201-DIFF BUS_0.22UF,6.3V,20%,X6S,SA  I95  C6589
   1 P5E_CPU0_P2_TX_BUF_C_DP<12>      1 @T6G_MB_LIB.T6G(SCH_1):P5E_CPU0_P2_TX_BUF_C_DP(12)
   2 P5E_CPU0_P2_TX_BUF_DP<12>      2 @T6G_MB_LIB.T6G(SCH_1):P5E_CPU0_P2_TX_BUF_DP(12)

Q_CAP_DIFFBUS_C0201-DIFF BUS_0.22UF,6.3V,20%,X6S,SA  I96  C6588
   1 P5E_CPU0_P2_TX_BUF_C_DN<11>      1 @T6G_MB_LIB.T6G(SCH_1):P5E_CPU0_P2_TX_BUF_C_DN(11)
   2 P5E_CPU0_P2_TX_BUF_DN<11>      2 @T6G_MB_LIB.T6G(SCH_1):P5E_CPU0_P2_TX_BUF_DN(11)

Q_CAP_DIFFBUS_C0201-DIFF BUS_0.22UF,6.3V,20%,X6S,SA  I97  C6587
   1 P5E_CPU0_P2_TX_BUF_C_DP<11>      1 @T6G_MB_LIB.T6G(SCH_1):P5E_CPU0_P2_TX_BUF_C_DP(11)
   2 P5E_CPU0_P2_TX_BUF_DP<11>      2 @T6G_MB_LIB.T6G(SCH_1):P5E_CPU0_P2_TX_BUF_DP(11)

Q_CAP_DIFFBUS_C0201-DIFF BUS_0.22UF,6.3V,20%,X6S,SA  I98  C6586
   1 P5E_CPU0_P2_TX_BUF_C_DN<10>      1 @T6G_MB_LIB.T6G(SCH_1):P5E_CPU0_P2_TX_BUF_C_DN(10)
   2 P5E_CPU0_P2_TX_BUF_DN<10>      2 @T6G_MB_LIB.T6G(SCH_1):P5E_CPU0_P2_TX_BUF_DN(10)

Q_CAP_DIFFBUS_C0201-DIFF BUS_0.22UF,6.3V,20%,X6S,SA  I99  C6585
   1 P5E_CPU0_P2_TX_BUF_C_DP<10>      1 @T6G_MB_LIB.T6G(SCH_1):P5E_CPU0_P2_TX_BUF_C_DP(10)
   2 P5E_CPU0_P2_TX_BUF_DP<10>      2 @T6G_MB_LIB.T6G(SCH_1):P5E_CPU0_P2_TX_BUF_DP(10)

Q_CAP_DIFFBUS_C0201-DIFF BUS_0.22UF,6.3V,20%,X6S,SA  I100  C6584
   1 P5E_CPU0_P2_TX_BUF_C_DN<9>      1 @T6G_MB_LIB.T6G(SCH_1):P5E_CPU0_P2_TX_BUF_C_DN(9)
   2 P5E_CPU0_P2_TX_BUF_DN<9>      2 @T6G_MB_LIB.T6G(SCH_1):P5E_CPU0_P2_TX_BUF_DN(9)

Q_CAP_DIFFBUS_C0201-DIFF BUS_0.22UF,6.3V,20%,X6S,SA  I101  C6583
   1 P5E_CPU0_P2_TX_BUF_C_DP<9>      1 @T6G_MB_LIB.T6G(SCH_1):P5E_CPU0_P2_TX_BUF_C_DP(9)
   2 P5E_CPU0_P2_TX_BUF_DP<9>      2 @T6G_MB_LIB.T6G(SCH_1):P5E_CPU0_P2_TX_BUF_DP(9)

Q_CAP_DIFFBUS_C0201-DIFF BUS_0.22UF,6.3V,20%,X6S,SA  I104  C6581
   1 P5E_CPU0_P2_TX_BUF_C_DP<8>      1 @T6G_MB_LIB.T6G(SCH_1):P5E_CPU0_P2_TX_BUF_C_DP(8)
   2 P5E_CPU0_P2_TX_BUF_DP<8>      2 @T6G_MB_LIB.T6G(SCH_1):P5E_CPU0_P2_TX_BUF_DP(8)

Q_CAP_DIFFBUS_C0201-DIFF BUS_0.22UF,6.3V,20%,X6S,SA  I105  C6582
   1 P5E_CPU0_P2_TX_BUF_C_DN<8>      1 @T6G_MB_LIB.T6G(SCH_1):P5E_CPU0_P2_TX_BUF_C_DN(8)
   2 P5E_CPU0_P2_TX_BUF_DN<8>      2 @T6G_MB_LIB.T6G(SCH_1):P5E_CPU0_P2_TX_BUF_DN(8)

PT5161LRS-PT5161LRS,SMLF,IC,AJ051610U03  I142  U6012
 CH7 P5E_CPU0_P2_TX_BUF_DP<7> B_PETP8 @T6G_MB_LIB.T6G(SCH_1):P5E_CPU0_P2_TX_BUF_DP(7)
CK10 P5E_CPU0_P2_TX_BUF_DN<7> B_PETN8 @T6G_MB_LIB.T6G(SCH_1):P5E_CPU0_P2_TX_BUF_DN(7)
 CR7 P5E_CPU0_P2_TX_BUF_DP<6> B_PETP9 @T6G_MB_LIB.T6G(SCH_1):P5E_CPU0_P2_TX_BUF_DP(6)
CU10 P5E_CPU0_P2_TX_BUF_DN<6> B_PETN9 @T6G_MB_LIB.T6G(SCH_1):P5E_CPU0_P2_TX_BUF_DN(6)
 DB7 P5E_CPU0_P2_TX_BUF_DP<5> B_PETP10 @T6G_MB_LIB.T6G(SCH_1):P5E_CPU0_P2_TX_BUF_DP(5)
DD10 P5E_CPU0_P2_TX_BUF_DN<5> B_PETN10 @T6G_MB_LIB.T6G(SCH_1):P5E_CPU0_P2_TX_BUF_DN(5)
 DJ7 P5E_CPU0_P2_TX_BUF_DP<4> B_PETP11 @T6G_MB_LIB.T6G(SCH_1):P5E_CPU0_P2_TX_BUF_DP(4)
DL10 P5E_CPU0_P2_TX_BUF_DN<4> B_PETN11 @T6G_MB_LIB.T6G(SCH_1):P5E_CPU0_P2_TX_BUF_DN(4)
 DT7 P5E_CPU0_P2_TX_BUF_DP<3> B_PETP12 @T6G_MB_LIB.T6G(SCH_1):P5E_CPU0_P2_TX_BUF_DP(3)
DV10 P5E_CPU0_P2_TX_BUF_DN<3> B_PETN12 @T6G_MB_LIB.T6G(SCH_1):P5E_CPU0_P2_TX_BUF_DN(3)
 EC7 P5E_CPU0_P2_TX_BUF_DP<2> B_PETP13 @T6G_MB_LIB.T6G(SCH_1):P5E_CPU0_P2_TX_BUF_DP(2)
EE10 P5E_CPU0_P2_TX_BUF_DN<2> B_PETN13 @T6G_MB_LIB.T6G(SCH_1):P5E_CPU0_P2_TX_BUF_DN(2)
 EK7 P5E_CPU0_P2_TX_BUF_DP<1> B_PETP14 @T6G_MB_LIB.T6G(SCH_1):P5E_CPU0_P2_TX_BUF_DP(1)
EM10 P5E_CPU0_P2_TX_BUF_DN<1> B_PETN14 @T6G_MB_LIB.T6G(SCH_1):P5E_CPU0_P2_TX_BUF_DN(1)
 EU7 P5E_CPU0_P2_TX_BUF_DP<0> B_PETP15 @T6G_MB_LIB.T6G(SCH_1):P5E_CPU0_P2_TX_BUF_DP(0)
EW10 P5E_CPU0_P2_TX_BUF_DN<0> B_PETN15 @T6G_MB_LIB.T6G(SCH_1):P5E_CPU0_P2_TX_BUF_DN(0)


DRAWING: @T6G_MB_LIB.T6G(SCH_1):PAGE426 

PT5161LRS-PT5161LRS,SMLF,IC,AJ051610U03  I1  U6013
 N34 P5E_CPU0_P3_TX_C_DN<15> B_PERP0 @T6G_MB_LIB.T6G(SCH_1):P5E_CPU0_P3_TX_C_DN(15)
 R35 P5E_CPU0_P3_TX_C_DP<15> B_PERN0 @T6G_MB_LIB.T6G(SCH_1):P5E_CPU0_P3_TX_C_DP(15)
 Y34 P5E_CPU0_P3_TX_C_DP<14> B_PERP1 @T6G_MB_LIB.T6G(SCH_1):P5E_CPU0_P3_TX_C_DP(14)
AB35 P5E_CPU0_P3_TX_C_DN<14> B_PERN1 @T6G_MB_LIB.T6G(SCH_1):P5E_CPU0_P3_TX_C_DN(14)
AG34 P5E_CPU0_P3_TX_C_DN<13> B_PERP2 @T6G_MB_LIB.T6G(SCH_1):P5E_CPU0_P3_TX_C_DN(13)
AJ35 P5E_CPU0_P3_TX_C_DP<13> B_PERN2 @T6G_MB_LIB.T6G(SCH_1):P5E_CPU0_P3_TX_C_DP(13)
AP34 P5E_CPU0_P3_TX_C_DN<12> B_PERP3 @T6G_MB_LIB.T6G(SCH_1):P5E_CPU0_P3_TX_C_DN(12)
AT35 P5E_CPU0_P3_TX_C_DP<12> B_PERN3 @T6G_MB_LIB.T6G(SCH_1):P5E_CPU0_P3_TX_C_DP(12)
BA34 P5E_CPU0_P3_TX_C_DN<11> B_PERP4 @T6G_MB_LIB.T6G(SCH_1):P5E_CPU0_P3_TX_C_DN(11)
BC35 P5E_CPU0_P3_TX_C_DP<11> B_PERN4 @T6G_MB_LIB.T6G(SCH_1):P5E_CPU0_P3_TX_C_DP(11)
BH34 P5E_CPU0_P3_TX_C_DN<10> B_PERP5 @T6G_MB_LIB.T6G(SCH_1):P5E_CPU0_P3_TX_C_DN(10)
BK35 P5E_CPU0_P3_TX_C_DP<10> B_PERN5 @T6G_MB_LIB.T6G(SCH_1):P5E_CPU0_P3_TX_C_DP(10)
BR34 P5E_CPU0_P3_TX_C_DN<9> B_PERP6 @T6G_MB_LIB.T6G(SCH_1):P5E_CPU0_P3_TX_C_DN(9)
BU35 P5E_CPU0_P3_TX_C_DP<9> B_PERN6 @T6G_MB_LIB.T6G(SCH_1):P5E_CPU0_P3_TX_C_DP(9)
CB34 P5E_CPU0_P3_TX_C_DN<8> B_PERP7 @T6G_MB_LIB.T6G(SCH_1):P5E_CPU0_P3_TX_C_DN(8)
CD35 P5E_CPU0_P3_TX_C_DP<8> B_PERN7 @T6G_MB_LIB.T6G(SCH_1):P5E_CPU0_P3_TX_C_DP(8)

PT5161LRS-PT5161LRS,SMLF,IC,AJ051610U03  I38  U6013
CJ34 P5E_CPU0_P3_TX_C_DN<7> B_PERP8 @T6G_MB_LIB.T6G(SCH_1):P5E_CPU0_P3_TX_C_DN(7)
CL35 P5E_CPU0_P3_TX_C_DP<7> B_PERN8 @T6G_MB_LIB.T6G(SCH_1):P5E_CPU0_P3_TX_C_DP(7)
CT34 P5E_CPU0_P3_TX_C_DN<6> B_PERP9 @T6G_MB_LIB.T6G(SCH_1):P5E_CPU0_P3_TX_C_DN(6)
CV35 P5E_CPU0_P3_TX_C_DP<6> B_PERN9 @T6G_MB_LIB.T6G(SCH_1):P5E_CPU0_P3_TX_C_DP(6)
DC34 P5E_CPU0_P3_TX_C_DN<5> B_PERP10 @T6G_MB_LIB.T6G(SCH_1):P5E_CPU0_P3_TX_C_DN(5)
DE35 P5E_CPU0_P3_TX_C_DP<5> B_PERN10 @T6G_MB_LIB.T6G(SCH_1):P5E_CPU0_P3_TX_C_DP(5)
DK34 P5E_CPU0_P3_TX_C_DN<4> B_PERP11 @T6G_MB_LIB.T6G(SCH_1):P5E_CPU0_P3_TX_C_DN(4)
DM35 P5E_CPU0_P3_TX_C_DP<4> B_PERN11 @T6G_MB_LIB.T6G(SCH_1):P5E_CPU0_P3_TX_C_DP(4)
DU34 P5E_CPU0_P3_TX_C_DN<3> B_PERP12 @T6G_MB_LIB.T6G(SCH_1):P5E_CPU0_P3_TX_C_DN(3)
DW35 P5E_CPU0_P3_TX_C_DP<3> B_PERN12 @T6G_MB_LIB.T6G(SCH_1):P5E_CPU0_P3_TX_C_DP(3)
ED34 P5E_CPU0_P3_TX_C_DN<2> B_PERP13 @T6G_MB_LIB.T6G(SCH_1):P5E_CPU0_P3_TX_C_DN(2)
EF35 P5E_CPU0_P3_TX_C_DP<2> B_PERN13 @T6G_MB_LIB.T6G(SCH_1):P5E_CPU0_P3_TX_C_DP(2)
EL34 P5E_CPU0_P3_TX_C_DP<1> B_PERP14 @T6G_MB_LIB.T6G(SCH_1):P5E_CPU0_P3_TX_C_DP(1)
EN35 P5E_CPU0_P3_TX_C_DN<1> B_PERN14 @T6G_MB_LIB.T6G(SCH_1):P5E_CPU0_P3_TX_C_DN(1)
EV34 P5E_CPU0_P3_TX_C_DN<0> B_PERP15 @T6G_MB_LIB.T6G(SCH_1):P5E_CPU0_P3_TX_C_DN(0)
EY35 P5E_CPU0_P3_TX_C_DP<0> B_PERN15 @T6G_MB_LIB.T6G(SCH_1):P5E_CPU0_P3_TX_C_DP(0)


DRAWING: @T6G_MB_LIB.T6G(SCH_1):PAGE427 

PT5161LRS-PT5161LRS,SMLF,IC,AJ051610U03  I1  U6013
 M26 P5E_CPU0_P3_RX_DP<15> A_PETP0 @T6G_MB_LIB.T6G(SCH_1):P5E_CPU0_P3_RX_DP(15)
 P29 P5E_CPU0_P3_RX_DN<15> A_PETN0 @T6G_MB_LIB.T6G(SCH_1):P5E_CPU0_P3_RX_DN(15)
 W26 P5E_CPU0_P3_RX_DP<14> A_PETP1 @T6G_MB_LIB.T6G(SCH_1):P5E_CPU0_P3_RX_DP(14)
AA29 P5E_CPU0_P3_RX_DN<14> A_PETN1 @T6G_MB_LIB.T6G(SCH_1):P5E_CPU0_P3_RX_DN(14)
AF26 P5E_CPU0_P3_RX_DP<13> A_PETP2 @T6G_MB_LIB.T6G(SCH_1):P5E_CPU0_P3_RX_DP(13)
AH29 P5E_CPU0_P3_RX_DN<13> A_PETN2 @T6G_MB_LIB.T6G(SCH_1):P5E_CPU0_P3_RX_DN(13)
AN26 P5E_CPU0_P3_RX_DP<12> A_PETP3 @T6G_MB_LIB.T6G(SCH_1):P5E_CPU0_P3_RX_DP(12)
AR29 P5E_CPU0_P3_RX_DN<12> A_PETN3 @T6G_MB_LIB.T6G(SCH_1):P5E_CPU0_P3_RX_DN(12)
AY26 P5E_CPU0_P3_RX_DP<11> A_PETP4 @T6G_MB_LIB.T6G(SCH_1):P5E_CPU0_P3_RX_DP(11)
BB29 P5E_CPU0_P3_RX_DN<11> A_PETN4 @T6G_MB_LIB.T6G(SCH_1):P5E_CPU0_P3_RX_DN(11)
BG26 P5E_CPU0_P3_RX_DP<10> A_PETP5 @T6G_MB_LIB.T6G(SCH_1):P5E_CPU0_P3_RX_DP(10)
BJ29 P5E_CPU0_P3_RX_DN<10> A_PETN5 @T6G_MB_LIB.T6G(SCH_1):P5E_CPU0_P3_RX_DN(10)
BP26 P5E_CPU0_P3_RX_DP<9> A_PETP6 @T6G_MB_LIB.T6G(SCH_1):P5E_CPU0_P3_RX_DP(9)
BT29 P5E_CPU0_P3_RX_DN<9> A_PETN6 @T6G_MB_LIB.T6G(SCH_1):P5E_CPU0_P3_RX_DN(9)
CA26 P5E_CPU0_P3_RX_DP<8> A_PETP7 @T6G_MB_LIB.T6G(SCH_1):P5E_CPU0_P3_RX_DP(8)
CC29 P5E_CPU0_P3_RX_DN<8> A_PETN7 @T6G_MB_LIB.T6G(SCH_1):P5E_CPU0_P3_RX_DN(8)

PT5161LRS-PT5161LRS,SMLF,IC,AJ051610U03  I38  U6013
CH26 P5E_CPU0_P3_RX_DP<7> A_PETP8 @T6G_MB_LIB.T6G(SCH_1):P5E_CPU0_P3_RX_DP(7)
CK29 P5E_CPU0_P3_RX_DN<7> A_PETN8 @T6G_MB_LIB.T6G(SCH_1):P5E_CPU0_P3_RX_DN(7)
CR26 P5E_CPU0_P3_RX_DP<6> A_PETP9 @T6G_MB_LIB.T6G(SCH_1):P5E_CPU0_P3_RX_DP(6)
CU29 P5E_CPU0_P3_RX_DN<6> A_PETN9 @T6G_MB_LIB.T6G(SCH_1):P5E_CPU0_P3_RX_DN(6)
DB26 P5E_CPU0_P3_RX_DP<5> A_PETP10 @T6G_MB_LIB.T6G(SCH_1):P5E_CPU0_P3_RX_DP(5)
DD29 P5E_CPU0_P3_RX_DN<5> A_PETN10 @T6G_MB_LIB.T6G(SCH_1):P5E_CPU0_P3_RX_DN(5)
DJ26 P5E_CPU0_P3_RX_DP<4> A_PETP11 @T6G_MB_LIB.T6G(SCH_1):P5E_CPU0_P3_RX_DP(4)
DL29 P5E_CPU0_P3_RX_DN<4> A_PETN11 @T6G_MB_LIB.T6G(SCH_1):P5E_CPU0_P3_RX_DN(4)
DT26 P5E_CPU0_P3_RX_DP<3> A_PETP12 @T6G_MB_LIB.T6G(SCH_1):P5E_CPU0_P3_RX_DP(3)
DV29 P5E_CPU0_P3_RX_DN<3> A_PETN12 @T6G_MB_LIB.T6G(SCH_1):P5E_CPU0_P3_RX_DN(3)
EC26 P5E_CPU0_P3_RX_DP<2> A_PETP13 @T6G_MB_LIB.T6G(SCH_1):P5E_CPU0_P3_RX_DP(2)
EE29 P5E_CPU0_P3_RX_DN<2> A_PETN13 @T6G_MB_LIB.T6G(SCH_1):P5E_CPU0_P3_RX_DN(2)
EK26 P5E_CPU0_P3_RX_DP<1> A_PETP14 @T6G_MB_LIB.T6G(SCH_1):P5E_CPU0_P3_RX_DP(1)
EM29 P5E_CPU0_P3_RX_DN<1> A_PETN14 @T6G_MB_LIB.T6G(SCH_1):P5E_CPU0_P3_RX_DN(1)
EU26 P5E_CPU0_P3_RX_DP<0> A_PETP15 @T6G_MB_LIB.T6G(SCH_1):P5E_CPU0_P3_RX_DP(0)
EW29 P5E_CPU0_P3_RX_DN<0> A_PETN15 @T6G_MB_LIB.T6G(SCH_1):P5E_CPU0_P3_RX_DN(0)


DRAWING: @T6G_MB_LIB.T6G(SCH_1):PAGE428 

PT5161LRS-PT5161LRS,SMLF,IC,AJ051610U03  I1  U6013
  R1 P5E_CPU0_P3_RX_BUF_DP<15> A_PERP0 @T6G_MB_LIB.T6G(SCH_1):P5E_CPU0_P3_RX_BUF_DP(15)
  N2 P5E_CPU0_P3_RX_BUF_DN<15> A_PERN0 @T6G_MB_LIB.T6G(SCH_1):P5E_CPU0_P3_RX_BUF_DN(15)
 AB1 P5E_CPU0_P3_RX_BUF_DP<14> A_PERP1 @T6G_MB_LIB.T6G(SCH_1):P5E_CPU0_P3_RX_BUF_DP(14)
  Y2 P5E_CPU0_P3_RX_BUF_DN<14> A_PERN1 @T6G_MB_LIB.T6G(SCH_1):P5E_CPU0_P3_RX_BUF_DN(14)
 AJ1 P5E_CPU0_P3_RX_BUF_DP<13> A_PERP2 @T6G_MB_LIB.T6G(SCH_1):P5E_CPU0_P3_RX_BUF_DP(13)
 AG2 P5E_CPU0_P3_RX_BUF_DN<13> A_PERN2 @T6G_MB_LIB.T6G(SCH_1):P5E_CPU0_P3_RX_BUF_DN(13)
 AT1 P5E_CPU0_P3_RX_BUF_DP<12> A_PERP3 @T6G_MB_LIB.T6G(SCH_1):P5E_CPU0_P3_RX_BUF_DP(12)
 AP2 P5E_CPU0_P3_RX_BUF_DN<12> A_PERN3 @T6G_MB_LIB.T6G(SCH_1):P5E_CPU0_P3_RX_BUF_DN(12)
 BC1 P5E_CPU0_P3_RX_BUF_DP<11> A_PERP4 @T6G_MB_LIB.T6G(SCH_1):P5E_CPU0_P3_RX_BUF_DP(11)
 BA2 P5E_CPU0_P3_RX_BUF_DN<11> A_PERN4 @T6G_MB_LIB.T6G(SCH_1):P5E_CPU0_P3_RX_BUF_DN(11)
 BK1 P5E_CPU0_P3_RX_BUF_DP<10> A_PERP5 @T6G_MB_LIB.T6G(SCH_1):P5E_CPU0_P3_RX_BUF_DP(10)
 BH2 P5E_CPU0_P3_RX_BUF_DN<10> A_PERN5 @T6G_MB_LIB.T6G(SCH_1):P5E_CPU0_P3_RX_BUF_DN(10)
 BU1 P5E_CPU0_P3_RX_BUF_DP<9> A_PERP6 @T6G_MB_LIB.T6G(SCH_1):P5E_CPU0_P3_RX_BUF_DP(9)
 BR2 P5E_CPU0_P3_RX_BUF_DN<9> A_PERN6 @T6G_MB_LIB.T6G(SCH_1):P5E_CPU0_P3_RX_BUF_DN(9)
 CD1 P5E_CPU0_P3_RX_BUF_DP<8> A_PERP7 @T6G_MB_LIB.T6G(SCH_1):P5E_CPU0_P3_RX_BUF_DP(8)
 CB2 P5E_CPU0_P3_RX_BUF_DN<8> A_PERN7 @T6G_MB_LIB.T6G(SCH_1):P5E_CPU0_P3_RX_BUF_DN(8)

PT5161LRS-PT5161LRS,SMLF,IC,AJ051610U03  I38  U6013
 CL1 P5E_CPU0_P3_RX_BUF_DP<7> A_PERP8 @T6G_MB_LIB.T6G(SCH_1):P5E_CPU0_P3_RX_BUF_DP(7)
 CJ2 P5E_CPU0_P3_RX_BUF_DN<7> A_PERN8 @T6G_MB_LIB.T6G(SCH_1):P5E_CPU0_P3_RX_BUF_DN(7)
 CV1 P5E_CPU0_P3_RX_BUF_DP<6> A_PERP9 @T6G_MB_LIB.T6G(SCH_1):P5E_CPU0_P3_RX_BUF_DP(6)
 CT2 P5E_CPU0_P3_RX_BUF_DN<6> A_PERN9 @T6G_MB_LIB.T6G(SCH_1):P5E_CPU0_P3_RX_BUF_DN(6)
 DE1 P5E_CPU0_P3_RX_BUF_DP<5> A_PERP10 @T6G_MB_LIB.T6G(SCH_1):P5E_CPU0_P3_RX_BUF_DP(5)
 DC2 P5E_CPU0_P3_RX_BUF_DN<5> A_PERN10 @T6G_MB_LIB.T6G(SCH_1):P5E_CPU0_P3_RX_BUF_DN(5)
 DM1 P5E_CPU0_P3_RX_BUF_DP<4> A_PERP11 @T6G_MB_LIB.T6G(SCH_1):P5E_CPU0_P3_RX_BUF_DP(4)
 DK2 P5E_CPU0_P3_RX_BUF_DN<4> A_PERN11 @T6G_MB_LIB.T6G(SCH_1):P5E_CPU0_P3_RX_BUF_DN(4)
 DW1 P5E_CPU0_P3_RX_BUF_DP<3> A_PERP12 @T6G_MB_LIB.T6G(SCH_1):P5E_CPU0_P3_RX_BUF_DP(3)
 DU2 P5E_CPU0_P3_RX_BUF_DN<3> A_PERN12 @T6G_MB_LIB.T6G(SCH_1):P5E_CPU0_P3_RX_BUF_DN(3)
 EF1 P5E_CPU0_P3_RX_BUF_DP<2> A_PERP13 @T6G_MB_LIB.T6G(SCH_1):P5E_CPU0_P3_RX_BUF_DP(2)
 ED2 P5E_CPU0_P3_RX_BUF_DN<2> A_PERN13 @T6G_MB_LIB.T6G(SCH_1):P5E_CPU0_P3_RX_BUF_DN(2)
 EN1 P5E_CPU0_P3_RX_BUF_DP<1> A_PERP14 @T6G_MB_LIB.T6G(SCH_1):P5E_CPU0_P3_RX_BUF_DP(1)
 EL2 P5E_CPU0_P3_RX_BUF_DN<1> A_PERN14 @T6G_MB_LIB.T6G(SCH_1):P5E_CPU0_P3_RX_BUF_DN(1)
 EY1 P5E_CPU0_P3_RX_BUF_DP<0> A_PERP15 @T6G_MB_LIB.T6G(SCH_1):P5E_CPU0_P3_RX_BUF_DP(0)
 EV2 P5E_CPU0_P3_RX_BUF_DN<0> A_PERN15 @T6G_MB_LIB.T6G(SCH_1):P5E_CPU0_P3_RX_BUF_DN(0)


DRAWING: @T6G_MB_LIB.T6G(SCH_1):PAGE429 

Q_CAP_DIFFBUS_C0201-DIFF BUS_0.22UF,6.3V,20%,X6S,SA  I19  C6611
   1 P5E_CPU0_P3_TX_BUF_C_DP<7>      1 @T6G_MB_LIB.T6G(SCH_1):P5E_CPU0_P3_TX_BUF_C_DP(7)
   2 P5E_CPU0_P3_TX_BUF_DP<7>      2 @T6G_MB_LIB.T6G(SCH_1):P5E_CPU0_P3_TX_BUF_DP(7)

Q_CAP_DIFFBUS_C0201-DIFF BUS_0.22UF,6.3V,20%,X6S,SA  I20  C6612
   1 P5E_CPU0_P3_TX_BUF_C_DN<7>      1 @T6G_MB_LIB.T6G(SCH_1):P5E_CPU0_P3_TX_BUF_C_DN(7)
   2 P5E_CPU0_P3_TX_BUF_DN<7>      2 @T6G_MB_LIB.T6G(SCH_1):P5E_CPU0_P3_TX_BUF_DN(7)

Q_CAP_DIFFBUS_C0201-DIFF BUS_0.22UF,6.3V,20%,X6S,SA  I21  C6610
   1 P5E_CPU0_P3_TX_BUF_C_DN<6>      1 @T6G_MB_LIB.T6G(SCH_1):P5E_CPU0_P3_TX_BUF_C_DN(6)
   2 P5E_CPU0_P3_TX_BUF_DN<6>      2 @T6G_MB_LIB.T6G(SCH_1):P5E_CPU0_P3_TX_BUF_DN(6)

Q_CAP_DIFFBUS_C0201-DIFF BUS_0.22UF,6.3V,20%,X6S,SA  I22  C6609
   1 P5E_CPU0_P3_TX_BUF_C_DP<6>      1 @T6G_MB_LIB.T6G(SCH_1):P5E_CPU0_P3_TX_BUF_C_DP(6)
   2 P5E_CPU0_P3_TX_BUF_DP<6>      2 @T6G_MB_LIB.T6G(SCH_1):P5E_CPU0_P3_TX_BUF_DP(6)

Q_CAP_DIFFBUS_C0201-DIFF BUS_0.22UF,6.3V,20%,X6S,SA  I23  C6608
   1 P5E_CPU0_P3_TX_BUF_C_DN<5>      1 @T6G_MB_LIB.T6G(SCH_1):P5E_CPU0_P3_TX_BUF_C_DN(5)
   2 P5E_CPU0_P3_TX_BUF_DN<5>      2 @T6G_MB_LIB.T6G(SCH_1):P5E_CPU0_P3_TX_BUF_DN(5)

Q_CAP_DIFFBUS_C0201-DIFF BUS_0.22UF,6.3V,20%,X6S,SA  I24  C6607
   1 P5E_CPU0_P3_TX_BUF_C_DP<5>      1 @T6G_MB_LIB.T6G(SCH_1):P5E_CPU0_P3_TX_BUF_C_DP(5)
   2 P5E_CPU0_P3_TX_BUF_DP<5>      2 @T6G_MB_LIB.T6G(SCH_1):P5E_CPU0_P3_TX_BUF_DP(5)

Q_CAP_DIFFBUS_C0201-DIFF BUS_0.22UF,6.3V,20%,X6S,SA  I31  C6606
   1 P5E_CPU0_P3_TX_BUF_C_DN<4>      1 @T6G_MB_LIB.T6G(SCH_1):P5E_CPU0_P3_TX_BUF_C_DN(4)
   2 P5E_CPU0_P3_TX_BUF_DN<4>      2 @T6G_MB_LIB.T6G(SCH_1):P5E_CPU0_P3_TX_BUF_DN(4)

Q_CAP_DIFFBUS_C0201-DIFF BUS_0.22UF,6.3V,20%,X6S,SA  I32  C6605
   1 P5E_CPU0_P3_TX_BUF_C_DP<4>      1 @T6G_MB_LIB.T6G(SCH_1):P5E_CPU0_P3_TX_BUF_C_DP(4)
   2 P5E_CPU0_P3_TX_BUF_DP<4>      2 @T6G_MB_LIB.T6G(SCH_1):P5E_CPU0_P3_TX_BUF_DP(4)

Q_CAP_DIFFBUS_C0201-DIFF BUS_0.22UF,6.3V,20%,X6S,SA  I33  C6604
   1 P5E_CPU0_P3_TX_BUF_C_DN<3>      1 @T6G_MB_LIB.T6G(SCH_1):P5E_CPU0_P3_TX_BUF_C_DN(3)
   2 P5E_CPU0_P3_TX_BUF_DN<3>      2 @T6G_MB_LIB.T6G(SCH_1):P5E_CPU0_P3_TX_BUF_DN(3)

Q_CAP_DIFFBUS_C0201-DIFF BUS_0.22UF,6.3V,20%,X6S,SA  I34  C6603
   1 P5E_CPU0_P3_TX_BUF_C_DP<3>      1 @T6G_MB_LIB.T6G(SCH_1):P5E_CPU0_P3_TX_BUF_C_DP(3)
   2 P5E_CPU0_P3_TX_BUF_DP<3>      2 @T6G_MB_LIB.T6G(SCH_1):P5E_CPU0_P3_TX_BUF_DP(3)

Q_CAP_DIFFBUS_C0201-DIFF BUS_0.22UF,6.3V,20%,X6S,SA  I35  C6602
   1 P5E_CPU0_P3_TX_BUF_C_DN<2>      1 @T6G_MB_LIB.T6G(SCH_1):P5E_CPU0_P3_TX_BUF_C_DN(2)
   2 P5E_CPU0_P3_TX_BUF_DN<2>      2 @T6G_MB_LIB.T6G(SCH_1):P5E_CPU0_P3_TX_BUF_DN(2)

Q_CAP_DIFFBUS_C0201-DIFF BUS_0.22UF,6.3V,20%,X6S,SA  I36  C6601
   1 P5E_CPU0_P3_TX_BUF_C_DP<2>      1 @T6G_MB_LIB.T6G(SCH_1):P5E_CPU0_P3_TX_BUF_C_DP(2)
   2 P5E_CPU0_P3_TX_BUF_DP<2>      2 @T6G_MB_LIB.T6G(SCH_1):P5E_CPU0_P3_TX_BUF_DP(2)

Q_CAP_DIFFBUS_C0201-DIFF BUS_0.22UF,6.3V,20%,X6S,SA  I37  C6600
   1 P5E_CPU0_P3_TX_BUF_C_DN<1>      1 @T6G_MB_LIB.T6G(SCH_1):P5E_CPU0_P3_TX_BUF_C_DN(1)
   2 P5E_CPU0_P3_TX_BUF_DN<1>      2 @T6G_MB_LIB.T6G(SCH_1):P5E_CPU0_P3_TX_BUF_DN(1)

Q_CAP_DIFFBUS_C0201-DIFF BUS_0.22UF,6.3V,20%,X6S,SA  I38  C6599
   1 P5E_CPU0_P3_TX_BUF_C_DP<1>      1 @T6G_MB_LIB.T6G(SCH_1):P5E_CPU0_P3_TX_BUF_C_DP(1)
   2 P5E_CPU0_P3_TX_BUF_DP<1>      2 @T6G_MB_LIB.T6G(SCH_1):P5E_CPU0_P3_TX_BUF_DP(1)

Q_CAP_DIFFBUS_C0201-DIFF BUS_0.22UF,6.3V,20%,X6S,SA  I39  C6598
   1 P5E_CPU0_P3_TX_BUF_C_DN<0>      1 @T6G_MB_LIB.T6G(SCH_1):P5E_CPU0_P3_TX_BUF_C_DN(0)
   2 P5E_CPU0_P3_TX_BUF_DN<0>      2 @T6G_MB_LIB.T6G(SCH_1):P5E_CPU0_P3_TX_BUF_DN(0)

Q_CAP_DIFFBUS_C0201-DIFF BUS_0.22UF,6.3V,20%,X6S,SA  I40  C6597
   1 P5E_CPU0_P3_TX_BUF_C_DP<0>      1 @T6G_MB_LIB.T6G(SCH_1):P5E_CPU0_P3_TX_BUF_C_DP(0)
   2 P5E_CPU0_P3_TX_BUF_DP<0>      2 @T6G_MB_LIB.T6G(SCH_1):P5E_CPU0_P3_TX_BUF_DP(0)

PT5161LRS-PT5161LRS,SMLF,IC,AJ051610U03  I51  U6013
  M7 P5E_CPU0_P3_TX_BUF_DP<15> B_PETP0 @T6G_MB_LIB.T6G(SCH_1):P5E_CPU0_P3_TX_BUF_DP(15)
 P10 P5E_CPU0_P3_TX_BUF_DN<15> B_PETN0 @T6G_MB_LIB.T6G(SCH_1):P5E_CPU0_P3_TX_BUF_DN(15)
  W7 P5E_CPU0_P3_TX_BUF_DP<14> B_PETP1 @T6G_MB_LIB.T6G(SCH_1):P5E_CPU0_P3_TX_BUF_DP(14)
AA10 P5E_CPU0_P3_TX_BUF_DN<14> B_PETN1 @T6G_MB_LIB.T6G(SCH_1):P5E_CPU0_P3_TX_BUF_DN(14)
 AF7 P5E_CPU0_P3_TX_BUF_DP<13> B_PETP2 @T6G_MB_LIB.T6G(SCH_1):P5E_CPU0_P3_TX_BUF_DP(13)
AH10 P5E_CPU0_P3_TX_BUF_DN<13> B_PETN2 @T6G_MB_LIB.T6G(SCH_1):P5E_CPU0_P3_TX_BUF_DN(13)
 AN7 P5E_CPU0_P3_TX_BUF_DP<12> B_PETP3 @T6G_MB_LIB.T6G(SCH_1):P5E_CPU0_P3_TX_BUF_DP(12)
AR10 P5E_CPU0_P3_TX_BUF_DN<12> B_PETN3 @T6G_MB_LIB.T6G(SCH_1):P5E_CPU0_P3_TX_BUF_DN(12)
 AY7 P5E_CPU0_P3_TX_BUF_DP<11> B_PETP4 @T6G_MB_LIB.T6G(SCH_1):P5E_CPU0_P3_TX_BUF_DP(11)
BB10 P5E_CPU0_P3_TX_BUF_DN<11> B_PETN4 @T6G_MB_LIB.T6G(SCH_1):P5E_CPU0_P3_TX_BUF_DN(11)
 BG7 P5E_CPU0_P3_TX_BUF_DP<10> B_PETP5 @T6G_MB_LIB.T6G(SCH_1):P5E_CPU0_P3_TX_BUF_DP(10)
BJ10 P5E_CPU0_P3_TX_BUF_DN<10> B_PETN5 @T6G_MB_LIB.T6G(SCH_1):P5E_CPU0_P3_TX_BUF_DN(10)
 BP7 P5E_CPU0_P3_TX_BUF_DP<9> B_PETP6 @T6G_MB_LIB.T6G(SCH_1):P5E_CPU0_P3_TX_BUF_DP(9)
BT10 P5E_CPU0_P3_TX_BUF_DN<9> B_PETN6 @T6G_MB_LIB.T6G(SCH_1):P5E_CPU0_P3_TX_BUF_DN(9)
 CA7 P5E_CPU0_P3_TX_BUF_DP<8> B_PETP7 @T6G_MB_LIB.T6G(SCH_1):P5E_CPU0_P3_TX_BUF_DP(8)
CC10 P5E_CPU0_P3_TX_BUF_DN<8> B_PETN7 @T6G_MB_LIB.T6G(SCH_1):P5E_CPU0_P3_TX_BUF_DN(8)

Q_CAP_DIFFBUS_C0201-DIFF BUS_0.22UF,6.3V,20%,X6S,SA  I90  C6628
   1 P5E_CPU0_P3_TX_BUF_C_DN<15>      1 @T6G_MB_LIB.T6G(SCH_1):P5E_CPU0_P3_TX_BUF_C_DN(15)
   2 P5E_CPU0_P3_TX_BUF_DN<15>      2 @T6G_MB_LIB.T6G(SCH_1):P5E_CPU0_P3_TX_BUF_DN(15)

Q_CAP_DIFFBUS_C0201-DIFF BUS_0.22UF,6.3V,20%,X6S,SA  I91  C6625
   1 P5E_CPU0_P3_TX_BUF_C_DP<14>      1 @T6G_MB_LIB.T6G(SCH_1):P5E_CPU0_P3_TX_BUF_C_DP(14)
   2 P5E_CPU0_P3_TX_BUF_DP<14>      2 @T6G_MB_LIB.T6G(SCH_1):P5E_CPU0_P3_TX_BUF_DP(14)

Q_CAP_DIFFBUS_C0201-DIFF BUS_0.22UF,6.3V,20%,X6S,SA  I92  C6626
   1 P5E_CPU0_P3_TX_BUF_C_DN<14>      1 @T6G_MB_LIB.T6G(SCH_1):P5E_CPU0_P3_TX_BUF_C_DN(14)
   2 P5E_CPU0_P3_TX_BUF_DN<14>      2 @T6G_MB_LIB.T6G(SCH_1):P5E_CPU0_P3_TX_BUF_DN(14)

Q_CAP_DIFFBUS_C0201-DIFF BUS_0.22UF,6.3V,20%,X6S,SA  I93  C6627
   1 P5E_CPU0_P3_TX_BUF_C_DP<15>      1 @T6G_MB_LIB.T6G(SCH_1):P5E_CPU0_P3_TX_BUF_C_DP(15)
   2 P5E_CPU0_P3_TX_BUF_DP<15>      2 @T6G_MB_LIB.T6G(SCH_1):P5E_CPU0_P3_TX_BUF_DP(15)

Q_CAP_DIFFBUS_C0201-DIFF BUS_0.22UF,6.3V,20%,X6S,SA  I94  C6623
   1 P5E_CPU0_P3_TX_BUF_C_DP<13>      1 @T6G_MB_LIB.T6G(SCH_1):P5E_CPU0_P3_TX_BUF_C_DP(13)
   2 P5E_CPU0_P3_TX_BUF_DP<13>      2 @T6G_MB_LIB.T6G(SCH_1):P5E_CPU0_P3_TX_BUF_DP(13)

Q_CAP_DIFFBUS_C0201-DIFF BUS_0.22UF,6.3V,20%,X6S,SA  I95  C6624
   1 P5E_CPU0_P3_TX_BUF_C_DN<13>      1 @T6G_MB_LIB.T6G(SCH_1):P5E_CPU0_P3_TX_BUF_C_DN(13)
   2 P5E_CPU0_P3_TX_BUF_DN<13>      2 @T6G_MB_LIB.T6G(SCH_1):P5E_CPU0_P3_TX_BUF_DN(13)

Q_CAP_DIFFBUS_C0201-DIFF BUS_0.22UF,6.3V,20%,X6S,SA  I96  C6621
   1 P5E_CPU0_P3_TX_BUF_C_DP<12>      1 @T6G_MB_LIB.T6G(SCH_1):P5E_CPU0_P3_TX_BUF_C_DP(12)
   2 P5E_CPU0_P3_TX_BUF_DP<12>      2 @T6G_MB_LIB.T6G(SCH_1):P5E_CPU0_P3_TX_BUF_DP(12)

Q_CAP_DIFFBUS_C0201-DIFF BUS_0.22UF,6.3V,20%,X6S,SA  I97  C6622
   1 P5E_CPU0_P3_TX_BUF_C_DN<12>      1 @T6G_MB_LIB.T6G(SCH_1):P5E_CPU0_P3_TX_BUF_C_DN(12)
   2 P5E_CPU0_P3_TX_BUF_DN<12>      2 @T6G_MB_LIB.T6G(SCH_1):P5E_CPU0_P3_TX_BUF_DN(12)

Q_CAP_DIFFBUS_C0201-DIFF BUS_0.22UF,6.3V,20%,X6S,SA  I98  C6620
   1 P5E_CPU0_P3_TX_BUF_C_DN<11>      1 @T6G_MB_LIB.T6G(SCH_1):P5E_CPU0_P3_TX_BUF_C_DN(11)
   2 P5E_CPU0_P3_TX_BUF_DN<11>      2 @T6G_MB_LIB.T6G(SCH_1):P5E_CPU0_P3_TX_BUF_DN(11)

Q_CAP_DIFFBUS_C0201-DIFF BUS_0.22UF,6.3V,20%,X6S,SA  I99  C6618
   1 P5E_CPU0_P3_TX_BUF_C_DN<10>      1 @T6G_MB_LIB.T6G(SCH_1):P5E_CPU0_P3_TX_BUF_C_DN(10)
   2 P5E_CPU0_P3_TX_BUF_DN<10>      2 @T6G_MB_LIB.T6G(SCH_1):P5E_CPU0_P3_TX_BUF_DN(10)

Q_CAP_DIFFBUS_C0201-DIFF BUS_0.22UF,6.3V,20%,X6S,SA  I100  C6619
   1 P5E_CPU0_P3_TX_BUF_C_DP<11>      1 @T6G_MB_LIB.T6G(SCH_1):P5E_CPU0_P3_TX_BUF_C_DP(11)
   2 P5E_CPU0_P3_TX_BUF_DP<11>      2 @T6G_MB_LIB.T6G(SCH_1):P5E_CPU0_P3_TX_BUF_DP(11)

Q_CAP_DIFFBUS_C0201-DIFF BUS_0.22UF,6.3V,20%,X6S,SA  I101  C6617
   1 P5E_CPU0_P3_TX_BUF_C_DP<10>      1 @T6G_MB_LIB.T6G(SCH_1):P5E_CPU0_P3_TX_BUF_C_DP(10)
   2 P5E_CPU0_P3_TX_BUF_DP<10>      2 @T6G_MB_LIB.T6G(SCH_1):P5E_CPU0_P3_TX_BUF_DP(10)

Q_CAP_DIFFBUS_C0201-DIFF BUS_0.22UF,6.3V,20%,X6S,SA  I102  C6615
   1 P5E_CPU0_P3_TX_BUF_C_DP<9>      1 @T6G_MB_LIB.T6G(SCH_1):P5E_CPU0_P3_TX_BUF_C_DP(9)
   2 P5E_CPU0_P3_TX_BUF_DP<9>      2 @T6G_MB_LIB.T6G(SCH_1):P5E_CPU0_P3_TX_BUF_DP(9)

Q_CAP_DIFFBUS_C0201-DIFF BUS_0.22UF,6.3V,20%,X6S,SA  I103  C6616
   1 P5E_CPU0_P3_TX_BUF_C_DN<9>      1 @T6G_MB_LIB.T6G(SCH_1):P5E_CPU0_P3_TX_BUF_C_DN(9)
   2 P5E_CPU0_P3_TX_BUF_DN<9>      2 @T6G_MB_LIB.T6G(SCH_1):P5E_CPU0_P3_TX_BUF_DN(9)

Q_CAP_DIFFBUS_C0201-DIFF BUS_0.22UF,6.3V,20%,X6S,SA  I104  C6614
   1 P5E_CPU0_P3_TX_BUF_C_DN<8>      1 @T6G_MB_LIB.T6G(SCH_1):P5E_CPU0_P3_TX_BUF_C_DN(8)
   2 P5E_CPU0_P3_TX_BUF_DN<8>      2 @T6G_MB_LIB.T6G(SCH_1):P5E_CPU0_P3_TX_BUF_DN(8)

Q_CAP_DIFFBUS_C0201-DIFF BUS_0.22UF,6.3V,20%,X6S,SA  I105  C6613
   1 P5E_CPU0_P3_TX_BUF_C_DP<8>      1 @T6G_MB_LIB.T6G(SCH_1):P5E_CPU0_P3_TX_BUF_C_DP(8)
   2 P5E_CPU0_P3_TX_BUF_DP<8>      2 @T6G_MB_LIB.T6G(SCH_1):P5E_CPU0_P3_TX_BUF_DP(8)

PT5161LRS-PT5161LRS,SMLF,IC,AJ051610U03  I142  U6013
 CH7 P5E_CPU0_P3_TX_BUF_DP<7> B_PETP8 @T6G_MB_LIB.T6G(SCH_1):P5E_CPU0_P3_TX_BUF_DP(7)
CK10 P5E_CPU0_P3_TX_BUF_DN<7> B_PETN8 @T6G_MB_LIB.T6G(SCH_1):P5E_CPU0_P3_TX_BUF_DN(7)
 CR7 P5E_CPU0_P3_TX_BUF_DP<6> B_PETP9 @T6G_MB_LIB.T6G(SCH_1):P5E_CPU0_P3_TX_BUF_DP(6)
CU10 P5E_CPU0_P3_TX_BUF_DN<6> B_PETN9 @T6G_MB_LIB.T6G(SCH_1):P5E_CPU0_P3_TX_BUF_DN(6)
 DB7 P5E_CPU0_P3_TX_BUF_DP<5> B_PETP10 @T6G_MB_LIB.T6G(SCH_1):P5E_CPU0_P3_TX_BUF_DP(5)
DD10 P5E_CPU0_P3_TX_BUF_DN<5> B_PETN10 @T6G_MB_LIB.T6G(SCH_1):P5E_CPU0_P3_TX_BUF_DN(5)
 DJ7 P5E_CPU0_P3_TX_BUF_DP<4> B_PETP11 @T6G_MB_LIB.T6G(SCH_1):P5E_CPU0_P3_TX_BUF_DP(4)
DL10 P5E_CPU0_P3_TX_BUF_DN<4> B_PETN11 @T6G_MB_LIB.T6G(SCH_1):P5E_CPU0_P3_TX_BUF_DN(4)
 DT7 P5E_CPU0_P3_TX_BUF_DP<3> B_PETP12 @T6G_MB_LIB.T6G(SCH_1):P5E_CPU0_P3_TX_BUF_DP(3)
DV10 P5E_CPU0_P3_TX_BUF_DN<3> B_PETN12 @T6G_MB_LIB.T6G(SCH_1):P5E_CPU0_P3_TX_BUF_DN(3)
 EC7 P5E_CPU0_P3_TX_BUF_DP<2> B_PETP13 @T6G_MB_LIB.T6G(SCH_1):P5E_CPU0_P3_TX_BUF_DP(2)
EE10 P5E_CPU0_P3_TX_BUF_DN<2> B_PETN13 @T6G_MB_LIB.T6G(SCH_1):P5E_CPU0_P3_TX_BUF_DN(2)
 EK7 P5E_CPU0_P3_TX_BUF_DP<1> B_PETP14 @T6G_MB_LIB.T6G(SCH_1):P5E_CPU0_P3_TX_BUF_DP(1)
EM10 P5E_CPU0_P3_TX_BUF_DN<1> B_PETN14 @T6G_MB_LIB.T6G(SCH_1):P5E_CPU0_P3_TX_BUF_DN(1)
 EU7 P5E_CPU0_P3_TX_BUF_DP<0> B_PETP15 @T6G_MB_LIB.T6G(SCH_1):P5E_CPU0_P3_TX_BUF_DP(0)
EW10 P5E_CPU0_P3_TX_BUF_DN<0> B_PETN15 @T6G_MB_LIB.T6G(SCH_1):P5E_CPU0_P3_TX_BUF_DN(0)


DRAWING: @T6G_MB_LIB.T6G(SCH_1):PAGE437 

PT5161LRS-PT5161LRS,SMLF,IC,AJ051610U03  I1  U6014
 N34 P5E_CPU1_P0_TX_C_DN<15> B_PERP0 @T6G_MB_LIB.T6G(SCH_1):P5E_CPU1_P0_TX_C_DN(15)
 R35 P5E_CPU1_P0_TX_C_DP<15> B_PERN0 @T6G_MB_LIB.T6G(SCH_1):P5E_CPU1_P0_TX_C_DP(15)
 Y34 P5E_CPU1_P0_TX_C_DN<14> B_PERP1 @T6G_MB_LIB.T6G(SCH_1):P5E_CPU1_P0_TX_C_DN(14)
AB35 P5E_CPU1_P0_TX_C_DP<14> B_PERN1 @T6G_MB_LIB.T6G(SCH_1):P5E_CPU1_P0_TX_C_DP(14)
AG34 P5E_CPU1_P0_TX_C_DP<13> B_PERP2 @T6G_MB_LIB.T6G(SCH_1):P5E_CPU1_P0_TX_C_DP(13)
AJ35 P5E_CPU1_P0_TX_C_DN<13> B_PERN2 @T6G_MB_LIB.T6G(SCH_1):P5E_CPU1_P0_TX_C_DN(13)
AP34 P5E_CPU1_P0_TX_C_DN<12> B_PERP3 @T6G_MB_LIB.T6G(SCH_1):P5E_CPU1_P0_TX_C_DN(12)
AT35 P5E_CPU1_P0_TX_C_DP<12> B_PERN3 @T6G_MB_LIB.T6G(SCH_1):P5E_CPU1_P0_TX_C_DP(12)
BA34 P5E_CPU1_P0_TX_C_DN<11> B_PERP4 @T6G_MB_LIB.T6G(SCH_1):P5E_CPU1_P0_TX_C_DN(11)
BC35 P5E_CPU1_P0_TX_C_DP<11> B_PERN4 @T6G_MB_LIB.T6G(SCH_1):P5E_CPU1_P0_TX_C_DP(11)
BH34 P5E_CPU1_P0_TX_C_DN<10> B_PERP5 @T6G_MB_LIB.T6G(SCH_1):P5E_CPU1_P0_TX_C_DN(10)
BK35 P5E_CPU1_P0_TX_C_DP<10> B_PERN5 @T6G_MB_LIB.T6G(SCH_1):P5E_CPU1_P0_TX_C_DP(10)
BR34 P5E_CPU1_P0_TX_C_DN<9> B_PERP6 @T6G_MB_LIB.T6G(SCH_1):P5E_CPU1_P0_TX_C_DN(9)
BU35 P5E_CPU1_P0_TX_C_DP<9> B_PERN6 @T6G_MB_LIB.T6G(SCH_1):P5E_CPU1_P0_TX_C_DP(9)
CB34 P5E_CPU1_P0_TX_C_DN<8> B_PERP7 @T6G_MB_LIB.T6G(SCH_1):P5E_CPU1_P0_TX_C_DN(8)
CD35 P5E_CPU1_P0_TX_C_DP<8> B_PERN7 @T6G_MB_LIB.T6G(SCH_1):P5E_CPU1_P0_TX_C_DP(8)

PT5161LRS-PT5161LRS,SMLF,IC,AJ051610U03  I38  U6014
CJ34 P5E_CPU1_P0_TX_C_DN<7> B_PERP8 @T6G_MB_LIB.T6G(SCH_1):P5E_CPU1_P0_TX_C_DN(7)
CL35 P5E_CPU1_P0_TX_C_DP<7> B_PERN8 @T6G_MB_LIB.T6G(SCH_1):P5E_CPU1_P0_TX_C_DP(7)
CT34 P5E_CPU1_P0_TX_C_DN<6> B_PERP9 @T6G_MB_LIB.T6G(SCH_1):P5E_CPU1_P0_TX_C_DN(6)
CV35 P5E_CPU1_P0_TX_C_DP<6> B_PERN9 @T6G_MB_LIB.T6G(SCH_1):P5E_CPU1_P0_TX_C_DP(6)
DC34 P5E_CPU1_P0_TX_C_DN<5> B_PERP10 @T6G_MB_LIB.T6G(SCH_1):P5E_CPU1_P0_TX_C_DN(5)
DE35 P5E_CPU1_P0_TX_C_DP<5> B_PERN10 @T6G_MB_LIB.T6G(SCH_1):P5E_CPU1_P0_TX_C_DP(5)
DK34 P5E_CPU1_P0_TX_C_DN<4> B_PERP11 @T6G_MB_LIB.T6G(SCH_1):P5E_CPU1_P0_TX_C_DN(4)
DM35 P5E_CPU1_P0_TX_C_DP<4> B_PERN11 @T6G_MB_LIB.T6G(SCH_1):P5E_CPU1_P0_TX_C_DP(4)
DU34 P5E_CPU1_P0_TX_C_DN<3> B_PERP12 @T6G_MB_LIB.T6G(SCH_1):P5E_CPU1_P0_TX_C_DN(3)
DW35 P5E_CPU1_P0_TX_C_DP<3> B_PERN12 @T6G_MB_LIB.T6G(SCH_1):P5E_CPU1_P0_TX_C_DP(3)
ED34 P5E_CPU1_P0_TX_C_DN<2> B_PERP13 @T6G_MB_LIB.T6G(SCH_1):P5E_CPU1_P0_TX_C_DN(2)
EF35 P5E_CPU1_P0_TX_C_DP<2> B_PERN13 @T6G_MB_LIB.T6G(SCH_1):P5E_CPU1_P0_TX_C_DP(2)
EL34 P5E_CPU1_P0_TX_C_DP<1> B_PERP14 @T6G_MB_LIB.T6G(SCH_1):P5E_CPU1_P0_TX_C_DP(1)
EN35 P5E_CPU1_P0_TX_C_DN<1> B_PERN14 @T6G_MB_LIB.T6G(SCH_1):P5E_CPU1_P0_TX_C_DN(1)
EV34 P5E_CPU1_P0_TX_C_DN<0> B_PERP15 @T6G_MB_LIB.T6G(SCH_1):P5E_CPU1_P0_TX_C_DN(0)
EY35 P5E_CPU1_P0_TX_C_DP<0> B_PERN15 @T6G_MB_LIB.T6G(SCH_1):P5E_CPU1_P0_TX_C_DP(0)


DRAWING: @T6G_MB_LIB.T6G(SCH_1):PAGE438 

PT5161LRS-PT5161LRS,SMLF,IC,AJ051610U03  I1  U6014
 M26 P5E_CPU1_P0_RX_DP<15> A_PETP0 @T6G_MB_LIB.T6G(SCH_1):P5E_CPU1_P0_RX_DP(15)
 P29 P5E_CPU1_P0_RX_DN<15> A_PETN0 @T6G_MB_LIB.T6G(SCH_1):P5E_CPU1_P0_RX_DN(15)
 W26 P5E_CPU1_P0_RX_DP<14> A_PETP1 @T6G_MB_LIB.T6G(SCH_1):P5E_CPU1_P0_RX_DP(14)
AA29 P5E_CPU1_P0_RX_DN<14> A_PETN1 @T6G_MB_LIB.T6G(SCH_1):P5E_CPU1_P0_RX_DN(14)
AF26 P5E_CPU1_P0_RX_DP<13> A_PETP2 @T6G_MB_LIB.T6G(SCH_1):P5E_CPU1_P0_RX_DP(13)
AH29 P5E_CPU1_P0_RX_DN<13> A_PETN2 @T6G_MB_LIB.T6G(SCH_1):P5E_CPU1_P0_RX_DN(13)
AN26 P5E_CPU1_P0_RX_DP<12> A_PETP3 @T6G_MB_LIB.T6G(SCH_1):P5E_CPU1_P0_RX_DP(12)
AR29 P5E_CPU1_P0_RX_DN<12> A_PETN3 @T6G_MB_LIB.T6G(SCH_1):P5E_CPU1_P0_RX_DN(12)
AY26 P5E_CPU1_P0_RX_DP<11> A_PETP4 @T6G_MB_LIB.T6G(SCH_1):P5E_CPU1_P0_RX_DP(11)
BB29 P5E_CPU1_P0_RX_DN<11> A_PETN4 @T6G_MB_LIB.T6G(SCH_1):P5E_CPU1_P0_RX_DN(11)
BG26 P5E_CPU1_P0_RX_DP<10> A_PETP5 @T6G_MB_LIB.T6G(SCH_1):P5E_CPU1_P0_RX_DP(10)
BJ29 P5E_CPU1_P0_RX_DN<10> A_PETN5 @T6G_MB_LIB.T6G(SCH_1):P5E_CPU1_P0_RX_DN(10)
BP26 P5E_CPU1_P0_RX_DP<9> A_PETP6 @T6G_MB_LIB.T6G(SCH_1):P5E_CPU1_P0_RX_DP(9)
BT29 P5E_CPU1_P0_RX_DN<9> A_PETN6 @T6G_MB_LIB.T6G(SCH_1):P5E_CPU1_P0_RX_DN(9)
CA26 P5E_CPU1_P0_RX_DP<8> A_PETP7 @T6G_MB_LIB.T6G(SCH_1):P5E_CPU1_P0_RX_DP(8)
CC29 P5E_CPU1_P0_RX_DN<8> A_PETN7 @T6G_MB_LIB.T6G(SCH_1):P5E_CPU1_P0_RX_DN(8)

PT5161LRS-PT5161LRS,SMLF,IC,AJ051610U03  I38  U6014
CH26 P5E_CPU1_P0_RX_DP<7> A_PETP8 @T6G_MB_LIB.T6G(SCH_1):P5E_CPU1_P0_RX_DP(7)
CK29 P5E_CPU1_P0_RX_DN<7> A_PETN8 @T6G_MB_LIB.T6G(SCH_1):P5E_CPU1_P0_RX_DN(7)
CR26 P5E_CPU1_P0_RX_DP<6> A_PETP9 @T6G_MB_LIB.T6G(SCH_1):P5E_CPU1_P0_RX_DP(6)
CU29 P5E_CPU1_P0_RX_DN<6> A_PETN9 @T6G_MB_LIB.T6G(SCH_1):P5E_CPU1_P0_RX_DN(6)
DB26 P5E_CPU1_P0_RX_DP<5> A_PETP10 @T6G_MB_LIB.T6G(SCH_1):P5E_CPU1_P0_RX_DP(5)
DD29 P5E_CPU1_P0_RX_DN<5> A_PETN10 @T6G_MB_LIB.T6G(SCH_1):P5E_CPU1_P0_RX_DN(5)
DJ26 P5E_CPU1_P0_RX_DP<4> A_PETP11 @T6G_MB_LIB.T6G(SCH_1):P5E_CPU1_P0_RX_DP(4)
DL29 P5E_CPU1_P0_RX_DN<4> A_PETN11 @T6G_MB_LIB.T6G(SCH_1):P5E_CPU1_P0_RX_DN(4)
DT26 P5E_CPU1_P0_RX_DP<3> A_PETP12 @T6G_MB_LIB.T6G(SCH_1):P5E_CPU1_P0_RX_DP(3)
DV29 P5E_CPU1_P0_RX_DN<3> A_PETN12 @T6G_MB_LIB.T6G(SCH_1):P5E_CPU1_P0_RX_DN(3)
EC26 P5E_CPU1_P0_RX_DP<2> A_PETP13 @T6G_MB_LIB.T6G(SCH_1):P5E_CPU1_P0_RX_DP(2)
EE29 P5E_CPU1_P0_RX_DN<2> A_PETN13 @T6G_MB_LIB.T6G(SCH_1):P5E_CPU1_P0_RX_DN(2)
EK26 P5E_CPU1_P0_RX_DP<1> A_PETP14 @T6G_MB_LIB.T6G(SCH_1):P5E_CPU1_P0_RX_DP(1)
EM29 P5E_CPU1_P0_RX_DN<1> A_PETN14 @T6G_MB_LIB.T6G(SCH_1):P5E_CPU1_P0_RX_DN(1)
EU26 P5E_CPU1_P0_RX_DP<0> A_PETP15 @T6G_MB_LIB.T6G(SCH_1):P5E_CPU1_P0_RX_DP(0)
EW29 P5E_CPU1_P0_RX_DN<0> A_PETN15 @T6G_MB_LIB.T6G(SCH_1):P5E_CPU1_P0_RX_DN(0)


DRAWING: @T6G_MB_LIB.T6G(SCH_1):PAGE439 

Q_CAP_DIFFBUS_C0201-DIFF BUS_0.22UF,6.3V,20%,X6S,SA  I15  C6644
   1 P5E_CPU1_P0_TX_BUF_C_DN<7>      1 @T6G_MB_LIB.T6G(SCH_1):P5E_CPU1_P0_TX_BUF_C_DN(7)
   2 P5E_CPU1_P0_TX_BUF_DN<7>      2 @T6G_MB_LIB.T6G(SCH_1):P5E_CPU1_P0_TX_BUF_DN(7)

Q_CAP_DIFFBUS_C0201-DIFF BUS_0.22UF,6.3V,20%,X6S,SA  I16  C6643
   1 P5E_CPU1_P0_TX_BUF_C_DP<7>      1 @T6G_MB_LIB.T6G(SCH_1):P5E_CPU1_P0_TX_BUF_C_DP(7)
   2 P5E_CPU1_P0_TX_BUF_DP<7>      2 @T6G_MB_LIB.T6G(SCH_1):P5E_CPU1_P0_TX_BUF_DP(7)

Q_CAP_DIFFBUS_C0201-DIFF BUS_0.22UF,6.3V,20%,X6S,SA  I18  C6641
   1 P5E_CPU1_P0_TX_BUF_C_DP<6>      1 @T6G_MB_LIB.T6G(SCH_1):P5E_CPU1_P0_TX_BUF_C_DP(6)
   2 P5E_CPU1_P0_TX_BUF_DP<6>      2 @T6G_MB_LIB.T6G(SCH_1):P5E_CPU1_P0_TX_BUF_DP(6)

Q_CAP_DIFFBUS_C0201-DIFF BUS_0.22UF,6.3V,20%,X6S,SA  I19  C6642
   1 P5E_CPU1_P0_TX_BUF_C_DN<6>      1 @T6G_MB_LIB.T6G(SCH_1):P5E_CPU1_P0_TX_BUF_C_DN(6)
   2 P5E_CPU1_P0_TX_BUF_DN<6>      2 @T6G_MB_LIB.T6G(SCH_1):P5E_CPU1_P0_TX_BUF_DN(6)

Q_CAP_DIFFBUS_C0201-DIFF BUS_0.22UF,6.3V,20%,X6S,SA  I20  C6639
   1 P5E_CPU1_P0_TX_BUF_C_DP<5>      1 @T6G_MB_LIB.T6G(SCH_1):P5E_CPU1_P0_TX_BUF_C_DP(5)
   2 P5E_CPU1_P0_TX_BUF_DP<5>      2 @T6G_MB_LIB.T6G(SCH_1):P5E_CPU1_P0_TX_BUF_DP(5)

Q_CAP_DIFFBUS_C0201-DIFF BUS_0.22UF,6.3V,20%,X6S,SA  I21  C6640
   1 P5E_CPU1_P0_TX_BUF_C_DN<5>      1 @T6G_MB_LIB.T6G(SCH_1):P5E_CPU1_P0_TX_BUF_C_DN(5)
   2 P5E_CPU1_P0_TX_BUF_DN<5>      2 @T6G_MB_LIB.T6G(SCH_1):P5E_CPU1_P0_TX_BUF_DN(5)

Q_CAP_DIFFBUS_C0201-DIFF BUS_0.22UF,6.3V,20%,X6S,SA  I22  C6637
   1 P5E_CPU1_P0_TX_BUF_C_DP<4>      1 @T6G_MB_LIB.T6G(SCH_1):P5E_CPU1_P0_TX_BUF_C_DP(4)
   2 P5E_CPU1_P0_TX_BUF_DP<4>      2 @T6G_MB_LIB.T6G(SCH_1):P5E_CPU1_P0_TX_BUF_DP(4)

Q_CAP_DIFFBUS_C0201-DIFF BUS_0.22UF,6.3V,20%,X6S,SA  I23  C6638
   1 P5E_CPU1_P0_TX_BUF_C_DN<4>      1 @T6G_MB_LIB.T6G(SCH_1):P5E_CPU1_P0_TX_BUF_C_DN(4)
   2 P5E_CPU1_P0_TX_BUF_DN<4>      2 @T6G_MB_LIB.T6G(SCH_1):P5E_CPU1_P0_TX_BUF_DN(4)

Q_CAP_DIFFBUS_C0201-DIFF BUS_0.22UF,6.3V,20%,X6S,SA  I24  C6636
   1 P5E_CPU1_P0_TX_BUF_C_DN<3>      1 @T6G_MB_LIB.T6G(SCH_1):P5E_CPU1_P0_TX_BUF_C_DN(3)
   2 P5E_CPU1_P0_TX_BUF_DN<3>      2 @T6G_MB_LIB.T6G(SCH_1):P5E_CPU1_P0_TX_BUF_DN(3)

Q_CAP_DIFFBUS_C0201-DIFF BUS_0.22UF,6.3V,20%,X6S,SA  I25  C6635
   1 P5E_CPU1_P0_TX_BUF_C_DP<3>      1 @T6G_MB_LIB.T6G(SCH_1):P5E_CPU1_P0_TX_BUF_C_DP(3)
   2 P5E_CPU1_P0_TX_BUF_DP<3>      2 @T6G_MB_LIB.T6G(SCH_1):P5E_CPU1_P0_TX_BUF_DP(3)

Q_CAP_DIFFBUS_C0201-DIFF BUS_0.22UF,6.3V,20%,X6S,SA  I26  C6634
   1 P5E_CPU1_P0_TX_BUF_C_DN<2>      1 @T6G_MB_LIB.T6G(SCH_1):P5E_CPU1_P0_TX_BUF_C_DN(2)
   2 P5E_CPU1_P0_TX_BUF_DN<2>      2 @T6G_MB_LIB.T6G(SCH_1):P5E_CPU1_P0_TX_BUF_DN(2)

Q_CAP_DIFFBUS_C0201-DIFF BUS_0.22UF,6.3V,20%,X6S,SA  I27  C6633
   1 P5E_CPU1_P0_TX_BUF_C_DP<2>      1 @T6G_MB_LIB.T6G(SCH_1):P5E_CPU1_P0_TX_BUF_C_DP(2)
   2 P5E_CPU1_P0_TX_BUF_DP<2>      2 @T6G_MB_LIB.T6G(SCH_1):P5E_CPU1_P0_TX_BUF_DP(2)

PT5161LRS-PT5161LRS,SMLF,IC,AJ051610U03  I43  U6014
  M7 P5E_CPU1_P0_TX_BUF_DP<15> B_PETP0 @T6G_MB_LIB.T6G(SCH_1):P5E_CPU1_P0_TX_BUF_DP(15)
 P10 P5E_CPU1_P0_TX_BUF_DN<15> B_PETN0 @T6G_MB_LIB.T6G(SCH_1):P5E_CPU1_P0_TX_BUF_DN(15)
  W7 P5E_CPU1_P0_TX_BUF_DP<14> B_PETP1 @T6G_MB_LIB.T6G(SCH_1):P5E_CPU1_P0_TX_BUF_DP(14)
AA10 P5E_CPU1_P0_TX_BUF_DN<14> B_PETN1 @T6G_MB_LIB.T6G(SCH_1):P5E_CPU1_P0_TX_BUF_DN(14)
 AF7 P5E_CPU1_P0_TX_BUF_DP<13> B_PETP2 @T6G_MB_LIB.T6G(SCH_1):P5E_CPU1_P0_TX_BUF_DP(13)
AH10 P5E_CPU1_P0_TX_BUF_DN<13> B_PETN2 @T6G_MB_LIB.T6G(SCH_1):P5E_CPU1_P0_TX_BUF_DN(13)
 AN7 P5E_CPU1_P0_TX_BUF_DP<12> B_PETP3 @T6G_MB_LIB.T6G(SCH_1):P5E_CPU1_P0_TX_BUF_DP(12)
AR10 P5E_CPU1_P0_TX_BUF_DN<12> B_PETN3 @T6G_MB_LIB.T6G(SCH_1):P5E_CPU1_P0_TX_BUF_DN(12)
 AY7 P5E_CPU1_P0_TX_BUF_DP<11> B_PETP4 @T6G_MB_LIB.T6G(SCH_1):P5E_CPU1_P0_TX_BUF_DP(11)
BB10 P5E_CPU1_P0_TX_BUF_DN<11> B_PETN4 @T6G_MB_LIB.T6G(SCH_1):P5E_CPU1_P0_TX_BUF_DN(11)
 BG7 P5E_CPU1_P0_TX_BUF_DP<10> B_PETP5 @T6G_MB_LIB.T6G(SCH_1):P5E_CPU1_P0_TX_BUF_DP(10)
BJ10 P5E_CPU1_P0_TX_BUF_DN<10> B_PETN5 @T6G_MB_LIB.T6G(SCH_1):P5E_CPU1_P0_TX_BUF_DN(10)
 BP7 P5E_CPU1_P0_TX_BUF_DP<9> B_PETP6 @T6G_MB_LIB.T6G(SCH_1):P5E_CPU1_P0_TX_BUF_DP(9)
BT10 P5E_CPU1_P0_TX_BUF_DN<9> B_PETN6 @T6G_MB_LIB.T6G(SCH_1):P5E_CPU1_P0_TX_BUF_DN(9)
 CA7 P5E_CPU1_P0_TX_BUF_DP<8> B_PETP7 @T6G_MB_LIB.T6G(SCH_1):P5E_CPU1_P0_TX_BUF_DP(8)
CC10 P5E_CPU1_P0_TX_BUF_DN<8> B_PETN7 @T6G_MB_LIB.T6G(SCH_1):P5E_CPU1_P0_TX_BUF_DN(8)

Q_CAP_DIFFBUS_C0201-DIFF BUS_0.22UF,6.3V,20%,X6S,SA  I44  C6632
   1 P5E_CPU1_P0_TX_BUF_C_DN<1>      1 @T6G_MB_LIB.T6G(SCH_1):P5E_CPU1_P0_TX_BUF_C_DN(1)
   2 P5E_CPU1_P0_TX_BUF_DN<1>      2 @T6G_MB_LIB.T6G(SCH_1):P5E_CPU1_P0_TX_BUF_DN(1)

Q_CAP_DIFFBUS_C0201-DIFF BUS_0.22UF,6.3V,20%,X6S,SA  I45  C6631
   1 P5E_CPU1_P0_TX_BUF_C_DP<1>      1 @T6G_MB_LIB.T6G(SCH_1):P5E_CPU1_P0_TX_BUF_C_DP(1)
   2 P5E_CPU1_P0_TX_BUF_DP<1>      2 @T6G_MB_LIB.T6G(SCH_1):P5E_CPU1_P0_TX_BUF_DP(1)

Q_CAP_DIFFBUS_C0201-DIFF BUS_0.22UF,6.3V,20%,X6S,SA  I46  C6629
   1 P5E_CPU1_P0_TX_BUF_C_DP<0>      1 @T6G_MB_LIB.T6G(SCH_1):P5E_CPU1_P0_TX_BUF_C_DP(0)
   2 P5E_CPU1_P0_TX_BUF_DP<0>      2 @T6G_MB_LIB.T6G(SCH_1):P5E_CPU1_P0_TX_BUF_DP(0)

Q_CAP_DIFFBUS_C0201-DIFF BUS_0.22UF,6.3V,20%,X6S,SA  I47  C6630
   1 P5E_CPU1_P0_TX_BUF_C_DN<0>      1 @T6G_MB_LIB.T6G(SCH_1):P5E_CPU1_P0_TX_BUF_C_DN(0)
   2 P5E_CPU1_P0_TX_BUF_DN<0>      2 @T6G_MB_LIB.T6G(SCH_1):P5E_CPU1_P0_TX_BUF_DN(0)

Q_CAP_DIFFBUS_C0201-DIFF BUS_0.22UF,6.3V,20%,X6S,SA  I86  C6660
   1 P5E_CPU1_P0_TX_BUF_C_DN<15>      1 @T6G_MB_LIB.T6G(SCH_1):P5E_CPU1_P0_TX_BUF_C_DN(15)
   2 P5E_CPU1_P0_TX_BUF_DN<15>      2 @T6G_MB_LIB.T6G(SCH_1):P5E_CPU1_P0_TX_BUF_DN(15)

Q_CAP_DIFFBUS_C0201-DIFF BUS_0.22UF,6.3V,20%,X6S,SA  I87  C6659
   1 P5E_CPU1_P0_TX_BUF_C_DP<15>      1 @T6G_MB_LIB.T6G(SCH_1):P5E_CPU1_P0_TX_BUF_C_DP(15)
   2 P5E_CPU1_P0_TX_BUF_DP<15>      2 @T6G_MB_LIB.T6G(SCH_1):P5E_CPU1_P0_TX_BUF_DP(15)

Q_CAP_DIFFBUS_C0201-DIFF BUS_0.22UF,6.3V,20%,X6S,SA  I88  C6658
   1 P5E_CPU1_P0_TX_BUF_C_DN<14>      1 @T6G_MB_LIB.T6G(SCH_1):P5E_CPU1_P0_TX_BUF_C_DN(14)
   2 P5E_CPU1_P0_TX_BUF_DN<14>      2 @T6G_MB_LIB.T6G(SCH_1):P5E_CPU1_P0_TX_BUF_DN(14)

Q_CAP_DIFFBUS_C0201-DIFF BUS_0.22UF,6.3V,20%,X6S,SA  I89  C6657
   1 P5E_CPU1_P0_TX_BUF_C_DP<14>      1 @T6G_MB_LIB.T6G(SCH_1):P5E_CPU1_P0_TX_BUF_C_DP(14)
   2 P5E_CPU1_P0_TX_BUF_DP<14>      2 @T6G_MB_LIB.T6G(SCH_1):P5E_CPU1_P0_TX_BUF_DP(14)

Q_CAP_DIFFBUS_C0201-DIFF BUS_0.22UF,6.3V,20%,X6S,SA  I90  C6656
   1 P5E_CPU1_P0_TX_BUF_C_DN<13>      1 @T6G_MB_LIB.T6G(SCH_1):P5E_CPU1_P0_TX_BUF_C_DN(13)
   2 P5E_CPU1_P0_TX_BUF_DN<13>      2 @T6G_MB_LIB.T6G(SCH_1):P5E_CPU1_P0_TX_BUF_DN(13)

Q_CAP_DIFFBUS_C0201-DIFF BUS_0.22UF,6.3V,20%,X6S,SA  I91  C6655
   1 P5E_CPU1_P0_TX_BUF_C_DP<13>      1 @T6G_MB_LIB.T6G(SCH_1):P5E_CPU1_P0_TX_BUF_C_DP(13)
   2 P5E_CPU1_P0_TX_BUF_DP<13>      2 @T6G_MB_LIB.T6G(SCH_1):P5E_CPU1_P0_TX_BUF_DP(13)

Q_CAP_DIFFBUS_C0201-DIFF BUS_0.22UF,6.3V,20%,X6S,SA  I92  C6654
   1 P5E_CPU1_P0_TX_BUF_C_DN<12>      1 @T6G_MB_LIB.T6G(SCH_1):P5E_CPU1_P0_TX_BUF_C_DN(12)
   2 P5E_CPU1_P0_TX_BUF_DN<12>      2 @T6G_MB_LIB.T6G(SCH_1):P5E_CPU1_P0_TX_BUF_DN(12)

Q_CAP_DIFFBUS_C0201-DIFF BUS_0.22UF,6.3V,20%,X6S,SA  I93  C6653
   1 P5E_CPU1_P0_TX_BUF_C_DP<12>      1 @T6G_MB_LIB.T6G(SCH_1):P5E_CPU1_P0_TX_BUF_C_DP(12)
   2 P5E_CPU1_P0_TX_BUF_DP<12>      2 @T6G_MB_LIB.T6G(SCH_1):P5E_CPU1_P0_TX_BUF_DP(12)

Q_CAP_DIFFBUS_C0201-DIFF BUS_0.22UF,6.3V,20%,X6S,SA  I94  C6652
   1 P5E_CPU1_P0_TX_BUF_C_DN<11>      1 @T6G_MB_LIB.T6G(SCH_1):P5E_CPU1_P0_TX_BUF_C_DN(11)
   2 P5E_CPU1_P0_TX_BUF_DN<11>      2 @T6G_MB_LIB.T6G(SCH_1):P5E_CPU1_P0_TX_BUF_DN(11)

Q_CAP_DIFFBUS_C0201-DIFF BUS_0.22UF,6.3V,20%,X6S,SA  I95  C6651
   1 P5E_CPU1_P0_TX_BUF_C_DP<11>      1 @T6G_MB_LIB.T6G(SCH_1):P5E_CPU1_P0_TX_BUF_C_DP(11)
   2 P5E_CPU1_P0_TX_BUF_DP<11>      2 @T6G_MB_LIB.T6G(SCH_1):P5E_CPU1_P0_TX_BUF_DP(11)

Q_CAP_DIFFBUS_C0201-DIFF BUS_0.22UF,6.3V,20%,X6S,SA  I96  C6649
   1 P5E_CPU1_P0_TX_BUF_C_DP<10>      1 @T6G_MB_LIB.T6G(SCH_1):P5E_CPU1_P0_TX_BUF_C_DP(10)
   2 P5E_CPU1_P0_TX_BUF_DP<10>      2 @T6G_MB_LIB.T6G(SCH_1):P5E_CPU1_P0_TX_BUF_DP(10)

Q_CAP_DIFFBUS_C0201-DIFF BUS_0.22UF,6.3V,20%,X6S,SA  I97  C6650
   1 P5E_CPU1_P0_TX_BUF_C_DN<10>      1 @T6G_MB_LIB.T6G(SCH_1):P5E_CPU1_P0_TX_BUF_C_DN(10)
   2 P5E_CPU1_P0_TX_BUF_DN<10>      2 @T6G_MB_LIB.T6G(SCH_1):P5E_CPU1_P0_TX_BUF_DN(10)

Q_CAP_DIFFBUS_C0201-DIFF BUS_0.22UF,6.3V,20%,X6S,SA  I102  C6647
   1 P5E_CPU1_P0_TX_BUF_C_DP<9>      1 @T6G_MB_LIB.T6G(SCH_1):P5E_CPU1_P0_TX_BUF_C_DP(9)
   2 P5E_CPU1_P0_TX_BUF_DP<9>      2 @T6G_MB_LIB.T6G(SCH_1):P5E_CPU1_P0_TX_BUF_DP(9)

Q_CAP_DIFFBUS_C0201-DIFF BUS_0.22UF,6.3V,20%,X6S,SA  I103  C6648
   1 P5E_CPU1_P0_TX_BUF_C_DN<9>      1 @T6G_MB_LIB.T6G(SCH_1):P5E_CPU1_P0_TX_BUF_C_DN(9)
   2 P5E_CPU1_P0_TX_BUF_DN<9>      2 @T6G_MB_LIB.T6G(SCH_1):P5E_CPU1_P0_TX_BUF_DN(9)

Q_CAP_DIFFBUS_C0201-DIFF BUS_0.22UF,6.3V,20%,X6S,SA  I104  C6646
   1 P5E_CPU1_P0_TX_BUF_C_DN<8>      1 @T6G_MB_LIB.T6G(SCH_1):P5E_CPU1_P0_TX_BUF_C_DN(8)
   2 P5E_CPU1_P0_TX_BUF_DN<8>      2 @T6G_MB_LIB.T6G(SCH_1):P5E_CPU1_P0_TX_BUF_DN(8)

Q_CAP_DIFFBUS_C0201-DIFF BUS_0.22UF,6.3V,20%,X6S,SA  I105  C6645
   1 P5E_CPU1_P0_TX_BUF_C_DP<8>      1 @T6G_MB_LIB.T6G(SCH_1):P5E_CPU1_P0_TX_BUF_C_DP(8)
   2 P5E_CPU1_P0_TX_BUF_DP<8>      2 @T6G_MB_LIB.T6G(SCH_1):P5E_CPU1_P0_TX_BUF_DP(8)

PT5161LRS-PT5161LRS,SMLF,IC,AJ051610U03  I142  U6014
 CH7 P5E_CPU1_P0_TX_BUF_DP<7> B_PETP8 @T6G_MB_LIB.T6G(SCH_1):P5E_CPU1_P0_TX_BUF_DP(7)
CK10 P5E_CPU1_P0_TX_BUF_DN<7> B_PETN8 @T6G_MB_LIB.T6G(SCH_1):P5E_CPU1_P0_TX_BUF_DN(7)
 CR7 P5E_CPU1_P0_TX_BUF_DP<6> B_PETP9 @T6G_MB_LIB.T6G(SCH_1):P5E_CPU1_P0_TX_BUF_DP(6)
CU10 P5E_CPU1_P0_TX_BUF_DN<6> B_PETN9 @T6G_MB_LIB.T6G(SCH_1):P5E_CPU1_P0_TX_BUF_DN(6)
 DB7 P5E_CPU1_P0_TX_BUF_DP<5> B_PETP10 @T6G_MB_LIB.T6G(SCH_1):P5E_CPU1_P0_TX_BUF_DP(5)
DD10 P5E_CPU1_P0_TX_BUF_DN<5> B_PETN10 @T6G_MB_LIB.T6G(SCH_1):P5E_CPU1_P0_TX_BUF_DN(5)
 DJ7 P5E_CPU1_P0_TX_BUF_DP<4> B_PETP11 @T6G_MB_LIB.T6G(SCH_1):P5E_CPU1_P0_TX_BUF_DP(4)
DL10 P5E_CPU1_P0_TX_BUF_DN<4> B_PETN11 @T6G_MB_LIB.T6G(SCH_1):P5E_CPU1_P0_TX_BUF_DN(4)
 DT7 P5E_CPU1_P0_TX_BUF_DP<3> B_PETP12 @T6G_MB_LIB.T6G(SCH_1):P5E_CPU1_P0_TX_BUF_DP(3)
DV10 P5E_CPU1_P0_TX_BUF_DN<3> B_PETN12 @T6G_MB_LIB.T6G(SCH_1):P5E_CPU1_P0_TX_BUF_DN(3)
 EC7 P5E_CPU1_P0_TX_BUF_DP<2> B_PETP13 @T6G_MB_LIB.T6G(SCH_1):P5E_CPU1_P0_TX_BUF_DP(2)
EE10 P5E_CPU1_P0_TX_BUF_DN<2> B_PETN13 @T6G_MB_LIB.T6G(SCH_1):P5E_CPU1_P0_TX_BUF_DN(2)
 EK7 P5E_CPU1_P0_TX_BUF_DP<1> B_PETP14 @T6G_MB_LIB.T6G(SCH_1):P5E_CPU1_P0_TX_BUF_DP(1)
EM10 P5E_CPU1_P0_TX_BUF_DN<1> B_PETN14 @T6G_MB_LIB.T6G(SCH_1):P5E_CPU1_P0_TX_BUF_DN(1)
 EU7 P5E_CPU1_P0_TX_BUF_DP<0> B_PETP15 @T6G_MB_LIB.T6G(SCH_1):P5E_CPU1_P0_TX_BUF_DP(0)
EW10 P5E_CPU1_P0_TX_BUF_DN<0> B_PETN15 @T6G_MB_LIB.T6G(SCH_1):P5E_CPU1_P0_TX_BUF_DN(0)


DRAWING: @T6G_MB_LIB.T6G(SCH_1):PAGE447 

PT5161LRS-PT5161LRS,SMLF,IC,AJ051610U03  I1  U6016
 N34 P5E_CPU1_P2_TX_C_DN<15> B_PERP0 @T6G_MB_LIB.T6G(SCH_1):P5E_CPU1_P2_TX_C_DN(15)
 R35 P5E_CPU1_P2_TX_C_DP<15> B_PERN0 @T6G_MB_LIB.T6G(SCH_1):P5E_CPU1_P2_TX_C_DP(15)
 Y34 P5E_CPU1_P2_TX_C_DN<14> B_PERP1 @T6G_MB_LIB.T6G(SCH_1):P5E_CPU1_P2_TX_C_DN(14)
AB35 P5E_CPU1_P2_TX_C_DP<14> B_PERN1 @T6G_MB_LIB.T6G(SCH_1):P5E_CPU1_P2_TX_C_DP(14)
AG34 P5E_CPU1_P2_TX_C_DN<13> B_PERP2 @T6G_MB_LIB.T6G(SCH_1):P5E_CPU1_P2_TX_C_DN(13)
AJ35 P5E_CPU1_P2_TX_C_DP<13> B_PERN2 @T6G_MB_LIB.T6G(SCH_1):P5E_CPU1_P2_TX_C_DP(13)
AP34 P5E_CPU1_P2_TX_C_DN<12> B_PERP3 @T6G_MB_LIB.T6G(SCH_1):P5E_CPU1_P2_TX_C_DN(12)
AT35 P5E_CPU1_P2_TX_C_DP<12> B_PERN3 @T6G_MB_LIB.T6G(SCH_1):P5E_CPU1_P2_TX_C_DP(12)
BA34 P5E_CPU1_P2_TX_C_DN<11> B_PERP4 @T6G_MB_LIB.T6G(SCH_1):P5E_CPU1_P2_TX_C_DN(11)
BC35 P5E_CPU1_P2_TX_C_DP<11> B_PERN4 @T6G_MB_LIB.T6G(SCH_1):P5E_CPU1_P2_TX_C_DP(11)
BH34 P5E_CPU1_P2_TX_C_DN<10> B_PERP5 @T6G_MB_LIB.T6G(SCH_1):P5E_CPU1_P2_TX_C_DN(10)
BK35 P5E_CPU1_P2_TX_C_DP<10> B_PERN5 @T6G_MB_LIB.T6G(SCH_1):P5E_CPU1_P2_TX_C_DP(10)
BR34 P5E_CPU1_P2_TX_C_DN<9> B_PERP6 @T6G_MB_LIB.T6G(SCH_1):P5E_CPU1_P2_TX_C_DN(9)
BU35 P5E_CPU1_P2_TX_C_DP<9> B_PERN6 @T6G_MB_LIB.T6G(SCH_1):P5E_CPU1_P2_TX_C_DP(9)
CB34 P5E_CPU1_P2_TX_C_DN<8> B_PERP7 @T6G_MB_LIB.T6G(SCH_1):P5E_CPU1_P2_TX_C_DN(8)
CD35 P5E_CPU1_P2_TX_C_DP<8> B_PERN7 @T6G_MB_LIB.T6G(SCH_1):P5E_CPU1_P2_TX_C_DP(8)

PT5161LRS-PT5161LRS,SMLF,IC,AJ051610U03  I38  U6016
CJ34 P5E_CPU1_P2_TX_C_DN<7> B_PERP8 @T6G_MB_LIB.T6G(SCH_1):P5E_CPU1_P2_TX_C_DN(7)
CL35 P5E_CPU1_P2_TX_C_DP<7> B_PERN8 @T6G_MB_LIB.T6G(SCH_1):P5E_CPU1_P2_TX_C_DP(7)
CT34 P5E_CPU1_P2_TX_C_DN<6> B_PERP9 @T6G_MB_LIB.T6G(SCH_1):P5E_CPU1_P2_TX_C_DN(6)
CV35 P5E_CPU1_P2_TX_C_DP<6> B_PERN9 @T6G_MB_LIB.T6G(SCH_1):P5E_CPU1_P2_TX_C_DP(6)
DC34 P5E_CPU1_P2_TX_C_DN<5> B_PERP10 @T6G_MB_LIB.T6G(SCH_1):P5E_CPU1_P2_TX_C_DN(5)
DE35 P5E_CPU1_P2_TX_C_DP<5> B_PERN10 @T6G_MB_LIB.T6G(SCH_1):P5E_CPU1_P2_TX_C_DP(5)
DK34 P5E_CPU1_P2_TX_C_DN<4> B_PERP11 @T6G_MB_LIB.T6G(SCH_1):P5E_CPU1_P2_TX_C_DN(4)
DM35 P5E_CPU1_P2_TX_C_DP<4> B_PERN11 @T6G_MB_LIB.T6G(SCH_1):P5E_CPU1_P2_TX_C_DP(4)
DU34 P5E_CPU1_P2_TX_C_DN<3> B_PERP12 @T6G_MB_LIB.T6G(SCH_1):P5E_CPU1_P2_TX_C_DN(3)
DW35 P5E_CPU1_P2_TX_C_DP<3> B_PERN12 @T6G_MB_LIB.T6G(SCH_1):P5E_CPU1_P2_TX_C_DP(3)
ED34 P5E_CPU1_P2_TX_C_DN<2> B_PERP13 @T6G_MB_LIB.T6G(SCH_1):P5E_CPU1_P2_TX_C_DN(2)
EF35 P5E_CPU1_P2_TX_C_DP<2> B_PERN13 @T6G_MB_LIB.T6G(SCH_1):P5E_CPU1_P2_TX_C_DP(2)
EL34 P5E_CPU1_P2_TX_C_DP<1> B_PERP14 @T6G_MB_LIB.T6G(SCH_1):P5E_CPU1_P2_TX_C_DP(1)
EN35 P5E_CPU1_P2_TX_C_DN<1> B_PERN14 @T6G_MB_LIB.T6G(SCH_1):P5E_CPU1_P2_TX_C_DN(1)
EV34 P5E_CPU1_P2_TX_C_DN<0> B_PERP15 @T6G_MB_LIB.T6G(SCH_1):P5E_CPU1_P2_TX_C_DN(0)
EY35 P5E_CPU1_P2_TX_C_DP<0> B_PERN15 @T6G_MB_LIB.T6G(SCH_1):P5E_CPU1_P2_TX_C_DP(0)


DRAWING: @T6G_MB_LIB.T6G(SCH_1):PAGE448 

PT5161LRS-PT5161LRS,SMLF,IC,AJ051610U03  I1  U6016
 M26 P5E_CPU1_P2_RX_DP<15> A_PETP0 @T6G_MB_LIB.T6G(SCH_1):P5E_CPU1_P2_RX_DP(15)
 P29 P5E_CPU1_P2_RX_DN<15> A_PETN0 @T6G_MB_LIB.T6G(SCH_1):P5E_CPU1_P2_RX_DN(15)
 W26 P5E_CPU1_P2_RX_DP<14> A_PETP1 @T6G_MB_LIB.T6G(SCH_1):P5E_CPU1_P2_RX_DP(14)
AA29 P5E_CPU1_P2_RX_DN<14> A_PETN1 @T6G_MB_LIB.T6G(SCH_1):P5E_CPU1_P2_RX_DN(14)
AF26 P5E_CPU1_P2_RX_DP<13> A_PETP2 @T6G_MB_LIB.T6G(SCH_1):P5E_CPU1_P2_RX_DP(13)
AH29 P5E_CPU1_P2_RX_DN<13> A_PETN2 @T6G_MB_LIB.T6G(SCH_1):P5E_CPU1_P2_RX_DN(13)
AN26 P5E_CPU1_P2_RX_DP<12> A_PETP3 @T6G_MB_LIB.T6G(SCH_1):P5E_CPU1_P2_RX_DP(12)
AR29 P5E_CPU1_P2_RX_DN<12> A_PETN3 @T6G_MB_LIB.T6G(SCH_1):P5E_CPU1_P2_RX_DN(12)
AY26 P5E_CPU1_P2_RX_DP<11> A_PETP4 @T6G_MB_LIB.T6G(SCH_1):P5E_CPU1_P2_RX_DP(11)
BB29 P5E_CPU1_P2_RX_DN<11> A_PETN4 @T6G_MB_LIB.T6G(SCH_1):P5E_CPU1_P2_RX_DN(11)
BG26 P5E_CPU1_P2_RX_DP<10> A_PETP5 @T6G_MB_LIB.T6G(SCH_1):P5E_CPU1_P2_RX_DP(10)
BJ29 P5E_CPU1_P2_RX_DN<10> A_PETN5 @T6G_MB_LIB.T6G(SCH_1):P5E_CPU1_P2_RX_DN(10)
BP26 P5E_CPU1_P2_RX_DP<9> A_PETP6 @T6G_MB_LIB.T6G(SCH_1):P5E_CPU1_P2_RX_DP(9)
BT29 P5E_CPU1_P2_RX_DN<9> A_PETN6 @T6G_MB_LIB.T6G(SCH_1):P5E_CPU1_P2_RX_DN(9)
CA26 P5E_CPU1_P2_RX_DP<8> A_PETP7 @T6G_MB_LIB.T6G(SCH_1):P5E_CPU1_P2_RX_DP(8)
CC29 P5E_CPU1_P2_RX_DN<8> A_PETN7 @T6G_MB_LIB.T6G(SCH_1):P5E_CPU1_P2_RX_DN(8)

PT5161LRS-PT5161LRS,SMLF,IC,AJ051610U03  I38  U6016
CH26 P5E_CPU1_P2_RX_DP<7> A_PETP8 @T6G_MB_LIB.T6G(SCH_1):P5E_CPU1_P2_RX_DP(7)
CK29 P5E_CPU1_P2_RX_DN<7> A_PETN8 @T6G_MB_LIB.T6G(SCH_1):P5E_CPU1_P2_RX_DN(7)
CR26 P5E_CPU1_P2_RX_DP<6> A_PETP9 @T6G_MB_LIB.T6G(SCH_1):P5E_CPU1_P2_RX_DP(6)
CU29 P5E_CPU1_P2_RX_DN<6> A_PETN9 @T6G_MB_LIB.T6G(SCH_1):P5E_CPU1_P2_RX_DN(6)
DB26 P5E_CPU1_P2_RX_DP<5> A_PETP10 @T6G_MB_LIB.T6G(SCH_1):P5E_CPU1_P2_RX_DP(5)
DD29 P5E_CPU1_P2_RX_DN<5> A_PETN10 @T6G_MB_LIB.T6G(SCH_1):P5E_CPU1_P2_RX_DN(5)
DJ26 P5E_CPU1_P2_RX_DP<4> A_PETP11 @T6G_MB_LIB.T6G(SCH_1):P5E_CPU1_P2_RX_DP(4)
DL29 P5E_CPU1_P2_RX_DN<4> A_PETN11 @T6G_MB_LIB.T6G(SCH_1):P5E_CPU1_P2_RX_DN(4)
DT26 P5E_CPU1_P2_RX_DP<3> A_PETP12 @T6G_MB_LIB.T6G(SCH_1):P5E_CPU1_P2_RX_DP(3)
DV29 P5E_CPU1_P2_RX_DN<3> A_PETN12 @T6G_MB_LIB.T6G(SCH_1):P5E_CPU1_P2_RX_DN(3)
EC26 P5E_CPU1_P2_RX_DP<2> A_PETP13 @T6G_MB_LIB.T6G(SCH_1):P5E_CPU1_P2_RX_DP(2)
EE29 P5E_CPU1_P2_RX_DN<2> A_PETN13 @T6G_MB_LIB.T6G(SCH_1):P5E_CPU1_P2_RX_DN(2)
EK26 P5E_CPU1_P2_RX_DP<1> A_PETP14 @T6G_MB_LIB.T6G(SCH_1):P5E_CPU1_P2_RX_DP(1)
EM29 P5E_CPU1_P2_RX_DN<1> A_PETN14 @T6G_MB_LIB.T6G(SCH_1):P5E_CPU1_P2_RX_DN(1)
EU26 P5E_CPU1_P2_RX_DP<0> A_PETP15 @T6G_MB_LIB.T6G(SCH_1):P5E_CPU1_P2_RX_DP(0)
EW29 P5E_CPU1_P2_RX_DN<0> A_PETN15 @T6G_MB_LIB.T6G(SCH_1):P5E_CPU1_P2_RX_DN(0)


DRAWING: @T6G_MB_LIB.T6G(SCH_1):PAGE449 

PT5161LRS-PT5161LRS,SMLF,IC,AJ051610U03  I1  U6016
  R1 P5E_CPU1_P2_RX_BUF_DP<15> A_PERP0 @T6G_MB_LIB.T6G(SCH_1):P5E_CPU1_P2_RX_BUF_DP(15)
  N2 P5E_CPU1_P2_RX_BUF_DN<15> A_PERN0 @T6G_MB_LIB.T6G(SCH_1):P5E_CPU1_P2_RX_BUF_DN(15)
 AB1 P5E_CPU1_P2_RX_BUF_DP<14> A_PERP1 @T6G_MB_LIB.T6G(SCH_1):P5E_CPU1_P2_RX_BUF_DP(14)
  Y2 P5E_CPU1_P2_RX_BUF_DN<14> A_PERN1 @T6G_MB_LIB.T6G(SCH_1):P5E_CPU1_P2_RX_BUF_DN(14)
 AJ1 P5E_CPU1_P2_RX_BUF_DP<13> A_PERP2 @T6G_MB_LIB.T6G(SCH_1):P5E_CPU1_P2_RX_BUF_DP(13)
 AG2 P5E_CPU1_P2_RX_BUF_DN<13> A_PERN2 @T6G_MB_LIB.T6G(SCH_1):P5E_CPU1_P2_RX_BUF_DN(13)
 AT1 P5E_CPU1_P2_RX_BUF_DP<12> A_PERP3 @T6G_MB_LIB.T6G(SCH_1):P5E_CPU1_P2_RX_BUF_DP(12)
 AP2 P5E_CPU1_P2_RX_BUF_DN<12> A_PERN3 @T6G_MB_LIB.T6G(SCH_1):P5E_CPU1_P2_RX_BUF_DN(12)
 BC1 P5E_CPU1_P2_RX_BUF_DP<11> A_PERP4 @T6G_MB_LIB.T6G(SCH_1):P5E_CPU1_P2_RX_BUF_DP(11)
 BA2 P5E_CPU1_P2_RX_BUF_DN<11> A_PERN4 @T6G_MB_LIB.T6G(SCH_1):P5E_CPU1_P2_RX_BUF_DN(11)
 BK1 P5E_CPU1_P2_RX_BUF_DP<10> A_PERP5 @T6G_MB_LIB.T6G(SCH_1):P5E_CPU1_P2_RX_BUF_DP(10)
 BH2 P5E_CPU1_P2_RX_BUF_DN<10> A_PERN5 @T6G_MB_LIB.T6G(SCH_1):P5E_CPU1_P2_RX_BUF_DN(10)
 BU1 P5E_CPU1_P2_RX_BUF_DP<9> A_PERP6 @T6G_MB_LIB.T6G(SCH_1):P5E_CPU1_P2_RX_BUF_DP(9)
 BR2 P5E_CPU1_P2_RX_BUF_DN<9> A_PERN6 @T6G_MB_LIB.T6G(SCH_1):P5E_CPU1_P2_RX_BUF_DN(9)
 CD1 P5E_CPU1_P2_RX_BUF_DP<8> A_PERP7 @T6G_MB_LIB.T6G(SCH_1):P5E_CPU1_P2_RX_BUF_DP(8)
 CB2 P5E_CPU1_P2_RX_BUF_DN<8> A_PERN7 @T6G_MB_LIB.T6G(SCH_1):P5E_CPU1_P2_RX_BUF_DN(8)

PT5161LRS-PT5161LRS,SMLF,IC,AJ051610U03  I38  U6016
 CL1 P5E_CPU1_P2_RX_BUF_DP<7> A_PERP8 @T6G_MB_LIB.T6G(SCH_1):P5E_CPU1_P2_RX_BUF_DP(7)
 CJ2 P5E_CPU1_P2_RX_BUF_DN<7> A_PERN8 @T6G_MB_LIB.T6G(SCH_1):P5E_CPU1_P2_RX_BUF_DN(7)
 CV1 P5E_CPU1_P2_RX_BUF_DP<6> A_PERP9 @T6G_MB_LIB.T6G(SCH_1):P5E_CPU1_P2_RX_BUF_DP(6)
 CT2 P5E_CPU1_P2_RX_BUF_DN<6> A_PERN9 @T6G_MB_LIB.T6G(SCH_1):P5E_CPU1_P2_RX_BUF_DN(6)
 DE1 P5E_CPU1_P2_RX_BUF_DP<5> A_PERP10 @T6G_MB_LIB.T6G(SCH_1):P5E_CPU1_P2_RX_BUF_DP(5)
 DC2 P5E_CPU1_P2_RX_BUF_DN<5> A_PERN10 @T6G_MB_LIB.T6G(SCH_1):P5E_CPU1_P2_RX_BUF_DN(5)
 DM1 P5E_CPU1_P2_RX_BUF_DP<4> A_PERP11 @T6G_MB_LIB.T6G(SCH_1):P5E_CPU1_P2_RX_BUF_DP(4)
 DK2 P5E_CPU1_P2_RX_BUF_DN<4> A_PERN11 @T6G_MB_LIB.T6G(SCH_1):P5E_CPU1_P2_RX_BUF_DN(4)
 DW1 P5E_CPU1_P2_RX_BUF_DP<3> A_PERP12 @T6G_MB_LIB.T6G(SCH_1):P5E_CPU1_P2_RX_BUF_DP(3)
 DU2 P5E_CPU1_P2_RX_BUF_DN<3> A_PERN12 @T6G_MB_LIB.T6G(SCH_1):P5E_CPU1_P2_RX_BUF_DN(3)
 EF1 P5E_CPU1_P2_RX_BUF_DP<2> A_PERP13 @T6G_MB_LIB.T6G(SCH_1):P5E_CPU1_P2_RX_BUF_DP(2)
 ED2 P5E_CPU1_P2_RX_BUF_DN<2> A_PERN13 @T6G_MB_LIB.T6G(SCH_1):P5E_CPU1_P2_RX_BUF_DN(2)
 EN1 P5E_CPU1_P2_RX_BUF_DP<1> A_PERP14 @T6G_MB_LIB.T6G(SCH_1):P5E_CPU1_P2_RX_BUF_DP(1)
 EL2 P5E_CPU1_P2_RX_BUF_DN<1> A_PERN14 @T6G_MB_LIB.T6G(SCH_1):P5E_CPU1_P2_RX_BUF_DN(1)
 EY1 P5E_CPU1_P2_RX_BUF_DP<0> A_PERP15 @T6G_MB_LIB.T6G(SCH_1):P5E_CPU1_P2_RX_BUF_DP(0)
 EV2 P5E_CPU1_P2_RX_BUF_DN<0> A_PERN15 @T6G_MB_LIB.T6G(SCH_1):P5E_CPU1_P2_RX_BUF_DN(0)


DRAWING: @T6G_MB_LIB.T6G(SCH_1):PAGE450 

Q_CAP_DIFFBUS_C0201-DIFF BUS_0.22UF,6.3V,20%,X6S,SA  I17  C6708
   1 P5E_CPU1_P2_TX_BUF_C_DN<7>      1 @T6G_MB_LIB.T6G(SCH_1):P5E_CPU1_P2_TX_BUF_C_DN(7)
   2 P5E_CPU1_P2_TX_BUF_DN<7>      2 @T6G_MB_LIB.T6G(SCH_1):P5E_CPU1_P2_TX_BUF_DN(7)

Q_CAP_DIFFBUS_C0201-DIFF BUS_0.22UF,6.3V,20%,X6S,SA  I18  C6707
   1 P5E_CPU1_P2_TX_BUF_C_DP<7>      1 @T6G_MB_LIB.T6G(SCH_1):P5E_CPU1_P2_TX_BUF_C_DP(7)
   2 P5E_CPU1_P2_TX_BUF_DP<7>      2 @T6G_MB_LIB.T6G(SCH_1):P5E_CPU1_P2_TX_BUF_DP(7)

Q_CAP_DIFFBUS_C0201-DIFF BUS_0.22UF,6.3V,20%,X6S,SA  I19  C6706
   1 P5E_CPU1_P2_TX_BUF_C_DN<6>      1 @T6G_MB_LIB.T6G(SCH_1):P5E_CPU1_P2_TX_BUF_C_DN(6)
   2 P5E_CPU1_P2_TX_BUF_DN<6>      2 @T6G_MB_LIB.T6G(SCH_1):P5E_CPU1_P2_TX_BUF_DN(6)

Q_CAP_DIFFBUS_C0201-DIFF BUS_0.22UF,6.3V,20%,X6S,SA  I20  C6705
   1 P5E_CPU1_P2_TX_BUF_C_DP<6>      1 @T6G_MB_LIB.T6G(SCH_1):P5E_CPU1_P2_TX_BUF_C_DP(6)
   2 P5E_CPU1_P2_TX_BUF_DP<6>      2 @T6G_MB_LIB.T6G(SCH_1):P5E_CPU1_P2_TX_BUF_DP(6)

Q_CAP_DIFFBUS_C0201-DIFF BUS_0.22UF,6.3V,20%,X6S,SA  I21  C6704
   1 P5E_CPU1_P2_TX_BUF_C_DN<5>      1 @T6G_MB_LIB.T6G(SCH_1):P5E_CPU1_P2_TX_BUF_C_DN(5)
   2 P5E_CPU1_P2_TX_BUF_DN<5>      2 @T6G_MB_LIB.T6G(SCH_1):P5E_CPU1_P2_TX_BUF_DN(5)

Q_CAP_DIFFBUS_C0201-DIFF BUS_0.22UF,6.3V,20%,X6S,SA  I22  C6703
   1 P5E_CPU1_P2_TX_BUF_C_DP<5>      1 @T6G_MB_LIB.T6G(SCH_1):P5E_CPU1_P2_TX_BUF_C_DP(5)
   2 P5E_CPU1_P2_TX_BUF_DP<5>      2 @T6G_MB_LIB.T6G(SCH_1):P5E_CPU1_P2_TX_BUF_DP(5)

Q_CAP_DIFFBUS_C0201-DIFF BUS_0.22UF,6.3V,20%,X6S,SA  I23  C6702
   1 P5E_CPU1_P2_TX_BUF_C_DN<4>      1 @T6G_MB_LIB.T6G(SCH_1):P5E_CPU1_P2_TX_BUF_C_DN(4)
   2 P5E_CPU1_P2_TX_BUF_DN<4>      2 @T6G_MB_LIB.T6G(SCH_1):P5E_CPU1_P2_TX_BUF_DN(4)

Q_CAP_DIFFBUS_C0201-DIFF BUS_0.22UF,6.3V,20%,X6S,SA  I24  C6701
   1 P5E_CPU1_P2_TX_BUF_C_DP<4>      1 @T6G_MB_LIB.T6G(SCH_1):P5E_CPU1_P2_TX_BUF_C_DP(4)
   2 P5E_CPU1_P2_TX_BUF_DP<4>      2 @T6G_MB_LIB.T6G(SCH_1):P5E_CPU1_P2_TX_BUF_DP(4)

Q_CAP_DIFFBUS_C0201-DIFF BUS_0.22UF,6.3V,20%,X6S,SA  I25  C6699
   1 P5E_CPU1_P2_TX_BUF_C_DP<3>      1 @T6G_MB_LIB.T6G(SCH_1):P5E_CPU1_P2_TX_BUF_C_DP(3)
   2 P5E_CPU1_P2_TX_BUF_DP<3>      2 @T6G_MB_LIB.T6G(SCH_1):P5E_CPU1_P2_TX_BUF_DP(3)

Q_CAP_DIFFBUS_C0201-DIFF BUS_0.22UF,6.3V,20%,X6S,SA  I26  C6700
   1 P5E_CPU1_P2_TX_BUF_C_DN<3>      1 @T6G_MB_LIB.T6G(SCH_1):P5E_CPU1_P2_TX_BUF_C_DN(3)
   2 P5E_CPU1_P2_TX_BUF_DN<3>      2 @T6G_MB_LIB.T6G(SCH_1):P5E_CPU1_P2_TX_BUF_DN(3)

Q_CAP_DIFFBUS_C0201-DIFF BUS_0.22UF,6.3V,20%,X6S,SA  I27  C6698
   1 P5E_CPU1_P2_TX_BUF_C_DN<2>      1 @T6G_MB_LIB.T6G(SCH_1):P5E_CPU1_P2_TX_BUF_C_DN(2)
   2 P5E_CPU1_P2_TX_BUF_DN<2>      2 @T6G_MB_LIB.T6G(SCH_1):P5E_CPU1_P2_TX_BUF_DN(2)

Q_CAP_DIFFBUS_C0201-DIFF BUS_0.22UF,6.3V,20%,X6S,SA  I28  C6696
   1 P5E_CPU1_P2_TX_BUF_C_DN<1>      1 @T6G_MB_LIB.T6G(SCH_1):P5E_CPU1_P2_TX_BUF_C_DN(1)
   2 P5E_CPU1_P2_TX_BUF_DN<1>      2 @T6G_MB_LIB.T6G(SCH_1):P5E_CPU1_P2_TX_BUF_DN(1)

Q_CAP_DIFFBUS_C0201-DIFF BUS_0.22UF,6.3V,20%,X6S,SA  I29  C6695
   1 P5E_CPU1_P2_TX_BUF_C_DP<1>      1 @T6G_MB_LIB.T6G(SCH_1):P5E_CPU1_P2_TX_BUF_C_DP(1)
   2 P5E_CPU1_P2_TX_BUF_DP<1>      2 @T6G_MB_LIB.T6G(SCH_1):P5E_CPU1_P2_TX_BUF_DP(1)

Q_CAP_DIFFBUS_C0201-DIFF BUS_0.22UF,6.3V,20%,X6S,SA  I30  C6697
   1 P5E_CPU1_P2_TX_BUF_C_DP<2>      1 @T6G_MB_LIB.T6G(SCH_1):P5E_CPU1_P2_TX_BUF_C_DP(2)
   2 P5E_CPU1_P2_TX_BUF_DP<2>      2 @T6G_MB_LIB.T6G(SCH_1):P5E_CPU1_P2_TX_BUF_DP(2)

PT5161LRS-PT5161LRS,SMLF,IC,AJ051610U03  I33  U6016
  M7 P5E_CPU1_P2_TX_BUF_DP<15> B_PETP0 @T6G_MB_LIB.T6G(SCH_1):P5E_CPU1_P2_TX_BUF_DP(15)
 P10 P5E_CPU1_P2_TX_BUF_DN<15> B_PETN0 @T6G_MB_LIB.T6G(SCH_1):P5E_CPU1_P2_TX_BUF_DN(15)
  W7 P5E_CPU1_P2_TX_BUF_DP<14> B_PETP1 @T6G_MB_LIB.T6G(SCH_1):P5E_CPU1_P2_TX_BUF_DP(14)
AA10 P5E_CPU1_P2_TX_BUF_DN<14> B_PETN1 @T6G_MB_LIB.T6G(SCH_1):P5E_CPU1_P2_TX_BUF_DN(14)
 AF7 P5E_CPU1_P2_TX_BUF_DP<13> B_PETP2 @T6G_MB_LIB.T6G(SCH_1):P5E_CPU1_P2_TX_BUF_DP(13)
AH10 P5E_CPU1_P2_TX_BUF_DN<13> B_PETN2 @T6G_MB_LIB.T6G(SCH_1):P5E_CPU1_P2_TX_BUF_DN(13)
 AN7 P5E_CPU1_P2_TX_BUF_DP<12> B_PETP3 @T6G_MB_LIB.T6G(SCH_1):P5E_CPU1_P2_TX_BUF_DP(12)
AR10 P5E_CPU1_P2_TX_BUF_DN<12> B_PETN3 @T6G_MB_LIB.T6G(SCH_1):P5E_CPU1_P2_TX_BUF_DN(12)
 AY7 P5E_CPU1_P2_TX_BUF_DP<11> B_PETP4 @T6G_MB_LIB.T6G(SCH_1):P5E_CPU1_P2_TX_BUF_DP(11)
BB10 P5E_CPU1_P2_TX_BUF_DN<11> B_PETN4 @T6G_MB_LIB.T6G(SCH_1):P5E_CPU1_P2_TX_BUF_DN(11)
 BG7 P5E_CPU1_P2_TX_BUF_DP<10> B_PETP5 @T6G_MB_LIB.T6G(SCH_1):P5E_CPU1_P2_TX_BUF_DP(10)
BJ10 P5E_CPU1_P2_TX_BUF_DN<10> B_PETN5 @T6G_MB_LIB.T6G(SCH_1):P5E_CPU1_P2_TX_BUF_DN(10)
 BP7 P5E_CPU1_P2_TX_BUF_DP<9> B_PETP6 @T6G_MB_LIB.T6G(SCH_1):P5E_CPU1_P2_TX_BUF_DP(9)
BT10 P5E_CPU1_P2_TX_BUF_DN<9> B_PETN6 @T6G_MB_LIB.T6G(SCH_1):P5E_CPU1_P2_TX_BUF_DN(9)
 CA7 P5E_CPU1_P2_TX_BUF_DP<8> B_PETP7 @T6G_MB_LIB.T6G(SCH_1):P5E_CPU1_P2_TX_BUF_DP(8)
CC10 P5E_CPU1_P2_TX_BUF_DN<8> B_PETN7 @T6G_MB_LIB.T6G(SCH_1):P5E_CPU1_P2_TX_BUF_DN(8)

Q_CAP_DIFFBUS_C0201-DIFF BUS_0.22UF,6.3V,20%,X6S,SA  I34  C6693
   1 P5E_CPU1_P2_TX_BUF_C_DP<0>      1 @T6G_MB_LIB.T6G(SCH_1):P5E_CPU1_P2_TX_BUF_C_DP(0)
   2 P5E_CPU1_P2_TX_BUF_DP<0>      2 @T6G_MB_LIB.T6G(SCH_1):P5E_CPU1_P2_TX_BUF_DP(0)

Q_CAP_DIFFBUS_C0201-DIFF BUS_0.22UF,6.3V,20%,X6S,SA  I35  C6694
   1 P5E_CPU1_P2_TX_BUF_C_DN<0>      1 @T6G_MB_LIB.T6G(SCH_1):P5E_CPU1_P2_TX_BUF_C_DN(0)
   2 P5E_CPU1_P2_TX_BUF_DN<0>      2 @T6G_MB_LIB.T6G(SCH_1):P5E_CPU1_P2_TX_BUF_DN(0)

Q_CAP_DIFFBUS_C0201-DIFF BUS_0.22UF,6.3V,20%,X6S,SA  I81  C6724
   1 P5E_CPU1_P2_TX_BUF_C_DN<15>      1 @T6G_MB_LIB.T6G(SCH_1):P5E_CPU1_P2_TX_BUF_C_DN(15)
   2 P5E_CPU1_P2_TX_BUF_DN<15>      2 @T6G_MB_LIB.T6G(SCH_1):P5E_CPU1_P2_TX_BUF_DN(15)

Q_CAP_DIFFBUS_C0201-DIFF BUS_0.22UF,6.3V,20%,X6S,SA  I82  C6723
   1 P5E_CPU1_P2_TX_BUF_C_DP<15>      1 @T6G_MB_LIB.T6G(SCH_1):P5E_CPU1_P2_TX_BUF_C_DP(15)
   2 P5E_CPU1_P2_TX_BUF_DP<15>      2 @T6G_MB_LIB.T6G(SCH_1):P5E_CPU1_P2_TX_BUF_DP(15)

Q_CAP_DIFFBUS_C0201-DIFF BUS_0.22UF,6.3V,20%,X6S,SA  I83  C6722
   1 P5E_CPU1_P2_TX_BUF_C_DN<14>      1 @T6G_MB_LIB.T6G(SCH_1):P5E_CPU1_P2_TX_BUF_C_DN(14)
   2 P5E_CPU1_P2_TX_BUF_DN<14>      2 @T6G_MB_LIB.T6G(SCH_1):P5E_CPU1_P2_TX_BUF_DN(14)

Q_CAP_DIFFBUS_C0201-DIFF BUS_0.22UF,6.3V,20%,X6S,SA  I84  C6721
   1 P5E_CPU1_P2_TX_BUF_C_DP<14>      1 @T6G_MB_LIB.T6G(SCH_1):P5E_CPU1_P2_TX_BUF_C_DP(14)
   2 P5E_CPU1_P2_TX_BUF_DP<14>      2 @T6G_MB_LIB.T6G(SCH_1):P5E_CPU1_P2_TX_BUF_DP(14)

Q_CAP_DIFFBUS_C0201-DIFF BUS_0.22UF,6.3V,20%,X6S,SA  I90  C6720
   1 P5E_CPU1_P2_TX_BUF_C_DN<13>      1 @T6G_MB_LIB.T6G(SCH_1):P5E_CPU1_P2_TX_BUF_C_DN(13)
   2 P5E_CPU1_P2_TX_BUF_DN<13>      2 @T6G_MB_LIB.T6G(SCH_1):P5E_CPU1_P2_TX_BUF_DN(13)

Q_CAP_DIFFBUS_C0201-DIFF BUS_0.22UF,6.3V,20%,X6S,SA  I91  C6719
   1 P5E_CPU1_P2_TX_BUF_C_DP<13>      1 @T6G_MB_LIB.T6G(SCH_1):P5E_CPU1_P2_TX_BUF_C_DP(13)
   2 P5E_CPU1_P2_TX_BUF_DP<13>      2 @T6G_MB_LIB.T6G(SCH_1):P5E_CPU1_P2_TX_BUF_DP(13)

Q_CAP_DIFFBUS_C0201-DIFF BUS_0.22UF,6.3V,20%,X6S,SA  I92  C6718
   1 P5E_CPU1_P2_TX_BUF_C_DN<12>      1 @T6G_MB_LIB.T6G(SCH_1):P5E_CPU1_P2_TX_BUF_C_DN(12)
   2 P5E_CPU1_P2_TX_BUF_DN<12>      2 @T6G_MB_LIB.T6G(SCH_1):P5E_CPU1_P2_TX_BUF_DN(12)

Q_CAP_DIFFBUS_C0201-DIFF BUS_0.22UF,6.3V,20%,X6S,SA  I93  C6717
   1 P5E_CPU1_P2_TX_BUF_C_DP<12>      1 @T6G_MB_LIB.T6G(SCH_1):P5E_CPU1_P2_TX_BUF_C_DP(12)
   2 P5E_CPU1_P2_TX_BUF_DP<12>      2 @T6G_MB_LIB.T6G(SCH_1):P5E_CPU1_P2_TX_BUF_DP(12)

Q_CAP_DIFFBUS_C0201-DIFF BUS_0.22UF,6.3V,20%,X6S,SA  I94  C6716
   1 P5E_CPU1_P2_TX_BUF_C_DN<11>      1 @T6G_MB_LIB.T6G(SCH_1):P5E_CPU1_P2_TX_BUF_C_DN(11)
   2 P5E_CPU1_P2_TX_BUF_DN<11>      2 @T6G_MB_LIB.T6G(SCH_1):P5E_CPU1_P2_TX_BUF_DN(11)

Q_CAP_DIFFBUS_C0201-DIFF BUS_0.22UF,6.3V,20%,X6S,SA  I95  C6715
   1 P5E_CPU1_P2_TX_BUF_C_DP<11>      1 @T6G_MB_LIB.T6G(SCH_1):P5E_CPU1_P2_TX_BUF_C_DP(11)
   2 P5E_CPU1_P2_TX_BUF_DP<11>      2 @T6G_MB_LIB.T6G(SCH_1):P5E_CPU1_P2_TX_BUF_DP(11)

Q_CAP_DIFFBUS_C0201-DIFF BUS_0.22UF,6.3V,20%,X6S,SA  I96  C6714
   1 P5E_CPU1_P2_TX_BUF_C_DN<10>      1 @T6G_MB_LIB.T6G(SCH_1):P5E_CPU1_P2_TX_BUF_C_DN(10)
   2 P5E_CPU1_P2_TX_BUF_DN<10>      2 @T6G_MB_LIB.T6G(SCH_1):P5E_CPU1_P2_TX_BUF_DN(10)

Q_CAP_DIFFBUS_C0201-DIFF BUS_0.22UF,6.3V,20%,X6S,SA  I97  C6713
   1 P5E_CPU1_P2_TX_BUF_C_DP<10>      1 @T6G_MB_LIB.T6G(SCH_1):P5E_CPU1_P2_TX_BUF_C_DP(10)
   2 P5E_CPU1_P2_TX_BUF_DP<10>      2 @T6G_MB_LIB.T6G(SCH_1):P5E_CPU1_P2_TX_BUF_DP(10)

Q_CAP_DIFFBUS_C0201-DIFF BUS_0.22UF,6.3V,20%,X6S,SA  I98  C6712
   1 P5E_CPU1_P2_TX_BUF_C_DN<9>      1 @T6G_MB_LIB.T6G(SCH_1):P5E_CPU1_P2_TX_BUF_C_DN(9)
   2 P5E_CPU1_P2_TX_BUF_DN<9>      2 @T6G_MB_LIB.T6G(SCH_1):P5E_CPU1_P2_TX_BUF_DN(9)

Q_CAP_DIFFBUS_C0201-DIFF BUS_0.22UF,6.3V,20%,X6S,SA  I99  C6711
   1 P5E_CPU1_P2_TX_BUF_C_DP<9>      1 @T6G_MB_LIB.T6G(SCH_1):P5E_CPU1_P2_TX_BUF_C_DP(9)
   2 P5E_CPU1_P2_TX_BUF_DP<9>      2 @T6G_MB_LIB.T6G(SCH_1):P5E_CPU1_P2_TX_BUF_DP(9)

Q_CAP_DIFFBUS_C0201-DIFF BUS_0.22UF,6.3V,20%,X6S,SA  I102  C6709
   1 P5E_CPU1_P2_TX_BUF_C_DP<8>      1 @T6G_MB_LIB.T6G(SCH_1):P5E_CPU1_P2_TX_BUF_C_DP(8)
   2 P5E_CPU1_P2_TX_BUF_DP<8>      2 @T6G_MB_LIB.T6G(SCH_1):P5E_CPU1_P2_TX_BUF_DP(8)

Q_CAP_DIFFBUS_C0201-DIFF BUS_0.22UF,6.3V,20%,X6S,SA  I103  C6710
   1 P5E_CPU1_P2_TX_BUF_C_DN<8>      1 @T6G_MB_LIB.T6G(SCH_1):P5E_CPU1_P2_TX_BUF_C_DN(8)
   2 P5E_CPU1_P2_TX_BUF_DN<8>      2 @T6G_MB_LIB.T6G(SCH_1):P5E_CPU1_P2_TX_BUF_DN(8)

PT5161LRS-PT5161LRS,SMLF,IC,AJ051610U03  I142  U6016
 CH7 P5E_CPU1_P2_TX_BUF_DP<7> B_PETP8 @T6G_MB_LIB.T6G(SCH_1):P5E_CPU1_P2_TX_BUF_DP(7)
CK10 P5E_CPU1_P2_TX_BUF_DN<7> B_PETN8 @T6G_MB_LIB.T6G(SCH_1):P5E_CPU1_P2_TX_BUF_DN(7)
 CR7 P5E_CPU1_P2_TX_BUF_DP<6> B_PETP9 @T6G_MB_LIB.T6G(SCH_1):P5E_CPU1_P2_TX_BUF_DP(6)
CU10 P5E_CPU1_P2_TX_BUF_DN<6> B_PETN9 @T6G_MB_LIB.T6G(SCH_1):P5E_CPU1_P2_TX_BUF_DN(6)
 DB7 P5E_CPU1_P2_TX_BUF_DP<5> B_PETP10 @T6G_MB_LIB.T6G(SCH_1):P5E_CPU1_P2_TX_BUF_DP(5)
DD10 P5E_CPU1_P2_TX_BUF_DN<5> B_PETN10 @T6G_MB_LIB.T6G(SCH_1):P5E_CPU1_P2_TX_BUF_DN(5)
 DJ7 P5E_CPU1_P2_TX_BUF_DP<4> B_PETP11 @T6G_MB_LIB.T6G(SCH_1):P5E_CPU1_P2_TX_BUF_DP(4)
DL10 P5E_CPU1_P2_TX_BUF_DN<4> B_PETN11 @T6G_MB_LIB.T6G(SCH_1):P5E_CPU1_P2_TX_BUF_DN(4)
 DT7 P5E_CPU1_P2_TX_BUF_DP<3> B_PETP12 @T6G_MB_LIB.T6G(SCH_1):P5E_CPU1_P2_TX_BUF_DP(3)
DV10 P5E_CPU1_P2_TX_BUF_DN<3> B_PETN12 @T6G_MB_LIB.T6G(SCH_1):P5E_CPU1_P2_TX_BUF_DN(3)
 EC7 P5E_CPU1_P2_TX_BUF_DP<2> B_PETP13 @T6G_MB_LIB.T6G(SCH_1):P5E_CPU1_P2_TX_BUF_DP(2)
EE10 P5E_CPU1_P2_TX_BUF_DN<2> B_PETN13 @T6G_MB_LIB.T6G(SCH_1):P5E_CPU1_P2_TX_BUF_DN(2)
 EK7 P5E_CPU1_P2_TX_BUF_DP<1> B_PETP14 @T6G_MB_LIB.T6G(SCH_1):P5E_CPU1_P2_TX_BUF_DP(1)
EM10 P5E_CPU1_P2_TX_BUF_DN<1> B_PETN14 @T6G_MB_LIB.T6G(SCH_1):P5E_CPU1_P2_TX_BUF_DN(1)
 EU7 P5E_CPU1_P2_TX_BUF_DP<0> B_PETP15 @T6G_MB_LIB.T6G(SCH_1):P5E_CPU1_P2_TX_BUF_DP(0)
EW10 P5E_CPU1_P2_TX_BUF_DN<0> B_PETN15 @T6G_MB_LIB.T6G(SCH_1):P5E_CPU1_P2_TX_BUF_DN(0)


DRAWING: @T6G_MB_LIB.T6G(SCH_1):PAGE458 

PT5161LRS-PT5161LRS,SMLF,IC,AJ051610U03  I1  U6017
 N34 P5E_CPU1_P3_TX_C_DN<15> B_PERP0 @T6G_MB_LIB.T6G(SCH_1):P5E_CPU1_P3_TX_C_DN(15)
 R35 P5E_CPU1_P3_TX_C_DP<15> B_PERN0 @T6G_MB_LIB.T6G(SCH_1):P5E_CPU1_P3_TX_C_DP(15)
 Y34 P5E_CPU1_P3_TX_C_DP<14> B_PERP1 @T6G_MB_LIB.T6G(SCH_1):P5E_CPU1_P3_TX_C_DP(14)
AB35 P5E_CPU1_P3_TX_C_DN<14> B_PERN1 @T6G_MB_LIB.T6G(SCH_1):P5E_CPU1_P3_TX_C_DN(14)
AG34 P5E_CPU1_P3_TX_C_DN<13> B_PERP2 @T6G_MB_LIB.T6G(SCH_1):P5E_CPU1_P3_TX_C_DN(13)
AJ35 P5E_CPU1_P3_TX_C_DP<13> B_PERN2 @T6G_MB_LIB.T6G(SCH_1):P5E_CPU1_P3_TX_C_DP(13)
AP34 P5E_CPU1_P3_TX_C_DN<12> B_PERP3 @T6G_MB_LIB.T6G(SCH_1):P5E_CPU1_P3_TX_C_DN(12)
AT35 P5E_CPU1_P3_TX_C_DP<12> B_PERN3 @T6G_MB_LIB.T6G(SCH_1):P5E_CPU1_P3_TX_C_DP(12)
BA34 P5E_CPU1_P3_TX_C_DN<11> B_PERP4 @T6G_MB_LIB.T6G(SCH_1):P5E_CPU1_P3_TX_C_DN(11)
BC35 P5E_CPU1_P3_TX_C_DP<11> B_PERN4 @T6G_MB_LIB.T6G(SCH_1):P5E_CPU1_P3_TX_C_DP(11)
BH34 P5E_CPU1_P3_TX_C_DN<10> B_PERP5 @T6G_MB_LIB.T6G(SCH_1):P5E_CPU1_P3_TX_C_DN(10)
BK35 P5E_CPU1_P3_TX_C_DP<10> B_PERN5 @T6G_MB_LIB.T6G(SCH_1):P5E_CPU1_P3_TX_C_DP(10)
BR34 P5E_CPU1_P3_TX_C_DN<9> B_PERP6 @T6G_MB_LIB.T6G(SCH_1):P5E_CPU1_P3_TX_C_DN(9)
BU35 P5E_CPU1_P3_TX_C_DP<9> B_PERN6 @T6G_MB_LIB.T6G(SCH_1):P5E_CPU1_P3_TX_C_DP(9)
CB34 P5E_CPU1_P3_TX_C_DN<8> B_PERP7 @T6G_MB_LIB.T6G(SCH_1):P5E_CPU1_P3_TX_C_DN(8)
CD35 P5E_CPU1_P3_TX_C_DP<8> B_PERN7 @T6G_MB_LIB.T6G(SCH_1):P5E_CPU1_P3_TX_C_DP(8)

PT5161LRS-PT5161LRS,SMLF,IC,AJ051610U03  I38  U6017
CJ34 P5E_CPU1_P3_TX_C_DN<7> B_PERP8 @T6G_MB_LIB.T6G(SCH_1):P5E_CPU1_P3_TX_C_DN(7)
CL35 P5E_CPU1_P3_TX_C_DP<7> B_PERN8 @T6G_MB_LIB.T6G(SCH_1):P5E_CPU1_P3_TX_C_DP(7)
CT34 P5E_CPU1_P3_TX_C_DN<6> B_PERP9 @T6G_MB_LIB.T6G(SCH_1):P5E_CPU1_P3_TX_C_DN(6)
CV35 P5E_CPU1_P3_TX_C_DP<6> B_PERN9 @T6G_MB_LIB.T6G(SCH_1):P5E_CPU1_P3_TX_C_DP(6)
DC34 P5E_CPU1_P3_TX_C_DN<5> B_PERP10 @T6G_MB_LIB.T6G(SCH_1):P5E_CPU1_P3_TX_C_DN(5)
DE35 P5E_CPU1_P3_TX_C_DP<5> B_PERN10 @T6G_MB_LIB.T6G(SCH_1):P5E_CPU1_P3_TX_C_DP(5)
DK34 P5E_CPU1_P3_TX_C_DN<4> B_PERP11 @T6G_MB_LIB.T6G(SCH_1):P5E_CPU1_P3_TX_C_DN(4)
DM35 P5E_CPU1_P3_TX_C_DP<4> B_PERN11 @T6G_MB_LIB.T6G(SCH_1):P5E_CPU1_P3_TX_C_DP(4)
DU34 P5E_CPU1_P3_TX_C_DN<3> B_PERP12 @T6G_MB_LIB.T6G(SCH_1):P5E_CPU1_P3_TX_C_DN(3)
DW35 P5E_CPU1_P3_TX_C_DP<3> B_PERN12 @T6G_MB_LIB.T6G(SCH_1):P5E_CPU1_P3_TX_C_DP(3)
ED34 P5E_CPU1_P3_TX_C_DN<2> B_PERP13 @T6G_MB_LIB.T6G(SCH_1):P5E_CPU1_P3_TX_C_DN(2)
EF35 P5E_CPU1_P3_TX_C_DP<2> B_PERN13 @T6G_MB_LIB.T6G(SCH_1):P5E_CPU1_P3_TX_C_DP(2)
EL34 P5E_CPU1_P3_TX_C_DP<1> B_PERP14 @T6G_MB_LIB.T6G(SCH_1):P5E_CPU1_P3_TX_C_DP(1)
EN35 P5E_CPU1_P3_TX_C_DN<1> B_PERN14 @T6G_MB_LIB.T6G(SCH_1):P5E_CPU1_P3_TX_C_DN(1)
EV34 P5E_CPU1_P3_TX_C_DN<0> B_PERP15 @T6G_MB_LIB.T6G(SCH_1):P5E_CPU1_P3_TX_C_DN(0)
EY35 P5E_CPU1_P3_TX_C_DP<0> B_PERN15 @T6G_MB_LIB.T6G(SCH_1):P5E_CPU1_P3_TX_C_DP(0)


DRAWING: @T6G_MB_LIB.T6G(SCH_1):PAGE459 

PT5161LRS-PT5161LRS,SMLF,IC,AJ051610U03  I1  U6017
 M26 P5E_CPU1_P3_RX_DP<15> A_PETP0 @T6G_MB_LIB.T6G(SCH_1):P5E_CPU1_P3_RX_DP(15)
 P29 P5E_CPU1_P3_RX_DN<15> A_PETN0 @T6G_MB_LIB.T6G(SCH_1):P5E_CPU1_P3_RX_DN(15)
 W26 P5E_CPU1_P3_RX_DP<14> A_PETP1 @T6G_MB_LIB.T6G(SCH_1):P5E_CPU1_P3_RX_DP(14)
AA29 P5E_CPU1_P3_RX_DN<14> A_PETN1 @T6G_MB_LIB.T6G(SCH_1):P5E_CPU1_P3_RX_DN(14)
AF26 P5E_CPU1_P3_RX_DP<13> A_PETP2 @T6G_MB_LIB.T6G(SCH_1):P5E_CPU1_P3_RX_DP(13)
AH29 P5E_CPU1_P3_RX_DN<13> A_PETN2 @T6G_MB_LIB.T6G(SCH_1):P5E_CPU1_P3_RX_DN(13)
AN26 P5E_CPU1_P3_RX_DP<12> A_PETP3 @T6G_MB_LIB.T6G(SCH_1):P5E_CPU1_P3_RX_DP(12)
AR29 P5E_CPU1_P3_RX_DN<12> A_PETN3 @T6G_MB_LIB.T6G(SCH_1):P5E_CPU1_P3_RX_DN(12)
AY26 P5E_CPU1_P3_RX_DP<11> A_PETP4 @T6G_MB_LIB.T6G(SCH_1):P5E_CPU1_P3_RX_DP(11)
BB29 P5E_CPU1_P3_RX_DN<11> A_PETN4 @T6G_MB_LIB.T6G(SCH_1):P5E_CPU1_P3_RX_DN(11)
BG26 P5E_CPU1_P3_RX_DP<10> A_PETP5 @T6G_MB_LIB.T6G(SCH_1):P5E_CPU1_P3_RX_DP(10)
BJ29 P5E_CPU1_P3_RX_DN<10> A_PETN5 @T6G_MB_LIB.T6G(SCH_1):P5E_CPU1_P3_RX_DN(10)
BP26 P5E_CPU1_P3_RX_DP<9> A_PETP6 @T6G_MB_LIB.T6G(SCH_1):P5E_CPU1_P3_RX_DP(9)
BT29 P5E_CPU1_P3_RX_DN<9> A_PETN6 @T6G_MB_LIB.T6G(SCH_1):P5E_CPU1_P3_RX_DN(9)
CA26 P5E_CPU1_P3_RX_DP<8> A_PETP7 @T6G_MB_LIB.T6G(SCH_1):P5E_CPU1_P3_RX_DP(8)
CC29 P5E_CPU1_P3_RX_DN<8> A_PETN7 @T6G_MB_LIB.T6G(SCH_1):P5E_CPU1_P3_RX_DN(8)

PT5161LRS-PT5161LRS,SMLF,IC,AJ051610U03  I38  U6017
CH26 P5E_CPU1_P3_RX_DP<7> A_PETP8 @T6G_MB_LIB.T6G(SCH_1):P5E_CPU1_P3_RX_DP(7)
CK29 P5E_CPU1_P3_RX_DN<7> A_PETN8 @T6G_MB_LIB.T6G(SCH_1):P5E_CPU1_P3_RX_DN(7)
CR26 P5E_CPU1_P3_RX_DP<6> A_PETP9 @T6G_MB_LIB.T6G(SCH_1):P5E_CPU1_P3_RX_DP(6)
CU29 P5E_CPU1_P3_RX_DN<6> A_PETN9 @T6G_MB_LIB.T6G(SCH_1):P5E_CPU1_P3_RX_DN(6)
DB26 P5E_CPU1_P3_RX_DP<5> A_PETP10 @T6G_MB_LIB.T6G(SCH_1):P5E_CPU1_P3_RX_DP(5)
DD29 P5E_CPU1_P3_RX_DN<5> A_PETN10 @T6G_MB_LIB.T6G(SCH_1):P5E_CPU1_P3_RX_DN(5)
DJ26 P5E_CPU1_P3_RX_DP<4> A_PETP11 @T6G_MB_LIB.T6G(SCH_1):P5E_CPU1_P3_RX_DP(4)
DL29 P5E_CPU1_P3_RX_DN<4> A_PETN11 @T6G_MB_LIB.T6G(SCH_1):P5E_CPU1_P3_RX_DN(4)
DT26 P5E_CPU1_P3_RX_DP<3> A_PETP12 @T6G_MB_LIB.T6G(SCH_1):P5E_CPU1_P3_RX_DP(3)
DV29 P5E_CPU1_P3_RX_DN<3> A_PETN12 @T6G_MB_LIB.T6G(SCH_1):P5E_CPU1_P3_RX_DN(3)
EC26 P5E_CPU1_P3_RX_DP<2> A_PETP13 @T6G_MB_LIB.T6G(SCH_1):P5E_CPU1_P3_RX_DP(2)
EE29 P5E_CPU1_P3_RX_DN<2> A_PETN13 @T6G_MB_LIB.T6G(SCH_1):P5E_CPU1_P3_RX_DN(2)
EK26 P5E_CPU1_P3_RX_DP<1> A_PETP14 @T6G_MB_LIB.T6G(SCH_1):P5E_CPU1_P3_RX_DP(1)
EM29 P5E_CPU1_P3_RX_DN<1> A_PETN14 @T6G_MB_LIB.T6G(SCH_1):P5E_CPU1_P3_RX_DN(1)
EU26 P5E_CPU1_P3_RX_DP<0> A_PETP15 @T6G_MB_LIB.T6G(SCH_1):P5E_CPU1_P3_RX_DP(0)
EW29 P5E_CPU1_P3_RX_DN<0> A_PETN15 @T6G_MB_LIB.T6G(SCH_1):P5E_CPU1_P3_RX_DN(0)


DRAWING: @T6G_MB_LIB.T6G(SCH_1):PAGE460 

PT5161LRS-PT5161LRS,SMLF,IC,AJ051610U03  I1  U6017
  R1 P5E_CPU1_P3_RX_BUF_DP<15> A_PERP0 @T6G_MB_LIB.T6G(SCH_1):P5E_CPU1_P3_RX_BUF_DP(15)
  N2 P5E_CPU1_P3_RX_BUF_DN<15> A_PERN0 @T6G_MB_LIB.T6G(SCH_1):P5E_CPU1_P3_RX_BUF_DN(15)
 AB1 P5E_CPU1_P3_RX_BUF_DP<14> A_PERP1 @T6G_MB_LIB.T6G(SCH_1):P5E_CPU1_P3_RX_BUF_DP(14)
  Y2 P5E_CPU1_P3_RX_BUF_DN<14> A_PERN1 @T6G_MB_LIB.T6G(SCH_1):P5E_CPU1_P3_RX_BUF_DN(14)
 AJ1 P5E_CPU1_P3_RX_BUF_DP<13> A_PERP2 @T6G_MB_LIB.T6G(SCH_1):P5E_CPU1_P3_RX_BUF_DP(13)
 AG2 P5E_CPU1_P3_RX_BUF_DN<13> A_PERN2 @T6G_MB_LIB.T6G(SCH_1):P5E_CPU1_P3_RX_BUF_DN(13)
 AT1 P5E_CPU1_P3_RX_BUF_DP<12> A_PERP3 @T6G_MB_LIB.T6G(SCH_1):P5E_CPU1_P3_RX_BUF_DP(12)
 AP2 P5E_CPU1_P3_RX_BUF_DN<12> A_PERN3 @T6G_MB_LIB.T6G(SCH_1):P5E_CPU1_P3_RX_BUF_DN(12)
 BC1 P5E_CPU1_P3_RX_BUF_DP<11> A_PERP4 @T6G_MB_LIB.T6G(SCH_1):P5E_CPU1_P3_RX_BUF_DP(11)
 BA2 P5E_CPU1_P3_RX_BUF_DN<11> A_PERN4 @T6G_MB_LIB.T6G(SCH_1):P5E_CPU1_P3_RX_BUF_DN(11)
 BK1 P5E_CPU1_P3_RX_BUF_DP<10> A_PERP5 @T6G_MB_LIB.T6G(SCH_1):P5E_CPU1_P3_RX_BUF_DP(10)
 BH2 P5E_CPU1_P3_RX_BUF_DN<10> A_PERN5 @T6G_MB_LIB.T6G(SCH_1):P5E_CPU1_P3_RX_BUF_DN(10)
 BU1 P5E_CPU1_P3_RX_BUF_DP<9> A_PERP6 @T6G_MB_LIB.T6G(SCH_1):P5E_CPU1_P3_RX_BUF_DP(9)
 BR2 P5E_CPU1_P3_RX_BUF_DN<9> A_PERN6 @T6G_MB_LIB.T6G(SCH_1):P5E_CPU1_P3_RX_BUF_DN(9)
 CD1 P5E_CPU1_P3_RX_BUF_DP<8> A_PERP7 @T6G_MB_LIB.T6G(SCH_1):P5E_CPU1_P3_RX_BUF_DP(8)
 CB2 P5E_CPU1_P3_RX_BUF_DN<8> A_PERN7 @T6G_MB_LIB.T6G(SCH_1):P5E_CPU1_P3_RX_BUF_DN(8)

PT5161LRS-PT5161LRS,SMLF,IC,AJ051610U03  I38  U6017
 CL1 P5E_CPU1_P3_RX_BUF_DP<7> A_PERP8 @T6G_MB_LIB.T6G(SCH_1):P5E_CPU1_P3_RX_BUF_DP(7)
 CJ2 P5E_CPU1_P3_RX_BUF_DN<7> A_PERN8 @T6G_MB_LIB.T6G(SCH_1):P5E_CPU1_P3_RX_BUF_DN(7)
 CV1 P5E_CPU1_P3_RX_BUF_DP<6> A_PERP9 @T6G_MB_LIB.T6G(SCH_1):P5E_CPU1_P3_RX_BUF_DP(6)
 CT2 P5E_CPU1_P3_RX_BUF_DN<6> A_PERN9 @T6G_MB_LIB.T6G(SCH_1):P5E_CPU1_P3_RX_BUF_DN(6)
 DE1 P5E_CPU1_P3_RX_BUF_DP<5> A_PERP10 @T6G_MB_LIB.T6G(SCH_1):P5E_CPU1_P3_RX_BUF_DP(5)
 DC2 P5E_CPU1_P3_RX_BUF_DN<5> A_PERN10 @T6G_MB_LIB.T6G(SCH_1):P5E_CPU1_P3_RX_BUF_DN(5)
 DM1 P5E_CPU1_P3_RX_BUF_DP<4> A_PERP11 @T6G_MB_LIB.T6G(SCH_1):P5E_CPU1_P3_RX_BUF_DP(4)
 DK2 P5E_CPU1_P3_RX_BUF_DN<4> A_PERN11 @T6G_MB_LIB.T6G(SCH_1):P5E_CPU1_P3_RX_BUF_DN(4)
 DW1 P5E_CPU1_P3_RX_BUF_DP<3> A_PERP12 @T6G_MB_LIB.T6G(SCH_1):P5E_CPU1_P3_RX_BUF_DP(3)
 DU2 P5E_CPU1_P3_RX_BUF_DN<3> A_PERN12 @T6G_MB_LIB.T6G(SCH_1):P5E_CPU1_P3_RX_BUF_DN(3)
 EF1 P5E_CPU1_P3_RX_BUF_DP<2> A_PERP13 @T6G_MB_LIB.T6G(SCH_1):P5E_CPU1_P3_RX_BUF_DP(2)
 ED2 P5E_CPU1_P3_RX_BUF_DN<2> A_PERN13 @T6G_MB_LIB.T6G(SCH_1):P5E_CPU1_P3_RX_BUF_DN(2)
 EN1 P5E_CPU1_P3_RX_BUF_DP<1> A_PERP14 @T6G_MB_LIB.T6G(SCH_1):P5E_CPU1_P3_RX_BUF_DP(1)
 EL2 P5E_CPU1_P3_RX_BUF_DN<1> A_PERN14 @T6G_MB_LIB.T6G(SCH_1):P5E_CPU1_P3_RX_BUF_DN(1)
 EY1 P5E_CPU1_P3_RX_BUF_DP<0> A_PERP15 @T6G_MB_LIB.T6G(SCH_1):P5E_CPU1_P3_RX_BUF_DP(0)
 EV2 P5E_CPU1_P3_RX_BUF_DN<0> A_PERN15 @T6G_MB_LIB.T6G(SCH_1):P5E_CPU1_P3_RX_BUF_DN(0)


DRAWING: @T6G_MB_LIB.T6G(SCH_1):PAGE461 

Q_CAP_DIFFBUS_C0201-DIFF BUS_0.22UF,6.3V,20%,X6S,SA  I16  C6738
   1 P5E_CPU1_P3_TX_BUF_C_DN<6>      1 @T6G_MB_LIB.T6G(SCH_1):P5E_CPU1_P3_TX_BUF_C_DN(6)
   2 P5E_CPU1_P3_TX_BUF_DN<6>      2 @T6G_MB_LIB.T6G(SCH_1):P5E_CPU1_P3_TX_BUF_DN(6)

Q_CAP_DIFFBUS_C0201-DIFF BUS_0.22UF,6.3V,20%,X6S,SA  I17  C6739
   1 P5E_CPU1_P3_TX_BUF_C_DP<7>      1 @T6G_MB_LIB.T6G(SCH_1):P5E_CPU1_P3_TX_BUF_C_DP(7)
   2 P5E_CPU1_P3_TX_BUF_DP<7>      2 @T6G_MB_LIB.T6G(SCH_1):P5E_CPU1_P3_TX_BUF_DP(7)

Q_CAP_DIFFBUS_C0201-DIFF BUS_0.22UF,6.3V,20%,X6S,SA  I18  C6740
   1 P5E_CPU1_P3_TX_BUF_C_DN<7>      1 @T6G_MB_LIB.T6G(SCH_1):P5E_CPU1_P3_TX_BUF_C_DN(7)
   2 P5E_CPU1_P3_TX_BUF_DN<7>      2 @T6G_MB_LIB.T6G(SCH_1):P5E_CPU1_P3_TX_BUF_DN(7)

Q_CAP_DIFFBUS_C0201-DIFF BUS_0.22UF,6.3V,20%,X6S,SA  I22  C6737
   1 P5E_CPU1_P3_TX_BUF_C_DP<6>      1 @T6G_MB_LIB.T6G(SCH_1):P5E_CPU1_P3_TX_BUF_C_DP(6)
   2 P5E_CPU1_P3_TX_BUF_DP<6>      2 @T6G_MB_LIB.T6G(SCH_1):P5E_CPU1_P3_TX_BUF_DP(6)

Q_CAP_DIFFBUS_C0201-DIFF BUS_0.22UF,6.3V,20%,X6S,SA  I23  C6736
   1 P5E_CPU1_P3_TX_BUF_C_DN<5>      1 @T6G_MB_LIB.T6G(SCH_1):P5E_CPU1_P3_TX_BUF_C_DN(5)
   2 P5E_CPU1_P3_TX_BUF_DN<5>      2 @T6G_MB_LIB.T6G(SCH_1):P5E_CPU1_P3_TX_BUF_DN(5)

Q_CAP_DIFFBUS_C0201-DIFF BUS_0.22UF,6.3V,20%,X6S,SA  I24  C6735
   1 P5E_CPU1_P3_TX_BUF_C_DP<5>      1 @T6G_MB_LIB.T6G(SCH_1):P5E_CPU1_P3_TX_BUF_C_DP(5)
   2 P5E_CPU1_P3_TX_BUF_DP<5>      2 @T6G_MB_LIB.T6G(SCH_1):P5E_CPU1_P3_TX_BUF_DP(5)

Q_CAP_DIFFBUS_C0201-DIFF BUS_0.22UF,6.3V,20%,X6S,SA  I25  C6734
   1 P5E_CPU1_P3_TX_BUF_C_DN<4>      1 @T6G_MB_LIB.T6G(SCH_1):P5E_CPU1_P3_TX_BUF_C_DN(4)
   2 P5E_CPU1_P3_TX_BUF_DN<4>      2 @T6G_MB_LIB.T6G(SCH_1):P5E_CPU1_P3_TX_BUF_DN(4)

Q_CAP_DIFFBUS_C0201-DIFF BUS_0.22UF,6.3V,20%,X6S,SA  I26  C6733
   1 P5E_CPU1_P3_TX_BUF_C_DP<4>      1 @T6G_MB_LIB.T6G(SCH_1):P5E_CPU1_P3_TX_BUF_C_DP(4)
   2 P5E_CPU1_P3_TX_BUF_DP<4>      2 @T6G_MB_LIB.T6G(SCH_1):P5E_CPU1_P3_TX_BUF_DP(4)

Q_CAP_DIFFBUS_C0201-DIFF BUS_0.22UF,6.3V,20%,X6S,SA  I27  C6731
   1 P5E_CPU1_P3_TX_BUF_C_DP<3>      1 @T6G_MB_LIB.T6G(SCH_1):P5E_CPU1_P3_TX_BUF_C_DP(3)
   2 P5E_CPU1_P3_TX_BUF_DP<3>      2 @T6G_MB_LIB.T6G(SCH_1):P5E_CPU1_P3_TX_BUF_DP(3)

Q_CAP_DIFFBUS_C0201-DIFF BUS_0.22UF,6.3V,20%,X6S,SA  I28  C6732
   1 P5E_CPU1_P3_TX_BUF_C_DN<3>      1 @T6G_MB_LIB.T6G(SCH_1):P5E_CPU1_P3_TX_BUF_C_DN(3)
   2 P5E_CPU1_P3_TX_BUF_DN<3>      2 @T6G_MB_LIB.T6G(SCH_1):P5E_CPU1_P3_TX_BUF_DN(3)

Q_CAP_DIFFBUS_C0201-DIFF BUS_0.22UF,6.3V,20%,X6S,SA  I29  C6730
   1 P5E_CPU1_P3_TX_BUF_C_DN<2>      1 @T6G_MB_LIB.T6G(SCH_1):P5E_CPU1_P3_TX_BUF_C_DN(2)
   2 P5E_CPU1_P3_TX_BUF_DN<2>      2 @T6G_MB_LIB.T6G(SCH_1):P5E_CPU1_P3_TX_BUF_DN(2)

Q_CAP_DIFFBUS_C0201-DIFF BUS_0.22UF,6.3V,20%,X6S,SA  I30  C6728
   1 P5E_CPU1_P3_TX_BUF_C_DN<1>      1 @T6G_MB_LIB.T6G(SCH_1):P5E_CPU1_P3_TX_BUF_C_DN(1)
   2 P5E_CPU1_P3_TX_BUF_DN<1>      2 @T6G_MB_LIB.T6G(SCH_1):P5E_CPU1_P3_TX_BUF_DN(1)

Q_CAP_DIFFBUS_C0201-DIFF BUS_0.22UF,6.3V,20%,X6S,SA  I31  C6729
   1 P5E_CPU1_P3_TX_BUF_C_DP<2>      1 @T6G_MB_LIB.T6G(SCH_1):P5E_CPU1_P3_TX_BUF_C_DP(2)
   2 P5E_CPU1_P3_TX_BUF_DP<2>      2 @T6G_MB_LIB.T6G(SCH_1):P5E_CPU1_P3_TX_BUF_DP(2)

Q_CAP_DIFFBUS_C0201-DIFF BUS_0.22UF,6.3V,20%,X6S,SA  I32  C6727
   1 P5E_CPU1_P3_TX_BUF_C_DP<1>      1 @T6G_MB_LIB.T6G(SCH_1):P5E_CPU1_P3_TX_BUF_C_DP(1)
   2 P5E_CPU1_P3_TX_BUF_DP<1>      2 @T6G_MB_LIB.T6G(SCH_1):P5E_CPU1_P3_TX_BUF_DP(1)

PT5161LRS-PT5161LRS,SMLF,IC,AJ051610U03  I46  U6017
  M7 P5E_CPU1_P3_TX_BUF_DP<15> B_PETP0 @T6G_MB_LIB.T6G(SCH_1):P5E_CPU1_P3_TX_BUF_DP(15)
 P10 P5E_CPU1_P3_TX_BUF_DN<15> B_PETN0 @T6G_MB_LIB.T6G(SCH_1):P5E_CPU1_P3_TX_BUF_DN(15)
  W7 P5E_CPU1_P3_TX_BUF_DP<14> B_PETP1 @T6G_MB_LIB.T6G(SCH_1):P5E_CPU1_P3_TX_BUF_DP(14)
AA10 P5E_CPU1_P3_TX_BUF_DN<14> B_PETN1 @T6G_MB_LIB.T6G(SCH_1):P5E_CPU1_P3_TX_BUF_DN(14)
 AF7 P5E_CPU1_P3_TX_BUF_DP<13> B_PETP2 @T6G_MB_LIB.T6G(SCH_1):P5E_CPU1_P3_TX_BUF_DP(13)
AH10 P5E_CPU1_P3_TX_BUF_DN<13> B_PETN2 @T6G_MB_LIB.T6G(SCH_1):P5E_CPU1_P3_TX_BUF_DN(13)
 AN7 P5E_CPU1_P3_TX_BUF_DP<12> B_PETP3 @T6G_MB_LIB.T6G(SCH_1):P5E_CPU1_P3_TX_BUF_DP(12)
AR10 P5E_CPU1_P3_TX_BUF_DN<12> B_PETN3 @T6G_MB_LIB.T6G(SCH_1):P5E_CPU1_P3_TX_BUF_DN(12)
 AY7 P5E_CPU1_P3_TX_BUF_DP<11> B_PETP4 @T6G_MB_LIB.T6G(SCH_1):P5E_CPU1_P3_TX_BUF_DP(11)
BB10 P5E_CPU1_P3_TX_BUF_DN<11> B_PETN4 @T6G_MB_LIB.T6G(SCH_1):P5E_CPU1_P3_TX_BUF_DN(11)
 BG7 P5E_CPU1_P3_TX_BUF_DP<10> B_PETP5 @T6G_MB_LIB.T6G(SCH_1):P5E_CPU1_P3_TX_BUF_DP(10)
BJ10 P5E_CPU1_P3_TX_BUF_DN<10> B_PETN5 @T6G_MB_LIB.T6G(SCH_1):P5E_CPU1_P3_TX_BUF_DN(10)
 BP7 P5E_CPU1_P3_TX_BUF_DP<9> B_PETP6 @T6G_MB_LIB.T6G(SCH_1):P5E_CPU1_P3_TX_BUF_DP(9)
BT10 P5E_CPU1_P3_TX_BUF_DN<9> B_PETN6 @T6G_MB_LIB.T6G(SCH_1):P5E_CPU1_P3_TX_BUF_DN(9)
 CA7 P5E_CPU1_P3_TX_BUF_DP<8> B_PETP7 @T6G_MB_LIB.T6G(SCH_1):P5E_CPU1_P3_TX_BUF_DP(8)
CC10 P5E_CPU1_P3_TX_BUF_DN<8> B_PETN7 @T6G_MB_LIB.T6G(SCH_1):P5E_CPU1_P3_TX_BUF_DN(8)

Q_CAP_DIFFBUS_C0201-DIFF BUS_0.22UF,6.3V,20%,X6S,SA  I47  C6726
   1 P5E_CPU1_P3_TX_BUF_C_DN<0>      1 @T6G_MB_LIB.T6G(SCH_1):P5E_CPU1_P3_TX_BUF_C_DN(0)
   2 P5E_CPU1_P3_TX_BUF_DN<0>      2 @T6G_MB_LIB.T6G(SCH_1):P5E_CPU1_P3_TX_BUF_DN(0)

Q_CAP_DIFFBUS_C0201-DIFF BUS_0.22UF,6.3V,20%,X6S,SA  I48  C6725
   1 P5E_CPU1_P3_TX_BUF_C_DP<0>      1 @T6G_MB_LIB.T6G(SCH_1):P5E_CPU1_P3_TX_BUF_C_DP(0)
   2 P5E_CPU1_P3_TX_BUF_DP<0>      2 @T6G_MB_LIB.T6G(SCH_1):P5E_CPU1_P3_TX_BUF_DP(0)

Q_CAP_DIFFBUS_C0201-DIFF BUS_0.22UF,6.3V,20%,X6S,SA  I88  C6756
   1 P5E_CPU1_P3_TX_BUF_C_DN<15>      1 @T6G_MB_LIB.T6G(SCH_1):P5E_CPU1_P3_TX_BUF_C_DN(15)
   2 P5E_CPU1_P3_TX_BUF_DN<15>      2 @T6G_MB_LIB.T6G(SCH_1):P5E_CPU1_P3_TX_BUF_DN(15)

Q_CAP_DIFFBUS_C0201-DIFF BUS_0.22UF,6.3V,20%,X6S,SA  I89  C6755
   1 P5E_CPU1_P3_TX_BUF_C_DP<15>      1 @T6G_MB_LIB.T6G(SCH_1):P5E_CPU1_P3_TX_BUF_C_DP(15)
   2 P5E_CPU1_P3_TX_BUF_DP<15>      2 @T6G_MB_LIB.T6G(SCH_1):P5E_CPU1_P3_TX_BUF_DP(15)

Q_CAP_DIFFBUS_C0201-DIFF BUS_0.22UF,6.3V,20%,X6S,SA  I90  C6754
   1 P5E_CPU1_P3_TX_BUF_C_DN<14>      1 @T6G_MB_LIB.T6G(SCH_1):P5E_CPU1_P3_TX_BUF_C_DN(14)
   2 P5E_CPU1_P3_TX_BUF_DN<14>      2 @T6G_MB_LIB.T6G(SCH_1):P5E_CPU1_P3_TX_BUF_DN(14)

Q_CAP_DIFFBUS_C0201-DIFF BUS_0.22UF,6.3V,20%,X6S,SA  I91  C6753
   1 P5E_CPU1_P3_TX_BUF_C_DP<14>      1 @T6G_MB_LIB.T6G(SCH_1):P5E_CPU1_P3_TX_BUF_C_DP(14)
   2 P5E_CPU1_P3_TX_BUF_DP<14>      2 @T6G_MB_LIB.T6G(SCH_1):P5E_CPU1_P3_TX_BUF_DP(14)

Q_CAP_DIFFBUS_C0201-DIFF BUS_0.22UF,6.3V,20%,X6S,SA  I92  C6752
   1 P5E_CPU1_P3_TX_BUF_C_DN<13>      1 @T6G_MB_LIB.T6G(SCH_1):P5E_CPU1_P3_TX_BUF_C_DN(13)
   2 P5E_CPU1_P3_TX_BUF_DN<13>      2 @T6G_MB_LIB.T6G(SCH_1):P5E_CPU1_P3_TX_BUF_DN(13)

Q_CAP_DIFFBUS_C0201-DIFF BUS_0.22UF,6.3V,20%,X6S,SA  I93  C6751
   1 P5E_CPU1_P3_TX_BUF_C_DP<13>      1 @T6G_MB_LIB.T6G(SCH_1):P5E_CPU1_P3_TX_BUF_C_DP(13)
   2 P5E_CPU1_P3_TX_BUF_DP<13>      2 @T6G_MB_LIB.T6G(SCH_1):P5E_CPU1_P3_TX_BUF_DP(13)

Q_CAP_DIFFBUS_C0201-DIFF BUS_0.22UF,6.3V,20%,X6S,SA  I94  C6750
   1 P5E_CPU1_P3_TX_BUF_C_DN<12>      1 @T6G_MB_LIB.T6G(SCH_1):P5E_CPU1_P3_TX_BUF_C_DN(12)
   2 P5E_CPU1_P3_TX_BUF_DN<12>      2 @T6G_MB_LIB.T6G(SCH_1):P5E_CPU1_P3_TX_BUF_DN(12)

Q_CAP_DIFFBUS_C0201-DIFF BUS_0.22UF,6.3V,20%,X6S,SA  I95  C6749
   1 P5E_CPU1_P3_TX_BUF_C_DP<12>      1 @T6G_MB_LIB.T6G(SCH_1):P5E_CPU1_P3_TX_BUF_C_DP(12)
   2 P5E_CPU1_P3_TX_BUF_DP<12>      2 @T6G_MB_LIB.T6G(SCH_1):P5E_CPU1_P3_TX_BUF_DP(12)

Q_CAP_DIFFBUS_C0201-DIFF BUS_0.22UF,6.3V,20%,X6S,SA  I96  C6748
   1 P5E_CPU1_P3_TX_BUF_C_DN<11>      1 @T6G_MB_LIB.T6G(SCH_1):P5E_CPU1_P3_TX_BUF_C_DN(11)
   2 P5E_CPU1_P3_TX_BUF_DN<11>      2 @T6G_MB_LIB.T6G(SCH_1):P5E_CPU1_P3_TX_BUF_DN(11)

Q_CAP_DIFFBUS_C0201-DIFF BUS_0.22UF,6.3V,20%,X6S,SA  I97  C6747
   1 P5E_CPU1_P3_TX_BUF_C_DP<11>      1 @T6G_MB_LIB.T6G(SCH_1):P5E_CPU1_P3_TX_BUF_C_DP(11)
   2 P5E_CPU1_P3_TX_BUF_DP<11>      2 @T6G_MB_LIB.T6G(SCH_1):P5E_CPU1_P3_TX_BUF_DP(11)

Q_CAP_DIFFBUS_C0201-DIFF BUS_0.22UF,6.3V,20%,X6S,SA  I98  C6746
   1 P5E_CPU1_P3_TX_BUF_C_DN<10>      1 @T6G_MB_LIB.T6G(SCH_1):P5E_CPU1_P3_TX_BUF_C_DN(10)
   2 P5E_CPU1_P3_TX_BUF_DN<10>      2 @T6G_MB_LIB.T6G(SCH_1):P5E_CPU1_P3_TX_BUF_DN(10)

Q_CAP_DIFFBUS_C0201-DIFF BUS_0.22UF,6.3V,20%,X6S,SA  I99  C6745
   1 P5E_CPU1_P3_TX_BUF_C_DP<10>      1 @T6G_MB_LIB.T6G(SCH_1):P5E_CPU1_P3_TX_BUF_C_DP(10)
   2 P5E_CPU1_P3_TX_BUF_DP<10>      2 @T6G_MB_LIB.T6G(SCH_1):P5E_CPU1_P3_TX_BUF_DP(10)

Q_CAP_DIFFBUS_C0201-DIFF BUS_0.22UF,6.3V,20%,X6S,SA  I100  C6744
   1 P5E_CPU1_P3_TX_BUF_C_DN<9>      1 @T6G_MB_LIB.T6G(SCH_1):P5E_CPU1_P3_TX_BUF_C_DN(9)
   2 P5E_CPU1_P3_TX_BUF_DN<9>      2 @T6G_MB_LIB.T6G(SCH_1):P5E_CPU1_P3_TX_BUF_DN(9)

Q_CAP_DIFFBUS_C0201-DIFF BUS_0.22UF,6.3V,20%,X6S,SA  I101  C6743
   1 P5E_CPU1_P3_TX_BUF_C_DP<9>      1 @T6G_MB_LIB.T6G(SCH_1):P5E_CPU1_P3_TX_BUF_C_DP(9)
   2 P5E_CPU1_P3_TX_BUF_DP<9>      2 @T6G_MB_LIB.T6G(SCH_1):P5E_CPU1_P3_TX_BUF_DP(9)

Q_CAP_DIFFBUS_C0201-DIFF BUS_0.22UF,6.3V,20%,X6S,SA  I104  C6742
   1 P5E_CPU1_P3_TX_BUF_C_DN<8>      1 @T6G_MB_LIB.T6G(SCH_1):P5E_CPU1_P3_TX_BUF_C_DN(8)
   2 P5E_CPU1_P3_TX_BUF_DN<8>      2 @T6G_MB_LIB.T6G(SCH_1):P5E_CPU1_P3_TX_BUF_DN(8)

Q_CAP_DIFFBUS_C0201-DIFF BUS_0.22UF,6.3V,20%,X6S,SA  I105  C6741
   1 P5E_CPU1_P3_TX_BUF_C_DP<8>      1 @T6G_MB_LIB.T6G(SCH_1):P5E_CPU1_P3_TX_BUF_C_DP(8)
   2 P5E_CPU1_P3_TX_BUF_DP<8>      2 @T6G_MB_LIB.T6G(SCH_1):P5E_CPU1_P3_TX_BUF_DP(8)

PT5161LRS-PT5161LRS,SMLF,IC,AJ051610U03  I142  U6017
 CH7 P5E_CPU1_P3_TX_BUF_DP<7> B_PETP8 @T6G_MB_LIB.T6G(SCH_1):P5E_CPU1_P3_TX_BUF_DP(7)
CK10 P5E_CPU1_P3_TX_BUF_DN<7> B_PETN8 @T6G_MB_LIB.T6G(SCH_1):P5E_CPU1_P3_TX_BUF_DN(7)
 CR7 P5E_CPU1_P3_TX_BUF_DP<6> B_PETP9 @T6G_MB_LIB.T6G(SCH_1):P5E_CPU1_P3_TX_BUF_DP(6)
CU10 P5E_CPU1_P3_TX_BUF_DN<6> B_PETN9 @T6G_MB_LIB.T6G(SCH_1):P5E_CPU1_P3_TX_BUF_DN(6)
 DB7 P5E_CPU1_P3_TX_BUF_DP<5> B_PETP10 @T6G_MB_LIB.T6G(SCH_1):P5E_CPU1_P3_TX_BUF_DP(5)
DD10 P5E_CPU1_P3_TX_BUF_DN<5> B_PETN10 @T6G_MB_LIB.T6G(SCH_1):P5E_CPU1_P3_TX_BUF_DN(5)
 DJ7 P5E_CPU1_P3_TX_BUF_DP<4> B_PETP11 @T6G_MB_LIB.T6G(SCH_1):P5E_CPU1_P3_TX_BUF_DP(4)
DL10 P5E_CPU1_P3_TX_BUF_DN<4> B_PETN11 @T6G_MB_LIB.T6G(SCH_1):P5E_CPU1_P3_TX_BUF_DN(4)
 DT7 P5E_CPU1_P3_TX_BUF_DP<3> B_PETP12 @T6G_MB_LIB.T6G(SCH_1):P5E_CPU1_P3_TX_BUF_DP(3)
DV10 P5E_CPU1_P3_TX_BUF_DN<3> B_PETN12 @T6G_MB_LIB.T6G(SCH_1):P5E_CPU1_P3_TX_BUF_DN(3)
 EC7 P5E_CPU1_P3_TX_BUF_DP<2> B_PETP13 @T6G_MB_LIB.T6G(SCH_1):P5E_CPU1_P3_TX_BUF_DP(2)
EE10 P5E_CPU1_P3_TX_BUF_DN<2> B_PETN13 @T6G_MB_LIB.T6G(SCH_1):P5E_CPU1_P3_TX_BUF_DN(2)
 EK7 P5E_CPU1_P3_TX_BUF_DP<1> B_PETP14 @T6G_MB_LIB.T6G(SCH_1):P5E_CPU1_P3_TX_BUF_DP(1)
EM10 P5E_CPU1_P3_TX_BUF_DN<1> B_PETN14 @T6G_MB_LIB.T6G(SCH_1):P5E_CPU1_P3_TX_BUF_DN(1)
 EU7 P5E_CPU1_P3_TX_BUF_DP<0> B_PETP15 @T6G_MB_LIB.T6G(SCH_1):P5E_CPU1_P3_TX_BUF_DP(0)
EW10 P5E_CPU1_P3_TX_BUF_DN<0> B_PETN15 @T6G_MB_LIB.T6G(SCH_1):P5E_CPU1_P3_TX_BUF_DN(0)


DRAWING: @T6G_MB_LIB.T6G(SCH_1):PAGE160 

Q_RES_0402LF-4.75K,1%,1/16W,EMPTY,CS24752FB03  I2  R4490
   1 CLK_9ZXL045_P0_SADR0      A @T6G_MB_LIB.T6G(SCH_1):CLK_9ZXL045_P0_SADR0
   2    GND      B @T6G_MB_LIB.T6G(SCH_1):GND

Q_RES_0402LF-4.75K,1%,1/16W,CHIP,CS24752FB03  I3  R4489
   1 P3V3_AUX      A @T6G_MB_LIB.T6G(SCH_1):P3V3_AUX
   2 CLK_9ZXL045_P0_SADR0      B @T6G_MB_LIB.T6G(SCH_1):CLK_9ZXL045_P0_SADR0

Q_RES_0603LF-1,1%,1/10W,CHIP,CS-1003F900  I6  R4475
   1 P3V3_9ZXL045_P0      A @T6G_MB_LIB.T6G(SCH_1):P3V3_9ZXL045_P0
   2 P3V3_9ZXL045_P0_VDDR      B @T6G_MB_LIB.T6G(SCH_1):P3V3_9ZXL045_P0_VDDR

Q_CAP_0402-0.1UF,25V,10%,X7R,CH4104K1B00  I18  C78
   1 P3V3_9ZXL045_P0_VDDR      A @T6G_MB_LIB.T6G(SCH_1):P3V3_9ZXL045_P0_VDDR
   2    GND      B @T6G_MB_LIB.T6G(SCH_1):GND

Q_CAP_0402-0.1UF,25V,10%,X7R,CH4104K1B00  I20  C2334
   1 P3V3_9ZXL045_P0_VDDA      A @T6G_MB_LIB.T6G(SCH_1):P3V3_9ZXL045_P0_VDDA
   2    GND      B @T6G_MB_LIB.T6G(SCH_1):GND

Q_INDUCTOR_SMLF-FCM2012KF-601T/0.5A,IND,CX601T05003  I24  L20
   2 P3V3_9ZXL045_P0_VDD      2 @T6G_MB_LIB.T6G(SCH_1):P3V3_9ZXL045_P0_VDD
   1 P3V3_AUX      1 @T6G_MB_LIB.T6G(SCH_1):P3V3_AUX

Q_INDUCTOR_SMLF-FCM2012KF-601T/0.5A,IND,CX601T05003  I26  L19
   2 P3V3_9ZXL045_P0      2 @T6G_MB_LIB.T6G(SCH_1):P3V3_9ZXL045_P0
   1 P3V3_AUX      1 @T6G_MB_LIB.T6G(SCH_1):P3V3_AUX

Q_RES_0603LF-1,1%,1/10W,CHIP,CS-1003F900  I27  R4493
   1 P3V3_9ZXL045_P0      A @T6G_MB_LIB.T6G(SCH_1):P3V3_9ZXL045_P0
   2 P3V3_9ZXL045_P0_VDDA      B @T6G_MB_LIB.T6G(SCH_1):P3V3_9ZXL045_P0_VDDA

Q_RES_0402LF-10K,1%,1/16W,CHIP,CS31002FB08  I29  R4492
   1 CLK_9ZXL045_P0_HIBW      A @T6G_MB_LIB.T6G(SCH_1):CLK_9ZXL045_P0_HIBW
   2    GND      B @T6G_MB_LIB.T6G(SCH_1):GND

Q_RES_0402LF-10K,1%,1/16W,CHIP,CS31002FB08  I31  R4491
   1 P3V3_AUX      A @T6G_MB_LIB.T6G(SCH_1):P3V3_AUX
   2 CLK_9ZXL045_P0_HIBW      B @T6G_MB_LIB.T6G(SCH_1):CLK_9ZXL045_P0_HIBW

Q_CAP_0402-0.1UF,25V,10%,X7R,CH4104K1B00  I40  C2329
   1 P3V3_9ZXL045_P0_VDD      A @T6G_MB_LIB.T6G(SCH_1):P3V3_9ZXL045_P0_VDD
   2    GND      B @T6G_MB_LIB.T6G(SCH_1):GND

Q_CAP_0402-0.1UF,25V,10%,X7R,CH4104K1B00  I41  C79
   1 P3V3_9ZXL045_P0_VDD      A @T6G_MB_LIB.T6G(SCH_1):P3V3_9ZXL045_P0_VDD
   2    GND      B @T6G_MB_LIB.T6G(SCH_1):GND

Q_CAP_0402-0.1UF,25V,10%,X7R,CH4104K1B00  I44  C80
   1 P3V3_9ZXL045_P0_VDD      A @T6G_MB_LIB.T6G(SCH_1):P3V3_9ZXL045_P0_VDD
   2    GND      B @T6G_MB_LIB.T6G(SCH_1):GND

Q_CAP_0402-0.1UF,25V,10%,X7R,CH4104K1B00  I45  C81
   1 P3V3_9ZXL045_P0_VDD      A @T6G_MB_LIB.T6G(SCH_1):P3V3_9ZXL045_P0_VDD
   2    GND      B @T6G_MB_LIB.T6G(SCH_1):GND

Q_CAP_0402-0.1UF,25V,10%,X7R,CH4104K1B00  I47  C2339
   1 P3V3_9ZXL045_P0_VDD      A @T6G_MB_LIB.T6G(SCH_1):P3V3_9ZXL045_P0_VDD
   2    GND      B @T6G_MB_LIB.T6G(SCH_1):GND

Q_RES_0402LF-10K,1%,1/16W,CHIP,CS31002FB08  I52  R4518
   1 FM_9ZXL045_P0_2_OE_N      A @T6G_MB_LIB.T6G(SCH_1):FM_9ZXL045_P0_2_OE_N
   2    GND      B @T6G_MB_LIB.T6G(SCH_1):GND

Q_RES_0402LF-10K,1%,1/16W,CHIP,CS31002FB08  I53  R4519
   1 FM_9ZXL045_P0_1_OE_N      A @T6G_MB_LIB.T6G(SCH_1):FM_9ZXL045_P0_1_OE_N
   2    GND      B @T6G_MB_LIB.T6G(SCH_1):GND

Q_RES_0402LF-10K,1%,1/16W,CHIP,CS31002FB08  I55  R4520
   1 FM_9ZXL045_P0_0_OE_N      A @T6G_MB_LIB.T6G(SCH_1):FM_9ZXL045_P0_0_OE_N
   2    GND      B @T6G_MB_LIB.T6G(SCH_1):GND

9ZXL0451EKILFT-9ZXL0451EKILFT,SMLF,IC,AL000451003  I63  U314
   3 CLK_100M_CPU0_CLK13_DP DIF_IN @T6G_MB_LIB.T6G(SCH_1):CLK_100M_CPU0_CLK13_DP
   4 CLK_100M_CPU0_CLK13_DN DIF_IN# @T6G_MB_LIB.T6G(SCH_1):CLK_100M_CPU0_CLK13_DN
   2 P3V3_9ZXL045_P0_VDDR   VDDR @T6G_MB_LIB.T6G(SCH_1):P3V3_9ZXL045_P0_VDDR
  25 P3V3_9ZXL045_P0_VDD   VDD3 @T6G_MB_LIB.T6G(SCH_1):P3V3_9ZXL045_P0_VDD
  29 P3V3_9ZXL045_P0_VDD   VDD4 @T6G_MB_LIB.T6G(SCH_1):P3V3_9ZXL045_P0_VDD
   9 NC_U314_FBOUT FBOUT_NC @T6G_MB_LIB.T6G(SCH_1):NC_U314_FBOUT
  15 FM_9ZXL045_P0_0_OE_N  VOE0# @T6G_MB_LIB.T6G(SCH_1):FM_9ZXL045_P0_0_OE_N
  26 FM_9ZXL045_P0_3_OE_N  VOE3# @T6G_MB_LIB.T6G(SCH_1):FM_9ZXL045_P0_3_OE_N
   6 SMB_9ZXL045_P0_SDA SMBDAT @T6G_MB_LIB.T6G(SCH_1):SMB_9ZXL045_P0_SDA
  11 NC_U314_NC1    NC1 @T6G_MB_LIB.T6G(SCH_1):NC_U314_NC1
   8 NC_U314_FBOUT_N FBOUT_NC# @T6G_MB_LIB.T6G(SCH_1):NC_U314_FBOUT_N
   7 SMB_9ZXL045_P0_SCL SMBCLK @T6G_MB_LIB.T6G(SCH_1):SMB_9ZXL045_P0_SCL
  21 P3V3_9ZXL045_P0_VDD   VDD2 @T6G_MB_LIB.T6G(SCH_1):P3V3_9ZXL045_P0_VDD
   1 FM_9ZXL045_P0_DEV_EN ^CKPWRGD_PD# @T6G_MB_LIB.T6G(SCH_1):FM_9ZXL045_P0_DEV_EN
  14 CLK_100M_RETIMER_CPU0_P0_R_DN  DIF0# @T6G_MB_LIB.T6G(SCH_1):CLK_100M_RETIMER_CPU0_P0_R_DN
  13 CLK_100M_RETIMER_CPU0_P0_R_DP   DIF0 @T6G_MB_LIB.T6G(SCH_1):CLK_100M_RETIMER_CPU0_P0_R_DP
  18 FM_9ZXL045_P0_1_OE_N  VOE1# @T6G_MB_LIB.T6G(SCH_1):FM_9ZXL045_P0_1_OE_N
  20 CLK_100M_RETIMER_CPU0_P1_R_DN  DIF1# @T6G_MB_LIB.T6G(SCH_1):CLK_100M_RETIMER_CPU0_P1_R_DN
  22 CLK_100M_RETIMER_CPU0_P2_R_DP   DIF2 @T6G_MB_LIB.T6G(SCH_1):CLK_100M_RETIMER_CPU0_P2_R_DP
  24 FM_9ZXL045_P0_2_OE_N  VOE2# @T6G_MB_LIB.T6G(SCH_1):FM_9ZXL045_P0_2_OE_N
  23 CLK_100M_RETIMER_CPU0_P2_R_DN  DIF2# @T6G_MB_LIB.T6G(SCH_1):CLK_100M_RETIMER_CPU0_P2_R_DN
  28 CLK_100M_RETIMER_CPU0_P3_R_DN  DIF3# @T6G_MB_LIB.T6G(SCH_1):CLK_100M_RETIMER_CPU0_P3_R_DN
  10 NC_U314_NC0    NC0 @T6G_MB_LIB.T6G(SCH_1):NC_U314_NC0
  31 P3V3_9ZXL045_P0_VDDA   VDDA @T6G_MB_LIB.T6G(SCH_1):P3V3_9ZXL045_P0_VDDA
  16 P3V3_9ZXL045_P0_VDD   VDD1 @T6G_MB_LIB.T6G(SCH_1):P3V3_9ZXL045_P0_VDD
  32 CLK_9ZXL045_P0_HIBW ^HIBW_BYPM_LOBW# @T6G_MB_LIB.T6G(SCH_1):CLK_9ZXL045_P0_HIBW
  33    GND EPAD_GND @T6G_MB_LIB.T6G(SCH_1):GND
  19 CLK_100M_RETIMER_CPU0_P1_R_DP   DIF1 @T6G_MB_LIB.T6G(SCH_1):CLK_100M_RETIMER_CPU0_P1_R_DP
  27 CLK_100M_RETIMER_CPU0_P3_R_DP   DIF3 @T6G_MB_LIB.T6G(SCH_1):CLK_100M_RETIMER_CPU0_P3_R_DP
  12 P3V3_9ZXL045_P0_VDD   VDD0 @T6G_MB_LIB.T6G(SCH_1):P3V3_9ZXL045_P0_VDD
  30 NC_U314_NC3    NC3 @T6G_MB_LIB.T6G(SCH_1):NC_U314_NC3
  17 NC_U314_NC2    NC2 @T6G_MB_LIB.T6G(SCH_1):NC_U314_NC2
   5 CLK_9ZXL045_P0_SADR0 VSADR0_TRI @T6G_MB_LIB.T6G(SCH_1):CLK_9ZXL045_P0_SADR0

Q_RES_0402LF-10K,1%,1/16W,CHIP,CS31002FB08  I68  R6802
   1 FM_9ZXL045_P0_3_OE_N      A @T6G_MB_LIB.T6G(SCH_1):FM_9ZXL045_P0_3_OE_N
   2    GND      B @T6G_MB_LIB.T6G(SCH_1):GND

Q_CAP_C0402-10UF,6.3V,20%,X6S,CH6101MEB01  I69  C76
   1 P3V3_9ZXL045_P0_VDDA      A @T6G_MB_LIB.T6G(SCH_1):P3V3_9ZXL045_P0_VDDA
   2    GND      B @T6G_MB_LIB.T6G(SCH_1):GND

Q_CAP_C0402-10UF,6.3V,20%,X6S,CH6101MEB01  I70  C77
   1 P3V3_9ZXL045_P0_VDDR      A @T6G_MB_LIB.T6G(SCH_1):P3V3_9ZXL045_P0_VDDR
   2    GND      B @T6G_MB_LIB.T6G(SCH_1):GND

Q_CAP_C0402-10UF,6.3V,20%,X6S,CH6101MEB01  I71  C2328
   1 P3V3_9ZXL045_P0_VDD      A @T6G_MB_LIB.T6G(SCH_1):P3V3_9ZXL045_P0_VDD
   2    GND      B @T6G_MB_LIB.T6G(SCH_1):GND

Q_RES_0402LF-10K,1%,1/16W,CHIP,CS31002FB08  I73  R4476
   1 P3V3_AUX      A @T6G_MB_LIB.T6G(SCH_1):P3V3_AUX
   2 FM_9ZXL045_P0_DEV_EN      B @T6G_MB_LIB.T6G(SCH_1):FM_9ZXL045_P0_DEV_EN


DRAWING: @T6G_MB_LIB.T6G(SCH_1):PAGE379 

Q_INDUCTOR_SMLF-FCM2012KF-601T/0.5A,IND,CX601T05003  I2  L1
   2 P3V3_9ZXL045_P1      2 @T6G_MB_LIB.T6G(SCH_1):P3V3_9ZXL045_P1
   1 P3V3_AUX      1 @T6G_MB_LIB.T6G(SCH_1):P3V3_AUX

Q_RES_0402LF-10K,1%,1/16W,CHIP,CS31002FB08  I15  R585
   1 CLK_9ZXL045_P1_HIBW      A @T6G_MB_LIB.T6G(SCH_1):CLK_9ZXL045_P1_HIBW
   2    GND      B @T6G_MB_LIB.T6G(SCH_1):GND

Q_RES_0402LF-10K,1%,1/16W,CHIP,CS31002FB08  I17  R580
   1 P3V3_AUX      A @T6G_MB_LIB.T6G(SCH_1):P3V3_AUX
   2 CLK_9ZXL045_P1_HIBW      B @T6G_MB_LIB.T6G(SCH_1):CLK_9ZXL045_P1_HIBW

Q_RES_0603LF-1,1%,1/10W,CHIP,CS-1003F900  I20  R555
   1 P3V3_9ZXL045_P1      A @T6G_MB_LIB.T6G(SCH_1):P3V3_9ZXL045_P1
   2 P3V3_9ZXL045_P1_VDDR      B @T6G_MB_LIB.T6G(SCH_1):P3V3_9ZXL045_P1_VDDR

Q_RES_0603LF-1,1%,1/10W,CHIP,CS-1003F900  I21  R586
   1 P3V3_9ZXL045_P1      A @T6G_MB_LIB.T6G(SCH_1):P3V3_9ZXL045_P1
   2 P3V3_9ZXL045_P1_VDDA      B @T6G_MB_LIB.T6G(SCH_1):P3V3_9ZXL045_P1_VDDA

Q_CAP_0402-0.1UF,25V,10%,X7R,CH4104K1B00  I24  C68
   1 P3V3_9ZXL045_P1_VDDA      A @T6G_MB_LIB.T6G(SCH_1):P3V3_9ZXL045_P1_VDDA
   2    GND      B @T6G_MB_LIB.T6G(SCH_1):GND

Q_CAP_0402-0.1UF,25V,10%,X7R,CH4104K1B00  I26  C84
   1 P3V3_9ZXL045_P1_VDDR      A @T6G_MB_LIB.T6G(SCH_1):P3V3_9ZXL045_P1_VDDR
   2    GND      B @T6G_MB_LIB.T6G(SCH_1):GND

Q_INDUCTOR_SMLF-FCM2012KF-601T/0.5A,IND,CX601T05003  I32  L2
   2 P3V3_9ZXL045_P1_VDD      2 @T6G_MB_LIB.T6G(SCH_1):P3V3_9ZXL045_P1_VDD
   1 P3V3_AUX      1 @T6G_MB_LIB.T6G(SCH_1):P3V3_AUX

Q_CAP_0402-0.1UF,25V,10%,X7R,CH4104K1B00  I34  C58
   1 P3V3_9ZXL045_P1_VDD      A @T6G_MB_LIB.T6G(SCH_1):P3V3_9ZXL045_P1_VDD
   2    GND      B @T6G_MB_LIB.T6G(SCH_1):GND

Q_CAP_0402-0.1UF,25V,10%,X7R,CH4104K1B00  I35  C90
   1 P3V3_9ZXL045_P1_VDD      A @T6G_MB_LIB.T6G(SCH_1):P3V3_9ZXL045_P1_VDD
   2    GND      B @T6G_MB_LIB.T6G(SCH_1):GND

Q_CAP_0402-0.1UF,25V,10%,X7R,CH4104K1B00  I36  C98
   1 P3V3_9ZXL045_P1_VDD      A @T6G_MB_LIB.T6G(SCH_1):P3V3_9ZXL045_P1_VDD
   2    GND      B @T6G_MB_LIB.T6G(SCH_1):GND

Q_RES_0402LF-10K,1%,1/16W,CHIP,CS31002FB08  I49  R592
   1 FM_9ZXL045_P1_2_OE_N      A @T6G_MB_LIB.T6G(SCH_1):FM_9ZXL045_P1_2_OE_N
   2    GND      B @T6G_MB_LIB.T6G(SCH_1):GND

Q_RES_0402LF-10K,1%,1/16W,CHIP,CS31002FB08  I50  R593
   1 FM_9ZXL045_P1_1_OE_N      A @T6G_MB_LIB.T6G(SCH_1):FM_9ZXL045_P1_1_OE_N
   2    GND      B @T6G_MB_LIB.T6G(SCH_1):GND

Q_RES_0402LF-10K,1%,1/16W,CHIP,CS31002FB08  I51  R594
   1 FM_9ZXL045_P1_0_OE_N      A @T6G_MB_LIB.T6G(SCH_1):FM_9ZXL045_P1_0_OE_N
   2    GND      B @T6G_MB_LIB.T6G(SCH_1):GND

Q_CAP_0402-0.1UF,25V,10%,X7R,CH4104K1B00  I58  C99
   1 P3V3_9ZXL045_P1_VDD      A @T6G_MB_LIB.T6G(SCH_1):P3V3_9ZXL045_P1_VDD
   2    GND      B @T6G_MB_LIB.T6G(SCH_1):GND

Q_CAP_0402-0.1UF,25V,10%,X7R,CH4104K1B00  I60  C75
   1 P3V3_9ZXL045_P1_VDD      A @T6G_MB_LIB.T6G(SCH_1):P3V3_9ZXL045_P1_VDD
   2    GND      B @T6G_MB_LIB.T6G(SCH_1):GND

9ZXL0451EKILFT-9ZXL0451EKILFT,SMLF,IC,AL000451003  I63  U10
   3 CLK_100M_CPU1_CLK13_DP DIF_IN @T6G_MB_LIB.T6G(SCH_1):CLK_100M_CPU1_CLK13_DP
   4 CLK_100M_CPU1_CLK13_DN DIF_IN# @T6G_MB_LIB.T6G(SCH_1):CLK_100M_CPU1_CLK13_DN
   2 P3V3_9ZXL045_P1_VDDR   VDDR @T6G_MB_LIB.T6G(SCH_1):P3V3_9ZXL045_P1_VDDR
  25 P3V3_9ZXL045_P1_VDD   VDD3 @T6G_MB_LIB.T6G(SCH_1):P3V3_9ZXL045_P1_VDD
  29 P3V3_9ZXL045_P1_VDD   VDD4 @T6G_MB_LIB.T6G(SCH_1):P3V3_9ZXL045_P1_VDD
   9 NC_U10_FBOUT FBOUT_NC @T6G_MB_LIB.T6G(SCH_1):NC_U10_FBOUT
  15 FM_9ZXL045_P1_0_OE_N  VOE0# @T6G_MB_LIB.T6G(SCH_1):FM_9ZXL045_P1_0_OE_N
  26 FM_9ZXL045_P1_3_OE_N  VOE3# @T6G_MB_LIB.T6G(SCH_1):FM_9ZXL045_P1_3_OE_N
   6 SMB_9ZXL045_P1_SDA SMBDAT @T6G_MB_LIB.T6G(SCH_1):SMB_9ZXL045_P1_SDA
  11 NC_U10_NC1    NC1 @T6G_MB_LIB.T6G(SCH_1):NC_U10_NC1
   8 NC_U10_FBOUT_N FBOUT_NC# @T6G_MB_LIB.T6G(SCH_1):NC_U10_FBOUT_N
   7 SMB_9ZXL045_P1_SCL SMBCLK @T6G_MB_LIB.T6G(SCH_1):SMB_9ZXL045_P1_SCL
  21 P3V3_9ZXL045_P1_VDD   VDD2 @T6G_MB_LIB.T6G(SCH_1):P3V3_9ZXL045_P1_VDD
   1 FM_9ZXL045_P1_DEV_EN ^CKPWRGD_PD# @T6G_MB_LIB.T6G(SCH_1):FM_9ZXL045_P1_DEV_EN
  14 CLK_100M_RETIMER_CPU1_P0_R_DN  DIF0# @T6G_MB_LIB.T6G(SCH_1):CLK_100M_RETIMER_CPU1_P0_R_DN
  13 CLK_100M_RETIMER_CPU1_P0_R_DP   DIF0 @T6G_MB_LIB.T6G(SCH_1):CLK_100M_RETIMER_CPU1_P0_R_DP
  18 FM_9ZXL045_P1_1_OE_N  VOE1# @T6G_MB_LIB.T6G(SCH_1):FM_9ZXL045_P1_1_OE_N
  20 CLK_100M_RETIMER_CPU1_P1_R_DN  DIF1# @T6G_MB_LIB.T6G(SCH_1):CLK_100M_RETIMER_CPU1_P1_R_DN
  22 CLK_100M_RETIMER_CPU1_P2_R_DP   DIF2 @T6G_MB_LIB.T6G(SCH_1):CLK_100M_RETIMER_CPU1_P2_R_DP
  24 FM_9ZXL045_P1_2_OE_N  VOE2# @T6G_MB_LIB.T6G(SCH_1):FM_9ZXL045_P1_2_OE_N
  23 CLK_100M_RETIMER_CPU1_P2_R_DN  DIF2# @T6G_MB_LIB.T6G(SCH_1):CLK_100M_RETIMER_CPU1_P2_R_DN
  28 CLK_100M_RETIMER_CPU1_P3_R_DN  DIF3# @T6G_MB_LIB.T6G(SCH_1):CLK_100M_RETIMER_CPU1_P3_R_DN
  10 NC_U10_NC0    NC0 @T6G_MB_LIB.T6G(SCH_1):NC_U10_NC0
  31 P3V3_9ZXL045_P1_VDDA   VDDA @T6G_MB_LIB.T6G(SCH_1):P3V3_9ZXL045_P1_VDDA
  16 P3V3_9ZXL045_P1_VDD   VDD1 @T6G_MB_LIB.T6G(SCH_1):P3V3_9ZXL045_P1_VDD
  32 CLK_9ZXL045_P1_HIBW ^HIBW_BYPM_LOBW# @T6G_MB_LIB.T6G(SCH_1):CLK_9ZXL045_P1_HIBW
  33    GND EPAD_GND @T6G_MB_LIB.T6G(SCH_1):GND
  19 CLK_100M_RETIMER_CPU1_P1_R_DP   DIF1 @T6G_MB_LIB.T6G(SCH_1):CLK_100M_RETIMER_CPU1_P1_R_DP
  27 CLK_100M_RETIMER_CPU1_P3_R_DP   DIF3 @T6G_MB_LIB.T6G(SCH_1):CLK_100M_RETIMER_CPU1_P3_R_DP
  12 P3V3_9ZXL045_P1_VDD   VDD0 @T6G_MB_LIB.T6G(SCH_1):P3V3_9ZXL045_P1_VDD
  30 NC_U10_NC3    NC3 @T6G_MB_LIB.T6G(SCH_1):NC_U10_NC3
  17 NC_U10_NC2    NC2 @T6G_MB_LIB.T6G(SCH_1):NC_U10_NC2
   5 CLK_9ZXL045_P1_SADR0 VSADR0_TRI @T6G_MB_LIB.T6G(SCH_1):CLK_9ZXL045_P1_SADR0

Q_RES_0402LF-4.75K,1%,1/16W,CHIP,CS24752FB03  I64  R579
   1 CLK_9ZXL045_P1_SADR0      A @T6G_MB_LIB.T6G(SCH_1):CLK_9ZXL045_P1_SADR0
   2    GND      B @T6G_MB_LIB.T6G(SCH_1):GND

Q_RES_0402LF-4.75K,1%,1/16W,EMPTY,CS24752FB03  I65  R578
   1 P3V3_AUX      A @T6G_MB_LIB.T6G(SCH_1):P3V3_AUX
   2 CLK_9ZXL045_P1_SADR0      B @T6G_MB_LIB.T6G(SCH_1):CLK_9ZXL045_P1_SADR0

Q_RES_0402LF-10K,1%,1/16W,CHIP,CS31002FB08  I76  R6803
   1 FM_9ZXL045_P1_3_OE_N      A @T6G_MB_LIB.T6G(SCH_1):FM_9ZXL045_P1_3_OE_N
   2    GND      B @T6G_MB_LIB.T6G(SCH_1):GND

Q_CAP_C0402-10UF,6.3V,20%,X6S,CH6101MEB01  I77  C82
   1 P3V3_9ZXL045_P1_VDDA      A @T6G_MB_LIB.T6G(SCH_1):P3V3_9ZXL045_P1_VDDA
   2    GND      B @T6G_MB_LIB.T6G(SCH_1):GND

Q_CAP_C0402-10UF,6.3V,20%,X6S,CH6101MEB01  I78  C83
   1 P3V3_9ZXL045_P1_VDDR      A @T6G_MB_LIB.T6G(SCH_1):P3V3_9ZXL045_P1_VDDR
   2    GND      B @T6G_MB_LIB.T6G(SCH_1):GND

Q_CAP_C0402-10UF,6.3V,20%,X6S,CH6101MEB01  I79  C28
   1 P3V3_9ZXL045_P1_VDD      A @T6G_MB_LIB.T6G(SCH_1):P3V3_9ZXL045_P1_VDD
   2    GND      B @T6G_MB_LIB.T6G(SCH_1):GND

Q_RES_0402LF-10K,1%,1/16W,CHIP,CS31002FB08  I81  R560
   1 P3V3_AUX      A @T6G_MB_LIB.T6G(SCH_1):P3V3_AUX
   2 FM_9ZXL045_P1_DEV_EN      B @T6G_MB_LIB.T6G(SCH_1):FM_9ZXL045_P1_DEV_EN


DRAWING: @T6G_MB_LIB.T6G(SCH_1):PAGE419 

Q_RES_0201LF-10K,1%,1/20W,CHIP,CS31001FE17  I7  R1070
   1 GPIO2_RT_CPU0_P2      A @T6G_MB_LIB.T6G(SCH_1):GPIO2_RT_CPU0_P2
   2    GND      B @T6G_MB_LIB.T6G(SCH_1):GND

Q_RES_0201LF-4.7K,5%,1/20W,CHIP,CS24701JE04  I9  R1074
   1 TEST0_RT_CPU0_P2      A @T6G_MB_LIB.T6G(SCH_1):TEST0_RT_CPU0_P2
   2    GND      B @T6G_MB_LIB.T6G(SCH_1):GND

Q_RES_0201LF-4.7K,5%,1/20W,EMPTY,CS24701JE04  I5  R1063
   1 P1V8_CPU0_RT_1D      A @T6G_MB_LIB.T6G(SCH_1):P1V8_CPU0_RT_1D
   2 RT_CPU0_P2_SCAN_MODE      B @T6G_MB_LIB.T6G(SCH_1):RT_CPU0_P2_SCAN_MODE

Q_RES_0201LF-10K,1%,1/20W,CHIP,CS31001FE17  I8  R1072
   1 GPIO3_RT_CPU0_P2      A @T6G_MB_LIB.T6G(SCH_1):GPIO3_RT_CPU0_P2
   2    GND      B @T6G_MB_LIB.T6G(SCH_1):GND

Q_RES_0201LF-4.7K,5%,1/20W,EMPTY,CS24701JE04  I10  R1069
   1 P1V8_CPU0_RT_1D      A @T6G_MB_LIB.T6G(SCH_1):P1V8_CPU0_RT_1D
   2 GPIO2_RT_CPU0_P2      B @T6G_MB_LIB.T6G(SCH_1):GPIO2_RT_CPU0_P2

Q_RES_0201LF-4.7K,5%,1/20W,EMPTY,CS24701JE04  I11  R1073
   1 P1V8_CPU0_RT_1D      A @T6G_MB_LIB.T6G(SCH_1):P1V8_CPU0_RT_1D
   2 TEST0_RT_CPU0_P2      B @T6G_MB_LIB.T6G(SCH_1):TEST0_RT_CPU0_P2

Q_RES_0201LF-51.1,1%,1/20W,EMPTY,CS05111FE00  I17  R631
   1 CLK_100M_RETIMER_CPU0_P2_DN      A @T6G_MB_LIB.T6G(SCH_1):CLK_100M_RETIMER_CPU0_P2_DN
   2    GND      B @T6G_MB_LIB.T6G(SCH_1):GND

Q_RES_0201LF-51.1,1%,1/20W,EMPTY,CS05111FE00  I18  R634
   1 CLK_100M_RETIMER_CPU0_P2_DP      A @T6G_MB_LIB.T6G(SCH_1):CLK_100M_RETIMER_CPU0_P2_DP
   2    GND      B @T6G_MB_LIB.T6G(SCH_1):GND

Q_RES_0201LF-0,5%,1/20W,CHIP,CS00001JE10  I19  R613
   1 CLK_100M_RETIMER_CPU0_P2_R_DP      A @T6G_MB_LIB.T6G(SCH_1):CLK_100M_RETIMER_CPU0_P2_R_DP
   2 CLK_100M_RETIMER_CPU0_P2_DP      B @T6G_MB_LIB.T6G(SCH_1):CLK_100M_RETIMER_CPU0_P2_DP

Q_RES_0201LF-0,5%,1/20W,CHIP,CS00001JE10  I20  R614
   1 CLK_100M_RETIMER_CPU0_P2_R_DN      A @T6G_MB_LIB.T6G(SCH_1):CLK_100M_RETIMER_CPU0_P2_R_DN
   2 CLK_100M_RETIMER_CPU0_P2_DN      B @T6G_MB_LIB.T6G(SCH_1):CLK_100M_RETIMER_CPU0_P2_DN

Q_RES_0201LF-49.9,1%,1/20W,CHIP,CS04991FE06  I21  R681
   1 SMB_RT_CPU0_P2_ROM_MUX_1D_SDA      A @T6G_MB_LIB.T6G(SCH_1):SMB_RT_CPU0_P2_ROM_MUX_1D_SDA
   2 SMB_RT_CPU0_P2_ROM_MUX_1D_R_SDA      B @T6G_MB_LIB.T6G(SCH_1):SMB_RT_CPU0_P2_ROM_MUX_1D_R_SDA

Q_RES_0201LF-49.9,1%,1/20W,CHIP,CS04991FE06  I22  R680
   1 SMB_RT_CPU0_P2_ROM_MUX_1D_SCL      A @T6G_MB_LIB.T6G(SCH_1):SMB_RT_CPU0_P2_ROM_MUX_1D_SCL
   2 SMB_RT_CPU0_P2_ROM_MUX_1D_R_SCL      B @T6G_MB_LIB.T6G(SCH_1):SMB_RT_CPU0_P2_ROM_MUX_1D_R_SCL

Q_RES_0201LF-0,5%,1/20W,CHIP,CS00001JE10  I29  R1067
   1 SMB_RT_CPU0_P2_R_SCL      A @T6G_MB_LIB.T6G(SCH_1):SMB_RT_CPU0_P2_R_SCL
   2 SMB_RT_CPU0_P2_R2_SCL      B @T6G_MB_LIB.T6G(SCH_1):SMB_RT_CPU0_P2_R2_SCL

Q_RES_0201LF-0,5%,1/20W,CHIP,CS00001JE10  I30  R1068
   1 SMB_RT_CPU0_P2_R_SDA      A @T6G_MB_LIB.T6G(SCH_1):SMB_RT_CPU0_P2_R_SDA
   2 SMB_RT_CPU0_P2_R2_SDA      B @T6G_MB_LIB.T6G(SCH_1):SMB_RT_CPU0_P2_R2_SDA

Q_RES_0201LF-4.7K,5%,1/20W,CHIP,CS24701JE04  I36  R1076
   1 TEST1_RT_CPU0_P2      A @T6G_MB_LIB.T6G(SCH_1):TEST1_RT_CPU0_P2
   2    GND      B @T6G_MB_LIB.T6G(SCH_1):GND

Q_RES_0201LF-4.7K,5%,1/20W,CHIP,CS24701JE04  I37  R1078
   1 TEST2_RT_CPU0_P2      A @T6G_MB_LIB.T6G(SCH_1):TEST2_RT_CPU0_P2
   2    GND      B @T6G_MB_LIB.T6G(SCH_1):GND

Q_RES_0201LF-4.7K,5%,1/20W,CHIP,CS24701JE04  I39  R1079
   1 JTAG_TEST_MODE_RT_CPU0_P2      A @T6G_MB_LIB.T6G(SCH_1):JTAG_TEST_MODE_RT_CPU0_P2
   2    GND      B @T6G_MB_LIB.T6G(SCH_1):GND

Q_RES_0201LF-4.7K,5%,1/20W,EMPTY,CS24701JE04  I40  R1075
   1 P1V8_CPU0_RT_1D      A @T6G_MB_LIB.T6G(SCH_1):P1V8_CPU0_RT_1D
   2 TEST1_RT_CPU0_P2      B @T6G_MB_LIB.T6G(SCH_1):TEST1_RT_CPU0_P2

Q_RES_0201LF-4.7K,5%,1/20W,EMPTY,CS24701JE04  I41  R1077
   1 P1V8_CPU0_RT_1D      A @T6G_MB_LIB.T6G(SCH_1):P1V8_CPU0_RT_1D
   2 TEST2_RT_CPU0_P2      B @T6G_MB_LIB.T6G(SCH_1):TEST2_RT_CPU0_P2

Q_RES_0201LF-4.7K,5%,1/20W,EMPTY,CS24701JE04  I42  R1066
   1 P1V8_CPU0_RT_1D      A @T6G_MB_LIB.T6G(SCH_1):P1V8_CPU0_RT_1D
   2 JTAG_TEST_MODE_RT_CPU0_P2      B @T6G_MB_LIB.T6G(SCH_1):JTAG_TEST_MODE_RT_CPU0_P2

Q_RES_0201LF-4.7K,5%,1/20W,EMPTY,CS24701JE04  I50  R1048
   1 MODE_RT_CPU0_P2      A @T6G_MB_LIB.T6G(SCH_1):MODE_RT_CPU0_P2
   2    GND      B @T6G_MB_LIB.T6G(SCH_1):GND

Q_RES_0201LF-4.7K,5%,1/20W,CHIP,CS24701JE04  I51  R1080
   1 P1V8_CPU0_RT_1D      A @T6G_MB_LIB.T6G(SCH_1):P1V8_CPU0_RT_1D
   2 MODE_RT_CPU0_P2      B @T6G_MB_LIB.T6G(SCH_1):MODE_RT_CPU0_P2

Q_RES_0201LF-0,5%,1/20W,CHIP,CS00001JE10  I55  R1054
   1 RST_RT_CPU0_P2_RESET_N      A @T6G_MB_LIB.T6G(SCH_1):RST_RT_CPU0_P2_RESET_N
   2 RST_RT_CPU0_P2_RESET_R_N      B @T6G_MB_LIB.T6G(SCH_1):RST_RT_CPU0_P2_RESET_R_N

Q_RES_0201LF-0,5%,1/20W,CHIP,CS00001JE10  I56  R1047
   1 RST_RT_CPU0_P2_PERST_N      A @T6G_MB_LIB.T6G(SCH_1):RST_RT_CPU0_P2_PERST_N
   2 RST_RT_CPU0_P2_PERST_R_N      B @T6G_MB_LIB.T6G(SCH_1):RST_RT_CPU0_P2_PERST_R_N

Q_RES_0201LF-1K,1%,1/20W,EMPTY,CS21001FE07  I65  R1056
   1 RT_CPU0_P2_ADDR3      A @T6G_MB_LIB.T6G(SCH_1):RT_CPU0_P2_ADDR3
   2    GND      B @T6G_MB_LIB.T6G(SCH_1):GND

Q_RES_0201LF-20K,1%,1/20W,CHIP,CS32001FE00  I66  R1058
   1 RT_CPU0_P2_ADDR2      A @T6G_MB_LIB.T6G(SCH_1):RT_CPU0_P2_ADDR2
   2    GND      B @T6G_MB_LIB.T6G(SCH_1):GND

Q_RES_0201LF-1K,1%,1/20W,CHIP,CS21001FE07  I67  R1055
   1 P1V8_CPU0_RT_1D      A @T6G_MB_LIB.T6G(SCH_1):P1V8_CPU0_RT_1D
   2 RT_CPU0_P2_ADDR3      B @T6G_MB_LIB.T6G(SCH_1):RT_CPU0_P2_ADDR3

Q_RES_0201LF-1K,1%,1/20W,EMPTY,CS21001FE07  I68  R1057
   1 P1V8_CPU0_RT_1D      A @T6G_MB_LIB.T6G(SCH_1):P1V8_CPU0_RT_1D
   2 RT_CPU0_P2_ADDR2      B @T6G_MB_LIB.T6G(SCH_1):RT_CPU0_P2_ADDR2

Q_RES_0201LF-1K,1%,1/20W,CHIP,CS21001FE07  I69  R1060
   1 RT_CPU0_P2_ADDR1      A @T6G_MB_LIB.T6G(SCH_1):RT_CPU0_P2_ADDR1
   2    GND      B @T6G_MB_LIB.T6G(SCH_1):GND

Q_RES_0201LF-1K,1%,1/20W,EMPTY,CS21001FE07  I70  R1059
   1 P1V8_CPU0_RT_1D      A @T6G_MB_LIB.T6G(SCH_1):P1V8_CPU0_RT_1D
   2 RT_CPU0_P2_ADDR1      B @T6G_MB_LIB.T6G(SCH_1):RT_CPU0_P2_ADDR1

Q_RES_0201LF-10K,1%,1/20W,CHIP,CS31001FE17  I76  R1062
   1 RST_RT_CPU0_P2_RESET_R_N      A @T6G_MB_LIB.T6G(SCH_1):RST_RT_CPU0_P2_RESET_R_N
   2    GND      B @T6G_MB_LIB.T6G(SCH_1):GND

Q_RES_0201LF-10K,1%,1/20W,CHIP,CS31001FE17  I77  R1061
   1 RST_RT_CPU0_P2_PERST_R_N      A @T6G_MB_LIB.T6G(SCH_1):RST_RT_CPU0_P2_PERST_R_N
   2    GND      B @T6G_MB_LIB.T6G(SCH_1):GND

Q_RES_0201LF-4.7K,5%,1/20W,EMPTY,CS24701JE04  I78  R1065
   1 P1V8_CPU0_RT_1D      A @T6G_MB_LIB.T6G(SCH_1):P1V8_CPU0_RT_1D
   2 RST_RT_CPU0_P2_RESET_R_N      B @T6G_MB_LIB.T6G(SCH_1):RST_RT_CPU0_P2_RESET_R_N

PT5161LRS-PT5161LRS,SMLF,IC,AJ051610U03  I83  U6012
 FJ6     NC  GPIO0     NC
FJ23     NC  GPIO1     NC
FJ25 GPIO2_RT_CPU0_P2  GPIO2 @T6G_MB_LIB.T6G(SCH_1):GPIO2_RT_CPU0_P2
FJ28 GPIO3_RT_CPU0_P2  GPIO3 @T6G_MB_LIB.T6G(SCH_1):GPIO3_RT_CPU0_P2
FJ31     NC  INT_N     NC
  B3 JTAG_TCK_RT_CPU0_P2 JTAG_TCK @T6G_MB_LIB.T6G(SCH_1):JTAG_TCK_RT_CPU0_P2
  B6 JTAG_TDI_RT_CPU0_P2 JTAG_TDI @T6G_MB_LIB.T6G(SCH_1):JTAG_TDI_RT_CPU0_P2
  B9 JTAG_TDO_RT_CPU0_P2 JTAG_TDO @T6G_MB_LIB.T6G(SCH_1):JTAG_TDO_RT_CPU0_P2
 FF8 JTAG_TEST_MODE_RT_CPU0_P2 JTAG_TEST_MODE @T6G_MB_LIB.T6G(SCH_1):JTAG_TEST_MODE_RT_CPU0_P2
 B12 JTAG_TMS_RT_CPU0_P2 JTAG_TMS @T6G_MB_LIB.T6G(SCH_1):JTAG_TMS_RT_CPU0_P2
  E8 JTAG_TRST_RT_CPU0_P2_N JTAG_TRST_N @T6G_MB_LIB.T6G(SCH_1):JTAG_TRST_RT_CPU0_P2_N
 FJ9 MODE_RT_CPU0_P2   MODE @T6G_MB_LIB.T6G(SCH_1):MODE_RT_CPU0_P2
  F2 RST_RT_CPU0_P2_PERST_N PERST_N @T6G_MB_LIB.T6G(SCH_1):RST_RT_CPU0_P2_PERST_N
 E18     NC REFCLK_OUTN     NC
 B16     NC REFCLK_OUTP     NC
FF18 CLK_100M_RETIMER_CPU0_P2_DN REFCLKN @T6G_MB_LIB.T6G(SCH_1):CLK_100M_RETIMER_CPU0_P2_DN
FJ16 CLK_100M_RETIMER_CPU0_P2_DP REFCLKP @T6G_MB_LIB.T6G(SCH_1):CLK_100M_RETIMER_CPU0_P2_DP
FF11 RST_RT_CPU0_P2_RESET_N RESET_N @T6G_MB_LIB.T6G(SCH_1):RST_RT_CPU0_P2_RESET_N
 E11 RXDET_BYP_RT_CPU0_P2 RXDET_BYP @T6G_MB_LIB.T6G(SCH_1):RXDET_BYP_RT_CPU0_P2
FF33 RT_CPU0_P2_SCAN_MODE SCAN_MODE @T6G_MB_LIB.T6G(SCH_1):RT_CPU0_P2_SCAN_MODE
 F34 RT_CPU0_P2_ADDR1 SMB_ADDR1 @T6G_MB_LIB.T6G(SCH_1):RT_CPU0_P2_ADDR1
 B23 RT_CPU0_P2_ADDR2 SMB_ADDR2 @T6G_MB_LIB.T6G(SCH_1):RT_CPU0_P2_ADDR2
 B25 RT_CPU0_P2_ADDR3 SMB_ADDR3 @T6G_MB_LIB.T6G(SCH_1):RT_CPU0_P2_ADDR3
 B31 SMB_RT_CPU0_P2_R2_SCL SMBCLK @T6G_MB_LIB.T6G(SCH_1):SMB_RT_CPU0_P2_R2_SCL
 B28 SMB_RT_CPU0_P2_R2_SDA SMBDAT @T6G_MB_LIB.T6G(SCH_1):SMB_RT_CPU0_P2_R2_SDA
 E30    GND T_SENSE @T6G_MB_LIB.T6G(SCH_1):GND
FF24 TEST0_RT_CPU0_P2  TEST0 @T6G_MB_LIB.T6G(SCH_1):TEST0_RT_CPU0_P2
FF27 TEST1_RT_CPU0_P2  TEST1 @T6G_MB_LIB.T6G(SCH_1):TEST1_RT_CPU0_P2
FF30 TEST2_RT_CPU0_P2  TEST2 @T6G_MB_LIB.T6G(SCH_1):TEST2_RT_CPU0_P2
 G35 CLKREQ_RT_CPU0_P2_N CLKREQ_N @T6G_MB_LIB.T6G(SCH_1):CLKREQ_RT_CPU0_P2_N
 FF5 SMB_RT_CPU0_P2_ROM_MUX_1D_R_SCL EE_CLK @T6G_MB_LIB.T6G(SCH_1):SMB_RT_CPU0_P2_ROM_MUX_1D_R_SCL
 FJ3 SMB_RT_CPU0_P2_ROM_MUX_1D_R_SDA EE_DAT @T6G_MB_LIB.T6G(SCH_1):SMB_RT_CPU0_P2_ROM_MUX_1D_R_SDA

Q_RES_0201LF-1K,1%,1/20W,CHIP,CS21001FE07  I84  R1400
   1 JTAG_TRST_RT_CPU0_P2_N      A @T6G_MB_LIB.T6G(SCH_1):JTAG_TRST_RT_CPU0_P2_N
   2    GND      B @T6G_MB_LIB.T6G(SCH_1):GND

Q_RES_0201LF-10K,1%,1/20W,CHIP,CS31001FE17  I95  R1406
   1 RXDET_BYP_RT_CPU0_P2      A @T6G_MB_LIB.T6G(SCH_1):RXDET_BYP_RT_CPU0_P2
   2    GND      B @T6G_MB_LIB.T6G(SCH_1):GND

Q_RES_0201LF-1K,1%,1/20W,EMPTY,CS21001FE07  I96  R1405
   1 P1V8_CPU0_RT_1D      A @T6G_MB_LIB.T6G(SCH_1):P1V8_CPU0_RT_1D
   2 RXDET_BYP_RT_CPU0_P2      B @T6G_MB_LIB.T6G(SCH_1):RXDET_BYP_RT_CPU0_P2

Q_RES_0201LF-4.7K,5%,1/20W,CHIP,CS24701JE04  I99  R1404
   1 CLKREQ_RT_CPU0_P2_N      A @T6G_MB_LIB.T6G(SCH_1):CLKREQ_RT_CPU0_P2_N
   2    GND      B @T6G_MB_LIB.T6G(SCH_1):GND

Q_RES_0201LF-200,1%,1/20W,CHIP,CS12001FE12  I102  R1064
   1 RT_CPU0_P2_SCAN_MODE      A @T6G_MB_LIB.T6G(SCH_1):RT_CPU0_P2_SCAN_MODE
   2    GND      B @T6G_MB_LIB.T6G(SCH_1):GND

Q_RES_0201LF-4.7K,5%,1/20W,EMPTY,CS24701JE04  I116  R1476
   1 P1V8_CPU0_RT_1D      A @T6G_MB_LIB.T6G(SCH_1):P1V8_CPU0_RT_1D
   2 JTAG_TDI_RT_CPU0_P2      B @T6G_MB_LIB.T6G(SCH_1):JTAG_TDI_RT_CPU0_P2

Q_RES_0201LF-4.7K,5%,1/20W,EMPTY,CS24701JE04  I117  R1477
   1 P1V8_CPU0_RT_1D      A @T6G_MB_LIB.T6G(SCH_1):P1V8_CPU0_RT_1D
   2 JTAG_TMS_RT_CPU0_P2      B @T6G_MB_LIB.T6G(SCH_1):JTAG_TMS_RT_CPU0_P2

Q_RES_0201LF-1K,1%,1/20W,EMPTY,CS21001FE07  I118  R1478
   1 P1V8_CPU0_RT_1D      A @T6G_MB_LIB.T6G(SCH_1):P1V8_CPU0_RT_1D
   2 JTAG_TDO_RT_CPU0_P2      B @T6G_MB_LIB.T6G(SCH_1):JTAG_TDO_RT_CPU0_P2

Q_RES_0201LF-4.7K,5%,1/20W,CHIP,CS24701JE04  I120  R1401
   1 JTAG_TCK_RT_CPU0_P2      A @T6G_MB_LIB.T6G(SCH_1):JTAG_TCK_RT_CPU0_P2
   2    GND      B @T6G_MB_LIB.T6G(SCH_1):GND

Q_RES_0201LF-4.7K,5%,1/20W,EMPTY,CS24701JE04  I121  R1479
   1 P1V8_CPU0_RT_1D      A @T6G_MB_LIB.T6G(SCH_1):P1V8_CPU0_RT_1D
   2 JTAG_TCK_RT_CPU0_P2      B @T6G_MB_LIB.T6G(SCH_1):JTAG_TCK_RT_CPU0_P2


DRAWING: @T6G_MB_LIB.T6G(SCH_1):PAGE430 

Q_RES_0201LF-4.7K,5%,1/20W,EMPTY,CS24701JE04  I5  R1105
   1 P1V8_CPU0_RT_1D      A @T6G_MB_LIB.T6G(SCH_1):P1V8_CPU0_RT_1D
   2 RT_CPU0_P3_SCAN_MODE      B @T6G_MB_LIB.T6G(SCH_1):RT_CPU0_P3_SCAN_MODE

Q_RES_0201LF-10K,1%,1/20W,CHIP,CS31001FE17  I7  R1112
   1 GPIO2_RT_CPU0_P3      A @T6G_MB_LIB.T6G(SCH_1):GPIO2_RT_CPU0_P3
   2    GND      B @T6G_MB_LIB.T6G(SCH_1):GND

Q_RES_0201LF-10K,1%,1/20W,CHIP,CS31001FE17  I8  R1113
   1 GPIO3_RT_CPU0_P3      A @T6G_MB_LIB.T6G(SCH_1):GPIO3_RT_CPU0_P3
   2    GND      B @T6G_MB_LIB.T6G(SCH_1):GND

Q_RES_0201LF-4.7K,5%,1/20W,CHIP,CS24701JE04  I9  R1115
   1 TEST0_RT_CPU0_P3      A @T6G_MB_LIB.T6G(SCH_1):TEST0_RT_CPU0_P3
   2    GND      B @T6G_MB_LIB.T6G(SCH_1):GND

Q_RES_0201LF-4.7K,5%,1/20W,EMPTY,CS24701JE04  I10  R1111
   1 P1V8_CPU0_RT_1D      A @T6G_MB_LIB.T6G(SCH_1):P1V8_CPU0_RT_1D
   2 GPIO2_RT_CPU0_P3      B @T6G_MB_LIB.T6G(SCH_1):GPIO2_RT_CPU0_P3

Q_RES_0201LF-4.7K,5%,1/20W,EMPTY,CS24701JE04  I11  R1114
   1 P1V8_CPU0_RT_1D      A @T6G_MB_LIB.T6G(SCH_1):P1V8_CPU0_RT_1D
   2 TEST0_RT_CPU0_P3      B @T6G_MB_LIB.T6G(SCH_1):TEST0_RT_CPU0_P3

Q_RES_0201LF-0,5%,1/20W,CHIP,CS00001JE10  I15  R616
   1 CLK_100M_RETIMER_CPU0_P3_R_DN      A @T6G_MB_LIB.T6G(SCH_1):CLK_100M_RETIMER_CPU0_P3_R_DN
   2 CLK_100M_RETIMER_CPU0_P3_DN      B @T6G_MB_LIB.T6G(SCH_1):CLK_100M_RETIMER_CPU0_P3_DN

Q_RES_0201LF-51.1,1%,1/20W,EMPTY,CS05111FE00  I18  R635
   1 CLK_100M_RETIMER_CPU0_P3_DN      A @T6G_MB_LIB.T6G(SCH_1):CLK_100M_RETIMER_CPU0_P3_DN
   2    GND      B @T6G_MB_LIB.T6G(SCH_1):GND

Q_RES_0201LF-51.1,1%,1/20W,EMPTY,CS05111FE00  I19  R636
   1 CLK_100M_RETIMER_CPU0_P3_DP      A @T6G_MB_LIB.T6G(SCH_1):CLK_100M_RETIMER_CPU0_P3_DP
   2    GND      B @T6G_MB_LIB.T6G(SCH_1):GND

Q_RES_0201LF-0,5%,1/20W,CHIP,CS00001JE10  I20  R615
   1 CLK_100M_RETIMER_CPU0_P3_R_DP      A @T6G_MB_LIB.T6G(SCH_1):CLK_100M_RETIMER_CPU0_P3_R_DP
   2 CLK_100M_RETIMER_CPU0_P3_DP      B @T6G_MB_LIB.T6G(SCH_1):CLK_100M_RETIMER_CPU0_P3_DP

Q_RES_0201LF-49.9,1%,1/20W,CHIP,CS04991FE06  I21  R686
   1 SMB_RT_CPU0_P3_ROM_MUX_1D_SDA      A @T6G_MB_LIB.T6G(SCH_1):SMB_RT_CPU0_P3_ROM_MUX_1D_SDA
   2 SMB_RT_CPU0_P3_ROM_MUX_1D_R_SDA      B @T6G_MB_LIB.T6G(SCH_1):SMB_RT_CPU0_P3_ROM_MUX_1D_R_SDA

Q_RES_0201LF-49.9,1%,1/20W,CHIP,CS04991FE06  I22  R684
   1 SMB_RT_CPU0_P3_ROM_MUX_1D_SCL      A @T6G_MB_LIB.T6G(SCH_1):SMB_RT_CPU0_P3_ROM_MUX_1D_SCL
   2 SMB_RT_CPU0_P3_ROM_MUX_1D_R_SCL      B @T6G_MB_LIB.T6G(SCH_1):SMB_RT_CPU0_P3_ROM_MUX_1D_R_SCL

Q_RES_0201LF-0,5%,1/20W,CHIP,CS00001JE10  I32  R1109
   1 SMB_RT_CPU0_P3_R_SCL      A @T6G_MB_LIB.T6G(SCH_1):SMB_RT_CPU0_P3_R_SCL
   2 SMB_RT_CPU0_P3_R2_SCL      B @T6G_MB_LIB.T6G(SCH_1):SMB_RT_CPU0_P3_R2_SCL

Q_RES_0201LF-0,5%,1/20W,CHIP,CS00001JE10  I33  R1110
   1 SMB_RT_CPU0_P3_R_SDA      A @T6G_MB_LIB.T6G(SCH_1):SMB_RT_CPU0_P3_R_SDA
   2 SMB_RT_CPU0_P3_R2_SDA      B @T6G_MB_LIB.T6G(SCH_1):SMB_RT_CPU0_P3_R2_SDA

Q_RES_0201LF-4.7K,5%,1/20W,CHIP,CS24701JE04  I36  R1118
   1 TEST1_RT_CPU0_P3      A @T6G_MB_LIB.T6G(SCH_1):TEST1_RT_CPU0_P3
   2    GND      B @T6G_MB_LIB.T6G(SCH_1):GND

Q_RES_0201LF-4.7K,5%,1/20W,CHIP,CS24701JE04  I37  R1120
   1 TEST2_RT_CPU0_P3      A @T6G_MB_LIB.T6G(SCH_1):TEST2_RT_CPU0_P3
   2    GND      B @T6G_MB_LIB.T6G(SCH_1):GND

Q_RES_0201LF-4.7K,5%,1/20W,CHIP,CS24701JE04  I39  R1121
   1 JTAG_TEST_MODE_RT_CPU0_P3      A @T6G_MB_LIB.T6G(SCH_1):JTAG_TEST_MODE_RT_CPU0_P3
   2    GND      B @T6G_MB_LIB.T6G(SCH_1):GND

Q_RES_0201LF-4.7K,5%,1/20W,EMPTY,CS24701JE04  I40  R1116
   1 P1V8_CPU0_RT_1D      A @T6G_MB_LIB.T6G(SCH_1):P1V8_CPU0_RT_1D
   2 TEST1_RT_CPU0_P3      B @T6G_MB_LIB.T6G(SCH_1):TEST1_RT_CPU0_P3

Q_RES_0201LF-4.7K,5%,1/20W,EMPTY,CS24701JE04  I41  R1119
   1 P1V8_CPU0_RT_1D      A @T6G_MB_LIB.T6G(SCH_1):P1V8_CPU0_RT_1D
   2 TEST2_RT_CPU0_P3      B @T6G_MB_LIB.T6G(SCH_1):TEST2_RT_CPU0_P3

Q_RES_0201LF-4.7K,5%,1/20W,EMPTY,CS24701JE04  I42  R1108
   1 P1V8_CPU0_RT_1D      A @T6G_MB_LIB.T6G(SCH_1):P1V8_CPU0_RT_1D
   2 JTAG_TEST_MODE_RT_CPU0_P3      B @T6G_MB_LIB.T6G(SCH_1):JTAG_TEST_MODE_RT_CPU0_P3

Q_RES_0201LF-4.7K,5%,1/20W,EMPTY,CS24701JE04  I50  R1091
   1 MODE_RT_CPU0_P3      A @T6G_MB_LIB.T6G(SCH_1):MODE_RT_CPU0_P3
   2    GND      B @T6G_MB_LIB.T6G(SCH_1):GND

Q_RES_0201LF-4.7K,5%,1/20W,CHIP,CS24701JE04  I51  R1122
   1 P1V8_CPU0_RT_1D      A @T6G_MB_LIB.T6G(SCH_1):P1V8_CPU0_RT_1D
   2 MODE_RT_CPU0_P3      B @T6G_MB_LIB.T6G(SCH_1):MODE_RT_CPU0_P3

Q_RES_0201LF-0,5%,1/20W,CHIP,CS00001JE10  I55  R1096
   1 RST_RT_CPU0_P3_RESET_N      A @T6G_MB_LIB.T6G(SCH_1):RST_RT_CPU0_P3_RESET_N
   2 RST_RT_CPU0_P3_RESET_R_N      B @T6G_MB_LIB.T6G(SCH_1):RST_RT_CPU0_P3_RESET_R_N

Q_RES_0201LF-0,5%,1/20W,CHIP,CS00001JE10  I56  R1088
   1 RST_RT_CPU0_P3_PERST_N      A @T6G_MB_LIB.T6G(SCH_1):RST_RT_CPU0_P3_PERST_N
   2 RST_RT_CPU0_P3_PERST_R_N      B @T6G_MB_LIB.T6G(SCH_1):RST_RT_CPU0_P3_PERST_R_N

Q_RES_0201LF-1K,1%,1/20W,EMPTY,CS21001FE07  I65  R1098
   1 RT_CPU0_P3_ADDR3      A @T6G_MB_LIB.T6G(SCH_1):RT_CPU0_P3_ADDR3
   2    GND      B @T6G_MB_LIB.T6G(SCH_1):GND

Q_RES_0201LF-20K,1%,1/20W,CHIP,CS32001FE00  I66  R1100
   1 RT_CPU0_P3_ADDR2      A @T6G_MB_LIB.T6G(SCH_1):RT_CPU0_P3_ADDR2
   2    GND      B @T6G_MB_LIB.T6G(SCH_1):GND

Q_RES_0201LF-1K,1%,1/20W,CHIP,CS21001FE07  I67  R1097
   1 P1V8_CPU0_RT_1D      A @T6G_MB_LIB.T6G(SCH_1):P1V8_CPU0_RT_1D
   2 RT_CPU0_P3_ADDR3      B @T6G_MB_LIB.T6G(SCH_1):RT_CPU0_P3_ADDR3

Q_RES_0201LF-1K,1%,1/20W,EMPTY,CS21001FE07  I68  R1099
   1 P1V8_CPU0_RT_1D      A @T6G_MB_LIB.T6G(SCH_1):P1V8_CPU0_RT_1D
   2 RT_CPU0_P3_ADDR2      B @T6G_MB_LIB.T6G(SCH_1):RT_CPU0_P3_ADDR2

Q_RES_0201LF-1K,1%,1/20W,CHIP,CS21001FE07  I69  R1102
   1 RT_CPU0_P3_ADDR1      A @T6G_MB_LIB.T6G(SCH_1):RT_CPU0_P3_ADDR1
   2    GND      B @T6G_MB_LIB.T6G(SCH_1):GND

Q_RES_0201LF-1K,1%,1/20W,EMPTY,CS21001FE07  I70  R1101
   1 P1V8_CPU0_RT_1D      A @T6G_MB_LIB.T6G(SCH_1):P1V8_CPU0_RT_1D
   2 RT_CPU0_P3_ADDR1      B @T6G_MB_LIB.T6G(SCH_1):RT_CPU0_P3_ADDR1

Q_RES_0201LF-10K,1%,1/20W,CHIP,CS31001FE17  I74  R1103
   1 RST_RT_CPU0_P3_PERST_R_N      A @T6G_MB_LIB.T6G(SCH_1):RST_RT_CPU0_P3_PERST_R_N
   2    GND      B @T6G_MB_LIB.T6G(SCH_1):GND

Q_RES_0201LF-10K,1%,1/20W,CHIP,CS31001FE17  I75  R1104
   1 RST_RT_CPU0_P3_RESET_R_N      A @T6G_MB_LIB.T6G(SCH_1):RST_RT_CPU0_P3_RESET_R_N
   2    GND      B @T6G_MB_LIB.T6G(SCH_1):GND

Q_RES_0201LF-4.7K,5%,1/20W,EMPTY,CS24701JE04  I79  R1107
   1 P1V8_CPU0_RT_1D      A @T6G_MB_LIB.T6G(SCH_1):P1V8_CPU0_RT_1D
   2 RST_RT_CPU0_P3_RESET_R_N      B @T6G_MB_LIB.T6G(SCH_1):RST_RT_CPU0_P3_RESET_R_N

PT5161LRS-PT5161LRS,SMLF,IC,AJ051610U03  I83  U6013
 FJ6     NC  GPIO0     NC
FJ23     NC  GPIO1     NC
FJ25 GPIO2_RT_CPU0_P3  GPIO2 @T6G_MB_LIB.T6G(SCH_1):GPIO2_RT_CPU0_P3
FJ28 GPIO3_RT_CPU0_P3  GPIO3 @T6G_MB_LIB.T6G(SCH_1):GPIO3_RT_CPU0_P3
FJ31     NC  INT_N     NC
  B3 JTAG_TCK_RT_CPU0_P3 JTAG_TCK @T6G_MB_LIB.T6G(SCH_1):JTAG_TCK_RT_CPU0_P3
  B6 JTAG_TDI_RT_CPU0_P3 JTAG_TDI @T6G_MB_LIB.T6G(SCH_1):JTAG_TDI_RT_CPU0_P3
  B9 JTAG_TDO_RT_CPU0_P3 JTAG_TDO @T6G_MB_LIB.T6G(SCH_1):JTAG_TDO_RT_CPU0_P3
 FF8 JTAG_TEST_MODE_RT_CPU0_P3 JTAG_TEST_MODE @T6G_MB_LIB.T6G(SCH_1):JTAG_TEST_MODE_RT_CPU0_P3
 B12 JTAG_TMS_RT_CPU0_P3 JTAG_TMS @T6G_MB_LIB.T6G(SCH_1):JTAG_TMS_RT_CPU0_P3
  E8 JTAG_TRST_RT_CPU0_P3_N JTAG_TRST_N @T6G_MB_LIB.T6G(SCH_1):JTAG_TRST_RT_CPU0_P3_N
 FJ9 MODE_RT_CPU0_P3   MODE @T6G_MB_LIB.T6G(SCH_1):MODE_RT_CPU0_P3
  F2 RST_RT_CPU0_P3_PERST_N PERST_N @T6G_MB_LIB.T6G(SCH_1):RST_RT_CPU0_P3_PERST_N
 E18     NC REFCLK_OUTN     NC
 B16     NC REFCLK_OUTP     NC
FF18 CLK_100M_RETIMER_CPU0_P3_DN REFCLKN @T6G_MB_LIB.T6G(SCH_1):CLK_100M_RETIMER_CPU0_P3_DN
FJ16 CLK_100M_RETIMER_CPU0_P3_DP REFCLKP @T6G_MB_LIB.T6G(SCH_1):CLK_100M_RETIMER_CPU0_P3_DP
FF11 RST_RT_CPU0_P3_RESET_N RESET_N @T6G_MB_LIB.T6G(SCH_1):RST_RT_CPU0_P3_RESET_N
 E11 RXDET_BYP_RT_CPU0_P3 RXDET_BYP @T6G_MB_LIB.T6G(SCH_1):RXDET_BYP_RT_CPU0_P3
FF33 RT_CPU0_P3_SCAN_MODE SCAN_MODE @T6G_MB_LIB.T6G(SCH_1):RT_CPU0_P3_SCAN_MODE
 F34 RT_CPU0_P3_ADDR1 SMB_ADDR1 @T6G_MB_LIB.T6G(SCH_1):RT_CPU0_P3_ADDR1
 B23 RT_CPU0_P3_ADDR2 SMB_ADDR2 @T6G_MB_LIB.T6G(SCH_1):RT_CPU0_P3_ADDR2
 B25 RT_CPU0_P3_ADDR3 SMB_ADDR3 @T6G_MB_LIB.T6G(SCH_1):RT_CPU0_P3_ADDR3
 B31 SMB_RT_CPU0_P3_R2_SCL SMBCLK @T6G_MB_LIB.T6G(SCH_1):SMB_RT_CPU0_P3_R2_SCL
 B28 SMB_RT_CPU0_P3_R2_SDA SMBDAT @T6G_MB_LIB.T6G(SCH_1):SMB_RT_CPU0_P3_R2_SDA
 E30    GND T_SENSE @T6G_MB_LIB.T6G(SCH_1):GND
FF24 TEST0_RT_CPU0_P3  TEST0 @T6G_MB_LIB.T6G(SCH_1):TEST0_RT_CPU0_P3
FF27 TEST1_RT_CPU0_P3  TEST1 @T6G_MB_LIB.T6G(SCH_1):TEST1_RT_CPU0_P3
FF30 TEST2_RT_CPU0_P3  TEST2 @T6G_MB_LIB.T6G(SCH_1):TEST2_RT_CPU0_P3
 G35 CLKREQ_RT_CPU0_P3_N CLKREQ_N @T6G_MB_LIB.T6G(SCH_1):CLKREQ_RT_CPU0_P3_N
 FF5 SMB_RT_CPU0_P3_ROM_MUX_1D_R_SCL EE_CLK @T6G_MB_LIB.T6G(SCH_1):SMB_RT_CPU0_P3_ROM_MUX_1D_R_SCL
 FJ3 SMB_RT_CPU0_P3_ROM_MUX_1D_R_SDA EE_DAT @T6G_MB_LIB.T6G(SCH_1):SMB_RT_CPU0_P3_ROM_MUX_1D_R_SDA

Q_RES_0201LF-1K,1%,1/20W,CHIP,CS21001FE07  I85  R1408
   1 JTAG_TRST_RT_CPU0_P3_N      A @T6G_MB_LIB.T6G(SCH_1):JTAG_TRST_RT_CPU0_P3_N
   2    GND      B @T6G_MB_LIB.T6G(SCH_1):GND

Q_RES_0201LF-10K,1%,1/20W,CHIP,CS31001FE17  I96  R1414
   1 RXDET_BYP_RT_CPU0_P3      A @T6G_MB_LIB.T6G(SCH_1):RXDET_BYP_RT_CPU0_P3
   2    GND      B @T6G_MB_LIB.T6G(SCH_1):GND

Q_RES_0201LF-1K,1%,1/20W,EMPTY,CS21001FE07  I97  R1413
   1 P1V8_CPU0_RT_1D      A @T6G_MB_LIB.T6G(SCH_1):P1V8_CPU0_RT_1D
   2 RXDET_BYP_RT_CPU0_P3      B @T6G_MB_LIB.T6G(SCH_1):RXDET_BYP_RT_CPU0_P3

Q_RES_0201LF-4.7K,5%,1/20W,CHIP,CS24701JE04  I101  R1412
   1 CLKREQ_RT_CPU0_P3_N      A @T6G_MB_LIB.T6G(SCH_1):CLKREQ_RT_CPU0_P3_N
   2    GND      B @T6G_MB_LIB.T6G(SCH_1):GND

Q_RES_0201LF-200,1%,1/20W,CHIP,CS12001FE12  I102  R1106
   1 RT_CPU0_P3_SCAN_MODE      A @T6G_MB_LIB.T6G(SCH_1):RT_CPU0_P3_SCAN_MODE
   2    GND      B @T6G_MB_LIB.T6G(SCH_1):GND

Q_RES_0201LF-4.7K,5%,1/20W,EMPTY,CS24701JE04  I112  R1482
   1 P1V8_CPU0_RT_1D      A @T6G_MB_LIB.T6G(SCH_1):P1V8_CPU0_RT_1D
   2 JTAG_TDI_RT_CPU0_P3      B @T6G_MB_LIB.T6G(SCH_1):JTAG_TDI_RT_CPU0_P3

Q_RES_0201LF-4.7K,5%,1/20W,EMPTY,CS24701JE04  I113  R1483
   1 P1V8_CPU0_RT_1D      A @T6G_MB_LIB.T6G(SCH_1):P1V8_CPU0_RT_1D
   2 JTAG_TMS_RT_CPU0_P3      B @T6G_MB_LIB.T6G(SCH_1):JTAG_TMS_RT_CPU0_P3

Q_RES_0201LF-4.7K,5%,1/20W,CHIP,CS24701JE04  I117  R1409
   1 JTAG_TCK_RT_CPU0_P3      A @T6G_MB_LIB.T6G(SCH_1):JTAG_TCK_RT_CPU0_P3
   2    GND      B @T6G_MB_LIB.T6G(SCH_1):GND

Q_RES_0201LF-1K,1%,1/20W,EMPTY,CS21001FE07  I118  R1484
   1 P1V8_CPU0_RT_1D      A @T6G_MB_LIB.T6G(SCH_1):P1V8_CPU0_RT_1D
   2 JTAG_TDO_RT_CPU0_P3      B @T6G_MB_LIB.T6G(SCH_1):JTAG_TDO_RT_CPU0_P3

Q_RES_0201LF-4.7K,5%,1/20W,EMPTY,CS24701JE04  I119  R1485
   1 P1V8_CPU0_RT_1D      A @T6G_MB_LIB.T6G(SCH_1):P1V8_CPU0_RT_1D
   2 JTAG_TCK_RT_CPU0_P3      B @T6G_MB_LIB.T6G(SCH_1):JTAG_TCK_RT_CPU0_P3


DRAWING: @T6G_MB_LIB.T6G(SCH_1):PAGE327 

CONN112_10137002101LF-CONN112_10137002-101LF,THLF,A  I19  J106
  A8    GND     A8 @T6G_MB_LIB.T6G(SCH_1):GND
  A7 PRSNT_CABLE_GPU_A1_N     A7 @T6G_MB_LIB.T6G(SCH_1):PRSNT_CABLE_GPU_A1_N
  A6    GND     A6 @T6G_MB_LIB.T6G(SCH_1):GND
  A5 NC_J106_A5     A5 @T6G_MB_LIB.T6G(SCH_1):NC_J106_A5
  B8 P5E_CPU0_P2_RX_BUF_DN<7>     B8 @T6G_MB_LIB.T6G(SCH_1):P5E_CPU0_P2_RX_BUF_DN(7)
  B7    GND     B7 @T6G_MB_LIB.T6G(SCH_1):GND
  B6 P5E_CPU0_P2_RX_BUF_DN<5>     B6 @T6G_MB_LIB.T6G(SCH_1):P5E_CPU0_P2_RX_BUF_DN(5)
  B5    GND     B5 @T6G_MB_LIB.T6G(SCH_1):GND
  C8 P5E_CPU0_P2_RX_BUF_DP<7>     C8 @T6G_MB_LIB.T6G(SCH_1):P5E_CPU0_P2_RX_BUF_DP(7)
  C7 P5E_CPU0_P2_RX_BUF_DN<6>     C7 @T6G_MB_LIB.T6G(SCH_1):P5E_CPU0_P2_RX_BUF_DN(6)
  C6 P5E_CPU0_P2_RX_BUF_DP<5>     C6 @T6G_MB_LIB.T6G(SCH_1):P5E_CPU0_P2_RX_BUF_DP(5)
  C5 P5E_CPU0_P2_RX_BUF_DN<4>     C5 @T6G_MB_LIB.T6G(SCH_1):P5E_CPU0_P2_RX_BUF_DN(4)
  D8    GND     D8 @T6G_MB_LIB.T6G(SCH_1):GND
  D7 P5E_CPU0_P2_RX_BUF_DP<6>     D7 @T6G_MB_LIB.T6G(SCH_1):P5E_CPU0_P2_RX_BUF_DP(6)
  D6    GND     D6 @T6G_MB_LIB.T6G(SCH_1):GND
  D5 P5E_CPU0_P2_RX_BUF_DP<4>     D5 @T6G_MB_LIB.T6G(SCH_1):P5E_CPU0_P2_RX_BUF_DP(4)
  E8 P5E_CPU0_P3_RX_BUF_DN<7>     E8 @T6G_MB_LIB.T6G(SCH_1):P5E_CPU0_P3_RX_BUF_DN(7)
  E7    GND     E7 @T6G_MB_LIB.T6G(SCH_1):GND
  E6 P5E_CPU0_P3_RX_BUF_DN<5>     E6 @T6G_MB_LIB.T6G(SCH_1):P5E_CPU0_P3_RX_BUF_DN(5)
  E5    GND     E5 @T6G_MB_LIB.T6G(SCH_1):GND
  F8 P5E_CPU0_P3_RX_BUF_DP<7>     F8 @T6G_MB_LIB.T6G(SCH_1):P5E_CPU0_P3_RX_BUF_DP(7)
  F7 P5E_CPU0_P3_RX_BUF_DN<6>     F7 @T6G_MB_LIB.T6G(SCH_1):P5E_CPU0_P3_RX_BUF_DN(6)
  F6 P5E_CPU0_P3_RX_BUF_DP<5>     F6 @T6G_MB_LIB.T6G(SCH_1):P5E_CPU0_P3_RX_BUF_DP(5)
  F5 P5E_CPU0_P3_RX_BUF_DN<4>     F5 @T6G_MB_LIB.T6G(SCH_1):P5E_CPU0_P3_RX_BUF_DN(4)
  G8    GND     G8 @T6G_MB_LIB.T6G(SCH_1):GND
  G7 P5E_CPU0_P3_RX_BUF_DP<6>     G7 @T6G_MB_LIB.T6G(SCH_1):P5E_CPU0_P3_RX_BUF_DP(6)
  G6    GND     G6 @T6G_MB_LIB.T6G(SCH_1):GND
  G5 P5E_CPU0_P3_RX_BUF_DP<4>     G5 @T6G_MB_LIB.T6G(SCH_1):P5E_CPU0_P3_RX_BUF_DP(4)
  H8 P5E_CPU0_P2_TX_BUF_C_DN<7>     H8 @T6G_MB_LIB.T6G(SCH_1):P5E_CPU0_P2_TX_BUF_C_DN(7)
  H7    GND     H7 @T6G_MB_LIB.T6G(SCH_1):GND
  H6 P5E_CPU0_P2_TX_BUF_C_DN<5>     H6 @T6G_MB_LIB.T6G(SCH_1):P5E_CPU0_P2_TX_BUF_C_DN(5)
  H5    GND     H5 @T6G_MB_LIB.T6G(SCH_1):GND
  I8 P5E_CPU0_P2_TX_BUF_C_DP<7>     I8 @T6G_MB_LIB.T6G(SCH_1):P5E_CPU0_P2_TX_BUF_C_DP(7)
  I7 P5E_CPU0_P2_TX_BUF_C_DN<6>     I7 @T6G_MB_LIB.T6G(SCH_1):P5E_CPU0_P2_TX_BUF_C_DN(6)
  I6 P5E_CPU0_P2_TX_BUF_C_DP<5>     I6 @T6G_MB_LIB.T6G(SCH_1):P5E_CPU0_P2_TX_BUF_C_DP(5)
  I5 P5E_CPU0_P2_TX_BUF_C_DN<4>     I5 @T6G_MB_LIB.T6G(SCH_1):P5E_CPU0_P2_TX_BUF_C_DN(4)
  J8    GND     J8 @T6G_MB_LIB.T6G(SCH_1):GND
  J7 P5E_CPU0_P2_TX_BUF_C_DP<6>     J7 @T6G_MB_LIB.T6G(SCH_1):P5E_CPU0_P2_TX_BUF_C_DP(6)
  J6    GND     J6 @T6G_MB_LIB.T6G(SCH_1):GND
  J5 P5E_CPU0_P2_TX_BUF_C_DP<4>     J5 @T6G_MB_LIB.T6G(SCH_1):P5E_CPU0_P2_TX_BUF_C_DP(4)
  K8 P5E_CPU0_P3_TX_BUF_C_DN<7>     K8 @T6G_MB_LIB.T6G(SCH_1):P5E_CPU0_P3_TX_BUF_C_DN(7)
  K7    GND     K7 @T6G_MB_LIB.T6G(SCH_1):GND
  K6 P5E_CPU0_P3_TX_BUF_C_DN<5>     K6 @T6G_MB_LIB.T6G(SCH_1):P5E_CPU0_P3_TX_BUF_C_DN(5)
  K5    GND     K5 @T6G_MB_LIB.T6G(SCH_1):GND
  L8 P5E_CPU0_P3_TX_BUF_C_DP<7>     L8 @T6G_MB_LIB.T6G(SCH_1):P5E_CPU0_P3_TX_BUF_C_DP(7)
  L7 P5E_CPU0_P3_TX_BUF_C_DN<6>     L7 @T6G_MB_LIB.T6G(SCH_1):P5E_CPU0_P3_TX_BUF_C_DN(6)
  L6 P5E_CPU0_P3_TX_BUF_C_DP<5>     L6 @T6G_MB_LIB.T6G(SCH_1):P5E_CPU0_P3_TX_BUF_C_DP(5)
  L5 P5E_CPU0_P3_TX_BUF_C_DN<4>     L5 @T6G_MB_LIB.T6G(SCH_1):P5E_CPU0_P3_TX_BUF_C_DN(4)
  M5 P5E_CPU0_P3_TX_BUF_C_DP<4>     M5 @T6G_MB_LIB.T6G(SCH_1):P5E_CPU0_P3_TX_BUF_C_DP(4)
  N5    GND     N5 @T6G_MB_LIB.T6G(SCH_1):GND
  M6    GND     M6 @T6G_MB_LIB.T6G(SCH_1):GND
  N6 UART_BMC_BIC_RX     N6 @T6G_MB_LIB.T6G(SCH_1):UART_BMC_BIC_RX
  M7 P5E_CPU0_P3_TX_BUF_C_DP<6>     M7 @T6G_MB_LIB.T6G(SCH_1):P5E_CPU0_P3_TX_BUF_C_DP(6)
  N7    GND     N7 @T6G_MB_LIB.T6G(SCH_1):GND
  M8    GND     M8 @T6G_MB_LIB.T6G(SCH_1):GND
  N8 UART_BMC_BIC_TX     N8 @T6G_MB_LIB.T6G(SCH_1):UART_BMC_BIC_TX

CONN112_10137002101LF-CONN112_10137002-101LF,THLF,A  I74  J106
  A4    GND     A4 @T6G_MB_LIB.T6G(SCH_1):GND
  A3 FM_SWB_PWRGD     A3 @T6G_MB_LIB.T6G(SCH_1):FM_SWB_PWRGD
  A2    GND     A2 @T6G_MB_LIB.T6G(SCH_1):GND
  A1 PRSNT_CABLE_SWB_B1_N     A1 @T6G_MB_LIB.T6G(SCH_1):PRSNT_CABLE_SWB_B1_N
  B4 P5E_CPU0_P2_RX_BUF_DN<3>     B4 @T6G_MB_LIB.T6G(SCH_1):P5E_CPU0_P2_RX_BUF_DN(3)
  B3    GND     B3 @T6G_MB_LIB.T6G(SCH_1):GND
  B2 P5E_CPU0_P2_RX_BUF_DN<1>     B2 @T6G_MB_LIB.T6G(SCH_1):P5E_CPU0_P2_RX_BUF_DN(1)
  B1    GND     B1 @T6G_MB_LIB.T6G(SCH_1):GND
  C4 P5E_CPU0_P2_RX_BUF_DP<3>     C4 @T6G_MB_LIB.T6G(SCH_1):P5E_CPU0_P2_RX_BUF_DP(3)
  C3 P5E_CPU0_P2_RX_BUF_DN<2>     C3 @T6G_MB_LIB.T6G(SCH_1):P5E_CPU0_P2_RX_BUF_DN(2)
  C2 P5E_CPU0_P2_RX_BUF_DP<1>     C2 @T6G_MB_LIB.T6G(SCH_1):P5E_CPU0_P2_RX_BUF_DP(1)
  C1 P5E_CPU0_P2_RX_BUF_DN<0>     C1 @T6G_MB_LIB.T6G(SCH_1):P5E_CPU0_P2_RX_BUF_DN(0)
  D4    GND     D4 @T6G_MB_LIB.T6G(SCH_1):GND
  D3 P5E_CPU0_P2_RX_BUF_DP<2>     D3 @T6G_MB_LIB.T6G(SCH_1):P5E_CPU0_P2_RX_BUF_DP(2)
  D2    GND     D2 @T6G_MB_LIB.T6G(SCH_1):GND
  D1 P5E_CPU0_P2_RX_BUF_DP<0>     D1 @T6G_MB_LIB.T6G(SCH_1):P5E_CPU0_P2_RX_BUF_DP(0)
  E4 P5E_CPU0_P3_RX_BUF_DN<3>     E4 @T6G_MB_LIB.T6G(SCH_1):P5E_CPU0_P3_RX_BUF_DN(3)
  E3    GND     E3 @T6G_MB_LIB.T6G(SCH_1):GND
  E2 P5E_CPU0_P3_RX_BUF_DN<1>     E2 @T6G_MB_LIB.T6G(SCH_1):P5E_CPU0_P3_RX_BUF_DN(1)
  E1    GND     E1 @T6G_MB_LIB.T6G(SCH_1):GND
  F4 P5E_CPU0_P3_RX_BUF_DP<3>     F4 @T6G_MB_LIB.T6G(SCH_1):P5E_CPU0_P3_RX_BUF_DP(3)
  F3 P5E_CPU0_P3_RX_BUF_DN<2>     F3 @T6G_MB_LIB.T6G(SCH_1):P5E_CPU0_P3_RX_BUF_DN(2)
  F2 P5E_CPU0_P3_RX_BUF_DP<1>     F2 @T6G_MB_LIB.T6G(SCH_1):P5E_CPU0_P3_RX_BUF_DP(1)
  F1 P5E_CPU0_P3_RX_BUF_DN<0>     F1 @T6G_MB_LIB.T6G(SCH_1):P5E_CPU0_P3_RX_BUF_DN(0)
  G4    GND     G4 @T6G_MB_LIB.T6G(SCH_1):GND
  G3 P5E_CPU0_P3_RX_BUF_DP<2>     G3 @T6G_MB_LIB.T6G(SCH_1):P5E_CPU0_P3_RX_BUF_DP(2)
  G2    GND     G2 @T6G_MB_LIB.T6G(SCH_1):GND
  G1 P5E_CPU0_P3_RX_BUF_DP<0>     G1 @T6G_MB_LIB.T6G(SCH_1):P5E_CPU0_P3_RX_BUF_DP(0)
  H4 P5E_CPU0_P2_TX_BUF_C_DN<3>     H4 @T6G_MB_LIB.T6G(SCH_1):P5E_CPU0_P2_TX_BUF_C_DN(3)
  H3    GND     H3 @T6G_MB_LIB.T6G(SCH_1):GND
  H2 P5E_CPU0_P2_TX_BUF_C_DN<1>     H2 @T6G_MB_LIB.T6G(SCH_1):P5E_CPU0_P2_TX_BUF_C_DN(1)
  H1    GND     H1 @T6G_MB_LIB.T6G(SCH_1):GND
  I4 P5E_CPU0_P2_TX_BUF_C_DP<3>     I4 @T6G_MB_LIB.T6G(SCH_1):P5E_CPU0_P2_TX_BUF_C_DP(3)
  I3 P5E_CPU0_P2_TX_BUF_C_DN<2>     I3 @T6G_MB_LIB.T6G(SCH_1):P5E_CPU0_P2_TX_BUF_C_DN(2)
  I2 P5E_CPU0_P2_TX_BUF_C_DP<1>     I2 @T6G_MB_LIB.T6G(SCH_1):P5E_CPU0_P2_TX_BUF_C_DP(1)
  I1 P5E_CPU0_P2_TX_BUF_C_DN<0>     I1 @T6G_MB_LIB.T6G(SCH_1):P5E_CPU0_P2_TX_BUF_C_DN(0)
  J4    GND     J4 @T6G_MB_LIB.T6G(SCH_1):GND
  J3 P5E_CPU0_P2_TX_BUF_C_DP<2>     J3 @T6G_MB_LIB.T6G(SCH_1):P5E_CPU0_P2_TX_BUF_C_DP(2)
  J2    GND     J2 @T6G_MB_LIB.T6G(SCH_1):GND
  J1 P5E_CPU0_P2_TX_BUF_C_DP<0>     J1 @T6G_MB_LIB.T6G(SCH_1):P5E_CPU0_P2_TX_BUF_C_DP(0)
  K4 P5E_CPU0_P3_TX_BUF_C_DN<3>     K4 @T6G_MB_LIB.T6G(SCH_1):P5E_CPU0_P3_TX_BUF_C_DN(3)
  K3    GND     K3 @T6G_MB_LIB.T6G(SCH_1):GND
  K2 P5E_CPU0_P3_TX_BUF_C_DN<1>     K2 @T6G_MB_LIB.T6G(SCH_1):P5E_CPU0_P3_TX_BUF_C_DN(1)
  K1    GND     K1 @T6G_MB_LIB.T6G(SCH_1):GND
  L4 P5E_CPU0_P3_TX_BUF_C_DP<3>     L4 @T6G_MB_LIB.T6G(SCH_1):P5E_CPU0_P3_TX_BUF_C_DP(3)
  L3 P5E_CPU0_P3_TX_BUF_C_DN<2>     L3 @T6G_MB_LIB.T6G(SCH_1):P5E_CPU0_P3_TX_BUF_C_DN(2)
  L2 P5E_CPU0_P3_TX_BUF_C_DP<1>     L2 @T6G_MB_LIB.T6G(SCH_1):P5E_CPU0_P3_TX_BUF_C_DP(1)
  L1 P5E_CPU0_P3_TX_BUF_C_DN<0>     L1 @T6G_MB_LIB.T6G(SCH_1):P5E_CPU0_P3_TX_BUF_C_DN(0)
  M1 P5E_CPU0_P3_TX_BUF_C_DP<0>     M1 @T6G_MB_LIB.T6G(SCH_1):P5E_CPU0_P3_TX_BUF_C_DP(0)
  N1    GND     N1 @T6G_MB_LIB.T6G(SCH_1):GND
  M2    GND     M2 @T6G_MB_LIB.T6G(SCH_1):GND
  N2 I3C_BMC_SWB_BUF_SDA     N2 @T6G_MB_LIB.T6G(SCH_1):I3C_BMC_SWB_BUF_SDA
  M3 P5E_CPU0_P3_TX_BUF_C_DP<2>     M3 @T6G_MB_LIB.T6G(SCH_1):P5E_CPU0_P3_TX_BUF_C_DP(2)
  N3    GND     N3 @T6G_MB_LIB.T6G(SCH_1):GND
  M4    GND     M4 @T6G_MB_LIB.T6G(SCH_1):GND
  N4 I3C_BMC_SWB_BUF_SCL     N4 @T6G_MB_LIB.T6G(SCH_1):I3C_BMC_SWB_BUF_SCL


DRAWING: @T6G_MB_LIB.T6G(SCH_1):PAGE326 

CONN112_10137002101LF-CONN112_10137002-101LF,THLF,A  I75  J105
  A4    GND     A4 @T6G_MB_LIB.T6G(SCH_1):GND
  A3 GPU_WP_HW_CTRL_ISO_N     A3 @T6G_MB_LIB.T6G(SCH_1):GPU_WP_HW_CTRL_ISO_N
  A2    GND     A2 @T6G_MB_LIB.T6G(SCH_1):GND
  A1 GPU_3V3IO_RSVD4     A1 @T6G_MB_LIB.T6G(SCH_1):GPU_3V3IO_RSVD4
  B4 P5E_CPU0_P2_RX_BUF_DN<11>     B4 @T6G_MB_LIB.T6G(SCH_1):P5E_CPU0_P2_RX_BUF_DN(11)
  B3    GND     B3 @T6G_MB_LIB.T6G(SCH_1):GND
  B2 P5E_CPU0_P2_RX_BUF_DN<9>     B2 @T6G_MB_LIB.T6G(SCH_1):P5E_CPU0_P2_RX_BUF_DN(9)
  B1    GND     B1 @T6G_MB_LIB.T6G(SCH_1):GND
  C4 P5E_CPU0_P2_RX_BUF_DP<11>     C4 @T6G_MB_LIB.T6G(SCH_1):P5E_CPU0_P2_RX_BUF_DP(11)
  C3 P5E_CPU0_P2_RX_BUF_DN<10>     C3 @T6G_MB_LIB.T6G(SCH_1):P5E_CPU0_P2_RX_BUF_DN(10)
  C2 P5E_CPU0_P2_RX_BUF_DP<9>     C2 @T6G_MB_LIB.T6G(SCH_1):P5E_CPU0_P2_RX_BUF_DP(9)
  C1 P5E_CPU0_P2_RX_BUF_DN<8>     C1 @T6G_MB_LIB.T6G(SCH_1):P5E_CPU0_P2_RX_BUF_DN(8)
  D4    GND     D4 @T6G_MB_LIB.T6G(SCH_1):GND
  D3 P5E_CPU0_P2_RX_BUF_DP<10>     D3 @T6G_MB_LIB.T6G(SCH_1):P5E_CPU0_P2_RX_BUF_DP(10)
  D2    GND     D2 @T6G_MB_LIB.T6G(SCH_1):GND
  D1 P5E_CPU0_P2_RX_BUF_DP<8>     D1 @T6G_MB_LIB.T6G(SCH_1):P5E_CPU0_P2_RX_BUF_DP(8)
  E4 P5E_CPU0_P3_RX_BUF_DN<11>     E4 @T6G_MB_LIB.T6G(SCH_1):P5E_CPU0_P3_RX_BUF_DN(11)
  E3    GND     E3 @T6G_MB_LIB.T6G(SCH_1):GND
  E2 P5E_CPU0_P3_RX_BUF_DN<9>     E2 @T6G_MB_LIB.T6G(SCH_1):P5E_CPU0_P3_RX_BUF_DN(9)
  E1    GND     E1 @T6G_MB_LIB.T6G(SCH_1):GND
  F4 P5E_CPU0_P3_RX_BUF_DP<11>     F4 @T6G_MB_LIB.T6G(SCH_1):P5E_CPU0_P3_RX_BUF_DP(11)
  F3 P5E_CPU0_P3_RX_BUF_DN<10>     F3 @T6G_MB_LIB.T6G(SCH_1):P5E_CPU0_P3_RX_BUF_DN(10)
  F2 P5E_CPU0_P3_RX_BUF_DP<9>     F2 @T6G_MB_LIB.T6G(SCH_1):P5E_CPU0_P3_RX_BUF_DP(9)
  F1 P5E_CPU0_P3_RX_BUF_DN<8>     F1 @T6G_MB_LIB.T6G(SCH_1):P5E_CPU0_P3_RX_BUF_DN(8)
  G4    GND     G4 @T6G_MB_LIB.T6G(SCH_1):GND
  G3 P5E_CPU0_P3_RX_BUF_DP<10>     G3 @T6G_MB_LIB.T6G(SCH_1):P5E_CPU0_P3_RX_BUF_DP(10)
  G2    GND     G2 @T6G_MB_LIB.T6G(SCH_1):GND
  G1 P5E_CPU0_P3_RX_BUF_DP<8>     G1 @T6G_MB_LIB.T6G(SCH_1):P5E_CPU0_P3_RX_BUF_DP(8)
  H4 P5E_CPU0_P2_TX_BUF_C_DN<11>     H4 @T6G_MB_LIB.T6G(SCH_1):P5E_CPU0_P2_TX_BUF_C_DN(11)
  H3    GND     H3 @T6G_MB_LIB.T6G(SCH_1):GND
  H2 P5E_CPU0_P2_TX_BUF_C_DN<9>     H2 @T6G_MB_LIB.T6G(SCH_1):P5E_CPU0_P2_TX_BUF_C_DN(9)
  H1    GND     H1 @T6G_MB_LIB.T6G(SCH_1):GND
  I4 P5E_CPU0_P2_TX_BUF_C_DP<11>     I4 @T6G_MB_LIB.T6G(SCH_1):P5E_CPU0_P2_TX_BUF_C_DP(11)
  I3 P5E_CPU0_P2_TX_BUF_C_DN<10>     I3 @T6G_MB_LIB.T6G(SCH_1):P5E_CPU0_P2_TX_BUF_C_DN(10)
  I2 P5E_CPU0_P2_TX_BUF_C_DP<9>     I2 @T6G_MB_LIB.T6G(SCH_1):P5E_CPU0_P2_TX_BUF_C_DP(9)
  I1 P5E_CPU0_P2_TX_BUF_C_DN<8>     I1 @T6G_MB_LIB.T6G(SCH_1):P5E_CPU0_P2_TX_BUF_C_DN(8)
  J4    GND     J4 @T6G_MB_LIB.T6G(SCH_1):GND
  J3 P5E_CPU0_P2_TX_BUF_C_DP<10>     J3 @T6G_MB_LIB.T6G(SCH_1):P5E_CPU0_P2_TX_BUF_C_DP(10)
  J2    GND     J2 @T6G_MB_LIB.T6G(SCH_1):GND
  J1 P5E_CPU0_P2_TX_BUF_C_DP<8>     J1 @T6G_MB_LIB.T6G(SCH_1):P5E_CPU0_P2_TX_BUF_C_DP(8)
  K4 P5E_CPU0_P3_TX_BUF_C_DN<11>     K4 @T6G_MB_LIB.T6G(SCH_1):P5E_CPU0_P3_TX_BUF_C_DN(11)
  K3    GND     K3 @T6G_MB_LIB.T6G(SCH_1):GND
  K2 P5E_CPU0_P3_TX_BUF_C_DN<9>     K2 @T6G_MB_LIB.T6G(SCH_1):P5E_CPU0_P3_TX_BUF_C_DN(9)
  K1    GND     K1 @T6G_MB_LIB.T6G(SCH_1):GND
  L4 P5E_CPU0_P3_TX_BUF_C_DP<11>     L4 @T6G_MB_LIB.T6G(SCH_1):P5E_CPU0_P3_TX_BUF_C_DP(11)
  L3 P5E_CPU0_P3_TX_BUF_C_DN<10>     L3 @T6G_MB_LIB.T6G(SCH_1):P5E_CPU0_P3_TX_BUF_C_DN(10)
  L2 P5E_CPU0_P3_TX_BUF_C_DP<9>     L2 @T6G_MB_LIB.T6G(SCH_1):P5E_CPU0_P3_TX_BUF_C_DP(9)
  L1 P5E_CPU0_P3_TX_BUF_C_DN<8>     L1 @T6G_MB_LIB.T6G(SCH_1):P5E_CPU0_P3_TX_BUF_C_DN(8)
  M1 P5E_CPU0_P3_TX_BUF_C_DP<8>     M1 @T6G_MB_LIB.T6G(SCH_1):P5E_CPU0_P3_TX_BUF_C_DP(8)
  N1    GND     N1 @T6G_MB_LIB.T6G(SCH_1):GND
  M2    GND     M2 @T6G_MB_LIB.T6G(SCH_1):GND
  N2 FM_SWB_PWR_EN_R_BUF     N2 @T6G_MB_LIB.T6G(SCH_1):FM_SWB_PWR_EN_R_BUF
  M3 P5E_CPU0_P3_TX_BUF_C_DP<10>     M3 @T6G_MB_LIB.T6G(SCH_1):P5E_CPU0_P3_TX_BUF_C_DP(10)
  N3    GND     N3 @T6G_MB_LIB.T6G(SCH_1):GND
  M4    GND     M4 @T6G_MB_LIB.T6G(SCH_1):GND
  N4 FM_SWB_BIC_READY_N     N4 @T6G_MB_LIB.T6G(SCH_1):FM_SWB_BIC_READY_N

CONN112_10137002101LF-CONN112_10137002-101LF,THLF,A  I76  J105
  A8    GND     A8 @T6G_MB_LIB.T6G(SCH_1):GND
  A7 GPU_3V3IO_RSVD1     A7 @T6G_MB_LIB.T6G(SCH_1):GPU_3V3IO_RSVD1
  A6    GND     A6 @T6G_MB_LIB.T6G(SCH_1):GND
  A5 GPU_3V3IO_RSVD3     A5 @T6G_MB_LIB.T6G(SCH_1):GPU_3V3IO_RSVD3
  B8 P5E_CPU0_P2_RX_BUF_DN<15>     B8 @T6G_MB_LIB.T6G(SCH_1):P5E_CPU0_P2_RX_BUF_DN(15)
  B7    GND     B7 @T6G_MB_LIB.T6G(SCH_1):GND
  B6 P5E_CPU0_P2_RX_BUF_DN<13>     B6 @T6G_MB_LIB.T6G(SCH_1):P5E_CPU0_P2_RX_BUF_DN(13)
  B5    GND     B5 @T6G_MB_LIB.T6G(SCH_1):GND
  C8 P5E_CPU0_P2_RX_BUF_DP<15>     C8 @T6G_MB_LIB.T6G(SCH_1):P5E_CPU0_P2_RX_BUF_DP(15)
  C7 P5E_CPU0_P2_RX_BUF_DN<14>     C7 @T6G_MB_LIB.T6G(SCH_1):P5E_CPU0_P2_RX_BUF_DN(14)
  C6 P5E_CPU0_P2_RX_BUF_DP<13>     C6 @T6G_MB_LIB.T6G(SCH_1):P5E_CPU0_P2_RX_BUF_DP(13)
  C5 P5E_CPU0_P2_RX_BUF_DN<12>     C5 @T6G_MB_LIB.T6G(SCH_1):P5E_CPU0_P2_RX_BUF_DN(12)
  D8    GND     D8 @T6G_MB_LIB.T6G(SCH_1):GND
  D7 P5E_CPU0_P2_RX_BUF_DP<14>     D7 @T6G_MB_LIB.T6G(SCH_1):P5E_CPU0_P2_RX_BUF_DP(14)
  D6    GND     D6 @T6G_MB_LIB.T6G(SCH_1):GND
  D5 P5E_CPU0_P2_RX_BUF_DP<12>     D5 @T6G_MB_LIB.T6G(SCH_1):P5E_CPU0_P2_RX_BUF_DP(12)
  E8 P5E_CPU0_P3_RX_BUF_DN<15>     E8 @T6G_MB_LIB.T6G(SCH_1):P5E_CPU0_P3_RX_BUF_DN(15)
  E7    GND     E7 @T6G_MB_LIB.T6G(SCH_1):GND
  E6 P5E_CPU0_P3_RX_BUF_DN<13>     E6 @T6G_MB_LIB.T6G(SCH_1):P5E_CPU0_P3_RX_BUF_DN(13)
  E5    GND     E5 @T6G_MB_LIB.T6G(SCH_1):GND
  F8 P5E_CPU0_P3_RX_BUF_DP<15>     F8 @T6G_MB_LIB.T6G(SCH_1):P5E_CPU0_P3_RX_BUF_DP(15)
  F7 P5E_CPU0_P3_RX_BUF_DN<14>     F7 @T6G_MB_LIB.T6G(SCH_1):P5E_CPU0_P3_RX_BUF_DN(14)
  F6 P5E_CPU0_P3_RX_BUF_DP<13>     F6 @T6G_MB_LIB.T6G(SCH_1):P5E_CPU0_P3_RX_BUF_DP(13)
  F5 P5E_CPU0_P3_RX_BUF_DN<12>     F5 @T6G_MB_LIB.T6G(SCH_1):P5E_CPU0_P3_RX_BUF_DN(12)
  G8    GND     G8 @T6G_MB_LIB.T6G(SCH_1):GND
  G7 P5E_CPU0_P3_RX_BUF_DP<14>     G7 @T6G_MB_LIB.T6G(SCH_1):P5E_CPU0_P3_RX_BUF_DP(14)
  G6    GND     G6 @T6G_MB_LIB.T6G(SCH_1):GND
  G5 P5E_CPU0_P3_RX_BUF_DP<12>     G5 @T6G_MB_LIB.T6G(SCH_1):P5E_CPU0_P3_RX_BUF_DP(12)
  H8 P5E_CPU0_P2_TX_BUF_C_DN<15>     H8 @T6G_MB_LIB.T6G(SCH_1):P5E_CPU0_P2_TX_BUF_C_DN(15)
  H7    GND     H7 @T6G_MB_LIB.T6G(SCH_1):GND
  H6 P5E_CPU0_P2_TX_BUF_C_DN<13>     H6 @T6G_MB_LIB.T6G(SCH_1):P5E_CPU0_P2_TX_BUF_C_DN(13)
  H5    GND     H5 @T6G_MB_LIB.T6G(SCH_1):GND
  I8 P5E_CPU0_P2_TX_BUF_C_DP<15>     I8 @T6G_MB_LIB.T6G(SCH_1):P5E_CPU0_P2_TX_BUF_C_DP(15)
  I7 P5E_CPU0_P2_TX_BUF_C_DN<14>     I7 @T6G_MB_LIB.T6G(SCH_1):P5E_CPU0_P2_TX_BUF_C_DN(14)
  I6 P5E_CPU0_P2_TX_BUF_C_DP<13>     I6 @T6G_MB_LIB.T6G(SCH_1):P5E_CPU0_P2_TX_BUF_C_DP(13)
  I5 P5E_CPU0_P2_TX_BUF_C_DN<12>     I5 @T6G_MB_LIB.T6G(SCH_1):P5E_CPU0_P2_TX_BUF_C_DN(12)
  J8    GND     J8 @T6G_MB_LIB.T6G(SCH_1):GND
  J7 P5E_CPU0_P2_TX_BUF_C_DP<14>     J7 @T6G_MB_LIB.T6G(SCH_1):P5E_CPU0_P2_TX_BUF_C_DP(14)
  J6    GND     J6 @T6G_MB_LIB.T6G(SCH_1):GND
  J5 P5E_CPU0_P2_TX_BUF_C_DP<12>     J5 @T6G_MB_LIB.T6G(SCH_1):P5E_CPU0_P2_TX_BUF_C_DP(12)
  K8 P5E_CPU0_P3_TX_BUF_C_DN<15>     K8 @T6G_MB_LIB.T6G(SCH_1):P5E_CPU0_P3_TX_BUF_C_DN(15)
  K7    GND     K7 @T6G_MB_LIB.T6G(SCH_1):GND
  K6 P5E_CPU0_P3_TX_BUF_C_DN<13>     K6 @T6G_MB_LIB.T6G(SCH_1):P5E_CPU0_P3_TX_BUF_C_DN(13)
  K5    GND     K5 @T6G_MB_LIB.T6G(SCH_1):GND
  L8 P5E_CPU0_P3_TX_BUF_C_DP<15>     L8 @T6G_MB_LIB.T6G(SCH_1):P5E_CPU0_P3_TX_BUF_C_DP(15)
  L7 P5E_CPU0_P3_TX_BUF_C_DN<14>     L7 @T6G_MB_LIB.T6G(SCH_1):P5E_CPU0_P3_TX_BUF_C_DN(14)
  L6 P5E_CPU0_P3_TX_BUF_C_DP<13>     L6 @T6G_MB_LIB.T6G(SCH_1):P5E_CPU0_P3_TX_BUF_C_DP(13)
  L5 P5E_CPU0_P3_TX_BUF_C_DN<12>     L5 @T6G_MB_LIB.T6G(SCH_1):P5E_CPU0_P3_TX_BUF_C_DN(12)
  M5 P5E_CPU0_P3_TX_BUF_C_DP<12>     M5 @T6G_MB_LIB.T6G(SCH_1):P5E_CPU0_P3_TX_BUF_C_DP(12)
  N5    GND     N5 @T6G_MB_LIB.T6G(SCH_1):GND
  M6    GND     M6 @T6G_MB_LIB.T6G(SCH_1):GND
  N6 RST_SWB_BIC_BUF_N     N6 @T6G_MB_LIB.T6G(SCH_1):RST_SWB_BIC_BUF_N
  M7 P5E_CPU0_P3_TX_BUF_C_DP<14>     M7 @T6G_MB_LIB.T6G(SCH_1):P5E_CPU0_P3_TX_BUF_C_DP(14)
  N7    GND     N7 @T6G_MB_LIB.T6G(SCH_1):GND
  M8    GND     M8 @T6G_MB_LIB.T6G(SCH_1):GND
  N8 RST_BMC_FROM_SWB_N     N8 @T6G_MB_LIB.T6G(SCH_1):RST_BMC_FROM_SWB_N


DRAWING: @T6G_MB_LIB.T6G(SCH_1):PAGE317 

CONN112_10137002101LF-CONN112_10137002-101LF,THLF,A  I49  J107
  A4    GND     A4 @T6G_MB_LIB.T6G(SCH_1):GND
  A3 NC_J107_A3     A3 @T6G_MB_LIB.T6G(SCH_1):NC_J107_A3
  A2    GND     A2 @T6G_MB_LIB.T6G(SCH_1):GND
  A1 NC_J107_A1     A1 @T6G_MB_LIB.T6G(SCH_1):NC_J107_A1
  B4 P5E_CPU0_P0_RX_BUF_DN<11>     B4 @T6G_MB_LIB.T6G(SCH_1):P5E_CPU0_P0_RX_BUF_DN(11)
  B3    GND     B3 @T6G_MB_LIB.T6G(SCH_1):GND
  B2 P5E_CPU0_P0_RX_BUF_DN<9>     B2 @T6G_MB_LIB.T6G(SCH_1):P5E_CPU0_P0_RX_BUF_DN(9)
  B1    GND     B1 @T6G_MB_LIB.T6G(SCH_1):GND
  C4 P5E_CPU0_P0_RX_BUF_DP<11>     C4 @T6G_MB_LIB.T6G(SCH_1):P5E_CPU0_P0_RX_BUF_DP(11)
  C3 P5E_CPU0_P0_RX_BUF_DN<10>     C3 @T6G_MB_LIB.T6G(SCH_1):P5E_CPU0_P0_RX_BUF_DN(10)
  C2 P5E_CPU0_P0_RX_BUF_DP<9>     C2 @T6G_MB_LIB.T6G(SCH_1):P5E_CPU0_P0_RX_BUF_DP(9)
  C1 P5E_CPU0_P0_RX_BUF_DN<8>     C1 @T6G_MB_LIB.T6G(SCH_1):P5E_CPU0_P0_RX_BUF_DN(8)
  D4    GND     D4 @T6G_MB_LIB.T6G(SCH_1):GND
  D3 P5E_CPU0_P0_RX_BUF_DP<10>     D3 @T6G_MB_LIB.T6G(SCH_1):P5E_CPU0_P0_RX_BUF_DP(10)
  D2    GND     D2 @T6G_MB_LIB.T6G(SCH_1):GND
  D1 P5E_CPU0_P0_RX_BUF_DP<8>     D1 @T6G_MB_LIB.T6G(SCH_1):P5E_CPU0_P0_RX_BUF_DP(8)
  E4 P5E_CPU0_P1_RX_BUF_DN<11>     E4 @T6G_MB_LIB.T6G(SCH_1):P5E_CPU0_P1_RX_BUF_DN(11)
  E3    GND     E3 @T6G_MB_LIB.T6G(SCH_1):GND
  E2 P5E_CPU0_P1_RX_BUF_DN<9>     E2 @T6G_MB_LIB.T6G(SCH_1):P5E_CPU0_P1_RX_BUF_DN(9)
  E1    GND     E1 @T6G_MB_LIB.T6G(SCH_1):GND
  F4 P5E_CPU0_P1_RX_BUF_DP<11>     F4 @T6G_MB_LIB.T6G(SCH_1):P5E_CPU0_P1_RX_BUF_DP(11)
  F3 P5E_CPU0_P1_RX_BUF_DN<10>     F3 @T6G_MB_LIB.T6G(SCH_1):P5E_CPU0_P1_RX_BUF_DN(10)
  F2 P5E_CPU0_P1_RX_BUF_DP<9>     F2 @T6G_MB_LIB.T6G(SCH_1):P5E_CPU0_P1_RX_BUF_DP(9)
  F1 P5E_CPU0_P1_RX_BUF_DN<8>     F1 @T6G_MB_LIB.T6G(SCH_1):P5E_CPU0_P1_RX_BUF_DN(8)
  G4    GND     G4 @T6G_MB_LIB.T6G(SCH_1):GND
  G3 P5E_CPU0_P1_RX_BUF_DP<10>     G3 @T6G_MB_LIB.T6G(SCH_1):P5E_CPU0_P1_RX_BUF_DP(10)
  G2    GND     G2 @T6G_MB_LIB.T6G(SCH_1):GND
  G1 P5E_CPU0_P1_RX_BUF_DP<8>     G1 @T6G_MB_LIB.T6G(SCH_1):P5E_CPU0_P1_RX_BUF_DP(8)
  H4 P5E_CPU0_P0_TX_BUF_C_DN<11>     H4 @T6G_MB_LIB.T6G(SCH_1):P5E_CPU0_P0_TX_BUF_C_DN(11)
  H3    GND     H3 @T6G_MB_LIB.T6G(SCH_1):GND
  H2 P5E_CPU0_P0_TX_BUF_C_DN<9>     H2 @T6G_MB_LIB.T6G(SCH_1):P5E_CPU0_P0_TX_BUF_C_DN(9)
  H1    GND     H1 @T6G_MB_LIB.T6G(SCH_1):GND
  I4 P5E_CPU0_P0_TX_BUF_C_DP<11>     I4 @T6G_MB_LIB.T6G(SCH_1):P5E_CPU0_P0_TX_BUF_C_DP(11)
  I3 P5E_CPU0_P0_TX_BUF_C_DN<10>     I3 @T6G_MB_LIB.T6G(SCH_1):P5E_CPU0_P0_TX_BUF_C_DN(10)
  I2 P5E_CPU0_P0_TX_BUF_C_DP<9>     I2 @T6G_MB_LIB.T6G(SCH_1):P5E_CPU0_P0_TX_BUF_C_DP(9)
  I1 P5E_CPU0_P0_TX_BUF_C_DN<8>     I1 @T6G_MB_LIB.T6G(SCH_1):P5E_CPU0_P0_TX_BUF_C_DN(8)
  J4    GND     J4 @T6G_MB_LIB.T6G(SCH_1):GND
  J3 P5E_CPU0_P0_TX_BUF_C_DP<10>     J3 @T6G_MB_LIB.T6G(SCH_1):P5E_CPU0_P0_TX_BUF_C_DP(10)
  J2    GND     J2 @T6G_MB_LIB.T6G(SCH_1):GND
  J1 P5E_CPU0_P0_TX_BUF_C_DP<8>     J1 @T6G_MB_LIB.T6G(SCH_1):P5E_CPU0_P0_TX_BUF_C_DP(8)
  K4 P5E_CPU0_P1_TX_BUF_C_DN<11>     K4 @T6G_MB_LIB.T6G(SCH_1):P5E_CPU0_P1_TX_BUF_C_DN(11)
  K3    GND     K3 @T6G_MB_LIB.T6G(SCH_1):GND
  K2 P5E_CPU0_P1_TX_BUF_C_DN<9>     K2 @T6G_MB_LIB.T6G(SCH_1):P5E_CPU0_P1_TX_BUF_C_DN(9)
  K1    GND     K1 @T6G_MB_LIB.T6G(SCH_1):GND
  L4 P5E_CPU0_P1_TX_BUF_C_DP<11>     L4 @T6G_MB_LIB.T6G(SCH_1):P5E_CPU0_P1_TX_BUF_C_DP(11)
  L3 P5E_CPU0_P1_TX_BUF_C_DN<10>     L3 @T6G_MB_LIB.T6G(SCH_1):P5E_CPU0_P1_TX_BUF_C_DN(10)
  L2 P5E_CPU0_P1_TX_BUF_C_DP<9>     L2 @T6G_MB_LIB.T6G(SCH_1):P5E_CPU0_P1_TX_BUF_C_DP(9)
  L1 P5E_CPU0_P1_TX_BUF_C_DN<8>     L1 @T6G_MB_LIB.T6G(SCH_1):P5E_CPU0_P1_TX_BUF_C_DN(8)
  M1 P5E_CPU0_P1_TX_BUF_C_DP<8>     M1 @T6G_MB_LIB.T6G(SCH_1):P5E_CPU0_P1_TX_BUF_C_DP(8)
  N1    GND     N1 @T6G_MB_LIB.T6G(SCH_1):GND
  M2    GND     M2 @T6G_MB_LIB.T6G(SCH_1):GND
  N2 PRSNT_CABLE_SWB_B2_N     N2 @T6G_MB_LIB.T6G(SCH_1):PRSNT_CABLE_SWB_B2_N
  M3 P5E_CPU0_P1_TX_BUF_C_DP<10>     M3 @T6G_MB_LIB.T6G(SCH_1):P5E_CPU0_P1_TX_BUF_C_DP(10)
  N3    GND     N3 @T6G_MB_LIB.T6G(SCH_1):GND
  M4    GND     M4 @T6G_MB_LIB.T6G(SCH_1):GND
  N4 NC_J107_N4     N4 @T6G_MB_LIB.T6G(SCH_1):NC_J107_N4

CONN112_10137002101LF-CONN112_10137002-101LF,THLF,A  I70  J107
  A8    GND     A8 @T6G_MB_LIB.T6G(SCH_1):GND
  A7 SWB_HSC_PWRGD     A7 @T6G_MB_LIB.T6G(SCH_1):SWB_HSC_PWRGD
  A6    GND     A6 @T6G_MB_LIB.T6G(SCH_1):GND
  A5 NC_J107_A5     A5 @T6G_MB_LIB.T6G(SCH_1):NC_J107_A5
  B8 P5E_CPU0_P0_RX_BUF_DN<15>     B8 @T6G_MB_LIB.T6G(SCH_1):P5E_CPU0_P0_RX_BUF_DN(15)
  B7    GND     B7 @T6G_MB_LIB.T6G(SCH_1):GND
  B6 P5E_CPU0_P0_RX_BUF_DN<13>     B6 @T6G_MB_LIB.T6G(SCH_1):P5E_CPU0_P0_RX_BUF_DN(13)
  B5    GND     B5 @T6G_MB_LIB.T6G(SCH_1):GND
  C8 P5E_CPU0_P0_RX_BUF_DP<15>     C8 @T6G_MB_LIB.T6G(SCH_1):P5E_CPU0_P0_RX_BUF_DP(15)
  C7 P5E_CPU0_P0_RX_BUF_DN<14>     C7 @T6G_MB_LIB.T6G(SCH_1):P5E_CPU0_P0_RX_BUF_DN(14)
  C6 P5E_CPU0_P0_RX_BUF_DP<13>     C6 @T6G_MB_LIB.T6G(SCH_1):P5E_CPU0_P0_RX_BUF_DP(13)
  C5 P5E_CPU0_P0_RX_BUF_DN<12>     C5 @T6G_MB_LIB.T6G(SCH_1):P5E_CPU0_P0_RX_BUF_DN(12)
  D8    GND     D8 @T6G_MB_LIB.T6G(SCH_1):GND
  D7 P5E_CPU0_P0_RX_BUF_DP<14>     D7 @T6G_MB_LIB.T6G(SCH_1):P5E_CPU0_P0_RX_BUF_DP(14)
  D6    GND     D6 @T6G_MB_LIB.T6G(SCH_1):GND
  D5 P5E_CPU0_P0_RX_BUF_DP<12>     D5 @T6G_MB_LIB.T6G(SCH_1):P5E_CPU0_P0_RX_BUF_DP(12)
  E8 P5E_CPU0_P1_RX_BUF_DN<15>     E8 @T6G_MB_LIB.T6G(SCH_1):P5E_CPU0_P1_RX_BUF_DN(15)
  E7    GND     E7 @T6G_MB_LIB.T6G(SCH_1):GND
  E6 P5E_CPU0_P1_RX_BUF_DN<13>     E6 @T6G_MB_LIB.T6G(SCH_1):P5E_CPU0_P1_RX_BUF_DN(13)
  E5    GND     E5 @T6G_MB_LIB.T6G(SCH_1):GND
  F8 P5E_CPU0_P1_RX_BUF_DP<15>     F8 @T6G_MB_LIB.T6G(SCH_1):P5E_CPU0_P1_RX_BUF_DP(15)
  F7 P5E_CPU0_P1_RX_BUF_DN<14>     F7 @T6G_MB_LIB.T6G(SCH_1):P5E_CPU0_P1_RX_BUF_DN(14)
  F6 P5E_CPU0_P1_RX_BUF_DP<13>     F6 @T6G_MB_LIB.T6G(SCH_1):P5E_CPU0_P1_RX_BUF_DP(13)
  F5 P5E_CPU0_P1_RX_BUF_DN<12>     F5 @T6G_MB_LIB.T6G(SCH_1):P5E_CPU0_P1_RX_BUF_DN(12)
  G8    GND     G8 @T6G_MB_LIB.T6G(SCH_1):GND
  G7 P5E_CPU0_P1_RX_BUF_DP<14>     G7 @T6G_MB_LIB.T6G(SCH_1):P5E_CPU0_P1_RX_BUF_DP(14)
  G6    GND     G6 @T6G_MB_LIB.T6G(SCH_1):GND
  G5 P5E_CPU0_P1_RX_BUF_DP<12>     G5 @T6G_MB_LIB.T6G(SCH_1):P5E_CPU0_P1_RX_BUF_DP(12)
  H8 P5E_CPU0_P0_TX_BUF_C_DN<15>     H8 @T6G_MB_LIB.T6G(SCH_1):P5E_CPU0_P0_TX_BUF_C_DN(15)
  H7    GND     H7 @T6G_MB_LIB.T6G(SCH_1):GND
  H6 P5E_CPU0_P0_TX_BUF_C_DN<13>     H6 @T6G_MB_LIB.T6G(SCH_1):P5E_CPU0_P0_TX_BUF_C_DN(13)
  H5    GND     H5 @T6G_MB_LIB.T6G(SCH_1):GND
  I8 P5E_CPU0_P0_TX_BUF_C_DP<15>     I8 @T6G_MB_LIB.T6G(SCH_1):P5E_CPU0_P0_TX_BUF_C_DP(15)
  I7 P5E_CPU0_P0_TX_BUF_C_DN<14>     I7 @T6G_MB_LIB.T6G(SCH_1):P5E_CPU0_P0_TX_BUF_C_DN(14)
  I6 P5E_CPU0_P0_TX_BUF_C_DP<13>     I6 @T6G_MB_LIB.T6G(SCH_1):P5E_CPU0_P0_TX_BUF_C_DP(13)
  I5 P5E_CPU0_P0_TX_BUF_C_DN<12>     I5 @T6G_MB_LIB.T6G(SCH_1):P5E_CPU0_P0_TX_BUF_C_DN(12)
  J8    GND     J8 @T6G_MB_LIB.T6G(SCH_1):GND
  J7 P5E_CPU0_P0_TX_BUF_C_DP<14>     J7 @T6G_MB_LIB.T6G(SCH_1):P5E_CPU0_P0_TX_BUF_C_DP(14)
  J6    GND     J6 @T6G_MB_LIB.T6G(SCH_1):GND
  J5 P5E_CPU0_P0_TX_BUF_C_DP<12>     J5 @T6G_MB_LIB.T6G(SCH_1):P5E_CPU0_P0_TX_BUF_C_DP(12)
  K8 P5E_CPU0_P1_TX_BUF_C_DN<15>     K8 @T6G_MB_LIB.T6G(SCH_1):P5E_CPU0_P1_TX_BUF_C_DN(15)
  K7    GND     K7 @T6G_MB_LIB.T6G(SCH_1):GND
  K6 P5E_CPU0_P1_TX_BUF_C_DN<13>     K6 @T6G_MB_LIB.T6G(SCH_1):P5E_CPU0_P1_TX_BUF_C_DN(13)
  K5    GND     K5 @T6G_MB_LIB.T6G(SCH_1):GND
  L8 P5E_CPU0_P1_TX_BUF_C_DP<15>     L8 @T6G_MB_LIB.T6G(SCH_1):P5E_CPU0_P1_TX_BUF_C_DP(15)
  L7 P5E_CPU0_P1_TX_BUF_C_DN<14>     L7 @T6G_MB_LIB.T6G(SCH_1):P5E_CPU0_P1_TX_BUF_C_DN(14)
  L6 P5E_CPU0_P1_TX_BUF_C_DP<13>     L6 @T6G_MB_LIB.T6G(SCH_1):P5E_CPU0_P1_TX_BUF_C_DP(13)
  L5 P5E_CPU0_P1_TX_BUF_C_DN<12>     L5 @T6G_MB_LIB.T6G(SCH_1):P5E_CPU0_P1_TX_BUF_C_DN(12)
  M5 P5E_CPU0_P1_TX_BUF_C_DP<12>     M5 @T6G_MB_LIB.T6G(SCH_1):P5E_CPU0_P1_TX_BUF_C_DP(12)
  N5    GND     N5 @T6G_MB_LIB.T6G(SCH_1):GND
  M6    GND     M6 @T6G_MB_LIB.T6G(SCH_1):GND
  N6 NC_J107_N6     N6 @T6G_MB_LIB.T6G(SCH_1):NC_J107_N6
  M7 P5E_CPU0_P1_TX_BUF_C_DP<14>     M7 @T6G_MB_LIB.T6G(SCH_1):P5E_CPU0_P1_TX_BUF_C_DP(14)
  N7    GND     N7 @T6G_MB_LIB.T6G(SCH_1):GND
  M8    GND     M8 @T6G_MB_LIB.T6G(SCH_1):GND
  N8 SWB_HSC_EN_BUF     N8 @T6G_MB_LIB.T6G(SCH_1):SWB_HSC_EN_BUF


DRAWING: @T6G_MB_LIB.T6G(SCH_1):PAGE320 

CONN112_10137002101LF-CONN112_10137002-101LF,THLF,A  I15  J108
  A8    GND     A8 @T6G_MB_LIB.T6G(SCH_1):GND
  A7 GPU_FPGA_OVERT_N     A7 @T6G_MB_LIB.T6G(SCH_1):GPU_FPGA_OVERT_N
  A6    GND     A6 @T6G_MB_LIB.T6G(SCH_1):GND
  A5 GPU_3V3IO_RSVD5_FFU     A5 @T6G_MB_LIB.T6G(SCH_1):GPU_3V3IO_RSVD5_FFU
  B8 P5E_CPU0_P0_RX_BUF_DN<7>     B8 @T6G_MB_LIB.T6G(SCH_1):P5E_CPU0_P0_RX_BUF_DN(7)
  B7    GND     B7 @T6G_MB_LIB.T6G(SCH_1):GND
  B6 P5E_CPU0_P0_RX_BUF_DN<5>     B6 @T6G_MB_LIB.T6G(SCH_1):P5E_CPU0_P0_RX_BUF_DN(5)
  B5    GND     B5 @T6G_MB_LIB.T6G(SCH_1):GND
  C8 P5E_CPU0_P0_RX_BUF_DP<7>     C8 @T6G_MB_LIB.T6G(SCH_1):P5E_CPU0_P0_RX_BUF_DP(7)
  C7 P5E_CPU0_P0_RX_BUF_DN<6>     C7 @T6G_MB_LIB.T6G(SCH_1):P5E_CPU0_P0_RX_BUF_DN(6)
  C6 P5E_CPU0_P0_RX_BUF_DP<5>     C6 @T6G_MB_LIB.T6G(SCH_1):P5E_CPU0_P0_RX_BUF_DP(5)
  C5 P5E_CPU0_P0_RX_BUF_DN<4>     C5 @T6G_MB_LIB.T6G(SCH_1):P5E_CPU0_P0_RX_BUF_DN(4)
  D8    GND     D8 @T6G_MB_LIB.T6G(SCH_1):GND
  D7 P5E_CPU0_P0_RX_BUF_DP<6>     D7 @T6G_MB_LIB.T6G(SCH_1):P5E_CPU0_P0_RX_BUF_DP(6)
  D6    GND     D6 @T6G_MB_LIB.T6G(SCH_1):GND
  D5 P5E_CPU0_P0_RX_BUF_DP<4>     D5 @T6G_MB_LIB.T6G(SCH_1):P5E_CPU0_P0_RX_BUF_DP(4)
  E8 P5E_CPU0_P1_RX_BUF_DN<7>     E8 @T6G_MB_LIB.T6G(SCH_1):P5E_CPU0_P1_RX_BUF_DN(7)
  E7    GND     E7 @T6G_MB_LIB.T6G(SCH_1):GND
  E6 P5E_CPU0_P1_RX_BUF_DN<5>     E6 @T6G_MB_LIB.T6G(SCH_1):P5E_CPU0_P1_RX_BUF_DN(5)
  E5    GND     E5 @T6G_MB_LIB.T6G(SCH_1):GND
  F8 P5E_CPU0_P1_RX_BUF_DP<7>     F8 @T6G_MB_LIB.T6G(SCH_1):P5E_CPU0_P1_RX_BUF_DP(7)
  F7 P5E_CPU0_P1_RX_BUF_DN<6>     F7 @T6G_MB_LIB.T6G(SCH_1):P5E_CPU0_P1_RX_BUF_DN(6)
  F6 P5E_CPU0_P1_RX_BUF_DP<5>     F6 @T6G_MB_LIB.T6G(SCH_1):P5E_CPU0_P1_RX_BUF_DP(5)
  F5 P5E_CPU0_P1_RX_BUF_DN<4>     F5 @T6G_MB_LIB.T6G(SCH_1):P5E_CPU0_P1_RX_BUF_DN(4)
  G8    GND     G8 @T6G_MB_LIB.T6G(SCH_1):GND
  G7 P5E_CPU0_P1_RX_BUF_DP<6>     G7 @T6G_MB_LIB.T6G(SCH_1):P5E_CPU0_P1_RX_BUF_DP(6)
  G6    GND     G6 @T6G_MB_LIB.T6G(SCH_1):GND
  G5 P5E_CPU0_P1_RX_BUF_DP<4>     G5 @T6G_MB_LIB.T6G(SCH_1):P5E_CPU0_P1_RX_BUF_DP(4)
  H8 P5E_CPU0_P0_TX_BUF_C_DN<7>     H8 @T6G_MB_LIB.T6G(SCH_1):P5E_CPU0_P0_TX_BUF_C_DN(7)
  H7    GND     H7 @T6G_MB_LIB.T6G(SCH_1):GND
  H6 P5E_CPU0_P0_TX_BUF_C_DN<5>     H6 @T6G_MB_LIB.T6G(SCH_1):P5E_CPU0_P0_TX_BUF_C_DN(5)
  H5    GND     H5 @T6G_MB_LIB.T6G(SCH_1):GND
  I8 P5E_CPU0_P0_TX_BUF_C_DP<7>     I8 @T6G_MB_LIB.T6G(SCH_1):P5E_CPU0_P0_TX_BUF_C_DP(7)
  I7 P5E_CPU0_P0_TX_BUF_C_DN<6>     I7 @T6G_MB_LIB.T6G(SCH_1):P5E_CPU0_P0_TX_BUF_C_DN(6)
  I6 P5E_CPU0_P0_TX_BUF_C_DP<5>     I6 @T6G_MB_LIB.T6G(SCH_1):P5E_CPU0_P0_TX_BUF_C_DP(5)
  I5 P5E_CPU0_P0_TX_BUF_C_DN<4>     I5 @T6G_MB_LIB.T6G(SCH_1):P5E_CPU0_P0_TX_BUF_C_DN(4)
  J8    GND     J8 @T6G_MB_LIB.T6G(SCH_1):GND
  J7 P5E_CPU0_P0_TX_BUF_C_DP<6>     J7 @T6G_MB_LIB.T6G(SCH_1):P5E_CPU0_P0_TX_BUF_C_DP(6)
  J6    GND     J6 @T6G_MB_LIB.T6G(SCH_1):GND
  J5 P5E_CPU0_P0_TX_BUF_C_DP<4>     J5 @T6G_MB_LIB.T6G(SCH_1):P5E_CPU0_P0_TX_BUF_C_DP(4)
  K8 P5E_CPU0_P1_TX_BUF_C_DN<7>     K8 @T6G_MB_LIB.T6G(SCH_1):P5E_CPU0_P1_TX_BUF_C_DN(7)
  K7    GND     K7 @T6G_MB_LIB.T6G(SCH_1):GND
  K6 P5E_CPU0_P1_TX_BUF_C_DN<5>     K6 @T6G_MB_LIB.T6G(SCH_1):P5E_CPU0_P1_TX_BUF_C_DN(5)
  K5    GND     K5 @T6G_MB_LIB.T6G(SCH_1):GND
  L8 P5E_CPU0_P1_TX_BUF_C_DP<7>     L8 @T6G_MB_LIB.T6G(SCH_1):P5E_CPU0_P1_TX_BUF_C_DP(7)
  L7 P5E_CPU0_P1_TX_BUF_C_DN<6>     L7 @T6G_MB_LIB.T6G(SCH_1):P5E_CPU0_P1_TX_BUF_C_DN(6)
  L6 P5E_CPU0_P1_TX_BUF_C_DP<5>     L6 @T6G_MB_LIB.T6G(SCH_1):P5E_CPU0_P1_TX_BUF_C_DP(5)
  L5 P5E_CPU0_P1_TX_BUF_C_DN<4>     L5 @T6G_MB_LIB.T6G(SCH_1):P5E_CPU0_P1_TX_BUF_C_DN(4)
  M5 P5E_CPU0_P1_TX_BUF_C_DP<4>     M5 @T6G_MB_LIB.T6G(SCH_1):P5E_CPU0_P1_TX_BUF_C_DP(4)
  N5    GND     N5 @T6G_MB_LIB.T6G(SCH_1):GND
  M6    GND     M6 @T6G_MB_LIB.T6G(SCH_1):GND
  N6 NC_J108_N6     N6 @T6G_MB_LIB.T6G(SCH_1):NC_J108_N6
  M7 P5E_CPU0_P1_TX_BUF_C_DP<6>     M7 @T6G_MB_LIB.T6G(SCH_1):P5E_CPU0_P1_TX_BUF_C_DP(6)
  N7    GND     N7 @T6G_MB_LIB.T6G(SCH_1):GND
  M8    GND     M8 @T6G_MB_LIB.T6G(SCH_1):GND
  N8 PRSNT_CABLE_GPU_A3_N     N8 @T6G_MB_LIB.T6G(SCH_1):PRSNT_CABLE_GPU_A3_N

CONN112_10137002101LF-CONN112_10137002-101LF,THLF,A  I72  J108
  A4    GND     A4 @T6G_MB_LIB.T6G(SCH_1):GND
  A3 PRSNT_CABLE_GPU_A2_N     A3 @T6G_MB_LIB.T6G(SCH_1):PRSNT_CABLE_GPU_A2_N
  A2    GND     A2 @T6G_MB_LIB.T6G(SCH_1):GND
  A1 GPU_3V3IO_RSVD3_FFU     A1 @T6G_MB_LIB.T6G(SCH_1):GPU_3V3IO_RSVD3_FFU
  B4 P5E_CPU0_P0_RX_BUF_DN<3>     B4 @T6G_MB_LIB.T6G(SCH_1):P5E_CPU0_P0_RX_BUF_DN(3)
  B3    GND     B3 @T6G_MB_LIB.T6G(SCH_1):GND
  B2 P5E_CPU0_P0_RX_BUF_DN<1>     B2 @T6G_MB_LIB.T6G(SCH_1):P5E_CPU0_P0_RX_BUF_DN(1)
  B1    GND     B1 @T6G_MB_LIB.T6G(SCH_1):GND
  C4 P5E_CPU0_P0_RX_BUF_DP<3>     C4 @T6G_MB_LIB.T6G(SCH_1):P5E_CPU0_P0_RX_BUF_DP(3)
  C3 P5E_CPU0_P0_RX_BUF_DN<2>     C3 @T6G_MB_LIB.T6G(SCH_1):P5E_CPU0_P0_RX_BUF_DN(2)
  C2 P5E_CPU0_P0_RX_BUF_DP<1>     C2 @T6G_MB_LIB.T6G(SCH_1):P5E_CPU0_P0_RX_BUF_DP(1)
  C1 P5E_CPU0_P0_RX_BUF_DN<0>     C1 @T6G_MB_LIB.T6G(SCH_1):P5E_CPU0_P0_RX_BUF_DN(0)
  D4    GND     D4 @T6G_MB_LIB.T6G(SCH_1):GND
  D3 P5E_CPU0_P0_RX_BUF_DP<2>     D3 @T6G_MB_LIB.T6G(SCH_1):P5E_CPU0_P0_RX_BUF_DP(2)
  D2    GND     D2 @T6G_MB_LIB.T6G(SCH_1):GND
  D1 P5E_CPU0_P0_RX_BUF_DP<0>     D1 @T6G_MB_LIB.T6G(SCH_1):P5E_CPU0_P0_RX_BUF_DP(0)
  E4 P5E_CPU0_P1_RX_BUF_DN<3>     E4 @T6G_MB_LIB.T6G(SCH_1):P5E_CPU0_P1_RX_BUF_DN(3)
  E3    GND     E3 @T6G_MB_LIB.T6G(SCH_1):GND
  E2 P5E_CPU0_P1_RX_BUF_DN<1>     E2 @T6G_MB_LIB.T6G(SCH_1):P5E_CPU0_P1_RX_BUF_DN(1)
  E1    GND     E1 @T6G_MB_LIB.T6G(SCH_1):GND
  F4 P5E_CPU0_P1_RX_BUF_DP<3>     F4 @T6G_MB_LIB.T6G(SCH_1):P5E_CPU0_P1_RX_BUF_DP(3)
  F3 P5E_CPU0_P1_RX_BUF_DN<2>     F3 @T6G_MB_LIB.T6G(SCH_1):P5E_CPU0_P1_RX_BUF_DN(2)
  F2 P5E_CPU0_P1_RX_BUF_DP<1>     F2 @T6G_MB_LIB.T6G(SCH_1):P5E_CPU0_P1_RX_BUF_DP(1)
  F1 P5E_CPU0_P1_RX_BUF_DN<0>     F1 @T6G_MB_LIB.T6G(SCH_1):P5E_CPU0_P1_RX_BUF_DN(0)
  G4    GND     G4 @T6G_MB_LIB.T6G(SCH_1):GND
  G3 P5E_CPU0_P1_RX_BUF_DP<2>     G3 @T6G_MB_LIB.T6G(SCH_1):P5E_CPU0_P1_RX_BUF_DP(2)
  G2    GND     G2 @T6G_MB_LIB.T6G(SCH_1):GND
  G1 P5E_CPU0_P1_RX_BUF_DP<0>     G1 @T6G_MB_LIB.T6G(SCH_1):P5E_CPU0_P1_RX_BUF_DP(0)
  H4 P5E_CPU0_P0_TX_BUF_C_DN<3>     H4 @T6G_MB_LIB.T6G(SCH_1):P5E_CPU0_P0_TX_BUF_C_DN(3)
  H3    GND     H3 @T6G_MB_LIB.T6G(SCH_1):GND
  H2 P5E_CPU0_P0_TX_BUF_C_DN<1>     H2 @T6G_MB_LIB.T6G(SCH_1):P5E_CPU0_P0_TX_BUF_C_DN(1)
  H1    GND     H1 @T6G_MB_LIB.T6G(SCH_1):GND
  I4 P5E_CPU0_P0_TX_BUF_C_DP<3>     I4 @T6G_MB_LIB.T6G(SCH_1):P5E_CPU0_P0_TX_BUF_C_DP(3)
  I3 P5E_CPU0_P0_TX_BUF_C_DN<2>     I3 @T6G_MB_LIB.T6G(SCH_1):P5E_CPU0_P0_TX_BUF_C_DN(2)
  I2 P5E_CPU0_P0_TX_BUF_C_DP<1>     I2 @T6G_MB_LIB.T6G(SCH_1):P5E_CPU0_P0_TX_BUF_C_DP(1)
  I1 P5E_CPU0_P0_TX_BUF_C_DN<0>     I1 @T6G_MB_LIB.T6G(SCH_1):P5E_CPU0_P0_TX_BUF_C_DN(0)
  J4    GND     J4 @T6G_MB_LIB.T6G(SCH_1):GND
  J3 P5E_CPU0_P0_TX_BUF_C_DP<2>     J3 @T6G_MB_LIB.T6G(SCH_1):P5E_CPU0_P0_TX_BUF_C_DP(2)
  J2    GND     J2 @T6G_MB_LIB.T6G(SCH_1):GND
  J1 P5E_CPU0_P0_TX_BUF_C_DP<0>     J1 @T6G_MB_LIB.T6G(SCH_1):P5E_CPU0_P0_TX_BUF_C_DP(0)
  K4 P5E_CPU0_P1_TX_BUF_C_DN<3>     K4 @T6G_MB_LIB.T6G(SCH_1):P5E_CPU0_P1_TX_BUF_C_DN(3)
  K3    GND     K3 @T6G_MB_LIB.T6G(SCH_1):GND
  K2 P5E_CPU0_P1_TX_BUF_C_DN<1>     K2 @T6G_MB_LIB.T6G(SCH_1):P5E_CPU0_P1_TX_BUF_C_DN(1)
  K1    GND     K1 @T6G_MB_LIB.T6G(SCH_1):GND
  L4 P5E_CPU0_P1_TX_BUF_C_DP<3>     L4 @T6G_MB_LIB.T6G(SCH_1):P5E_CPU0_P1_TX_BUF_C_DP(3)
  L3 P5E_CPU0_P1_TX_BUF_C_DN<2>     L3 @T6G_MB_LIB.T6G(SCH_1):P5E_CPU0_P1_TX_BUF_C_DN(2)
  L2 P5E_CPU0_P1_TX_BUF_C_DP<1>     L2 @T6G_MB_LIB.T6G(SCH_1):P5E_CPU0_P1_TX_BUF_C_DP(1)
  L1 P5E_CPU0_P1_TX_BUF_C_DN<0>     L1 @T6G_MB_LIB.T6G(SCH_1):P5E_CPU0_P1_TX_BUF_C_DN(0)
  M1 P5E_CPU0_P1_TX_BUF_C_DP<0>     M1 @T6G_MB_LIB.T6G(SCH_1):P5E_CPU0_P1_TX_BUF_C_DP(0)
  N1    GND     N1 @T6G_MB_LIB.T6G(SCH_1):GND
  M2    GND     M2 @T6G_MB_LIB.T6G(SCH_1):GND
  N2 NC_J108_N2     N2 @T6G_MB_LIB.T6G(SCH_1):NC_J108_N2
  M3 P5E_CPU0_P1_TX_BUF_C_DP<2>     M3 @T6G_MB_LIB.T6G(SCH_1):P5E_CPU0_P1_TX_BUF_C_DP(2)
  N3    GND     N3 @T6G_MB_LIB.T6G(SCH_1):GND
  M4    GND     M4 @T6G_MB_LIB.T6G(SCH_1):GND
  N4 NC_J108_N4     N4 @T6G_MB_LIB.T6G(SCH_1):NC_J108_N4


DRAWING: @T6G_MB_LIB.T6G(SCH_1):PAGE319 

CONN112_10137002101LF-CONN112_10137002-101LF,THLF,A  I16  J109
  A8    GND     A8 @T6G_MB_LIB.T6G(SCH_1):GND
  A7 SMB_BMC_SWB_BUF_SDA     A7 @T6G_MB_LIB.T6G(SCH_1):SMB_BMC_SWB_BUF_SDA
  A6    GND     A6 @T6G_MB_LIB.T6G(SCH_1):GND
  A5 SMB_BMC_SWB_BUF_SCL     A5 @T6G_MB_LIB.T6G(SCH_1):SMB_BMC_SWB_BUF_SCL
  B8 P5E_CPU1_P2_RX_BUF_DN<15>     B8 @T6G_MB_LIB.T6G(SCH_1):P5E_CPU1_P2_RX_BUF_DN(15)
  B7    GND     B7 @T6G_MB_LIB.T6G(SCH_1):GND
  B6 P5E_CPU1_P2_RX_BUF_DN<13>     B6 @T6G_MB_LIB.T6G(SCH_1):P5E_CPU1_P2_RX_BUF_DN(13)
  B5    GND     B5 @T6G_MB_LIB.T6G(SCH_1):GND
  C8 P5E_CPU1_P2_RX_BUF_DP<15>     C8 @T6G_MB_LIB.T6G(SCH_1):P5E_CPU1_P2_RX_BUF_DP(15)
  C7 P5E_CPU1_P2_RX_BUF_DN<14>     C7 @T6G_MB_LIB.T6G(SCH_1):P5E_CPU1_P2_RX_BUF_DN(14)
  C6 P5E_CPU1_P2_RX_BUF_DP<13>     C6 @T6G_MB_LIB.T6G(SCH_1):P5E_CPU1_P2_RX_BUF_DP(13)
  C5 P5E_CPU1_P2_RX_BUF_DN<12>     C5 @T6G_MB_LIB.T6G(SCH_1):P5E_CPU1_P2_RX_BUF_DN(12)
  D8    GND     D8 @T6G_MB_LIB.T6G(SCH_1):GND
  D7 P5E_CPU1_P2_RX_BUF_DP<14>     D7 @T6G_MB_LIB.T6G(SCH_1):P5E_CPU1_P2_RX_BUF_DP(14)
  D6    GND     D6 @T6G_MB_LIB.T6G(SCH_1):GND
  D5 P5E_CPU1_P2_RX_BUF_DP<12>     D5 @T6G_MB_LIB.T6G(SCH_1):P5E_CPU1_P2_RX_BUF_DP(12)
  E8 P5E_CPU1_P3_RX_BUF_DN<15>     E8 @T6G_MB_LIB.T6G(SCH_1):P5E_CPU1_P3_RX_BUF_DN(15)
  E7    GND     E7 @T6G_MB_LIB.T6G(SCH_1):GND
  E6 P5E_CPU1_P3_RX_BUF_DN<13>     E6 @T6G_MB_LIB.T6G(SCH_1):P5E_CPU1_P3_RX_BUF_DN(13)
  E5    GND     E5 @T6G_MB_LIB.T6G(SCH_1):GND
  F8 P5E_CPU1_P3_RX_BUF_DP<15>     F8 @T6G_MB_LIB.T6G(SCH_1):P5E_CPU1_P3_RX_BUF_DP(15)
  F7 P5E_CPU1_P3_RX_BUF_DN<14>     F7 @T6G_MB_LIB.T6G(SCH_1):P5E_CPU1_P3_RX_BUF_DN(14)
  F6 P5E_CPU1_P3_RX_BUF_DP<13>     F6 @T6G_MB_LIB.T6G(SCH_1):P5E_CPU1_P3_RX_BUF_DP(13)
  F5 P5E_CPU1_P3_RX_BUF_DN<12>     F5 @T6G_MB_LIB.T6G(SCH_1):P5E_CPU1_P3_RX_BUF_DN(12)
  G8    GND     G8 @T6G_MB_LIB.T6G(SCH_1):GND
  G7 P5E_CPU1_P3_RX_BUF_DP<14>     G7 @T6G_MB_LIB.T6G(SCH_1):P5E_CPU1_P3_RX_BUF_DP(14)
  G6    GND     G6 @T6G_MB_LIB.T6G(SCH_1):GND
  G5 P5E_CPU1_P3_RX_BUF_DP<12>     G5 @T6G_MB_LIB.T6G(SCH_1):P5E_CPU1_P3_RX_BUF_DP(12)
  H8 P5E_CPU1_P2_TX_BUF_C_DN<15>     H8 @T6G_MB_LIB.T6G(SCH_1):P5E_CPU1_P2_TX_BUF_C_DN(15)
  H7    GND     H7 @T6G_MB_LIB.T6G(SCH_1):GND
  H6 P5E_CPU1_P2_TX_BUF_C_DN<13>     H6 @T6G_MB_LIB.T6G(SCH_1):P5E_CPU1_P2_TX_BUF_C_DN(13)
  H5    GND     H5 @T6G_MB_LIB.T6G(SCH_1):GND
  I8 P5E_CPU1_P2_TX_BUF_C_DP<15>     I8 @T6G_MB_LIB.T6G(SCH_1):P5E_CPU1_P2_TX_BUF_C_DP(15)
  I7 P5E_CPU1_P2_TX_BUF_C_DN<14>     I7 @T6G_MB_LIB.T6G(SCH_1):P5E_CPU1_P2_TX_BUF_C_DN(14)
  I6 P5E_CPU1_P2_TX_BUF_C_DP<13>     I6 @T6G_MB_LIB.T6G(SCH_1):P5E_CPU1_P2_TX_BUF_C_DP(13)
  I5 P5E_CPU1_P2_TX_BUF_C_DN<12>     I5 @T6G_MB_LIB.T6G(SCH_1):P5E_CPU1_P2_TX_BUF_C_DN(12)
  J8    GND     J8 @T6G_MB_LIB.T6G(SCH_1):GND
  J7 P5E_CPU1_P2_TX_BUF_C_DP<14>     J7 @T6G_MB_LIB.T6G(SCH_1):P5E_CPU1_P2_TX_BUF_C_DP(14)
  J6    GND     J6 @T6G_MB_LIB.T6G(SCH_1):GND
  J5 P5E_CPU1_P2_TX_BUF_C_DP<12>     J5 @T6G_MB_LIB.T6G(SCH_1):P5E_CPU1_P2_TX_BUF_C_DP(12)
  K8 P5E_CPU1_P3_TX_BUF_C_DN<15>     K8 @T6G_MB_LIB.T6G(SCH_1):P5E_CPU1_P3_TX_BUF_C_DN(15)
  K7    GND     K7 @T6G_MB_LIB.T6G(SCH_1):GND
  K6 P5E_CPU1_P3_TX_BUF_C_DN<13>     K6 @T6G_MB_LIB.T6G(SCH_1):P5E_CPU1_P3_TX_BUF_C_DN(13)
  K5    GND     K5 @T6G_MB_LIB.T6G(SCH_1):GND
  L8 P5E_CPU1_P3_TX_BUF_C_DP<15>     L8 @T6G_MB_LIB.T6G(SCH_1):P5E_CPU1_P3_TX_BUF_C_DP(15)
  L7 P5E_CPU1_P3_TX_BUF_C_DN<14>     L7 @T6G_MB_LIB.T6G(SCH_1):P5E_CPU1_P3_TX_BUF_C_DN(14)
  L6 P5E_CPU1_P3_TX_BUF_C_DP<13>     L6 @T6G_MB_LIB.T6G(SCH_1):P5E_CPU1_P3_TX_BUF_C_DP(13)
  L5 P5E_CPU1_P3_TX_BUF_C_DN<12>     L5 @T6G_MB_LIB.T6G(SCH_1):P5E_CPU1_P3_TX_BUF_C_DN(12)
  M5 P5E_CPU1_P3_TX_BUF_C_DP<12>     M5 @T6G_MB_LIB.T6G(SCH_1):P5E_CPU1_P3_TX_BUF_C_DP(12)
  N5    GND     N5 @T6G_MB_LIB.T6G(SCH_1):GND
  M6    GND     M6 @T6G_MB_LIB.T6G(SCH_1):GND
  N6 GPU_3V3IO_RSVD1_FFU     N6 @T6G_MB_LIB.T6G(SCH_1):GPU_3V3IO_RSVD1_FFU
  M7 P5E_CPU1_P3_TX_BUF_C_DP<14>     M7 @T6G_MB_LIB.T6G(SCH_1):P5E_CPU1_P3_TX_BUF_C_DP(14)
  N7    GND     N7 @T6G_MB_LIB.T6G(SCH_1):GND
  M8    GND     M8 @T6G_MB_LIB.T6G(SCH_1):GND
  N8 PRSNT_CABLE_GPU_B3_N     N8 @T6G_MB_LIB.T6G(SCH_1):PRSNT_CABLE_GPU_B3_N

CONN112_10137002101LF-CONN112_10137002-101LF,THLF,A  I76  J109
  A4    GND     A4 @T6G_MB_LIB.T6G(SCH_1):GND
  A3 BIC_MONITER     A3 @T6G_MB_LIB.T6G(SCH_1):BIC_MONITER
  A2    GND     A2 @T6G_MB_LIB.T6G(SCH_1):GND
  A1 BMC_MONITER_BUF     A1 @T6G_MB_LIB.T6G(SCH_1):BMC_MONITER_BUF
  B4 P5E_CPU1_P2_RX_BUF_DN<11>     B4 @T6G_MB_LIB.T6G(SCH_1):P5E_CPU1_P2_RX_BUF_DN(11)
  B3    GND     B3 @T6G_MB_LIB.T6G(SCH_1):GND
  B2 P5E_CPU1_P2_RX_BUF_DN<9>     B2 @T6G_MB_LIB.T6G(SCH_1):P5E_CPU1_P2_RX_BUF_DN(9)
  B1    GND     B1 @T6G_MB_LIB.T6G(SCH_1):GND
  C4 P5E_CPU1_P2_RX_BUF_DP<11>     C4 @T6G_MB_LIB.T6G(SCH_1):P5E_CPU1_P2_RX_BUF_DP(11)
  C3 P5E_CPU1_P2_RX_BUF_DN<10>     C3 @T6G_MB_LIB.T6G(SCH_1):P5E_CPU1_P2_RX_BUF_DN(10)
  C2 P5E_CPU1_P2_RX_BUF_DP<9>     C2 @T6G_MB_LIB.T6G(SCH_1):P5E_CPU1_P2_RX_BUF_DP(9)
  C1 P5E_CPU1_P2_RX_BUF_DN<8>     C1 @T6G_MB_LIB.T6G(SCH_1):P5E_CPU1_P2_RX_BUF_DN(8)
  D4    GND     D4 @T6G_MB_LIB.T6G(SCH_1):GND
  D3 P5E_CPU1_P2_RX_BUF_DP<10>     D3 @T6G_MB_LIB.T6G(SCH_1):P5E_CPU1_P2_RX_BUF_DP(10)
  D2    GND     D2 @T6G_MB_LIB.T6G(SCH_1):GND
  D1 P5E_CPU1_P2_RX_BUF_DP<8>     D1 @T6G_MB_LIB.T6G(SCH_1):P5E_CPU1_P2_RX_BUF_DP(8)
  E4 P5E_CPU1_P3_RX_BUF_DN<11>     E4 @T6G_MB_LIB.T6G(SCH_1):P5E_CPU1_P3_RX_BUF_DN(11)
  E3    GND     E3 @T6G_MB_LIB.T6G(SCH_1):GND
  E2 P5E_CPU1_P3_RX_BUF_DN<9>     E2 @T6G_MB_LIB.T6G(SCH_1):P5E_CPU1_P3_RX_BUF_DN(9)
  E1    GND     E1 @T6G_MB_LIB.T6G(SCH_1):GND
  F4 P5E_CPU1_P3_RX_BUF_DP<11>     F4 @T6G_MB_LIB.T6G(SCH_1):P5E_CPU1_P3_RX_BUF_DP(11)
  F3 P5E_CPU1_P3_RX_BUF_DN<10>     F3 @T6G_MB_LIB.T6G(SCH_1):P5E_CPU1_P3_RX_BUF_DN(10)
  F2 P5E_CPU1_P3_RX_BUF_DP<9>     F2 @T6G_MB_LIB.T6G(SCH_1):P5E_CPU1_P3_RX_BUF_DP(9)
  F1 P5E_CPU1_P3_RX_BUF_DN<8>     F1 @T6G_MB_LIB.T6G(SCH_1):P5E_CPU1_P3_RX_BUF_DN(8)
  G4    GND     G4 @T6G_MB_LIB.T6G(SCH_1):GND
  G3 P5E_CPU1_P3_RX_BUF_DP<10>     G3 @T6G_MB_LIB.T6G(SCH_1):P5E_CPU1_P3_RX_BUF_DP(10)
  G2    GND     G2 @T6G_MB_LIB.T6G(SCH_1):GND
  G1 P5E_CPU1_P3_RX_BUF_DP<8>     G1 @T6G_MB_LIB.T6G(SCH_1):P5E_CPU1_P3_RX_BUF_DP(8)
  H4 P5E_CPU1_P2_TX_BUF_C_DN<11>     H4 @T6G_MB_LIB.T6G(SCH_1):P5E_CPU1_P2_TX_BUF_C_DN(11)
  H3    GND     H3 @T6G_MB_LIB.T6G(SCH_1):GND
  H2 P5E_CPU1_P2_TX_BUF_C_DN<9>     H2 @T6G_MB_LIB.T6G(SCH_1):P5E_CPU1_P2_TX_BUF_C_DN(9)
  H1    GND     H1 @T6G_MB_LIB.T6G(SCH_1):GND
  I4 P5E_CPU1_P2_TX_BUF_C_DP<11>     I4 @T6G_MB_LIB.T6G(SCH_1):P5E_CPU1_P2_TX_BUF_C_DP(11)
  I3 P5E_CPU1_P2_TX_BUF_C_DN<10>     I3 @T6G_MB_LIB.T6G(SCH_1):P5E_CPU1_P2_TX_BUF_C_DN(10)
  I2 P5E_CPU1_P2_TX_BUF_C_DP<9>     I2 @T6G_MB_LIB.T6G(SCH_1):P5E_CPU1_P2_TX_BUF_C_DP(9)
  I1 P5E_CPU1_P2_TX_BUF_C_DN<8>     I1 @T6G_MB_LIB.T6G(SCH_1):P5E_CPU1_P2_TX_BUF_C_DN(8)
  J4    GND     J4 @T6G_MB_LIB.T6G(SCH_1):GND
  J3 P5E_CPU1_P2_TX_BUF_C_DP<10>     J3 @T6G_MB_LIB.T6G(SCH_1):P5E_CPU1_P2_TX_BUF_C_DP(10)
  J2    GND     J2 @T6G_MB_LIB.T6G(SCH_1):GND
  J1 P5E_CPU1_P2_TX_BUF_C_DP<8>     J1 @T6G_MB_LIB.T6G(SCH_1):P5E_CPU1_P2_TX_BUF_C_DP(8)
  K4 P5E_CPU1_P3_TX_BUF_C_DN<11>     K4 @T6G_MB_LIB.T6G(SCH_1):P5E_CPU1_P3_TX_BUF_C_DN(11)
  K3    GND     K3 @T6G_MB_LIB.T6G(SCH_1):GND
  K2 P5E_CPU1_P3_TX_BUF_C_DN<9>     K2 @T6G_MB_LIB.T6G(SCH_1):P5E_CPU1_P3_TX_BUF_C_DN(9)
  K1    GND     K1 @T6G_MB_LIB.T6G(SCH_1):GND
  L4 P5E_CPU1_P3_TX_BUF_C_DP<11>     L4 @T6G_MB_LIB.T6G(SCH_1):P5E_CPU1_P3_TX_BUF_C_DP(11)
  L3 P5E_CPU1_P3_TX_BUF_C_DN<10>     L3 @T6G_MB_LIB.T6G(SCH_1):P5E_CPU1_P3_TX_BUF_C_DN(10)
  L2 P5E_CPU1_P3_TX_BUF_C_DP<9>     L2 @T6G_MB_LIB.T6G(SCH_1):P5E_CPU1_P3_TX_BUF_C_DP(9)
  L1 P5E_CPU1_P3_TX_BUF_C_DN<8>     L1 @T6G_MB_LIB.T6G(SCH_1):P5E_CPU1_P3_TX_BUF_C_DN(8)
  M1 P5E_CPU1_P3_TX_BUF_C_DP<8>     M1 @T6G_MB_LIB.T6G(SCH_1):P5E_CPU1_P3_TX_BUF_C_DP(8)
  N1    GND     N1 @T6G_MB_LIB.T6G(SCH_1):GND
  M2    GND     M2 @T6G_MB_LIB.T6G(SCH_1):GND
  N2 GPU_FPGA_EROT_FATALERR_N     N2 @T6G_MB_LIB.T6G(SCH_1):GPU_FPGA_EROT_FATALERR_N
  M3 P5E_CPU1_P3_TX_BUF_C_DP<10>     M3 @T6G_MB_LIB.T6G(SCH_1):P5E_CPU1_P3_TX_BUF_C_DP(10)
  N3    GND     N3 @T6G_MB_LIB.T6G(SCH_1):GND
  M4    GND     M4 @T6G_MB_LIB.T6G(SCH_1):GND
  N4 GPU_3V3IO_RSVD0_FFU     N4 @T6G_MB_LIB.T6G(SCH_1):GPU_3V3IO_RSVD0_FFU


DRAWING: @T6G_MB_LIB.T6G(SCH_1):PAGE318 

CONN112_10137002101LF-CONN112_10137002-101LF,THLF,A  I16  J110
  A8    GND     A8 @T6G_MB_LIB.T6G(SCH_1):GND
  A7 GPU_BASE_STBY_EN_BUF     A7 @T6G_MB_LIB.T6G(SCH_1):GPU_BASE_STBY_EN_BUF
  A6    GND     A6 @T6G_MB_LIB.T6G(SCH_1):GND
  A5 GPU_BASE_HMC_READY     A5 @T6G_MB_LIB.T6G(SCH_1):GPU_BASE_HMC_READY
  B8 P5E_CPU1_P2_RX_BUF_DN<7>     B8 @T6G_MB_LIB.T6G(SCH_1):P5E_CPU1_P2_RX_BUF_DN(7)
  B7    GND     B7 @T6G_MB_LIB.T6G(SCH_1):GND
  B6 P5E_CPU1_P2_RX_BUF_DN<5>     B6 @T6G_MB_LIB.T6G(SCH_1):P5E_CPU1_P2_RX_BUF_DN(5)
  B5    GND     B5 @T6G_MB_LIB.T6G(SCH_1):GND
  C8 P5E_CPU1_P2_RX_BUF_DP<7>     C8 @T6G_MB_LIB.T6G(SCH_1):P5E_CPU1_P2_RX_BUF_DP(7)
  C7 P5E_CPU1_P2_RX_BUF_DN<6>     C7 @T6G_MB_LIB.T6G(SCH_1):P5E_CPU1_P2_RX_BUF_DN(6)
  C6 P5E_CPU1_P2_RX_BUF_DP<5>     C6 @T6G_MB_LIB.T6G(SCH_1):P5E_CPU1_P2_RX_BUF_DP(5)
  C5 P5E_CPU1_P2_RX_BUF_DN<4>     C5 @T6G_MB_LIB.T6G(SCH_1):P5E_CPU1_P2_RX_BUF_DN(4)
  D8    GND     D8 @T6G_MB_LIB.T6G(SCH_1):GND
  D7 P5E_CPU1_P2_RX_BUF_DP<6>     D7 @T6G_MB_LIB.T6G(SCH_1):P5E_CPU1_P2_RX_BUF_DP(6)
  D6    GND     D6 @T6G_MB_LIB.T6G(SCH_1):GND
  D5 P5E_CPU1_P2_RX_BUF_DP<4>     D5 @T6G_MB_LIB.T6G(SCH_1):P5E_CPU1_P2_RX_BUF_DP(4)
  E8 P5E_CPU1_P3_RX_BUF_DN<7>     E8 @T6G_MB_LIB.T6G(SCH_1):P5E_CPU1_P3_RX_BUF_DN(7)
  E7    GND     E7 @T6G_MB_LIB.T6G(SCH_1):GND
  E6 P5E_CPU1_P3_RX_BUF_DN<5>     E6 @T6G_MB_LIB.T6G(SCH_1):P5E_CPU1_P3_RX_BUF_DN(5)
  E5    GND     E5 @T6G_MB_LIB.T6G(SCH_1):GND
  F8 P5E_CPU1_P3_RX_BUF_DP<7>     F8 @T6G_MB_LIB.T6G(SCH_1):P5E_CPU1_P3_RX_BUF_DP(7)
  F7 P5E_CPU1_P3_RX_BUF_DN<6>     F7 @T6G_MB_LIB.T6G(SCH_1):P5E_CPU1_P3_RX_BUF_DN(6)
  F6 P5E_CPU1_P3_RX_BUF_DP<5>     F6 @T6G_MB_LIB.T6G(SCH_1):P5E_CPU1_P3_RX_BUF_DP(5)
  F5 P5E_CPU1_P3_RX_BUF_DN<4>     F5 @T6G_MB_LIB.T6G(SCH_1):P5E_CPU1_P3_RX_BUF_DN(4)
  G8    GND     G8 @T6G_MB_LIB.T6G(SCH_1):GND
  G7 P5E_CPU1_P3_RX_BUF_DP<6>     G7 @T6G_MB_LIB.T6G(SCH_1):P5E_CPU1_P3_RX_BUF_DP(6)
  G6    GND     G6 @T6G_MB_LIB.T6G(SCH_1):GND
  G5 P5E_CPU1_P3_RX_BUF_DP<4>     G5 @T6G_MB_LIB.T6G(SCH_1):P5E_CPU1_P3_RX_BUF_DP(4)
  H8 P5E_CPU1_P2_TX_BUF_C_DN<7>     H8 @T6G_MB_LIB.T6G(SCH_1):P5E_CPU1_P2_TX_BUF_C_DN(7)
  H7    GND     H7 @T6G_MB_LIB.T6G(SCH_1):GND
  H6 P5E_CPU1_P2_TX_BUF_C_DN<5>     H6 @T6G_MB_LIB.T6G(SCH_1):P5E_CPU1_P2_TX_BUF_C_DN(5)
  H5    GND     H5 @T6G_MB_LIB.T6G(SCH_1):GND
  I8 P5E_CPU1_P2_TX_BUF_C_DP<7>     I8 @T6G_MB_LIB.T6G(SCH_1):P5E_CPU1_P2_TX_BUF_C_DP(7)
  I7 P5E_CPU1_P2_TX_BUF_C_DN<6>     I7 @T6G_MB_LIB.T6G(SCH_1):P5E_CPU1_P2_TX_BUF_C_DN(6)
  I6 P5E_CPU1_P2_TX_BUF_C_DP<5>     I6 @T6G_MB_LIB.T6G(SCH_1):P5E_CPU1_P2_TX_BUF_C_DP(5)
  I5 P5E_CPU1_P2_TX_BUF_C_DN<4>     I5 @T6G_MB_LIB.T6G(SCH_1):P5E_CPU1_P2_TX_BUF_C_DN(4)
  J8    GND     J8 @T6G_MB_LIB.T6G(SCH_1):GND
  J7 P5E_CPU1_P2_TX_BUF_C_DP<6>     J7 @T6G_MB_LIB.T6G(SCH_1):P5E_CPU1_P2_TX_BUF_C_DP(6)
  J6    GND     J6 @T6G_MB_LIB.T6G(SCH_1):GND
  J5 P5E_CPU1_P2_TX_BUF_C_DP<4>     J5 @T6G_MB_LIB.T6G(SCH_1):P5E_CPU1_P2_TX_BUF_C_DP(4)
  K8 P5E_CPU1_P3_TX_BUF_C_DN<7>     K8 @T6G_MB_LIB.T6G(SCH_1):P5E_CPU1_P3_TX_BUF_C_DN(7)
  K7    GND     K7 @T6G_MB_LIB.T6G(SCH_1):GND
  K6 P5E_CPU1_P3_TX_BUF_C_DN<5>     K6 @T6G_MB_LIB.T6G(SCH_1):P5E_CPU1_P3_TX_BUF_C_DN(5)
  K5    GND     K5 @T6G_MB_LIB.T6G(SCH_1):GND
  L8 P5E_CPU1_P3_TX_BUF_C_DP<7>     L8 @T6G_MB_LIB.T6G(SCH_1):P5E_CPU1_P3_TX_BUF_C_DP(7)
  L7 P5E_CPU1_P3_TX_BUF_C_DN<6>     L7 @T6G_MB_LIB.T6G(SCH_1):P5E_CPU1_P3_TX_BUF_C_DN(6)
  L6 P5E_CPU1_P3_TX_BUF_C_DP<5>     L6 @T6G_MB_LIB.T6G(SCH_1):P5E_CPU1_P3_TX_BUF_C_DP(5)
  L5 P5E_CPU1_P3_TX_BUF_C_DN<4>     L5 @T6G_MB_LIB.T6G(SCH_1):P5E_CPU1_P3_TX_BUF_C_DN(4)
  M5 P5E_CPU1_P3_TX_BUF_C_DP<4>     M5 @T6G_MB_LIB.T6G(SCH_1):P5E_CPU1_P3_TX_BUF_C_DP(4)
  N5    GND     N5 @T6G_MB_LIB.T6G(SCH_1):GND
  M6    GND     M6 @T6G_MB_LIB.T6G(SCH_1):GND
  N6 FM_SMB_2_ALERT_GPU_N     N6 @T6G_MB_LIB.T6G(SCH_1):FM_SMB_2_ALERT_GPU_N
  M7 P5E_CPU1_P3_TX_BUF_C_DP<6>     M7 @T6G_MB_LIB.T6G(SCH_1):P5E_CPU1_P3_TX_BUF_C_DP(6)
  N7    GND     N7 @T6G_MB_LIB.T6G(SCH_1):GND
  M8    GND     M8 @T6G_MB_LIB.T6G(SCH_1):GND
  N8 GPU_FPGA_EROT_RST_BUF_N     N8 @T6G_MB_LIB.T6G(SCH_1):GPU_FPGA_EROT_RST_BUF_N

CONN112_10137002101LF-CONN112_10137002-101LF,THLF,A  I76  J110
  A4    GND     A4 @T6G_MB_LIB.T6G(SCH_1):GND
  A3 GPU_HMC_PRSNT_N     A3 @T6G_MB_LIB.T6G(SCH_1):GPU_HMC_PRSNT_N
  A2    GND     A2 @T6G_MB_LIB.T6G(SCH_1):GND
  A1 GPU_FPGA_EROT_RECOV_BUF_N     A1 @T6G_MB_LIB.T6G(SCH_1):GPU_FPGA_EROT_RECOV_BUF_N
  B4 P5E_CPU1_P2_RX_BUF_DN<3>     B4 @T6G_MB_LIB.T6G(SCH_1):P5E_CPU1_P2_RX_BUF_DN(3)
  B3    GND     B3 @T6G_MB_LIB.T6G(SCH_1):GND
  B2 P5E_CPU1_P2_RX_BUF_DN<1>     B2 @T6G_MB_LIB.T6G(SCH_1):P5E_CPU1_P2_RX_BUF_DN(1)
  B1    GND     B1 @T6G_MB_LIB.T6G(SCH_1):GND
  C4 P5E_CPU1_P2_RX_BUF_DP<3>     C4 @T6G_MB_LIB.T6G(SCH_1):P5E_CPU1_P2_RX_BUF_DP(3)
  C3 P5E_CPU1_P2_RX_BUF_DN<2>     C3 @T6G_MB_LIB.T6G(SCH_1):P5E_CPU1_P2_RX_BUF_DN(2)
  C2 P5E_CPU1_P2_RX_BUF_DP<1>     C2 @T6G_MB_LIB.T6G(SCH_1):P5E_CPU1_P2_RX_BUF_DP(1)
  C1 P5E_CPU1_P2_RX_BUF_DN<0>     C1 @T6G_MB_LIB.T6G(SCH_1):P5E_CPU1_P2_RX_BUF_DN(0)
  D4    GND     D4 @T6G_MB_LIB.T6G(SCH_1):GND
  D3 P5E_CPU1_P2_RX_BUF_DP<2>     D3 @T6G_MB_LIB.T6G(SCH_1):P5E_CPU1_P2_RX_BUF_DP(2)
  D2    GND     D2 @T6G_MB_LIB.T6G(SCH_1):GND
  D1 P5E_CPU1_P2_RX_BUF_DP<0>     D1 @T6G_MB_LIB.T6G(SCH_1):P5E_CPU1_P2_RX_BUF_DP(0)
  E4 P5E_CPU1_P3_RX_BUF_DN<3>     E4 @T6G_MB_LIB.T6G(SCH_1):P5E_CPU1_P3_RX_BUF_DN(3)
  E3    GND     E3 @T6G_MB_LIB.T6G(SCH_1):GND
  E2 P5E_CPU1_P3_RX_BUF_DN<1>     E2 @T6G_MB_LIB.T6G(SCH_1):P5E_CPU1_P3_RX_BUF_DN(1)
  E1    GND     E1 @T6G_MB_LIB.T6G(SCH_1):GND
  F4 P5E_CPU1_P3_RX_BUF_DP<3>     F4 @T6G_MB_LIB.T6G(SCH_1):P5E_CPU1_P3_RX_BUF_DP(3)
  F3 P5E_CPU1_P3_RX_BUF_DN<2>     F3 @T6G_MB_LIB.T6G(SCH_1):P5E_CPU1_P3_RX_BUF_DN(2)
  F2 P5E_CPU1_P3_RX_BUF_DP<1>     F2 @T6G_MB_LIB.T6G(SCH_1):P5E_CPU1_P3_RX_BUF_DP(1)
  F1 P5E_CPU1_P3_RX_BUF_DN<0>     F1 @T6G_MB_LIB.T6G(SCH_1):P5E_CPU1_P3_RX_BUF_DN(0)
  G4    GND     G4 @T6G_MB_LIB.T6G(SCH_1):GND
  G3 P5E_CPU1_P3_RX_BUF_DP<2>     G3 @T6G_MB_LIB.T6G(SCH_1):P5E_CPU1_P3_RX_BUF_DP(2)
  G2    GND     G2 @T6G_MB_LIB.T6G(SCH_1):GND
  G1 P5E_CPU1_P3_RX_BUF_DP<0>     G1 @T6G_MB_LIB.T6G(SCH_1):P5E_CPU1_P3_RX_BUF_DP(0)
  H4 P5E_CPU1_P2_TX_BUF_C_DN<3>     H4 @T6G_MB_LIB.T6G(SCH_1):P5E_CPU1_P2_TX_BUF_C_DN(3)
  H3    GND     H3 @T6G_MB_LIB.T6G(SCH_1):GND
  H2 P5E_CPU1_P2_TX_BUF_C_DN<1>     H2 @T6G_MB_LIB.T6G(SCH_1):P5E_CPU1_P2_TX_BUF_C_DN(1)
  H1    GND     H1 @T6G_MB_LIB.T6G(SCH_1):GND
  I4 P5E_CPU1_P2_TX_BUF_C_DP<3>     I4 @T6G_MB_LIB.T6G(SCH_1):P5E_CPU1_P2_TX_BUF_C_DP(3)
  I3 P5E_CPU1_P2_TX_BUF_C_DN<2>     I3 @T6G_MB_LIB.T6G(SCH_1):P5E_CPU1_P2_TX_BUF_C_DN(2)
  I2 P5E_CPU1_P2_TX_BUF_C_DP<1>     I2 @T6G_MB_LIB.T6G(SCH_1):P5E_CPU1_P2_TX_BUF_C_DP(1)
  I1 P5E_CPU1_P2_TX_BUF_C_DN<0>     I1 @T6G_MB_LIB.T6G(SCH_1):P5E_CPU1_P2_TX_BUF_C_DN(0)
  J4    GND     J4 @T6G_MB_LIB.T6G(SCH_1):GND
  J3 P5E_CPU1_P2_TX_BUF_C_DP<2>     J3 @T6G_MB_LIB.T6G(SCH_1):P5E_CPU1_P2_TX_BUF_C_DP(2)
  J2    GND     J2 @T6G_MB_LIB.T6G(SCH_1):GND
  J1 P5E_CPU1_P2_TX_BUF_C_DP<0>     J1 @T6G_MB_LIB.T6G(SCH_1):P5E_CPU1_P2_TX_BUF_C_DP(0)
  K4 P5E_CPU1_P3_TX_BUF_C_DN<3>     K4 @T6G_MB_LIB.T6G(SCH_1):P5E_CPU1_P3_TX_BUF_C_DN(3)
  K3    GND     K3 @T6G_MB_LIB.T6G(SCH_1):GND
  K2 P5E_CPU1_P3_TX_BUF_C_DN<1>     K2 @T6G_MB_LIB.T6G(SCH_1):P5E_CPU1_P3_TX_BUF_C_DN(1)
  K1    GND     K1 @T6G_MB_LIB.T6G(SCH_1):GND
  L4 P5E_CPU1_P3_TX_BUF_C_DP<3>     L4 @T6G_MB_LIB.T6G(SCH_1):P5E_CPU1_P3_TX_BUF_C_DP(3)
  L3 P5E_CPU1_P3_TX_BUF_C_DN<2>     L3 @T6G_MB_LIB.T6G(SCH_1):P5E_CPU1_P3_TX_BUF_C_DN(2)
  L2 P5E_CPU1_P3_TX_BUF_C_DP<1>     L2 @T6G_MB_LIB.T6G(SCH_1):P5E_CPU1_P3_TX_BUF_C_DP(1)
  L1 P5E_CPU1_P3_TX_BUF_C_DN<0>     L1 @T6G_MB_LIB.T6G(SCH_1):P5E_CPU1_P3_TX_BUF_C_DN(0)
  M1 P5E_CPU1_P3_TX_BUF_C_DP<0>     M1 @T6G_MB_LIB.T6G(SCH_1):P5E_CPU1_P3_TX_BUF_C_DP(0)
  N1    GND     N1 @T6G_MB_LIB.T6G(SCH_1):GND
  M2    GND     M2 @T6G_MB_LIB.T6G(SCH_1):GND
  N2 GPU_FPGA_BOOT_EN_BUF     N2 @T6G_MB_LIB.T6G(SCH_1):GPU_FPGA_BOOT_EN_BUF
  M3 P5E_CPU1_P3_TX_BUF_C_DP<2>     M3 @T6G_MB_LIB.T6G(SCH_1):P5E_CPU1_P3_TX_BUF_C_DP(2)
  N3    GND     N3 @T6G_MB_LIB.T6G(SCH_1):GND
  M4    GND     M4 @T6G_MB_LIB.T6G(SCH_1):GND
  N4 FM_SMB_1_ALERT_GPU_N     N4 @T6G_MB_LIB.T6G(SCH_1):FM_SMB_1_ALERT_GPU_N


DRAWING: @T6G_MB_LIB.T6G(SCH_1):PAGE328 

CONN112_10137002101LF-CONN112_10137002-101LF,THLF,A  I38  J111
  A8    GND     A8 @T6G_MB_LIB.T6G(SCH_1):GND
  A7 GPU_FPGA_RST_R_BUF_N     A7 @T6G_MB_LIB.T6G(SCH_1):GPU_FPGA_RST_R_BUF_N
  A6    GND     A6 @T6G_MB_LIB.T6G(SCH_1):GND
  A5 GPU_PEX_STRAP0     A5 @T6G_MB_LIB.T6G(SCH_1):GPU_PEX_STRAP0
  B8 P5E_CPU1_P0_RX_BUF_DN<15>     B8 @T6G_MB_LIB.T6G(SCH_1):P5E_CPU1_P0_RX_BUF_DN(15)
  B7    GND     B7 @T6G_MB_LIB.T6G(SCH_1):GND
  B6 P5E_CPU1_P0_RX_BUF_DN<13>     B6 @T6G_MB_LIB.T6G(SCH_1):P5E_CPU1_P0_RX_BUF_DN(13)
  B5    GND     B5 @T6G_MB_LIB.T6G(SCH_1):GND
  C8 P5E_CPU1_P0_RX_BUF_DP<15>     C8 @T6G_MB_LIB.T6G(SCH_1):P5E_CPU1_P0_RX_BUF_DP(15)
  C7 P5E_CPU1_P0_RX_BUF_DN<14>     C7 @T6G_MB_LIB.T6G(SCH_1):P5E_CPU1_P0_RX_BUF_DN(14)
  C6 P5E_CPU1_P0_RX_BUF_DP<13>     C6 @T6G_MB_LIB.T6G(SCH_1):P5E_CPU1_P0_RX_BUF_DP(13)
  C5 P5E_CPU1_P0_RX_BUF_DN<12>     C5 @T6G_MB_LIB.T6G(SCH_1):P5E_CPU1_P0_RX_BUF_DN(12)
  D8    GND     D8 @T6G_MB_LIB.T6G(SCH_1):GND
  D7 P5E_CPU1_P0_RX_BUF_DP<14>     D7 @T6G_MB_LIB.T6G(SCH_1):P5E_CPU1_P0_RX_BUF_DP(14)
  D6    GND     D6 @T6G_MB_LIB.T6G(SCH_1):GND
  D5 P5E_CPU1_P0_RX_BUF_DP<12>     D5 @T6G_MB_LIB.T6G(SCH_1):P5E_CPU1_P0_RX_BUF_DP(12)
  E8 P5E_CPU1_P1_RX_BUF_DN<15>     E8 @T6G_MB_LIB.T6G(SCH_1):P5E_CPU1_P1_RX_BUF_DN(15)
  E7    GND     E7 @T6G_MB_LIB.T6G(SCH_1):GND
  E6 P5E_CPU1_P1_RX_BUF_DN<13>     E6 @T6G_MB_LIB.T6G(SCH_1):P5E_CPU1_P1_RX_BUF_DN(13)
  E5    GND     E5 @T6G_MB_LIB.T6G(SCH_1):GND
  F8 P5E_CPU1_P1_RX_BUF_DP<15>     F8 @T6G_MB_LIB.T6G(SCH_1):P5E_CPU1_P1_RX_BUF_DP(15)
  F7 P5E_CPU1_P1_RX_BUF_DN<14>     F7 @T6G_MB_LIB.T6G(SCH_1):P5E_CPU1_P1_RX_BUF_DN(14)
  F6 P5E_CPU1_P1_RX_BUF_DP<13>     F6 @T6G_MB_LIB.T6G(SCH_1):P5E_CPU1_P1_RX_BUF_DP(13)
  F5 P5E_CPU1_P1_RX_BUF_DN<12>     F5 @T6G_MB_LIB.T6G(SCH_1):P5E_CPU1_P1_RX_BUF_DN(12)
  G8    GND     G8 @T6G_MB_LIB.T6G(SCH_1):GND
  G7 P5E_CPU1_P1_RX_BUF_DP<14>     G7 @T6G_MB_LIB.T6G(SCH_1):P5E_CPU1_P1_RX_BUF_DP(14)
  G6    GND     G6 @T6G_MB_LIB.T6G(SCH_1):GND
  G5 P5E_CPU1_P1_RX_BUF_DP<12>     G5 @T6G_MB_LIB.T6G(SCH_1):P5E_CPU1_P1_RX_BUF_DP(12)
  H8 P5E_CPU1_P0_TX_BUF_C_DN<15>     H8 @T6G_MB_LIB.T6G(SCH_1):P5E_CPU1_P0_TX_BUF_C_DN(15)
  H7    GND     H7 @T6G_MB_LIB.T6G(SCH_1):GND
  H6 P5E_CPU1_P0_TX_BUF_C_DN<13>     H6 @T6G_MB_LIB.T6G(SCH_1):P5E_CPU1_P0_TX_BUF_C_DN(13)
  H5    GND     H5 @T6G_MB_LIB.T6G(SCH_1):GND
  I8 P5E_CPU1_P0_TX_BUF_C_DP<15>     I8 @T6G_MB_LIB.T6G(SCH_1):P5E_CPU1_P0_TX_BUF_C_DP(15)
  I7 P5E_CPU1_P0_TX_BUF_C_DN<14>     I7 @T6G_MB_LIB.T6G(SCH_1):P5E_CPU1_P0_TX_BUF_C_DN(14)
  I6 P5E_CPU1_P0_TX_BUF_C_DP<13>     I6 @T6G_MB_LIB.T6G(SCH_1):P5E_CPU1_P0_TX_BUF_C_DP(13)
  I5 P5E_CPU1_P0_TX_BUF_C_DN<12>     I5 @T6G_MB_LIB.T6G(SCH_1):P5E_CPU1_P0_TX_BUF_C_DN(12)
  J8    GND     J8 @T6G_MB_LIB.T6G(SCH_1):GND
  J7 P5E_CPU1_P0_TX_BUF_C_DP<14>     J7 @T6G_MB_LIB.T6G(SCH_1):P5E_CPU1_P0_TX_BUF_C_DP(14)
  J6    GND     J6 @T6G_MB_LIB.T6G(SCH_1):GND
  J5 P5E_CPU1_P0_TX_BUF_C_DP<12>     J5 @T6G_MB_LIB.T6G(SCH_1):P5E_CPU1_P0_TX_BUF_C_DP(12)
  K8 P5E_CPU1_P1_TX_BUF_C_DN<15>     K8 @T6G_MB_LIB.T6G(SCH_1):P5E_CPU1_P1_TX_BUF_C_DN(15)
  K7    GND     K7 @T6G_MB_LIB.T6G(SCH_1):GND
  K6 P5E_CPU1_P1_TX_BUF_C_DN<13>     K6 @T6G_MB_LIB.T6G(SCH_1):P5E_CPU1_P1_TX_BUF_C_DN(13)
  K5    GND     K5 @T6G_MB_LIB.T6G(SCH_1):GND
  L8 P5E_CPU1_P1_TX_BUF_C_DP<15>     L8 @T6G_MB_LIB.T6G(SCH_1):P5E_CPU1_P1_TX_BUF_C_DP(15)
  L7 P5E_CPU1_P1_TX_BUF_C_DN<14>     L7 @T6G_MB_LIB.T6G(SCH_1):P5E_CPU1_P1_TX_BUF_C_DN(14)
  L6 P5E_CPU1_P1_TX_BUF_C_DP<13>     L6 @T6G_MB_LIB.T6G(SCH_1):P5E_CPU1_P1_TX_BUF_C_DP(13)
  L5 P5E_CPU1_P1_TX_BUF_C_DN<12>     L5 @T6G_MB_LIB.T6G(SCH_1):P5E_CPU1_P1_TX_BUF_C_DN(12)
  M5 P5E_CPU1_P1_TX_BUF_C_DP<12>     M5 @T6G_MB_LIB.T6G(SCH_1):P5E_CPU1_P1_TX_BUF_C_DP(12)
  N5    GND     N5 @T6G_MB_LIB.T6G(SCH_1):GND
  M6    GND     M6 @T6G_MB_LIB.T6G(SCH_1):GND
  N6 FM_GPU_PWRGD     N6 @T6G_MB_LIB.T6G(SCH_1):FM_GPU_PWRGD
  M7 P5E_CPU1_P1_TX_BUF_C_DP<14>     M7 @T6G_MB_LIB.T6G(SCH_1):P5E_CPU1_P1_TX_BUF_C_DP(14)
  N7    GND     N7 @T6G_MB_LIB.T6G(SCH_1):GND
  M8    GND     M8 @T6G_MB_LIB.T6G(SCH_1):GND
  N8 GPU_BASE_ID1     N8 @T6G_MB_LIB.T6G(SCH_1):GPU_BASE_ID1

CONN112_10137002101LF-CONN112_10137002-101LF,THLF,A  I76  J111
  A4    GND     A4 @T6G_MB_LIB.T6G(SCH_1):GND
  A3 GPU_BASE_ID0     A3 @T6G_MB_LIB.T6G(SCH_1):GPU_BASE_ID0
  A2    GND     A2 @T6G_MB_LIB.T6G(SCH_1):GND
  A1 GPU_PEX_STRAP1     A1 @T6G_MB_LIB.T6G(SCH_1):GPU_PEX_STRAP1
  B4 P5E_CPU1_P0_RX_BUF_DN<11>     B4 @T6G_MB_LIB.T6G(SCH_1):P5E_CPU1_P0_RX_BUF_DN(11)
  B3    GND     B3 @T6G_MB_LIB.T6G(SCH_1):GND
  B2 P5E_CPU1_P0_RX_BUF_DN<9>     B2 @T6G_MB_LIB.T6G(SCH_1):P5E_CPU1_P0_RX_BUF_DN(9)
  B1    GND     B1 @T6G_MB_LIB.T6G(SCH_1):GND
  C4 P5E_CPU1_P0_RX_BUF_DP<11>     C4 @T6G_MB_LIB.T6G(SCH_1):P5E_CPU1_P0_RX_BUF_DP(11)
  C3 P5E_CPU1_P0_RX_BUF_DN<10>     C3 @T6G_MB_LIB.T6G(SCH_1):P5E_CPU1_P0_RX_BUF_DN(10)
  C2 P5E_CPU1_P0_RX_BUF_DP<9>     C2 @T6G_MB_LIB.T6G(SCH_1):P5E_CPU1_P0_RX_BUF_DP(9)
  C1 P5E_CPU1_P0_RX_BUF_DN<8>     C1 @T6G_MB_LIB.T6G(SCH_1):P5E_CPU1_P0_RX_BUF_DN(8)
  D4    GND     D4 @T6G_MB_LIB.T6G(SCH_1):GND
  D3 P5E_CPU1_P0_RX_BUF_DP<10>     D3 @T6G_MB_LIB.T6G(SCH_1):P5E_CPU1_P0_RX_BUF_DP(10)
  D2    GND     D2 @T6G_MB_LIB.T6G(SCH_1):GND
  D1 P5E_CPU1_P0_RX_BUF_DP<8>     D1 @T6G_MB_LIB.T6G(SCH_1):P5E_CPU1_P0_RX_BUF_DP(8)
  E4 P5E_CPU1_P1_RX_BUF_DN<11>     E4 @T6G_MB_LIB.T6G(SCH_1):P5E_CPU1_P1_RX_BUF_DN(11)
  E3    GND     E3 @T6G_MB_LIB.T6G(SCH_1):GND
  E2 P5E_CPU1_P1_RX_BUF_DN<9>     E2 @T6G_MB_LIB.T6G(SCH_1):P5E_CPU1_P1_RX_BUF_DN(9)
  E1    GND     E1 @T6G_MB_LIB.T6G(SCH_1):GND
  F4 P5E_CPU1_P1_RX_BUF_DP<11>     F4 @T6G_MB_LIB.T6G(SCH_1):P5E_CPU1_P1_RX_BUF_DP(11)
  F3 P5E_CPU1_P1_RX_BUF_DN<10>     F3 @T6G_MB_LIB.T6G(SCH_1):P5E_CPU1_P1_RX_BUF_DN(10)
  F2 P5E_CPU1_P1_RX_BUF_DP<9>     F2 @T6G_MB_LIB.T6G(SCH_1):P5E_CPU1_P1_RX_BUF_DP(9)
  F1 P5E_CPU1_P1_RX_BUF_DN<8>     F1 @T6G_MB_LIB.T6G(SCH_1):P5E_CPU1_P1_RX_BUF_DN(8)
  G4    GND     G4 @T6G_MB_LIB.T6G(SCH_1):GND
  G3 P5E_CPU1_P1_RX_BUF_DP<10>     G3 @T6G_MB_LIB.T6G(SCH_1):P5E_CPU1_P1_RX_BUF_DP(10)
  G2    GND     G2 @T6G_MB_LIB.T6G(SCH_1):GND
  G1 P5E_CPU1_P1_RX_BUF_DP<8>     G1 @T6G_MB_LIB.T6G(SCH_1):P5E_CPU1_P1_RX_BUF_DP(8)
  H4 P5E_CPU1_P0_TX_BUF_C_DN<11>     H4 @T6G_MB_LIB.T6G(SCH_1):P5E_CPU1_P0_TX_BUF_C_DN(11)
  H3    GND     H3 @T6G_MB_LIB.T6G(SCH_1):GND
  H2 P5E_CPU1_P0_TX_BUF_C_DN<9>     H2 @T6G_MB_LIB.T6G(SCH_1):P5E_CPU1_P0_TX_BUF_C_DN(9)
  H1    GND     H1 @T6G_MB_LIB.T6G(SCH_1):GND
  I4 P5E_CPU1_P0_TX_BUF_C_DP<11>     I4 @T6G_MB_LIB.T6G(SCH_1):P5E_CPU1_P0_TX_BUF_C_DP(11)
  I3 P5E_CPU1_P0_TX_BUF_C_DN<10>     I3 @T6G_MB_LIB.T6G(SCH_1):P5E_CPU1_P0_TX_BUF_C_DN(10)
  I2 P5E_CPU1_P0_TX_BUF_C_DP<9>     I2 @T6G_MB_LIB.T6G(SCH_1):P5E_CPU1_P0_TX_BUF_C_DP(9)
  I1 P5E_CPU1_P0_TX_BUF_C_DN<8>     I1 @T6G_MB_LIB.T6G(SCH_1):P5E_CPU1_P0_TX_BUF_C_DN(8)
  J4    GND     J4 @T6G_MB_LIB.T6G(SCH_1):GND
  J3 P5E_CPU1_P0_TX_BUF_C_DP<10>     J3 @T6G_MB_LIB.T6G(SCH_1):P5E_CPU1_P0_TX_BUF_C_DP(10)
  J2    GND     J2 @T6G_MB_LIB.T6G(SCH_1):GND
  J1 P5E_CPU1_P0_TX_BUF_C_DP<8>     J1 @T6G_MB_LIB.T6G(SCH_1):P5E_CPU1_P0_TX_BUF_C_DP(8)
  K4 P5E_CPU1_P1_TX_BUF_C_DN<11>     K4 @T6G_MB_LIB.T6G(SCH_1):P5E_CPU1_P1_TX_BUF_C_DN(11)
  K3    GND     K3 @T6G_MB_LIB.T6G(SCH_1):GND
  K2 P5E_CPU1_P1_TX_BUF_C_DN<9>     K2 @T6G_MB_LIB.T6G(SCH_1):P5E_CPU1_P1_TX_BUF_C_DN(9)
  K1    GND     K1 @T6G_MB_LIB.T6G(SCH_1):GND
  L4 P5E_CPU1_P1_TX_BUF_C_DP<11>     L4 @T6G_MB_LIB.T6G(SCH_1):P5E_CPU1_P1_TX_BUF_C_DP(11)
  L3 P5E_CPU1_P1_TX_BUF_C_DN<10>     L3 @T6G_MB_LIB.T6G(SCH_1):P5E_CPU1_P1_TX_BUF_C_DN(10)
  L2 P5E_CPU1_P1_TX_BUF_C_DP<9>     L2 @T6G_MB_LIB.T6G(SCH_1):P5E_CPU1_P1_TX_BUF_C_DP(9)
  L1 P5E_CPU1_P1_TX_BUF_C_DN<8>     L1 @T6G_MB_LIB.T6G(SCH_1):P5E_CPU1_P1_TX_BUF_C_DN(8)
  M1 P5E_CPU1_P1_TX_BUF_C_DP<8>     M1 @T6G_MB_LIB.T6G(SCH_1):P5E_CPU1_P1_TX_BUF_C_DP(8)
  N1    GND     N1 @T6G_MB_LIB.T6G(SCH_1):GND
  M2    GND     M2 @T6G_MB_LIB.T6G(SCH_1):GND
  N2 GPU_PRSNT_N     N2 @T6G_MB_LIB.T6G(SCH_1):GPU_PRSNT_N
  M3 P5E_CPU1_P1_TX_BUF_C_DP<10>     M3 @T6G_MB_LIB.T6G(SCH_1):P5E_CPU1_P1_TX_BUF_C_DP(10)
  N3    GND     N3 @T6G_MB_LIB.T6G(SCH_1):GND
  M4    GND     M4 @T6G_MB_LIB.T6G(SCH_1):GND
  N4 FM_GPU_PWR_EN_R_BUF     N4 @T6G_MB_LIB.T6G(SCH_1):FM_GPU_PWR_EN_R_BUF


DRAWING: @T6G_MB_LIB.T6G(SCH_1):PAGE329 

CONN160_10131762101LF-CONN160_10131762-101LF,THLF,A  I7  J112
  A8    GND     A8 @T6G_MB_LIB.T6G(SCH_1):GND
  A7 PRSNT_SWB_N     A7 @T6G_MB_LIB.T6G(SCH_1):PRSNT_SWB_N
  A6    GND     A6 @T6G_MB_LIB.T6G(SCH_1):GND
  A5 RST_PERST_1_SWB_BUF_N     A5 @T6G_MB_LIB.T6G(SCH_1):RST_PERST_1_SWB_BUF_N
  B8 P5E_CPU1_P0_RX_BUF_DN<7>     B8 @T6G_MB_LIB.T6G(SCH_1):P5E_CPU1_P0_RX_BUF_DN(7)
  B7    GND     B7 @T6G_MB_LIB.T6G(SCH_1):GND
  B6 P5E_CPU1_P0_RX_BUF_DN<5>     B6 @T6G_MB_LIB.T6G(SCH_1):P5E_CPU1_P0_RX_BUF_DN(5)
  B5    GND     B5 @T6G_MB_LIB.T6G(SCH_1):GND
  C8 P5E_CPU1_P0_RX_BUF_DP<7>     C8 @T6G_MB_LIB.T6G(SCH_1):P5E_CPU1_P0_RX_BUF_DP(7)
  C7 P5E_CPU1_P0_RX_BUF_DN<6>     C7 @T6G_MB_LIB.T6G(SCH_1):P5E_CPU1_P0_RX_BUF_DN(6)
  C6 P5E_CPU1_P0_RX_BUF_DP<5>     C6 @T6G_MB_LIB.T6G(SCH_1):P5E_CPU1_P0_RX_BUF_DP(5)
  C5 P5E_CPU1_P0_RX_BUF_DN<4>     C5 @T6G_MB_LIB.T6G(SCH_1):P5E_CPU1_P0_RX_BUF_DN(4)
  D8    GND     D8 @T6G_MB_LIB.T6G(SCH_1):GND
  D7 P5E_CPU1_P0_RX_BUF_DP<6>     D7 @T6G_MB_LIB.T6G(SCH_1):P5E_CPU1_P0_RX_BUF_DP(6)
  D6    GND     D6 @T6G_MB_LIB.T6G(SCH_1):GND
  D5 P5E_CPU1_P0_RX_BUF_DP<4>     D5 @T6G_MB_LIB.T6G(SCH_1):P5E_CPU1_P0_RX_BUF_DP(4)
  E8 P5E_CPU1_P1_RX_BUF_DN<7>     E8 @T6G_MB_LIB.T6G(SCH_1):P5E_CPU1_P1_RX_BUF_DN(7)
  E7    GND     E7 @T6G_MB_LIB.T6G(SCH_1):GND
  E6 P5E_CPU1_P1_RX_BUF_DN<5>     E6 @T6G_MB_LIB.T6G(SCH_1):P5E_CPU1_P1_RX_BUF_DN(5)
  E5    GND     E5 @T6G_MB_LIB.T6G(SCH_1):GND
  F8 P5E_CPU1_P1_RX_BUF_DP<7>     F8 @T6G_MB_LIB.T6G(SCH_1):P5E_CPU1_P1_RX_BUF_DP(7)
  F7 P5E_CPU1_P1_RX_BUF_DN<6>     F7 @T6G_MB_LIB.T6G(SCH_1):P5E_CPU1_P1_RX_BUF_DN(6)
  F6 P5E_CPU1_P1_RX_BUF_DP<5>     F6 @T6G_MB_LIB.T6G(SCH_1):P5E_CPU1_P1_RX_BUF_DP(5)
  F5 P5E_CPU1_P1_RX_BUF_DN<4>     F5 @T6G_MB_LIB.T6G(SCH_1):P5E_CPU1_P1_RX_BUF_DN(4)
  G8    GND     G8 @T6G_MB_LIB.T6G(SCH_1):GND
  G7 P5E_CPU1_P1_RX_BUF_DP<6>     G7 @T6G_MB_LIB.T6G(SCH_1):P5E_CPU1_P1_RX_BUF_DP(6)
  G6    GND     G6 @T6G_MB_LIB.T6G(SCH_1):GND
  G5 P5E_CPU1_P1_RX_BUF_DP<4>     G5 @T6G_MB_LIB.T6G(SCH_1):P5E_CPU1_P1_RX_BUF_DP(4)
  H8 P5E_CPU1_P0_TX_BUF_C_DN<7>     H8 @T6G_MB_LIB.T6G(SCH_1):P5E_CPU1_P0_TX_BUF_C_DN(7)
  H7    GND     H7 @T6G_MB_LIB.T6G(SCH_1):GND
  H6 P5E_CPU1_P0_TX_BUF_C_DN<5>     H6 @T6G_MB_LIB.T6G(SCH_1):P5E_CPU1_P0_TX_BUF_C_DN(5)
  H5    GND     H5 @T6G_MB_LIB.T6G(SCH_1):GND
  I8 P5E_CPU1_P0_TX_BUF_C_DP<7>     I8 @T6G_MB_LIB.T6G(SCH_1):P5E_CPU1_P0_TX_BUF_C_DP(7)
  I7 P5E_CPU1_P0_TX_BUF_C_DN<6>     I7 @T6G_MB_LIB.T6G(SCH_1):P5E_CPU1_P0_TX_BUF_C_DN(6)
  I6 P5E_CPU1_P0_TX_BUF_C_DP<5>     I6 @T6G_MB_LIB.T6G(SCH_1):P5E_CPU1_P0_TX_BUF_C_DP(5)
  I5 P5E_CPU1_P0_TX_BUF_C_DN<4>     I5 @T6G_MB_LIB.T6G(SCH_1):P5E_CPU1_P0_TX_BUF_C_DN(4)
  J8    GND     J8 @T6G_MB_LIB.T6G(SCH_1):GND
  J7 P5E_CPU1_P0_TX_BUF_C_DP<6>     J7 @T6G_MB_LIB.T6G(SCH_1):P5E_CPU1_P0_TX_BUF_C_DP(6)
  J6    GND     J6 @T6G_MB_LIB.T6G(SCH_1):GND
  J5 P5E_CPU1_P0_TX_BUF_C_DP<4>     J5 @T6G_MB_LIB.T6G(SCH_1):P5E_CPU1_P0_TX_BUF_C_DP(4)
  K8 P5E_CPU1_P1_TX_BUF_C_DN<7>     K8 @T6G_MB_LIB.T6G(SCH_1):P5E_CPU1_P1_TX_BUF_C_DN(7)
  K7    GND     K7 @T6G_MB_LIB.T6G(SCH_1):GND
  K6 P5E_CPU1_P1_TX_BUF_C_DN<5>     K6 @T6G_MB_LIB.T6G(SCH_1):P5E_CPU1_P1_TX_BUF_C_DN(5)
  K5    GND     K5 @T6G_MB_LIB.T6G(SCH_1):GND
  L8 P5E_CPU1_P1_TX_BUF_C_DP<7>     L8 @T6G_MB_LIB.T6G(SCH_1):P5E_CPU1_P1_TX_BUF_C_DP(7)
  L7 P5E_CPU1_P1_TX_BUF_C_DN<6>     L7 @T6G_MB_LIB.T6G(SCH_1):P5E_CPU1_P1_TX_BUF_C_DN(6)
  L6 P5E_CPU1_P1_TX_BUF_C_DP<5>     L6 @T6G_MB_LIB.T6G(SCH_1):P5E_CPU1_P1_TX_BUF_C_DP(5)
  L5 P5E_CPU1_P1_TX_BUF_C_DN<4>     L5 @T6G_MB_LIB.T6G(SCH_1):P5E_CPU1_P1_TX_BUF_C_DN(4)
  M5 P5E_CPU1_P1_TX_BUF_C_DP<4>     M5 @T6G_MB_LIB.T6G(SCH_1):P5E_CPU1_P1_TX_BUF_C_DP(4)
  N5    GND     N5 @T6G_MB_LIB.T6G(SCH_1):GND
  M6    GND     M6 @T6G_MB_LIB.T6G(SCH_1):GND
  N6 P2E_MB_BMC_RX_DP<0>     N6 @T6G_MB_LIB.T6G(SCH_1):P2E_MB_BMC_RX_DP(0)
  M7 P5E_CPU1_P1_TX_BUF_C_DP<6>     M7 @T6G_MB_LIB.T6G(SCH_1):P5E_CPU1_P1_TX_BUF_C_DP(6)
  N7    GND     N7 @T6G_MB_LIB.T6G(SCH_1):GND
  M8    GND     M8 @T6G_MB_LIB.T6G(SCH_1):GND
  N8 P3E_CPU1_P5_RX_DN<0>     N8 @T6G_MB_LIB.T6G(SCH_1):P3E_CPU1_P5_RX_DN(0)
  O5 NC_J112_O5     O5 @T6G_MB_LIB.T6G(SCH_1):NC_J112_O5
  P5 NC_J112_P5     P5 @T6G_MB_LIB.T6G(SCH_1):NC_J112_P5
  Q5    GND     Q5 @T6G_MB_LIB.T6G(SCH_1):GND
  R5 NC_J112_R5     R5 @T6G_MB_LIB.T6G(SCH_1):NC_J112_R5
  S5 NC_J112_S5     S5 @T6G_MB_LIB.T6G(SCH_1):NC_J112_S5
  T5    GND     T5 @T6G_MB_LIB.T6G(SCH_1):GND
  O6 P2E_MB_BMC_RX_DN<0>     O6 @T6G_MB_LIB.T6G(SCH_1):P2E_MB_BMC_RX_DN(0)
  P6    GND     P6 @T6G_MB_LIB.T6G(SCH_1):GND
  Q6 P2E_MB_BMC_TX_BUF_C_DP<0>     Q6 @T6G_MB_LIB.T6G(SCH_1):P2E_MB_BMC_TX_BUF_C_DP(0)
  R6 P2E_MB_BMC_TX_BUF_C_DN<0>     R6 @T6G_MB_LIB.T6G(SCH_1):P2E_MB_BMC_TX_BUF_C_DN(0)
  S6    GND     S6 @T6G_MB_LIB.T6G(SCH_1):GND
  T6 GPU_FPGA_THERM_OVERT_N     T6 @T6G_MB_LIB.T6G(SCH_1):GPU_FPGA_THERM_OVERT_N
  O7 P3E_CPU1_P5_RX_DN<1>     O7 @T6G_MB_LIB.T6G(SCH_1):P3E_CPU1_P5_RX_DN(1)
  P7 P3E_CPU1_P5_RX_DP<1>     P7 @T6G_MB_LIB.T6G(SCH_1):P3E_CPU1_P5_RX_DP(1)
  Q7    GND     Q7 @T6G_MB_LIB.T6G(SCH_1):GND
  R7 P3E_CPU1_P5_TX_C_DP<1>     R7 @T6G_MB_LIB.T6G(SCH_1):P3E_CPU1_P5_TX_C_DP(1)
  S7 P3E_CPU1_P5_TX_C_DN<1>     S7 @T6G_MB_LIB.T6G(SCH_1):P3E_CPU1_P5_TX_C_DN(1)
  T7    GND     T7 @T6G_MB_LIB.T6G(SCH_1):GND
  O8 P3E_CPU1_P5_RX_DP<0>     O8 @T6G_MB_LIB.T6G(SCH_1):P3E_CPU1_P5_RX_DP(0)
  P8    GND     P8 @T6G_MB_LIB.T6G(SCH_1):GND
  Q8 P3E_CPU1_P5_TX_C_DN<0>     Q8 @T6G_MB_LIB.T6G(SCH_1):P3E_CPU1_P5_TX_C_DN(0)
  R8 P3E_CPU1_P5_TX_C_DP<0>     R8 @T6G_MB_LIB.T6G(SCH_1):P3E_CPU1_P5_TX_C_DP(0)
  S8    GND     S8 @T6G_MB_LIB.T6G(SCH_1):GND
  T8 RST_PERST_0_SWB_BUF_N     T8 @T6G_MB_LIB.T6G(SCH_1):RST_PERST_0_SWB_BUF_N

CONN160_10131762101LF-CONN160_10131762-101LF,THLF,A  I102  J112
  A4    GND     A4 @T6G_MB_LIB.T6G(SCH_1):GND
  A3 HGX_DETECT_N_ISO     A3 @T6G_MB_LIB.T6G(SCH_1):HGX_DETECT_N_ISO
  A2    GND     A2 @T6G_MB_LIB.T6G(SCH_1):GND
  A1 RST_PERST_2_SWB_BUF_N     A1 @T6G_MB_LIB.T6G(SCH_1):RST_PERST_2_SWB_BUF_N
  B4 P5E_CPU1_P0_RX_BUF_DN<3>     B4 @T6G_MB_LIB.T6G(SCH_1):P5E_CPU1_P0_RX_BUF_DN(3)
  B3    GND     B3 @T6G_MB_LIB.T6G(SCH_1):GND
  B2 P5E_CPU1_P0_RX_BUF_DN<1>     B2 @T6G_MB_LIB.T6G(SCH_1):P5E_CPU1_P0_RX_BUF_DN(1)
  B1    GND     B1 @T6G_MB_LIB.T6G(SCH_1):GND
  C4 P5E_CPU1_P0_RX_BUF_DP<3>     C4 @T6G_MB_LIB.T6G(SCH_1):P5E_CPU1_P0_RX_BUF_DP(3)
  C3 P5E_CPU1_P0_RX_BUF_DN<2>     C3 @T6G_MB_LIB.T6G(SCH_1):P5E_CPU1_P0_RX_BUF_DN(2)
  C2 P5E_CPU1_P0_RX_BUF_DP<1>     C2 @T6G_MB_LIB.T6G(SCH_1):P5E_CPU1_P0_RX_BUF_DP(1)
  C1 P5E_CPU1_P0_RX_BUF_DN<0>     C1 @T6G_MB_LIB.T6G(SCH_1):P5E_CPU1_P0_RX_BUF_DN(0)
  D4    GND     D4 @T6G_MB_LIB.T6G(SCH_1):GND
  D3 P5E_CPU1_P0_RX_BUF_DP<2>     D3 @T6G_MB_LIB.T6G(SCH_1):P5E_CPU1_P0_RX_BUF_DP(2)
  D2    GND     D2 @T6G_MB_LIB.T6G(SCH_1):GND
  D1 P5E_CPU1_P0_RX_BUF_DP<0>     D1 @T6G_MB_LIB.T6G(SCH_1):P5E_CPU1_P0_RX_BUF_DP(0)
  E4 P5E_CPU1_P1_RX_BUF_DN<3>     E4 @T6G_MB_LIB.T6G(SCH_1):P5E_CPU1_P1_RX_BUF_DN(3)
  E3    GND     E3 @T6G_MB_LIB.T6G(SCH_1):GND
  E2 P5E_CPU1_P1_RX_BUF_DN<1>     E2 @T6G_MB_LIB.T6G(SCH_1):P5E_CPU1_P1_RX_BUF_DN(1)
  E1    GND     E1 @T6G_MB_LIB.T6G(SCH_1):GND
  F4 P5E_CPU1_P1_RX_BUF_DP<3>     F4 @T6G_MB_LIB.T6G(SCH_1):P5E_CPU1_P1_RX_BUF_DP(3)
  F3 P5E_CPU1_P1_RX_BUF_DN<2>     F3 @T6G_MB_LIB.T6G(SCH_1):P5E_CPU1_P1_RX_BUF_DN(2)
  F2 P5E_CPU1_P1_RX_BUF_DP<1>     F2 @T6G_MB_LIB.T6G(SCH_1):P5E_CPU1_P1_RX_BUF_DP(1)
  F1 P5E_CPU1_P1_RX_BUF_DN<0>     F1 @T6G_MB_LIB.T6G(SCH_1):P5E_CPU1_P1_RX_BUF_DN(0)
  G4    GND     G4 @T6G_MB_LIB.T6G(SCH_1):GND
  G3 P5E_CPU1_P1_RX_BUF_DP<2>     G3 @T6G_MB_LIB.T6G(SCH_1):P5E_CPU1_P1_RX_BUF_DP(2)
  G2    GND     G2 @T6G_MB_LIB.T6G(SCH_1):GND
  G1 P5E_CPU1_P1_RX_BUF_DP<0>     G1 @T6G_MB_LIB.T6G(SCH_1):P5E_CPU1_P1_RX_BUF_DP(0)
  H4 P5E_CPU1_P0_TX_BUF_C_DN<3>     H4 @T6G_MB_LIB.T6G(SCH_1):P5E_CPU1_P0_TX_BUF_C_DN(3)
  H3    GND     H3 @T6G_MB_LIB.T6G(SCH_1):GND
  H2 P5E_CPU1_P0_TX_BUF_C_DN<1>     H2 @T6G_MB_LIB.T6G(SCH_1):P5E_CPU1_P0_TX_BUF_C_DN(1)
  H1    GND     H1 @T6G_MB_LIB.T6G(SCH_1):GND
  I4 P5E_CPU1_P0_TX_BUF_C_DP<3>     I4 @T6G_MB_LIB.T6G(SCH_1):P5E_CPU1_P0_TX_BUF_C_DP(3)
  I3 P5E_CPU1_P0_TX_BUF_C_DN<2>     I3 @T6G_MB_LIB.T6G(SCH_1):P5E_CPU1_P0_TX_BUF_C_DN(2)
  I2 P5E_CPU1_P0_TX_BUF_C_DP<1>     I2 @T6G_MB_LIB.T6G(SCH_1):P5E_CPU1_P0_TX_BUF_C_DP(1)
  I1 P5E_CPU1_P0_TX_BUF_C_DN<0>     I1 @T6G_MB_LIB.T6G(SCH_1):P5E_CPU1_P0_TX_BUF_C_DN(0)
  J4    GND     J4 @T6G_MB_LIB.T6G(SCH_1):GND
  J3 P5E_CPU1_P0_TX_BUF_C_DP<2>     J3 @T6G_MB_LIB.T6G(SCH_1):P5E_CPU1_P0_TX_BUF_C_DP(2)
  J2    GND     J2 @T6G_MB_LIB.T6G(SCH_1):GND
  J1 P5E_CPU1_P0_TX_BUF_C_DP<0>     J1 @T6G_MB_LIB.T6G(SCH_1):P5E_CPU1_P0_TX_BUF_C_DP(0)
  K4 P5E_CPU1_P1_TX_BUF_C_DN<3>     K4 @T6G_MB_LIB.T6G(SCH_1):P5E_CPU1_P1_TX_BUF_C_DN(3)
  K3    GND     K3 @T6G_MB_LIB.T6G(SCH_1):GND
  K2 P5E_CPU1_P1_TX_BUF_C_DN<1>     K2 @T6G_MB_LIB.T6G(SCH_1):P5E_CPU1_P1_TX_BUF_C_DN(1)
  K1    GND     K1 @T6G_MB_LIB.T6G(SCH_1):GND
  L4 P5E_CPU1_P1_TX_BUF_C_DP<3>     L4 @T6G_MB_LIB.T6G(SCH_1):P5E_CPU1_P1_TX_BUF_C_DP(3)
  L3 P5E_CPU1_P1_TX_BUF_C_DN<2>     L3 @T6G_MB_LIB.T6G(SCH_1):P5E_CPU1_P1_TX_BUF_C_DN(2)
  L2 P5E_CPU1_P1_TX_BUF_C_DP<1>     L2 @T6G_MB_LIB.T6G(SCH_1):P5E_CPU1_P1_TX_BUF_C_DP(1)
  L1 P5E_CPU1_P1_TX_BUF_C_DN<0>     L1 @T6G_MB_LIB.T6G(SCH_1):P5E_CPU1_P1_TX_BUF_C_DN(0)
  M1 P5E_CPU1_P1_TX_BUF_C_DP<0>     M1 @T6G_MB_LIB.T6G(SCH_1):P5E_CPU1_P1_TX_BUF_C_DP(0)
  N1    GND     N1 @T6G_MB_LIB.T6G(SCH_1):GND
  M2    GND     M2 @T6G_MB_LIB.T6G(SCH_1):GND
  N2 NC_J112_N2     N2 @T6G_MB_LIB.T6G(SCH_1):NC_J112_N2
  M3 P5E_CPU1_P1_TX_BUF_C_DP<2>     M3 @T6G_MB_LIB.T6G(SCH_1):P5E_CPU1_P1_TX_BUF_C_DP(2)
  N3    GND     N3 @T6G_MB_LIB.T6G(SCH_1):GND
  M4    GND     M4 @T6G_MB_LIB.T6G(SCH_1):GND
  N4 CLK_100M_CPU0_CLK11_DN     N4 @T6G_MB_LIB.T6G(SCH_1):CLK_100M_CPU0_CLK11_DN
  O1 CLK_100M_CPU1_CLK01_DN     O1 @T6G_MB_LIB.T6G(SCH_1):CLK_100M_CPU1_CLK01_DN
  P1 CLK_100M_CPU1_CLK01_DP     P1 @T6G_MB_LIB.T6G(SCH_1):CLK_100M_CPU1_CLK01_DP
  Q1    GND     Q1 @T6G_MB_LIB.T6G(SCH_1):GND
  R1 USB2_HUB_BUF_SWB_DN     R1 @T6G_MB_LIB.T6G(SCH_1):USB2_HUB_BUF_SWB_DN
  S1 USB2_HUB_BUF_SWB_DP     S1 @T6G_MB_LIB.T6G(SCH_1):USB2_HUB_BUF_SWB_DP
  T1    GND     T1 @T6G_MB_LIB.T6G(SCH_1):GND
  O2 NC_J112_O2     O2 @T6G_MB_LIB.T6G(SCH_1):NC_J112_O2
  P2    GND     P2 @T6G_MB_LIB.T6G(SCH_1):GND
  Q2 CLK_100M_GPU_FPGA_DN     Q2 @T6G_MB_LIB.T6G(SCH_1):CLK_100M_GPU_FPGA_DN
  R2 CLK_100M_GPU_FPGA_DP     R2 @T6G_MB_LIB.T6G(SCH_1):CLK_100M_GPU_FPGA_DP
  S2    GND     S2 @T6G_MB_LIB.T6G(SCH_1):GND
  T2 GPU_FPGA_READY     T2 @T6G_MB_LIB.T6G(SCH_1):GPU_FPGA_READY
  O3 CLK_100M_CPU1_CLK11_DN     O3 @T6G_MB_LIB.T6G(SCH_1):CLK_100M_CPU1_CLK11_DN
  P3 CLK_100M_CPU1_CLK11_DP     P3 @T6G_MB_LIB.T6G(SCH_1):CLK_100M_CPU1_CLK11_DP
  Q3    GND     Q3 @T6G_MB_LIB.T6G(SCH_1):GND
  R3 SMB_2_BMC_GPU_BUF_SCL     R3 @T6G_MB_LIB.T6G(SCH_1):SMB_2_BMC_GPU_BUF_SCL
  S3 SMB_2_BMC_GPU_BUF_SDA     S3 @T6G_MB_LIB.T6G(SCH_1):SMB_2_BMC_GPU_BUF_SDA
  T3    GND     T3 @T6G_MB_LIB.T6G(SCH_1):GND
  O4 CLK_100M_CPU0_CLK11_DP     O4 @T6G_MB_LIB.T6G(SCH_1):CLK_100M_CPU0_CLK11_DP
  P4    GND     P4 @T6G_MB_LIB.T6G(SCH_1):GND
  Q4 SMB_1_BMC_GPU_BUF_SCL     Q4 @T6G_MB_LIB.T6G(SCH_1):SMB_1_BMC_GPU_BUF_SCL
  R4 SMB_1_BMC_GPU_BUF_SDA     R4 @T6G_MB_LIB.T6G(SCH_1):SMB_1_BMC_GPU_BUF_SDA
  S4    GND     S4 @T6G_MB_LIB.T6G(SCH_1):GND
  T4 GPU_NVS_PWR_BRAKE_N_BUF     T4 @T6G_MB_LIB.T6G(SCH_1):GPU_NVS_PWR_BRAKE_N_BUF


DRAWING: @T6G_MB_LIB.T6G(SCH_1):PAGE387 

M24M02DRMN6TP-M24M02-DRMN6TP,SMLF,IC,AKE33Z00600  I3  U11
   8 P1V8_CPU0_RT_1D    VCC @T6G_MB_LIB.T6G(SCH_1):P1V8_CPU0_RT_1D
   7    GND   WC_N @T6G_MB_LIB.T6G(SCH_1):GND
   6 SMB_RT_CPU0_P0_ROM_SCL    SCL @T6G_MB_LIB.T6G(SCH_1):SMB_RT_CPU0_P0_ROM_SCL
   5 SMB_RT_CPU0_P0_ROM_SDA    SDA @T6G_MB_LIB.T6G(SCH_1):SMB_RT_CPU0_P0_ROM_SDA
   4    GND    VSS @T6G_MB_LIB.T6G(SCH_1):GND
   3 U11_E2     E2 @T6G_MB_LIB.T6G(SCH_1):U11_E2
   2     NC    DU2     NC
   1     NC    DU1     NC

Q_RES_0201LF-33.2,1%,1/20W,CHIP,CS03321FE09  I6  R668
   1 SMB_RT_CPU0_P0_ROM_R_SCL      A @T6G_MB_LIB.T6G(SCH_1):SMB_RT_CPU0_P0_ROM_R_SCL
   2 SMB_RT_CPU0_P0_ROM_SCL      B @T6G_MB_LIB.T6G(SCH_1):SMB_RT_CPU0_P0_ROM_SCL

Q_RES_0201LF-33.2,1%,1/20W,CHIP,CS03321FE09  I7  R669
   1 SMB_RT_CPU0_P0_ROM_R_SDA      A @T6G_MB_LIB.T6G(SCH_1):SMB_RT_CPU0_P0_ROM_R_SDA
   2 SMB_RT_CPU0_P0_ROM_SDA      B @T6G_MB_LIB.T6G(SCH_1):SMB_RT_CPU0_P0_ROM_SDA

Q_CAP_C0201-0.1UF,10V,10%,X7S,CH4102K6E00  I21  C7510
   1 P1V8_CPU0_RT_1D      A @T6G_MB_LIB.T6G(SCH_1):P1V8_CPU0_RT_1D
   2    GND      B @T6G_MB_LIB.T6G(SCH_1):GND

Q_RES_0201LF-1K,1%,1/20W,CHIP,CS21001FE07  I24  R6822
   1 U11_E2      A @T6G_MB_LIB.T6G(SCH_1):U11_E2
   2    GND      B @T6G_MB_LIB.T6G(SCH_1):GND


DRAWING: @T6G_MB_LIB.T6G(SCH_1):PAGE410 

M24M02DRMN6TP-M24M02-DRMN6TP,SMLF,IC,AKE33Z00600  I5  U15
   8 P1V8_CPU0_RT_1D    VCC @T6G_MB_LIB.T6G(SCH_1):P1V8_CPU0_RT_1D
   7    GND   WC_N @T6G_MB_LIB.T6G(SCH_1):GND
   6 SMB_RT_CPU0_P1_ROM_SCL    SCL @T6G_MB_LIB.T6G(SCH_1):SMB_RT_CPU0_P1_ROM_SCL
   5 SMB_RT_CPU0_P1_ROM_SDA    SDA @T6G_MB_LIB.T6G(SCH_1):SMB_RT_CPU0_P1_ROM_SDA
   4    GND    VSS @T6G_MB_LIB.T6G(SCH_1):GND
   3 U15_E2     E2 @T6G_MB_LIB.T6G(SCH_1):U15_E2
   2     NC    DU2     NC
   1     NC    DU1     NC

Q_RES_0201LF-33.2,1%,1/20W,CHIP,CS03321FE09  I6  R678
   1 SMB_RT_CPU0_P1_ROM_R_SCL      A @T6G_MB_LIB.T6G(SCH_1):SMB_RT_CPU0_P1_ROM_R_SCL
   2 SMB_RT_CPU0_P1_ROM_SCL      B @T6G_MB_LIB.T6G(SCH_1):SMB_RT_CPU0_P1_ROM_SCL

Q_RES_0201LF-33.2,1%,1/20W,CHIP,CS03321FE09  I7  R679
   1 SMB_RT_CPU0_P1_ROM_R_SDA      A @T6G_MB_LIB.T6G(SCH_1):SMB_RT_CPU0_P1_ROM_R_SDA
   2 SMB_RT_CPU0_P1_ROM_SDA      B @T6G_MB_LIB.T6G(SCH_1):SMB_RT_CPU0_P1_ROM_SDA

Q_RES_0201LF-1K,1%,1/20W,CHIP,CS21001FE07  I20  R1044
   1 U15_E2      A @T6G_MB_LIB.T6G(SCH_1):U15_E2
   2    GND      B @T6G_MB_LIB.T6G(SCH_1):GND

Q_CAP_C0201-0.1UF,10V,10%,X7S,CH4102K6E00  I24  C664
   1 P1V8_CPU0_RT_1D      A @T6G_MB_LIB.T6G(SCH_1):P1V8_CPU0_RT_1D
   2    GND      B @T6G_MB_LIB.T6G(SCH_1):GND


DRAWING: @T6G_MB_LIB.T6G(SCH_1):PAGE421 

Q_RES_0201LF-33.2,1%,1/20W,CHIP,CS03321FE09  I3  R682
   1 SMB_RT_CPU0_P2_ROM_R_SCL      A @T6G_MB_LIB.T6G(SCH_1):SMB_RT_CPU0_P2_ROM_R_SCL
   2 SMB_RT_CPU0_P2_ROM_SCL      B @T6G_MB_LIB.T6G(SCH_1):SMB_RT_CPU0_P2_ROM_SCL

Q_RES_0201LF-33.2,1%,1/20W,CHIP,CS03321FE09  I4  R683
   1 SMB_RT_CPU0_P2_ROM_R_SDA      A @T6G_MB_LIB.T6G(SCH_1):SMB_RT_CPU0_P2_ROM_R_SDA
   2 SMB_RT_CPU0_P2_ROM_SDA      B @T6G_MB_LIB.T6G(SCH_1):SMB_RT_CPU0_P2_ROM_SDA

M24M02DRMN6TP-M24M02-DRMN6TP,SMLF,IC,AKE33Z00600  I5  U16
   8 P1V8_CPU0_RT_1D    VCC @T6G_MB_LIB.T6G(SCH_1):P1V8_CPU0_RT_1D
   7    GND   WC_N @T6G_MB_LIB.T6G(SCH_1):GND
   6 SMB_RT_CPU0_P2_ROM_SCL    SCL @T6G_MB_LIB.T6G(SCH_1):SMB_RT_CPU0_P2_ROM_SCL
   5 SMB_RT_CPU0_P2_ROM_SDA    SDA @T6G_MB_LIB.T6G(SCH_1):SMB_RT_CPU0_P2_ROM_SDA
   4    GND    VSS @T6G_MB_LIB.T6G(SCH_1):GND
   3 U16_E2     E2 @T6G_MB_LIB.T6G(SCH_1):U16_E2
   2     NC    DU2     NC
   1     NC    DU1     NC

Q_RES_0201LF-1K,1%,1/20W,CHIP,CS21001FE07  I18  R1085
   1 U16_E2      A @T6G_MB_LIB.T6G(SCH_1):U16_E2
   2    GND      B @T6G_MB_LIB.T6G(SCH_1):GND

Q_CAP_C0201-0.1UF,10V,10%,X7S,CH4102K6E00  I23  C989
   1 P1V8_CPU0_RT_1D      A @T6G_MB_LIB.T6G(SCH_1):P1V8_CPU0_RT_1D
   2    GND      B @T6G_MB_LIB.T6G(SCH_1):GND


DRAWING: @T6G_MB_LIB.T6G(SCH_1):PAGE432 

Q_RES_0201LF-33.2,1%,1/20W,CHIP,CS03321FE09  I3  R687
   1 SMB_RT_CPU0_P3_ROM_R_SCL      A @T6G_MB_LIB.T6G(SCH_1):SMB_RT_CPU0_P3_ROM_R_SCL
   2 SMB_RT_CPU0_P3_ROM_SCL      B @T6G_MB_LIB.T6G(SCH_1):SMB_RT_CPU0_P3_ROM_SCL

Q_RES_0201LF-33.2,1%,1/20W,CHIP,CS03321FE09  I4  R688
   1 SMB_RT_CPU0_P3_ROM_R_SDA      A @T6G_MB_LIB.T6G(SCH_1):SMB_RT_CPU0_P3_ROM_R_SDA
   2 SMB_RT_CPU0_P3_ROM_SDA      B @T6G_MB_LIB.T6G(SCH_1):SMB_RT_CPU0_P3_ROM_SDA

M24M02DRMN6TP-M24M02-DRMN6TP,SMLF,IC,AKE33Z00600  I5  U17
   8 P1V8_CPU0_RT_1D    VCC @T6G_MB_LIB.T6G(SCH_1):P1V8_CPU0_RT_1D
   7    GND   WC_N @T6G_MB_LIB.T6G(SCH_1):GND
   6 SMB_RT_CPU0_P3_ROM_SCL    SCL @T6G_MB_LIB.T6G(SCH_1):SMB_RT_CPU0_P3_ROM_SCL
   5 SMB_RT_CPU0_P3_ROM_SDA    SDA @T6G_MB_LIB.T6G(SCH_1):SMB_RT_CPU0_P3_ROM_SDA
   4    GND    VSS @T6G_MB_LIB.T6G(SCH_1):GND
   3 U17_E2     E2 @T6G_MB_LIB.T6G(SCH_1):U17_E2
   2     NC    DU2     NC
   1     NC    DU1     NC

Q_RES_0201LF-1K,1%,1/20W,CHIP,CS21001FE07  I18  R1127
   1 U17_E2      A @T6G_MB_LIB.T6G(SCH_1):U17_E2
   2    GND      B @T6G_MB_LIB.T6G(SCH_1):GND

Q_CAP_C0201-0.1UF,10V,10%,X7S,CH4102K6E00  I23  C1057
   1 P1V8_CPU0_RT_1D      A @T6G_MB_LIB.T6G(SCH_1):P1V8_CPU0_RT_1D
   2    GND      B @T6G_MB_LIB.T6G(SCH_1):GND


DRAWING: @T6G_MB_LIB.T6G(SCH_1):PAGE399 

Q_RES_0201LF-33.2,1%,1/20W,CHIP,CS03321FE09  I3  R672
   1 SMB_RT_CPU1_P0_ROM_R_SCL      A @T6G_MB_LIB.T6G(SCH_1):SMB_RT_CPU1_P0_ROM_R_SCL
   2 SMB_RT_CPU1_P0_ROM_SCL      B @T6G_MB_LIB.T6G(SCH_1):SMB_RT_CPU1_P0_ROM_SCL

Q_RES_0201LF-33.2,1%,1/20W,CHIP,CS03321FE09  I4  R673
   1 SMB_RT_CPU1_P0_ROM_R_SDA      A @T6G_MB_LIB.T6G(SCH_1):SMB_RT_CPU1_P0_ROM_R_SDA
   2 SMB_RT_CPU1_P0_ROM_SDA      B @T6G_MB_LIB.T6G(SCH_1):SMB_RT_CPU1_P0_ROM_SDA

M24M02DRMN6TP-M24M02-DRMN6TP,SMLF,IC,AKE33Z00600  I5  U12
   8 P1V8_CPU1_RT_1D    VCC @T6G_MB_LIB.T6G(SCH_1):P1V8_CPU1_RT_1D
   7    GND   WC_N @T6G_MB_LIB.T6G(SCH_1):GND
   6 SMB_RT_CPU1_P0_ROM_SCL    SCL @T6G_MB_LIB.T6G(SCH_1):SMB_RT_CPU1_P0_ROM_SCL
   5 SMB_RT_CPU1_P0_ROM_SDA    SDA @T6G_MB_LIB.T6G(SCH_1):SMB_RT_CPU1_P0_ROM_SDA
   4    GND    VSS @T6G_MB_LIB.T6G(SCH_1):GND
   3 U12_E2     E2 @T6G_MB_LIB.T6G(SCH_1):U12_E2
   2     NC    DU2     NC
   1     NC    DU1     NC

Q_CAP_C0201-0.1UF,10V,10%,X7S,CH4102K6E00  I11  C7501
   1 P1V8_CPU1_RT_1D      A @T6G_MB_LIB.T6G(SCH_1):P1V8_CPU1_RT_1D
   2    GND      B @T6G_MB_LIB.T6G(SCH_1):GND

Q_RES_0201LF-1K,1%,1/20W,CHIP,CS21001FE07  I13  R6788
   1 U12_E2      A @T6G_MB_LIB.T6G(SCH_1):U12_E2
   2    GND      B @T6G_MB_LIB.T6G(SCH_1):GND


DRAWING: @T6G_MB_LIB.T6G(SCH_1):PAGE442 

Q_RES_0201LF-33.2,1%,1/20W,CHIP,CS03321FE09  I3  R690
   1 SMB_RT_CPU1_P1_ROM_R_SDA      A @T6G_MB_LIB.T6G(SCH_1):SMB_RT_CPU1_P1_ROM_R_SDA
   2 SMB_RT_CPU1_P1_ROM_SDA      B @T6G_MB_LIB.T6G(SCH_1):SMB_RT_CPU1_P1_ROM_SDA

Q_RES_0201LF-33.2,1%,1/20W,CHIP,CS03321FE09  I4  R689
   1 SMB_RT_CPU1_P1_ROM_R_SCL      A @T6G_MB_LIB.T6G(SCH_1):SMB_RT_CPU1_P1_ROM_R_SCL
   2 SMB_RT_CPU1_P1_ROM_SCL      B @T6G_MB_LIB.T6G(SCH_1):SMB_RT_CPU1_P1_ROM_SCL

M24M02DRMN6TP-M24M02-DRMN6TP,SMLF,IC,AKE33Z00600  I5  U19
   8 P1V8_CPU1_RT_1D    VCC @T6G_MB_LIB.T6G(SCH_1):P1V8_CPU1_RT_1D
   7    GND   WC_N @T6G_MB_LIB.T6G(SCH_1):GND
   6 SMB_RT_CPU1_P1_ROM_SCL    SCL @T6G_MB_LIB.T6G(SCH_1):SMB_RT_CPU1_P1_ROM_SCL
   5 SMB_RT_CPU1_P1_ROM_SDA    SDA @T6G_MB_LIB.T6G(SCH_1):SMB_RT_CPU1_P1_ROM_SDA
   4    GND    VSS @T6G_MB_LIB.T6G(SCH_1):GND
   3 U19_E2     E2 @T6G_MB_LIB.T6G(SCH_1):U19_E2
   2     NC    DU2     NC
   1     NC    DU1     NC

Q_RES_0201LF-1K,1%,1/20W,CHIP,CS21001FE07  I19  R6789
   1 U19_E2      A @T6G_MB_LIB.T6G(SCH_1):U19_E2
   2    GND      B @T6G_MB_LIB.T6G(SCH_1):GND

Q_CAP_C0201-0.1UF,10V,10%,X7S,CH4102K6E00  I22  C7502
   1 P1V8_CPU1_RT_1D      A @T6G_MB_LIB.T6G(SCH_1):P1V8_CPU1_RT_1D
   2    GND      B @T6G_MB_LIB.T6G(SCH_1):GND


DRAWING: @T6G_MB_LIB.T6G(SCH_1):PAGE453 

Q_RES_0201LF-33.2,1%,1/20W,CHIP,CS03321FE09  I3  R694
   1 SMB_RT_CPU1_P2_ROM_R_SDA      A @T6G_MB_LIB.T6G(SCH_1):SMB_RT_CPU1_P2_ROM_R_SDA
   2 SMB_RT_CPU1_P2_ROM_SDA      B @T6G_MB_LIB.T6G(SCH_1):SMB_RT_CPU1_P2_ROM_SDA

Q_RES_0201LF-33.2,1%,1/20W,CHIP,CS03321FE09  I4  R693
   1 SMB_RT_CPU1_P2_ROM_R_SCL      A @T6G_MB_LIB.T6G(SCH_1):SMB_RT_CPU1_P2_ROM_R_SCL
   2 SMB_RT_CPU1_P2_ROM_SCL      B @T6G_MB_LIB.T6G(SCH_1):SMB_RT_CPU1_P2_ROM_SCL

M24M02DRMN6TP-M24M02-DRMN6TP,SMLF,IC,AKE33Z00600  I5  U20
   8 P1V8_CPU1_RT_1D    VCC @T6G_MB_LIB.T6G(SCH_1):P1V8_CPU1_RT_1D
   7    GND   WC_N @T6G_MB_LIB.T6G(SCH_1):GND
   6 SMB_RT_CPU1_P2_ROM_SCL    SCL @T6G_MB_LIB.T6G(SCH_1):SMB_RT_CPU1_P2_ROM_SCL
   5 SMB_RT_CPU1_P2_ROM_SDA    SDA @T6G_MB_LIB.T6G(SCH_1):SMB_RT_CPU1_P2_ROM_SDA
   4    GND    VSS @T6G_MB_LIB.T6G(SCH_1):GND
   3 U20_E2     E2 @T6G_MB_LIB.T6G(SCH_1):U20_E2
   2     NC    DU2     NC
   1     NC    DU1     NC

Q_RES_0201LF-1K,1%,1/20W,CHIP,CS21001FE07  I19  R6790
   1 U20_E2      A @T6G_MB_LIB.T6G(SCH_1):U20_E2
   2    GND      B @T6G_MB_LIB.T6G(SCH_1):GND

Q_CAP_C0201-0.1UF,10V,10%,X7S,CH4102K6E00  I23  C7503
   1 P1V8_CPU1_RT_1D      A @T6G_MB_LIB.T6G(SCH_1):P1V8_CPU1_RT_1D
   2    GND      B @T6G_MB_LIB.T6G(SCH_1):GND


DRAWING: @T6G_MB_LIB.T6G(SCH_1):PAGE464 

Q_RES_0201LF-33.2,1%,1/20W,CHIP,CS03321FE09  I4  R698
   1 SMB_RT_CPU1_P3_ROM_R_SDA      A @T6G_MB_LIB.T6G(SCH_1):SMB_RT_CPU1_P3_ROM_R_SDA
   2 SMB_RT_CPU1_P3_ROM_SDA      B @T6G_MB_LIB.T6G(SCH_1):SMB_RT_CPU1_P3_ROM_SDA

M24M02DRMN6TP-M24M02-DRMN6TP,SMLF,IC,AKE33Z00600  I5  U21
   8 P1V8_CPU1_RT_1D    VCC @T6G_MB_LIB.T6G(SCH_1):P1V8_CPU1_RT_1D
   7    GND   WC_N @T6G_MB_LIB.T6G(SCH_1):GND
   6 SMB_RT_CPU1_P3_ROM_SCL    SCL @T6G_MB_LIB.T6G(SCH_1):SMB_RT_CPU1_P3_ROM_SCL
   5 SMB_RT_CPU1_P3_ROM_SDA    SDA @T6G_MB_LIB.T6G(SCH_1):SMB_RT_CPU1_P3_ROM_SDA
   4    GND    VSS @T6G_MB_LIB.T6G(SCH_1):GND
   3 U21_E2     E2 @T6G_MB_LIB.T6G(SCH_1):U21_E2
   2     NC    DU2     NC
   1     NC    DU1     NC

Q_CAP_C0201-0.1UF,10V,10%,X7S,CH4102K6E00  I19  C7504
   1 P1V8_CPU1_RT_1D      A @T6G_MB_LIB.T6G(SCH_1):P1V8_CPU1_RT_1D
   2    GND      B @T6G_MB_LIB.T6G(SCH_1):GND

Q_RES_0201LF-1K,1%,1/20W,CHIP,CS21001FE07  I22  R6791
   1 U21_E2      A @T6G_MB_LIB.T6G(SCH_1):U21_E2
   2    GND      B @T6G_MB_LIB.T6G(SCH_1):GND

Q_RES_0201LF-0,5%,1/20W,CHIP,CS00001JE10  I25  R697
   1 SMB_RT_CPU1_P3_ROM_R_SCL      A @T6G_MB_LIB.T6G(SCH_1):SMB_RT_CPU1_P3_ROM_R_SCL
   2 SMB_RT_CPU1_P3_ROM_SCL      B @T6G_MB_LIB.T6G(SCH_1):SMB_RT_CPU1_P3_ROM_SCL


DRAWING: @T6G_MB_LIB.T6G(SCH_1):PAGE398 

Q_CAP_C0805-100UF,4V,20%,X6S,CH710KMEA01  I4  C114
   1 P1V8_CPU1_RT0_1A      A @T6G_MB_LIB.T6G(SCH_1):P1V8_CPU1_RT0_1A
   2    GND      B @T6G_MB_LIB.T6G(SCH_1):GND

Q_CAP_C0402-22UF,4V,20%,X6S,CH622KMEB02  I5  C117
   1 P1V8_CPU1_RT0_1A      A @T6G_MB_LIB.T6G(SCH_1):P1V8_CPU1_RT0_1A
   2    GND      B @T6G_MB_LIB.T6G(SCH_1):GND

Q_CAP_0402-4.7UF,6.3V,20%,X6S,CH5471MEB01  I7  C121
   1 P1V8_CPU1_RT0_1A      A @T6G_MB_LIB.T6G(SCH_1):P1V8_CPU1_RT0_1A
   2    GND      B @T6G_MB_LIB.T6G(SCH_1):GND

Q_CAP_0201-1UF,4V,20%,X6S,CH-10KMEE00  I9  C126
   1 P1V8_CPU1_RT0_1A      A @T6G_MB_LIB.T6G(SCH_1):P1V8_CPU1_RT0_1A
   2    GND      B @T6G_MB_LIB.T6G(SCH_1):GND

Q_CAP_C0805-100UF,4V,20%,X6S,CH710KMEA01  I12  C113
   1 P1V8_CPU1_RT_1D      A @T6G_MB_LIB.T6G(SCH_1):P1V8_CPU1_RT_1D
   2    GND      B @T6G_MB_LIB.T6G(SCH_1):GND

Q_CAP_C0402-10UF,6.3V,20%,X6S,CH6101MEB01  I14  C118
   1 P1V8_CPU1_RT_1D      A @T6G_MB_LIB.T6G(SCH_1):P1V8_CPU1_RT_1D
   2    GND      B @T6G_MB_LIB.T6G(SCH_1):GND

Q_CAP_0402-4.7UF,6.3V,20%,X6S,CH5471MEB01  I15  C122
   1 P1V8_CPU1_RT_1D      A @T6G_MB_LIB.T6G(SCH_1):P1V8_CPU1_RT_1D
   2    GND      B @T6G_MB_LIB.T6G(SCH_1):GND

Q_CAP_0201-1UF,4V,20%,X6S,CH-10KMEE00  I18  C123
   1 P1V8_CPU1_RT0_1A      A @T6G_MB_LIB.T6G(SCH_1):P1V8_CPU1_RT0_1A
   2    GND      B @T6G_MB_LIB.T6G(SCH_1):GND

Q_CAP_0201-1UF,4V,20%,X6S,CH-10KMEE00  I19  C125
   1 P1V8_CPU1_RT0_1A_1D      A @T6G_MB_LIB.T6G(SCH_1):P1V8_CPU1_RT0_1A_1D
   2    GND      B @T6G_MB_LIB.T6G(SCH_1):GND

Q_CAP_C0402-10UF,6.3V,20%,X6S,CH6101MEB01  I20  C119
   1 P1V8_CPU1_RT0_1A      A @T6G_MB_LIB.T6G(SCH_1):P1V8_CPU1_RT0_1A
   2    GND      B @T6G_MB_LIB.T6G(SCH_1):GND

Q_CAP_C0402-22UF,4V,20%,X6S,CH622KMEB02  I21  C115
   1 P1V8_CPU1_RT_1D      A @T6G_MB_LIB.T6G(SCH_1):P1V8_CPU1_RT_1D
   2    GND      B @T6G_MB_LIB.T6G(SCH_1):GND

Q_INDUCTOR_SMLF-BLM21SN300SN1D/5A,IND,CX300SN1000  I22  L3
   2 P1V8_CPU1_RT0_1A      2 @T6G_MB_LIB.T6G(SCH_1):P1V8_CPU1_RT0_1A
   1 P1V8_CPU1_RT_1D      1 @T6G_MB_LIB.T6G(SCH_1):P1V8_CPU1_RT_1D

Q_CAP_C0201-0.1UF,10V,10%,X7S,CH4102K6E00  I23  C129
   1 P1V8_CPU1_RT0_1A      A @T6G_MB_LIB.T6G(SCH_1):P1V8_CPU1_RT0_1A
   2    GND      B @T6G_MB_LIB.T6G(SCH_1):GND

Q_CAP_C0201-0.1UF,10V,10%,X7S,CH4102K6E00  I24  C131
   1 P1V8_CPU1_RT0_1A      A @T6G_MB_LIB.T6G(SCH_1):P1V8_CPU1_RT0_1A
   2    GND      B @T6G_MB_LIB.T6G(SCH_1):GND

Q_CAP_C0201-0.1UF,10V,10%,X7S,CH4102K6E00  I25  C133
   1 P1V8_CPU1_RT0_1A      A @T6G_MB_LIB.T6G(SCH_1):P1V8_CPU1_RT0_1A
   2    GND      B @T6G_MB_LIB.T6G(SCH_1):GND

Q_CAP_C0201-0.1UF,10V,10%,X7S,CH4102K6E00  I26  C134
   1 P1V8_CPU1_RT0_1A      A @T6G_MB_LIB.T6G(SCH_1):P1V8_CPU1_RT0_1A
   2    GND      B @T6G_MB_LIB.T6G(SCH_1):GND

Q_CAP_C0201-0.1UF,10V,10%,X7S,CH4102K6E00  I27  C130
   1 P1V8_CPU1_RT0_1A_1D      A @T6G_MB_LIB.T6G(SCH_1):P1V8_CPU1_RT0_1A_1D
   2    GND      B @T6G_MB_LIB.T6G(SCH_1):GND

Q_RES_0402LF-0,5%,1/16W,EMPTY,CS00002JB13  I32  R6702
   1 P1V8_CPU1_RT0_1A_1D      A @T6G_MB_LIB.T6G(SCH_1):P1V8_CPU1_RT0_1A_1D
   2 P1V8_CPU1_RT0_1A      B @T6G_MB_LIB.T6G(SCH_1):P1V8_CPU1_RT0_1A

Q_RES_0402LF-0,5%,1/16W,EMPTY,CS00002JB13  I33  R6703
   1 P1V8_CPU1_RT0_1A_1D      A @T6G_MB_LIB.T6G(SCH_1):P1V8_CPU1_RT0_1A_1D
   2 P1V8_CPU1_RT0_1A      B @T6G_MB_LIB.T6G(SCH_1):P1V8_CPU1_RT0_1A

Q_CAP_C0805-100UF,4V,20%,X6S,CH710KMEA01  I34  C229
   1 P0V9_CPU1_RT_2D      A @T6G_MB_LIB.T6G(SCH_1):P0V9_CPU1_RT_2D
   2    GND      B @T6G_MB_LIB.T6G(SCH_1):GND

Q_CAP_C0402-22UF,4V,20%,X6S,CH622KMEB02  I35  C244
   1 P0V9_CPU1_RT_2D      A @T6G_MB_LIB.T6G(SCH_1):P0V9_CPU1_RT_2D
   2    GND      B @T6G_MB_LIB.T6G(SCH_1):GND

Q_CAP_C0402-10UF,6.3V,20%,X6S,CH6101MEB01  I36  C261
   1 P0V9_CPU1_RT_2D      A @T6G_MB_LIB.T6G(SCH_1):P0V9_CPU1_RT_2D
   2    GND      B @T6G_MB_LIB.T6G(SCH_1):GND

Q_CAP_0402-4.7UF,6.3V,20%,X6S,CH5471MEB01  I39  C256
   1 P0V9_CPU1_RT_2D      A @T6G_MB_LIB.T6G(SCH_1):P0V9_CPU1_RT_2D
   2    GND      B @T6G_MB_LIB.T6G(SCH_1):GND

Q_CAP_0201-1UF,4V,20%,X6S,CH-10KMEE00  I40  C185
   1 P0V9_CPU1_RT_2D      A @T6G_MB_LIB.T6G(SCH_1):P0V9_CPU1_RT_2D
   2    GND      B @T6G_MB_LIB.T6G(SCH_1):GND

Q_CAP_0201-1UF,4V,20%,X6S,CH-10KMEE00  I42  C222
   1 P0V9_CPU1_RT0_2A      A @T6G_MB_LIB.T6G(SCH_1):P0V9_CPU1_RT0_2A
   2    GND      B @T6G_MB_LIB.T6G(SCH_1):GND

Q_CAP_C0805-100UF,4V,20%,X6S,CH710KMEA01  I44  C220
   1 P0V9_CPU1_RT0_2A      A @T6G_MB_LIB.T6G(SCH_1):P0V9_CPU1_RT0_2A
   2    GND      B @T6G_MB_LIB.T6G(SCH_1):GND

Q_CAP_0201-1UF,4V,20%,X6S,CH-10KMEE00  I46  C135
   1 P0V9_CPU1_RT0_2A      A @T6G_MB_LIB.T6G(SCH_1):P0V9_CPU1_RT0_2A
   2    GND      B @T6G_MB_LIB.T6G(SCH_1):GND

Q_CAP_0201-1UF,4V,20%,X6S,CH-10KMEE00  I47  C243
   1 P0V9_CPU1_RT0_2A      A @T6G_MB_LIB.T6G(SCH_1):P0V9_CPU1_RT0_2A
   2    GND      B @T6G_MB_LIB.T6G(SCH_1):GND

Q_CAP_0201-1UF,4V,20%,X6S,CH-10KMEE00  I48  C138
   1 P0V9_CPU1_RT0_2A      A @T6G_MB_LIB.T6G(SCH_1):P0V9_CPU1_RT0_2A
   2    GND      B @T6G_MB_LIB.T6G(SCH_1):GND

Q_CAP_0201-1UF,4V,20%,X6S,CH-10KMEE00  I49  C257
   1 P0V9_CPU1_RT0_2A      A @T6G_MB_LIB.T6G(SCH_1):P0V9_CPU1_RT0_2A
   2    GND      B @T6G_MB_LIB.T6G(SCH_1):GND

Q_CAP_0402-4.7UF,6.3V,20%,X6S,CH5471MEB01  I50  C221
   1 P0V9_CPU1_RT0_2A      A @T6G_MB_LIB.T6G(SCH_1):P0V9_CPU1_RT0_2A
   2    GND      B @T6G_MB_LIB.T6G(SCH_1):GND

Q_CAP_0402-4.7UF,6.3V,20%,X6S,CH5471MEB01  I51  C258
   1 P0V9_CPU1_RT0_2A      A @T6G_MB_LIB.T6G(SCH_1):P0V9_CPU1_RT0_2A
   2    GND      B @T6G_MB_LIB.T6G(SCH_1):GND

Q_CAP_C0805-100UF,4V,20%,X6S,CH710KMEA01  I52  C225
   1 P0V9_CPU1_RT0_2A      A @T6G_MB_LIB.T6G(SCH_1):P0V9_CPU1_RT0_2A
   2    GND      B @T6G_MB_LIB.T6G(SCH_1):GND

Q_CAP_C0805-100UF,4V,20%,X6S,CH710KMEA01  I53  C240
   1 P0V9_CPU1_RT0_2A      A @T6G_MB_LIB.T6G(SCH_1):P0V9_CPU1_RT0_2A
   2    GND      B @T6G_MB_LIB.T6G(SCH_1):GND

Q_CAP_C0402-22UF,4V,20%,X6S,CH622KMEB02  I54  C284
   1 P0V9_CPU1_RT0_2A      A @T6G_MB_LIB.T6G(SCH_1):P0V9_CPU1_RT0_2A
   2    GND      B @T6G_MB_LIB.T6G(SCH_1):GND

Q_CAP_0201-1UF,4V,20%,X6S,CH-10KMEE00  I55  C188
   1 P0V9_CPU1_RT0_2A      A @T6G_MB_LIB.T6G(SCH_1):P0V9_CPU1_RT0_2A
   2    GND      B @T6G_MB_LIB.T6G(SCH_1):GND

Q_CAP_0201-1UF,4V,20%,X6S,CH-10KMEE00  I56  C265
   1 P0V9_CPU1_RT0_2A      A @T6G_MB_LIB.T6G(SCH_1):P0V9_CPU1_RT0_2A
   2    GND      B @T6G_MB_LIB.T6G(SCH_1):GND

Q_CAP_0402-4.7UF,6.3V,20%,X6S,CH5471MEB01  I57  C227
   1 P0V9_CPU1_RT0_2A      A @T6G_MB_LIB.T6G(SCH_1):P0V9_CPU1_RT0_2A
   2    GND      B @T6G_MB_LIB.T6G(SCH_1):GND

Q_CAP_0201-1UF,4V,20%,X6S,CH-10KMEE00  I58  C186
   1 P0V9_CPU1_RT0_2A      A @T6G_MB_LIB.T6G(SCH_1):P0V9_CPU1_RT0_2A
   2    GND      B @T6G_MB_LIB.T6G(SCH_1):GND

Q_CAP_0201-1UF,4V,20%,X6S,CH-10KMEE00  I59  C280
   1 P0V9_CPU1_RT0_2A      A @T6G_MB_LIB.T6G(SCH_1):P0V9_CPU1_RT0_2A
   2    GND      B @T6G_MB_LIB.T6G(SCH_1):GND

Q_CAP_0201-1UF,4V,20%,X6S,CH-10KMEE00  I62  C190
   1 P0V9_CPU1_RT0_2A      A @T6G_MB_LIB.T6G(SCH_1):P0V9_CPU1_RT0_2A
   2    GND      B @T6G_MB_LIB.T6G(SCH_1):GND

Q_CAP_0201-1UF,4V,20%,X6S,CH-10KMEE00  I63  C285
   1 P0V9_CPU1_RT0_2A      A @T6G_MB_LIB.T6G(SCH_1):P0V9_CPU1_RT0_2A
   2    GND      B @T6G_MB_LIB.T6G(SCH_1):GND

Q_CAP_C0402-22UF,4V,20%,X6S,CH622KMEB02  I64  C255
   1 P0V9_CPU1_RT0_2A      A @T6G_MB_LIB.T6G(SCH_1):P0V9_CPU1_RT0_2A
   2    GND      B @T6G_MB_LIB.T6G(SCH_1):GND

Q_CAP_C0402-22UF,4V,20%,X6S,CH622KMEB02  I65  C262
   1 P0V9_CPU1_RT0_2A      A @T6G_MB_LIB.T6G(SCH_1):P0V9_CPU1_RT0_2A
   2    GND      B @T6G_MB_LIB.T6G(SCH_1):GND

Q_CAP_C0402-22UF,4V,20%,X6S,CH622KMEB02  I66  C259
   1 P0V9_CPU1_RT0_2A      A @T6G_MB_LIB.T6G(SCH_1):P0V9_CPU1_RT0_2A
   2    GND      B @T6G_MB_LIB.T6G(SCH_1):GND

Q_CAP_C0402-10UF,6.3V,20%,X6S,CH6101MEB01  I67  C254
   1 P0V9_CPU1_RT0_2A      A @T6G_MB_LIB.T6G(SCH_1):P0V9_CPU1_RT0_2A
   2    GND      B @T6G_MB_LIB.T6G(SCH_1):GND

Q_CAP_C0402-10UF,6.3V,20%,X6S,CH6101MEB01  I68  C286
   1 P0V9_CPU1_RT0_2A      A @T6G_MB_LIB.T6G(SCH_1):P0V9_CPU1_RT0_2A
   2    GND      B @T6G_MB_LIB.T6G(SCH_1):GND

Q_CAP_C0402-10UF,6.3V,20%,X6S,CH6101MEB01  I70  C250
   1 P0V9_CPU1_RT0_2A      A @T6G_MB_LIB.T6G(SCH_1):P0V9_CPU1_RT0_2A
   2    GND      B @T6G_MB_LIB.T6G(SCH_1):GND

Q_CAP_C0402-10UF,6.3V,20%,X6S,CH6101MEB01  I71  C269
   1 P0V9_CPU1_RT0_2A      A @T6G_MB_LIB.T6G(SCH_1):P0V9_CPU1_RT0_2A
   2    GND      B @T6G_MB_LIB.T6G(SCH_1):GND

Q_CAP_0402-4.7UF,6.3V,20%,X6S,CH5471MEB01  I72  C241
   1 P0V9_CPU1_RT0_2A      A @T6G_MB_LIB.T6G(SCH_1):P0V9_CPU1_RT0_2A
   2    GND      B @T6G_MB_LIB.T6G(SCH_1):GND

Q_CAP_C0805-100UF,4V,20%,X6S,CH710KMEA01  I73  C247
   1 P0V9_CPU1_RT0_2A      A @T6G_MB_LIB.T6G(SCH_1):P0V9_CPU1_RT0_2A
   2    GND      B @T6G_MB_LIB.T6G(SCH_1):GND

Q_INDUCTOR_SMLF-100NH/16A,IND,CV+10G0MZ04  I74  L4
   2 P0V9_CPU1_RT0_2A      2 @T6G_MB_LIB.T6G(SCH_1):P0V9_CPU1_RT0_2A
   1 P0V9_CPU1_RT_2D      1 @T6G_MB_LIB.T6G(SCH_1):P0V9_CPU1_RT_2D

Q_CAP_C0201-0.1UF,10V,10%,X7S,CH4102K6E00  I75  C189
   1 P0V9_CPU1_RT_2D      A @T6G_MB_LIB.T6G(SCH_1):P0V9_CPU1_RT_2D
   2    GND      B @T6G_MB_LIB.T6G(SCH_1):GND

Q_CAP_C0201-0.1UF,10V,10%,X7S,CH4102K6E00  I76  C266
   1 P0V9_CPU1_RT_2D      A @T6G_MB_LIB.T6G(SCH_1):P0V9_CPU1_RT_2D
   2    GND      B @T6G_MB_LIB.T6G(SCH_1):GND

Q_CAP_C0201-0.1UF,10V,10%,X7S,CH4102K6E00  I77  C139
   1 P0V9_CPU1_RT_2D      A @T6G_MB_LIB.T6G(SCH_1):P0V9_CPU1_RT_2D
   2    GND      B @T6G_MB_LIB.T6G(SCH_1):GND

Q_CAP_C0201-0.1UF,10V,10%,X7S,CH4102K6E00  I78  C137
   1 P0V9_CPU1_RT_2D      A @T6G_MB_LIB.T6G(SCH_1):P0V9_CPU1_RT_2D
   2    GND      B @T6G_MB_LIB.T6G(SCH_1):GND

Q_CAP_C0201-0.1UF,10V,10%,X7S,CH4102K6E00  I80  C282
   1 P0V9_CPU1_RT0_2A      A @T6G_MB_LIB.T6G(SCH_1):P0V9_CPU1_RT0_2A
   2    GND      B @T6G_MB_LIB.T6G(SCH_1):GND

Q_CAP_C0201-0.1UF,10V,10%,X7S,CH4102K6E00  I81  C264
   1 P0V9_CPU1_RT0_2A      A @T6G_MB_LIB.T6G(SCH_1):P0V9_CPU1_RT0_2A
   2    GND      B @T6G_MB_LIB.T6G(SCH_1):GND

Q_CAP_C0201-0.1UF,10V,10%,X7S,CH4102K6E00  I82  C141
   1 P0V9_CPU1_RT0_2A      A @T6G_MB_LIB.T6G(SCH_1):P0V9_CPU1_RT0_2A
   2    GND      B @T6G_MB_LIB.T6G(SCH_1):GND

Q_CAP_C0201-0.1UF,10V,10%,X7S,CH4102K6E00  I83  C192
   1 P0V9_CPU1_RT0_2A      A @T6G_MB_LIB.T6G(SCH_1):P0V9_CPU1_RT0_2A
   2    GND      B @T6G_MB_LIB.T6G(SCH_1):GND

Q_CAP_C0201-0.1UF,10V,10%,X7S,CH4102K6E00  I84  C260
   1 P0V9_CPU1_RT0_2A      A @T6G_MB_LIB.T6G(SCH_1):P0V9_CPU1_RT0_2A
   2    GND      B @T6G_MB_LIB.T6G(SCH_1):GND

Q_CAP_C0201-0.1UF,10V,10%,X7S,CH4102K6E00  I85  C184
   1 P0V9_CPU1_RT0_2A      A @T6G_MB_LIB.T6G(SCH_1):P0V9_CPU1_RT0_2A
   2    GND      B @T6G_MB_LIB.T6G(SCH_1):GND

Q_CAP_C0201-0.1UF,10V,10%,X7S,CH4102K6E00  I86  C253
   1 P0V9_CPU1_RT0_2A      A @T6G_MB_LIB.T6G(SCH_1):P0V9_CPU1_RT0_2A
   2    GND      B @T6G_MB_LIB.T6G(SCH_1):GND

Q_CAP_C0201-0.1UF,10V,10%,X7S,CH4102K6E00  I87  C228
   1 P0V9_CPU1_RT0_2A      A @T6G_MB_LIB.T6G(SCH_1):P0V9_CPU1_RT0_2A
   2    GND      B @T6G_MB_LIB.T6G(SCH_1):GND

Q_CAP_C0201-0.1UF,10V,10%,X7S,CH4102K6E00  I92  C198
   1 P0V9_CPU1_RT0_2A_2D      A @T6G_MB_LIB.T6G(SCH_1):P0V9_CPU1_RT0_2A_2D
   2    GND      B @T6G_MB_LIB.T6G(SCH_1):GND

Q_CAP_C0201-0.1UF,10V,10%,X7S,CH4102K6E00  I93  C191
   1 P0V9_CPU1_RT0_2A_2D      A @T6G_MB_LIB.T6G(SCH_1):P0V9_CPU1_RT0_2A_2D
   2    GND      B @T6G_MB_LIB.T6G(SCH_1):GND

Q_RES_0603LF-0,5%,1/4W,CHIP,CS00006J900  I95  R6705
   1 P0V9_CPU1_RT0_2A_2D      A @T6G_MB_LIB.T6G(SCH_1):P0V9_CPU1_RT0_2A_2D
   2 P0V9_CPU1_RT0_2A      B @T6G_MB_LIB.T6G(SCH_1):P0V9_CPU1_RT0_2A

Q_RES_0603LF-0,5%,1/4W,EMPTY,CS00006J900  I96  R6704
   1 P0V9_CPU1_RT_2D      A @T6G_MB_LIB.T6G(SCH_1):P0V9_CPU1_RT_2D
   2 P0V9_CPU1_RT0_2A_2D      B @T6G_MB_LIB.T6G(SCH_1):P0V9_CPU1_RT0_2A_2D

Q_INDUCTOR_SMLF-BLM15PD121SN1D/1300MA,IND,CX5PD121A  I97  L27
   2 P1V8_CPU1_RT0_1A_1D      2 @T6G_MB_LIB.T6G(SCH_1):P1V8_CPU1_RT0_1A_1D
   1 P1V8_CPU1_RT_1D      1 @T6G_MB_LIB.T6G(SCH_1):P1V8_CPU1_RT_1D

Q_RES_0402LF-0,5%,1/16W,EMPTY,CS00002JB13  I98  R6701
   1 P1V8_CPU1_RT_1D      A @T6G_MB_LIB.T6G(SCH_1):P1V8_CPU1_RT_1D
   2 P1V8_CPU1_RT0_1A_1D      B @T6G_MB_LIB.T6G(SCH_1):P1V8_CPU1_RT0_1A_1D

Q_CAP_0201-1UF,4V,20%,X6S,CH-10KMEE00  I99  C187
   1 P0V9_CPU1_RT0_2A_2D      A @T6G_MB_LIB.T6G(SCH_1):P0V9_CPU1_RT0_2A_2D
   2    GND      B @T6G_MB_LIB.T6G(SCH_1):GND

Q_CAP_0201-1UF,4V,20%,X6S,CH-10KMEE00  I100  C201
   1 P0V9_CPU1_RT0_2A_2D      A @T6G_MB_LIB.T6G(SCH_1):P0V9_CPU1_RT0_2A_2D
   2    GND      B @T6G_MB_LIB.T6G(SCH_1):GND

Q_CAP_C0201-0.1UF,10V,10%,X7S,CH4102K6E00  I101  C281
   1 P0V9_CPU1_RT0_2A      A @T6G_MB_LIB.T6G(SCH_1):P0V9_CPU1_RT0_2A
   2    GND      B @T6G_MB_LIB.T6G(SCH_1):GND

Q_CAP_C0201-0.1UF,10V,10%,X7S,CH4102K6E00  I102  C283
   1 P0V9_CPU1_RT0_2A      A @T6G_MB_LIB.T6G(SCH_1):P0V9_CPU1_RT0_2A
   2    GND      B @T6G_MB_LIB.T6G(SCH_1):GND

Q_CAPP_SMLF-470UF,2.5V,20%,SPCAP,CH747LM8818  I103  C7020
   1 P0V9_CPU1_RT0_2A      A @T6G_MB_LIB.T6G(SCH_1):P0V9_CPU1_RT0_2A
   2    GND      B @T6G_MB_LIB.T6G(SCH_1):GND

Q_CAPP_SMLF-470UF,2.5V,20%,SPCAP,CH747LM8818  I104  C7021
   1 P0V9_CPU1_RT0_2A      A @T6G_MB_LIB.T6G(SCH_1):P0V9_CPU1_RT0_2A
   2    GND      B @T6G_MB_LIB.T6G(SCH_1):GND

Q_CAP_C0805-100UF,4V,20%,X6S,CH710KMEA01  I105  C7022
   1 P0V9_CPU1_RT0_2A      A @T6G_MB_LIB.T6G(SCH_1):P0V9_CPU1_RT0_2A
   2    GND      B @T6G_MB_LIB.T6G(SCH_1):GND


DRAWING: @T6G_MB_LIB.T6G(SCH_1):PAGE469 

Q_CAP_C0402-0.1UF,25V,10%,X6S,CH4104KEB00  I4  PC6500
   1 P12V_AUX      A @T6G_MB_LIB.T6G(SCH_1):P12V_AUX
   2    GND      B @T6G_MB_LIB.T6G(SCH_1):GND

Q_CAP_0402-0.1UF,25V,10%,EMPTY,CH4104K1B00  I5  C6757
   1 P1V8_RETIMER_CPU0_EN      A @T6G_MB_LIB.T6G(SCH_1):P1V8_RETIMER_CPU0_EN
   2    GND      B @T6G_MB_LIB.T6G(SCH_1):GND

Q_CAPP_SMLF-270UF,16V,20%,OSCON,CC72703MZ11  I6  PC6800
   1 SW_P12V_AUX_P1V8_RETIMER_CPU0_FLT      A @T6G_MB_LIB.T6G(SCH_1):SW_P12V_AUX_P1V8_RETIMER_CPU0_FLT
   2    GND      B @T6G_MB_LIB.T6G(SCH_1):GND

Q_CAP_C0805-22UF,16V,20%,X6S,CH6223MEA01  I7  PC6802
   1 SW_P12V_AUX_P1V8_RETIMER_CPU0_FLT      A @T6G_MB_LIB.T6G(SCH_1):SW_P12V_AUX_P1V8_RETIMER_CPU0_FLT
   2    GND      B @T6G_MB_LIB.T6G(SCH_1):GND

Q_INDUCTOR_SMLF-100NH/16A,IND,CV+10G0MZ04  I9  PL6500
   2 SW_P12V_AUX_P1V8_RETIMER_CPU0_FLT      2 @T6G_MB_LIB.T6G(SCH_1):SW_P12V_AUX_P1V8_RETIMER_CPU0_FLT
   1 P12V_AUX      1 @T6G_MB_LIB.T6G(SCH_1):P12V_AUX

Q_CAP_C0402-1UF,25V,10%,X6S,CH5104KEB02  I12  PC6506
   1 P1V8_RETIMER_CPU0_VCC      A @T6G_MB_LIB.T6G(SCH_1):P1V8_RETIMER_CPU0_VCC
   2    GND      B @T6G_MB_LIB.T6G(SCH_1):GND

Q_RES_0402LF-0,5%,1/16W,CHIP,CS00002JB13  I13  PR6501
   1 P3V3_AUX      A @T6G_MB_LIB.T6G(SCH_1):P3V3_AUX
   2 P1V8_RETIMER_CPU0_VCC      B @T6G_MB_LIB.T6G(SCH_1):P1V8_RETIMER_CPU0_VCC

Q_CAP_C0805-22UF,16V,20%,X6S,CH6223MEA01  I16  PC6501
   1 SW_P12V_AUX_P1V8_RETIMER_CPU0_FLT      A @T6G_MB_LIB.T6G(SCH_1):SW_P12V_AUX_P1V8_RETIMER_CPU0_FLT
   2    GND      B @T6G_MB_LIB.T6G(SCH_1):GND

Q_CAP_C0805-22UF,16V,20%,X6S,CH6223MEA01  I17  PC6502
   1 SW_P12V_AUX_P1V8_RETIMER_CPU0_FLT      A @T6G_MB_LIB.T6G(SCH_1):SW_P12V_AUX_P1V8_RETIMER_CPU0_FLT
   2    GND      B @T6G_MB_LIB.T6G(SCH_1):GND

Q_CAP_C0805-22UF,16V,20%,X6S,CH6223MEA01  I18  PC6503
   1 SW_P12V_AUX_P1V8_RETIMER_CPU0_FLT      A @T6G_MB_LIB.T6G(SCH_1):SW_P12V_AUX_P1V8_RETIMER_CPU0_FLT
   2    GND      B @T6G_MB_LIB.T6G(SCH_1):GND

Q_RES_0402LF-7.15K,1%,1/16W,CHIP,CS27152FB03  I20  PR6502
   1 P1V8_RETIMER_CPU0_CS      A @T6G_MB_LIB.T6G(SCH_1):P1V8_RETIMER_CPU0_CS
   2    GND      B @T6G_MB_LIB.T6G(SCH_1):GND

Q_RES_0402LF-0,5%,1/16W,CHIP,CS00002JB13  I21  PR6500
   1    GND      A @T6G_MB_LIB.T6G(SCH_1):GND
   2 P1V8_RETIMER_CPU0_MODE      B @T6G_MB_LIB.T6G(SCH_1):P1V8_RETIMER_CPU0_MODE

Q_CAP_C0805-22UF,16V,20%,X6S,CH6223MEA01  I22  PC6504
   1 SW_P12V_AUX_P1V8_RETIMER_CPU0_FLT      A @T6G_MB_LIB.T6G(SCH_1):SW_P12V_AUX_P1V8_RETIMER_CPU0_FLT
   2    GND      B @T6G_MB_LIB.T6G(SCH_1):GND

Q_CAP_C0402-1UF,25V,10%,X6S,CH5104KEB02  I23  PC6505
   1 SW_P12V_AUX_P1V8_RETIMER_CPU0_FLT      A @T6G_MB_LIB.T6G(SCH_1):SW_P12V_AUX_P1V8_RETIMER_CPU0_FLT
   2    GND      B @T6G_MB_LIB.T6G(SCH_1):GND

Q_CAP_0402-0.1UF,25V,10%,X7R,CH4104K1B00  I26  PC6518
   1 P1V8_RETIMER_CPU0_REF      A @T6G_MB_LIB.T6G(SCH_1):P1V8_RETIMER_CPU0_REF
   2    GND      B @T6G_MB_LIB.T6G(SCH_1):GND

Q_RES_0402LF-10K,5%,1/16W,CHIP,CS31002JB08  I28  R6505
   1 P3V3_AUX      A @T6G_MB_LIB.T6G(SCH_1):P3V3_AUX
   2 PWRGD_P1V8_RETIMER_CPU0      B @T6G_MB_LIB.T6G(SCH_1):PWRGD_P1V8_RETIMER_CPU0

Q_RES_0402LF-2.2,1%,1/16W,CHIP,CS-2202FB01  I29  PR6800
   1 SW_P1V8_RETIMER_CPU0_BST      A @T6G_MB_LIB.T6G(SCH_1):SW_P1V8_RETIMER_CPU0_BST
   2 SW_P1V8_RETIMER_CPU0_BST_R      B @T6G_MB_LIB.T6G(SCH_1):SW_P1V8_RETIMER_CPU0_BST_R

Q_CAP_0402-0.22UF,16V,10%,X7R,CH4223K1B00  I32  PC6507
   1 SW_P1V8_RETIMER_CPU0_BST_R      A @T6G_MB_LIB.T6G(SCH_1):SW_P1V8_RETIMER_CPU0_BST_R
   2 SW_P1V8_RETIMER_CPU0_SW      B @T6G_MB_LIB.T6G(SCH_1):SW_P1V8_RETIMER_CPU0_SW

Q_RES_0402LF-10K,1%,1/16W,CHIP,CS31002FB08  I33  PR6507
   1 P1V8_RETIMER_CPU0_FB      A @T6G_MB_LIB.T6G(SCH_1):P1V8_RETIMER_CPU0_FB
   2    GND      B @T6G_MB_LIB.T6G(SCH_1):GND

Q_CAP_0402-150PF,50V,5%,NPO,TMP_QCH11506JB08  I34  PC6515
   1 P1V8_RETIMER_CPU0_FB      A @T6G_MB_LIB.T6G(SCH_1):P1V8_RETIMER_CPU0_FB
   2 P1V8_CPU0_RT_1D      B @T6G_MB_LIB.T6G(SCH_1):P1V8_CPU0_RT_1D

Q_RES_0402LF-20K,1%,1/16W,CHIP,CS32002FB06  I35  PR6505
   1 P1V8_RETIMER_CPU0_FB      A @T6G_MB_LIB.T6G(SCH_1):P1V8_RETIMER_CPU0_FB
   2 P1V8_CPU0_RT_1D      B @T6G_MB_LIB.T6G(SCH_1):P1V8_CPU0_RT_1D

Q_INDUCTOR_SMLF-1UH,IND,CV-10U0MZ01  I36  PL6501
   2 P1V8_CPU0_RT_1D      2 @T6G_MB_LIB.T6G(SCH_1):P1V8_CPU0_RT_1D
   1 SW_P1V8_RETIMER_CPU0_SW      1 @T6G_MB_LIB.T6G(SCH_1):SW_P1V8_RETIMER_CPU0_SW

Q_RES_0402LF-33,5%,1/16W,CHIP,CS03302JB10  I37  R6506
   1 PWRGD_P1V8_RETIMER_CPU0      A @T6G_MB_LIB.T6G(SCH_1):PWRGD_P1V8_RETIMER_CPU0
   2 FM_PWRGD_P1V8_RETIMER_CPU0      B @T6G_MB_LIB.T6G(SCH_1):FM_PWRGD_P1V8_RETIMER_CPU0

Q_CAP_C0805-22UF,4V,20%,X6S,CH622KMEA03  I38  PC6508
   1 P1V8_CPU0_RT_1D      A @T6G_MB_LIB.T6G(SCH_1):P1V8_CPU0_RT_1D
   2    GND      B @T6G_MB_LIB.T6G(SCH_1):GND

Q_CAP_C0805-22UF,4V,20%,X6S,CH622KMEA03  I39  PC6509
   1 P1V8_CPU0_RT_1D      A @T6G_MB_LIB.T6G(SCH_1):P1V8_CPU0_RT_1D
   2    GND      B @T6G_MB_LIB.T6G(SCH_1):GND

Q_CAP_C0805-22UF,4V,20%,X6S,CH622KMEA03  I40  PC6510
   1 P1V8_CPU0_RT_1D      A @T6G_MB_LIB.T6G(SCH_1):P1V8_CPU0_RT_1D
   2    GND      B @T6G_MB_LIB.T6G(SCH_1):GND

Q_CAP_0402-1000PF,50V,5%,X7R,TMP_QCH21006JB10  I42  C6758
   1 FM_PWRGD_P1V8_RETIMER_CPU0      A @T6G_MB_LIB.T6G(SCH_1):FM_PWRGD_P1V8_RETIMER_CPU0
   2    GND      B @T6G_MB_LIB.T6G(SCH_1):GND

Q_CAP_C0805-22UF,4V,20%,X6S,CH622KMEA03  I44  PC6511
   1 P1V8_CPU0_RT_1D      A @T6G_MB_LIB.T6G(SCH_1):P1V8_CPU0_RT_1D
   2    GND      B @T6G_MB_LIB.T6G(SCH_1):GND

Q_CAPP_SMLF-390UF,2.5V,20%,ALUM,CC7390JMZ13  I46  PC6513
   1 P1V8_CPU0_RT_1D      A @T6G_MB_LIB.T6G(SCH_1):P1V8_CPU0_RT_1D
   2    GND      B @T6G_MB_LIB.T6G(SCH_1):GND

Q_CAPP_SMLF-390UF,2.5V,20%,ALUM,CC7390JMZ13  I48  PC6805
   1 P1V8_CPU0_RT_1D      A @T6G_MB_LIB.T6G(SCH_1):P1V8_CPU0_RT_1D
   2    GND      B @T6G_MB_LIB.T6G(SCH_1):GND

Q_CAP_0402-0.1UF,25V,10%,X7R,CH4104K1B00  I49  PC6514
   1 P1V8_CPU0_RT_1D      A @T6G_MB_LIB.T6G(SCH_1):P1V8_CPU0_RT_1D
   2    GND      B @T6G_MB_LIB.T6G(SCH_1):GND

MPQ8633BGLEC838Z-MPQ8633BGLE-C838-Z,SMLF,IC,AL0086A  I51  PU6500
  10 SW_P12V_AUX_P1V8_RETIMER_CPU0_FLT   VIN1 @T6G_MB_LIB.T6G(SCH_1):SW_P12V_AUX_P1V8_RETIMER_CPU0_FLT
   9 PWRGD_P1V8_RETIMER_CPU0  PGOOD @T6G_MB_LIB.T6G(SCH_1):PWRGD_P1V8_RETIMER_CPU0
11_18    GND   PGND @T6G_MB_LIB.T6G(SCH_1):GND
   8 P1V8_RETIMER_CPU0_EN     EN @T6G_MB_LIB.T6G(SCH_1):P1V8_RETIMER_CPU0_EN
   1 SW_P1V8_RETIMER_CPU0_BST    BST @T6G_MB_LIB.T6G(SCH_1):SW_P1V8_RETIMER_CPU0_BST
   7 P1V8_RETIMER_CPU0_FB     FB @T6G_MB_LIB.T6G(SCH_1):P1V8_RETIMER_CPU0_FB
   2    GND   AGND @T6G_MB_LIB.T6G(SCH_1):GND
  19 P1V8_RETIMER_CPU0_VCC    VCC @T6G_MB_LIB.T6G(SCH_1):P1V8_RETIMER_CPU0_VCC
   6    GND   RGND @T6G_MB_LIB.T6G(SCH_1):GND
  20 SW_P1V8_RETIMER_CPU0_SW     SW @T6G_MB_LIB.T6G(SCH_1):SW_P1V8_RETIMER_CPU0_SW
   5 P1V8_RETIMER_CPU0_REF TRK_REF @T6G_MB_LIB.T6G(SCH_1):P1V8_RETIMER_CPU0_REF
   4 P1V8_RETIMER_CPU0_MODE   MODE @T6G_MB_LIB.T6G(SCH_1):P1V8_RETIMER_CPU0_MODE
   3 P1V8_RETIMER_CPU0_CS     CS @T6G_MB_LIB.T6G(SCH_1):P1V8_RETIMER_CPU0_CS
  21 SW_P12V_AUX_P1V8_RETIMER_CPU0_FLT   VIN2 @T6G_MB_LIB.T6G(SCH_1):SW_P12V_AUX_P1V8_RETIMER_CPU0_FLT

Q_CAP_C0805-22UF,4V,20%,X6S,CH622KMEA03  I52  PC6512
   1 P1V8_CPU0_RT_1D      A @T6G_MB_LIB.T6G(SCH_1):P1V8_CPU0_RT_1D
   2    GND      B @T6G_MB_LIB.T6G(SCH_1):GND

Q_CAP_C0805-22UF,16V,20%,X6S,CH6223MEA01  I56  PC6902
   1 SW_P12V_AUX_P1V8_RETIMER_CPU0_FLT      A @T6G_MB_LIB.T6G(SCH_1):SW_P12V_AUX_P1V8_RETIMER_CPU0_FLT
   2    GND      B @T6G_MB_LIB.T6G(SCH_1):GND

Q_CAP_C0805-22UF,16V,20%,X6S,CH6223MEA01  I57  PC6901
   1 SW_P12V_AUX_P1V8_RETIMER_CPU0_FLT      A @T6G_MB_LIB.T6G(SCH_1):SW_P12V_AUX_P1V8_RETIMER_CPU0_FLT
   2    GND      B @T6G_MB_LIB.T6G(SCH_1):GND

Q_CAP_C0805-22UF,16V,20%,X6S,CH6223MEA01  I58  PC6900
   1 SW_P12V_AUX_P1V8_RETIMER_CPU0_FLT      A @T6G_MB_LIB.T6G(SCH_1):SW_P12V_AUX_P1V8_RETIMER_CPU0_FLT
   2    GND      B @T6G_MB_LIB.T6G(SCH_1):GND


DRAWING: @T6G_MB_LIB.T6G(SCH_1):PAGE470 

Q_CAP_C0402-0.1UF,25V,10%,X6S,CH4104KEB00  I3  PC6519
   1 P12V_AUX      A @T6G_MB_LIB.T6G(SCH_1):P12V_AUX
   2    GND      B @T6G_MB_LIB.T6G(SCH_1):GND

Q_CAP_0402-0.1UF,25V,10%,EMPTY,CH4104K1B00  I5  C105
   1 P1V8_RETIMER_CPU1_EN      A @T6G_MB_LIB.T6G(SCH_1):P1V8_RETIMER_CPU1_EN
   2    GND      B @T6G_MB_LIB.T6G(SCH_1):GND

Q_CAPP_SMLF-270UF,16V,20%,OSCON,CC72703MZ11  I6  PC6801
   1 SW_P12V_AUX_P1V8_RETIMER_CPU1_FLT      A @T6G_MB_LIB.T6G(SCH_1):SW_P12V_AUX_P1V8_RETIMER_CPU1_FLT
   2    GND      B @T6G_MB_LIB.T6G(SCH_1):GND

Q_CAP_C0805-22UF,16V,20%,X6S,CH6223MEA01  I7  PC6803
   1 SW_P12V_AUX_P1V8_RETIMER_CPU1_FLT      A @T6G_MB_LIB.T6G(SCH_1):SW_P12V_AUX_P1V8_RETIMER_CPU1_FLT
   2    GND      B @T6G_MB_LIB.T6G(SCH_1):GND

Q_INDUCTOR_SMLF-100NH/16A,IND,CV+10G0MZ04  I9  PL6503
   2 SW_P12V_AUX_P1V8_RETIMER_CPU1_FLT      2 @T6G_MB_LIB.T6G(SCH_1):SW_P12V_AUX_P1V8_RETIMER_CPU1_FLT
   1 P12V_AUX      1 @T6G_MB_LIB.T6G(SCH_1):P12V_AUX

Q_CAP_C0402-1UF,25V,10%,X6S,CH5104KEB02  I12  PC6525
   1 P1V8_RETIMER_CPU1_VCC      A @T6G_MB_LIB.T6G(SCH_1):P1V8_RETIMER_CPU1_VCC
   2    GND      B @T6G_MB_LIB.T6G(SCH_1):GND

Q_RES_0402LF-0,5%,1/16W,CHIP,CS00002JB13  I13  PR6521
   1 P3V3_AUX      A @T6G_MB_LIB.T6G(SCH_1):P3V3_AUX
   2 P1V8_RETIMER_CPU1_VCC      B @T6G_MB_LIB.T6G(SCH_1):P1V8_RETIMER_CPU1_VCC

Q_CAP_C0805-22UF,16V,20%,X6S,CH6223MEA01  I16  PC6520
   1 SW_P12V_AUX_P1V8_RETIMER_CPU1_FLT      A @T6G_MB_LIB.T6G(SCH_1):SW_P12V_AUX_P1V8_RETIMER_CPU1_FLT
   2    GND      B @T6G_MB_LIB.T6G(SCH_1):GND

Q_CAP_C0805-22UF,16V,20%,X6S,CH6223MEA01  I17  PC6521
   1 SW_P12V_AUX_P1V8_RETIMER_CPU1_FLT      A @T6G_MB_LIB.T6G(SCH_1):SW_P12V_AUX_P1V8_RETIMER_CPU1_FLT
   2    GND      B @T6G_MB_LIB.T6G(SCH_1):GND

Q_CAP_C0805-22UF,16V,20%,X6S,CH6223MEA01  I18  PC6522
   1 SW_P12V_AUX_P1V8_RETIMER_CPU1_FLT      A @T6G_MB_LIB.T6G(SCH_1):SW_P12V_AUX_P1V8_RETIMER_CPU1_FLT
   2    GND      B @T6G_MB_LIB.T6G(SCH_1):GND

Q_RES_0402LF-7.15K,1%,1/16W,CHIP,CS27152FB03  I20  PR6522
   1 P1V8_RETIMER_CPU1_CS      A @T6G_MB_LIB.T6G(SCH_1):P1V8_RETIMER_CPU1_CS
   2    GND      B @T6G_MB_LIB.T6G(SCH_1):GND

Q_RES_0402LF-0,5%,1/16W,CHIP,CS00002JB13  I21  PR6520
   1    GND      A @T6G_MB_LIB.T6G(SCH_1):GND
   2 P1V8_RETIMER_CPU1_MODE      B @T6G_MB_LIB.T6G(SCH_1):P1V8_RETIMER_CPU1_MODE

Q_CAP_C0805-22UF,16V,20%,X6S,CH6223MEA01  I22  PC6523
   1 SW_P12V_AUX_P1V8_RETIMER_CPU1_FLT      A @T6G_MB_LIB.T6G(SCH_1):SW_P12V_AUX_P1V8_RETIMER_CPU1_FLT
   2    GND      B @T6G_MB_LIB.T6G(SCH_1):GND

Q_CAP_C0402-1UF,25V,10%,X6S,CH5104KEB02  I23  PC6524
   1 SW_P12V_AUX_P1V8_RETIMER_CPU1_FLT      A @T6G_MB_LIB.T6G(SCH_1):SW_P12V_AUX_P1V8_RETIMER_CPU1_FLT
   2    GND      B @T6G_MB_LIB.T6G(SCH_1):GND

Q_CAP_0402-0.1UF,25V,10%,X7R,CH4104K1B00  I25  PC6537
   1 P1V8_RETIMER_CPU1_REF      A @T6G_MB_LIB.T6G(SCH_1):P1V8_RETIMER_CPU1_REF
   2    GND      B @T6G_MB_LIB.T6G(SCH_1):GND

Q_RES_0402LF-2.2,1%,1/16W,CHIP,CS-2202FB01  I28  PR6801
   1 SW_P1V8_RETIMER_CPU1_BST      A @T6G_MB_LIB.T6G(SCH_1):SW_P1V8_RETIMER_CPU1_BST
   2 SW_P1V8_RETIMER_CPU1_BST_R      B @T6G_MB_LIB.T6G(SCH_1):SW_P1V8_RETIMER_CPU1_BST_R

Q_RES_0402LF-10K,5%,1/16W,CHIP,CS31002JB08  I29  R644
   1 P3V3_AUX      A @T6G_MB_LIB.T6G(SCH_1):P3V3_AUX
   2 PWRGD_P1V8_RETIMER_CPU1      B @T6G_MB_LIB.T6G(SCH_1):PWRGD_P1V8_RETIMER_CPU1

Q_RES_0402LF-10K,1%,1/16W,CHIP,CS31002FB08  I32  PR6526
   1 P1V8_RETIMER_CPU1_FB      A @T6G_MB_LIB.T6G(SCH_1):P1V8_RETIMER_CPU1_FB
   2    GND      B @T6G_MB_LIB.T6G(SCH_1):GND

Q_CAP_0402-150PF,50V,5%,NPO,TMP_QCH11506JB08  I33  PC6534
   1 P1V8_RETIMER_CPU1_FB      A @T6G_MB_LIB.T6G(SCH_1):P1V8_RETIMER_CPU1_FB
   2 P1V8_CPU1_RT_1D      B @T6G_MB_LIB.T6G(SCH_1):P1V8_CPU1_RT_1D

Q_RES_0402LF-20K,1%,1/16W,CHIP,CS32002FB06  I34  PR6524
   1 P1V8_RETIMER_CPU1_FB      A @T6G_MB_LIB.T6G(SCH_1):P1V8_RETIMER_CPU1_FB
   2 P1V8_CPU1_RT_1D      B @T6G_MB_LIB.T6G(SCH_1):P1V8_CPU1_RT_1D

Q_CAP_0402-0.22UF,16V,10%,X7R,CH4223K1B00  I35  PC6526
   1 SW_P1V8_RETIMER_CPU1_BST_R      A @T6G_MB_LIB.T6G(SCH_1):SW_P1V8_RETIMER_CPU1_BST_R
   2 SW_P1V8_RETIMER_CPU1_SW      B @T6G_MB_LIB.T6G(SCH_1):SW_P1V8_RETIMER_CPU1_SW

Q_RES_0402LF-33,5%,1/16W,CHIP,CS03302JB10  I36  R645
   1 PWRGD_P1V8_RETIMER_CPU1      A @T6G_MB_LIB.T6G(SCH_1):PWRGD_P1V8_RETIMER_CPU1
   2 FM_PWRGD_P1V8_RETIMER_CPU1      B @T6G_MB_LIB.T6G(SCH_1):FM_PWRGD_P1V8_RETIMER_CPU1

Q_INDUCTOR_SMLF-1UH,IND,CV-10U0MZ01  I37  PL6502
   2 P1V8_CPU1_RT_1D      2 @T6G_MB_LIB.T6G(SCH_1):P1V8_CPU1_RT_1D
   1 SW_P1V8_RETIMER_CPU1_SW      1 @T6G_MB_LIB.T6G(SCH_1):SW_P1V8_RETIMER_CPU1_SW

Q_CAP_C0805-22UF,4V,20%,X6S,CH622KMEA03  I38  PC6527
   1 P1V8_CPU1_RT_1D      A @T6G_MB_LIB.T6G(SCH_1):P1V8_CPU1_RT_1D
   2    GND      B @T6G_MB_LIB.T6G(SCH_1):GND

Q_CAP_0402-1000PF,50V,5%,X7R,TMP_QCH21006JB10  I39  C109
   1 FM_PWRGD_P1V8_RETIMER_CPU1      A @T6G_MB_LIB.T6G(SCH_1):FM_PWRGD_P1V8_RETIMER_CPU1
   2    GND      B @T6G_MB_LIB.T6G(SCH_1):GND

Q_CAP_C0805-22UF,4V,20%,X6S,CH622KMEA03  I41  PC6528
   1 P1V8_CPU1_RT_1D      A @T6G_MB_LIB.T6G(SCH_1):P1V8_CPU1_RT_1D
   2    GND      B @T6G_MB_LIB.T6G(SCH_1):GND

Q_CAP_C0805-22UF,4V,20%,X6S,CH622KMEA03  I42  PC6529
   1 P1V8_CPU1_RT_1D      A @T6G_MB_LIB.T6G(SCH_1):P1V8_CPU1_RT_1D
   2    GND      B @T6G_MB_LIB.T6G(SCH_1):GND

Q_CAP_C0805-22UF,4V,20%,X6S,CH622KMEA03  I44  PC6530
   1 P1V8_CPU1_RT_1D      A @T6G_MB_LIB.T6G(SCH_1):P1V8_CPU1_RT_1D
   2    GND      B @T6G_MB_LIB.T6G(SCH_1):GND

Q_CAP_C0805-22UF,4V,20%,X6S,CH622KMEA03  I45  PC6531
   1 P1V8_CPU1_RT_1D      A @T6G_MB_LIB.T6G(SCH_1):P1V8_CPU1_RT_1D
   2    GND      B @T6G_MB_LIB.T6G(SCH_1):GND

Q_CAPP_SMLF-390UF,2.5V,20%,ALUM,CC7390JMZ13  I46  PC6532
   1 P1V8_CPU1_RT_1D      A @T6G_MB_LIB.T6G(SCH_1):P1V8_CPU1_RT_1D
   2    GND      B @T6G_MB_LIB.T6G(SCH_1):GND

Q_CAPP_SMLF-390UF,2.5V,20%,ALUM,CC7390JMZ13  I47  PC6804
   1 P1V8_CPU1_RT_1D      A @T6G_MB_LIB.T6G(SCH_1):P1V8_CPU1_RT_1D
   2    GND      B @T6G_MB_LIB.T6G(SCH_1):GND

Q_CAP_0402-0.1UF,25V,10%,X7R,CH4104K1B00  I49  PC6533
   1 P1V8_CPU1_RT_1D      A @T6G_MB_LIB.T6G(SCH_1):P1V8_CPU1_RT_1D
   2    GND      B @T6G_MB_LIB.T6G(SCH_1):GND

MPQ8633BGLEC838Z-MPQ8633BGLE-C838-Z,SMLF,IC,AL0086A  I51  PU6501
  10 SW_P12V_AUX_P1V8_RETIMER_CPU1_FLT   VIN1 @T6G_MB_LIB.T6G(SCH_1):SW_P12V_AUX_P1V8_RETIMER_CPU1_FLT
   9 PWRGD_P1V8_RETIMER_CPU1  PGOOD @T6G_MB_LIB.T6G(SCH_1):PWRGD_P1V8_RETIMER_CPU1
11_18    GND   PGND @T6G_MB_LIB.T6G(SCH_1):GND
   8 P1V8_RETIMER_CPU1_EN     EN @T6G_MB_LIB.T6G(SCH_1):P1V8_RETIMER_CPU1_EN
   1 SW_P1V8_RETIMER_CPU1_BST    BST @T6G_MB_LIB.T6G(SCH_1):SW_P1V8_RETIMER_CPU1_BST
   7 P1V8_RETIMER_CPU1_FB     FB @T6G_MB_LIB.T6G(SCH_1):P1V8_RETIMER_CPU1_FB
   2    GND   AGND @T6G_MB_LIB.T6G(SCH_1):GND
  19 P1V8_RETIMER_CPU1_VCC    VCC @T6G_MB_LIB.T6G(SCH_1):P1V8_RETIMER_CPU1_VCC
   6    GND   RGND @T6G_MB_LIB.T6G(SCH_1):GND
  20 SW_P1V8_RETIMER_CPU1_SW     SW @T6G_MB_LIB.T6G(SCH_1):SW_P1V8_RETIMER_CPU1_SW
   5 P1V8_RETIMER_CPU1_REF TRK_REF @T6G_MB_LIB.T6G(SCH_1):P1V8_RETIMER_CPU1_REF
   4 P1V8_RETIMER_CPU1_MODE   MODE @T6G_MB_LIB.T6G(SCH_1):P1V8_RETIMER_CPU1_MODE
   3 P1V8_RETIMER_CPU1_CS     CS @T6G_MB_LIB.T6G(SCH_1):P1V8_RETIMER_CPU1_CS
  21 SW_P12V_AUX_P1V8_RETIMER_CPU1_FLT   VIN2 @T6G_MB_LIB.T6G(SCH_1):SW_P12V_AUX_P1V8_RETIMER_CPU1_FLT

Q_CAP_C0805-22UF,16V,20%,X6S,CH6223MEA01  I55  PC6905
   1 SW_P12V_AUX_P1V8_RETIMER_CPU1_FLT      A @T6G_MB_LIB.T6G(SCH_1):SW_P12V_AUX_P1V8_RETIMER_CPU1_FLT
   2    GND      B @T6G_MB_LIB.T6G(SCH_1):GND

Q_CAP_C0805-22UF,16V,20%,X6S,CH6223MEA01  I56  PC6904
   1 SW_P12V_AUX_P1V8_RETIMER_CPU1_FLT      A @T6G_MB_LIB.T6G(SCH_1):SW_P12V_AUX_P1V8_RETIMER_CPU1_FLT
   2    GND      B @T6G_MB_LIB.T6G(SCH_1):GND

Q_CAP_C0805-22UF,16V,20%,X6S,CH6223MEA01  I57  PC6903
   1 SW_P12V_AUX_P1V8_RETIMER_CPU1_FLT      A @T6G_MB_LIB.T6G(SCH_1):SW_P12V_AUX_P1V8_RETIMER_CPU1_FLT
   2    GND      B @T6G_MB_LIB.T6G(SCH_1):GND


DRAWING: @T6G_MB_LIB.T6G(SCH_1):PAGE475 

Q_RES_0402LF-49.9,1%,1/16W,CHIP,CS04992FB07  I32  PR6532
   1 P0V9_RETIMER_CPU0_SENSE_SH_N      A @T6G_MB_LIB.T6G(SCH_1):P0V9_RETIMER_CPU0_SENSE_SH_N
   2    GND      B @T6G_MB_LIB.T6G(SCH_1):GND

Q_RES_0402LF-49.9,1%,1/16W,CHIP,CS04992FB07  I34  PR6530
   1 P0V9_RETIMER_CPU0_SENSE_SH_P      A @T6G_MB_LIB.T6G(SCH_1):P0V9_RETIMER_CPU0_SENSE_SH_P
   2 P0V9_CPU0_RT_2D      B @T6G_MB_LIB.T6G(SCH_1):P0V9_CPU0_RT_2D

ISL69260IRAZT-ISL69260IRAZ-T,SMLF,IC,AL069260000  I42  PU6502
  23 P0V9_RETIMER_CPU0_IMON1    CS7 @T6G_MB_LIB.T6G(SCH_1):P0V9_RETIMER_CPU0_IMON1
  39 P0V9_RETIMER_CPU0_VCC    VCC @T6G_MB_LIB.T6G(SCH_1):P0V9_RETIMER_CPU0_VCC
  20 P0V9_RETIMER_CPU0_EN1_R    EN1 @T6G_MB_LIB.T6G(SCH_1):P0V9_RETIMER_CPU0_EN1_R
  10 P0V9_RETIMER_CPU0_PMSCL_R  PMSCL @T6G_MB_LIB.T6G(SCH_1):P0V9_RETIMER_CPU0_PMSCL_R
  18 P0V9_RETIMER_CPU0_SVID_SDA SVDATA @T6G_MB_LIB.T6G(SCH_1):P0V9_RETIMER_CPU0_SVID_SDA
  24 P0V9_RETIMER_CPU0_IMON2    CS6 @T6G_MB_LIB.T6G(SCH_1):P0V9_RETIMER_CPU0_IMON2
  19 TP_P0V9_RETIMER_CPU0_SVID_ALERT_N NSVALERT# @T6G_MB_LIB.T6G(SCH_1):TP_P0V9_RETIMER_CPU0_SVID_ALERT_N
  14 P0V9_RETIMER_CPU0_VRHOT NVRHOT# @T6G_MB_LIB.T6G(SCH_1):P0V9_RETIMER_CPU0_VRHOT
  25 NC_P0V9_RETIMER_CPU0_IMON3    CS5 @T6G_MB_LIB.T6G(SCH_1):NC_P0V9_RETIMER_CPU0_IMON3
  26 NC_P0V9_RETIMER_CPU0_IMON4    CS4 @T6G_MB_LIB.T6G(SCH_1):NC_P0V9_RETIMER_CPU0_IMON4
  16 NC_P0V9_RETIMER_CPU0_PG1    PG1 @T6G_MB_LIB.T6G(SCH_1):NC_P0V9_RETIMER_CPU0_PG1
  17 P0V9_RETIMER_CPU0_SVID_CLK  SVCLK @T6G_MB_LIB.T6G(SCH_1):P0V9_RETIMER_CPU0_SVID_CLK
  11 TP_P0V9_RETIMER_CPU0_PMALERT NPMALERT# @T6G_MB_LIB.T6G(SCH_1):TP_P0V9_RETIMER_CPU0_PMALERT
  13 P0V9_RETIMER_CPU0_EN0_R    EN0 @T6G_MB_LIB.T6G(SCH_1):P0V9_RETIMER_CPU0_EN0_R
  22 P0V9_RETIMER_CPU0_SENSE_SH_N  RGND0 @T6G_MB_LIB.T6G(SCH_1):P0V9_RETIMER_CPU0_SENSE_SH_N
   9 P0V9_RETIMER_CPU0_PMSDA_R  PMSDA @T6G_MB_LIB.T6G(SCH_1):P0V9_RETIMER_CPU0_PMSDA_R
   5 NC_P0V9_RETIMER_CPU0_PWM4   PWM4 @T6G_MB_LIB.T6G(SCH_1):NC_P0V9_RETIMER_CPU0_PWM4
   6 NC_P0V9_RETIMER_CPU0_PWM3   PWM5 @T6G_MB_LIB.T6G(SCH_1):NC_P0V9_RETIMER_CPU0_PWM3
  21 P0V9_RETIMER_CPU0_SENSE_R_P  VSEN0 @T6G_MB_LIB.T6G(SCH_1):P0V9_RETIMER_CPU0_SENSE_R_P
   2 NC_P0V9_RETIMER_CPU0_PWM7   PWM1 @T6G_MB_LIB.T6G(SCH_1):NC_P0V9_RETIMER_CPU0_PWM7
  12 PWRGD_P0V9_RETIMER_CPU0_R    PG0 @T6G_MB_LIB.T6G(SCH_1):PWRGD_P0V9_RETIMER_CPU0_R
   7 P0V9_RETIMER_CPU0_PWM2   PWM6 @T6G_MB_LIB.T6G(SCH_1):P0V9_RETIMER_CPU0_PWM2
  40 PV09_RETIMER_CPU0_VCCS   VCCS @T6G_MB_LIB.T6G(SCH_1):PV09_RETIMER_CPU0_VCCS
  37 P0V9_RETIMER_CPU0_VMON VMON||IINSEN||VSYS||ISYS @T6G_MB_LIB.T6G(SCH_1):P0V9_RETIMER_CPU0_VMON
  38 P0V9_RETIMER_CPU0_VINSEN VINSEN||VSYS @T6G_MB_LIB.T6G(SCH_1):P0V9_RETIMER_CPU0_VINSEN
  36 P0V9_RETIMER_CPU0_TEMP1_R TEMP1||ISYS @T6G_MB_LIB.T6G(SCH_1):P0V9_RETIMER_CPU0_TEMP1_R
  15 P0V9_RETIMER_CPU0_INALERT NPINALERT#||NPSYSCRIT# @T6G_MB_LIB.T6G(SCH_1):P0V9_RETIMER_CPU0_INALERT
  32    GND  VSEN1 @T6G_MB_LIB.T6G(SCH_1):GND
  31    GND  RGND1 @T6G_MB_LIB.T6G(SCH_1):GND
  29 NC_P0V9_RETIMER_CPU0_IMON7    CS1 @T6G_MB_LIB.T6G(SCH_1):NC_P0V9_RETIMER_CPU0_IMON7
   8 P0V9_RETIMER_CPU0_PWM1   PWM7 @T6G_MB_LIB.T6G(SCH_1):P0V9_RETIMER_CPU0_PWM1
   4 NC_P0V9_RETIMER_CPU0_PWM5   PWM3 @T6G_MB_LIB.T6G(SCH_1):NC_P0V9_RETIMER_CPU0_PWM5
  27 NC_P0V9_RETIMER_CPU0_IMON5    CS3 @T6G_MB_LIB.T6G(SCH_1):NC_P0V9_RETIMER_CPU0_IMON5
   3 NC_P0V9_RETIMER_CPU0_PWM6   PWM2 @T6G_MB_LIB.T6G(SCH_1):NC_P0V9_RETIMER_CPU0_PWM6
  28 NC_P0V9_RETIMER_CPU0_IMON6    CS2 @T6G_MB_LIB.T6G(SCH_1):NC_P0V9_RETIMER_CPU0_IMON6
  33 P0V9_RETIMER_CPU0_CFP    CFP @T6G_MB_LIB.T6G(SCH_1):P0V9_RETIMER_CPU0_CFP
  TH    GND TH_GND @T6G_MB_LIB.T6G(SCH_1):GND
  34 P0V9_RETIMER_CPU0_ADDR ADDR_CFG @T6G_MB_LIB.T6G(SCH_1):P0V9_RETIMER_CPU0_ADDR
  35 P0V9_RETIMER_CPU0_TEMP0  TEMP0 @T6G_MB_LIB.T6G(SCH_1):P0V9_RETIMER_CPU0_TEMP0
   1 NC_P0V9_RETIMER_CPU0_PWM8   PWM0 @T6G_MB_LIB.T6G(SCH_1):NC_P0V9_RETIMER_CPU0_PWM8
  30 NC_P0V9_RETIMER_CPU0_IMON8    CS0 @T6G_MB_LIB.T6G(SCH_1):NC_P0V9_RETIMER_CPU0_IMON8

Q_RES_0402LF-0,5%,1/16W,CHIP,CS00002JB13  I94  R646
   1 P0V9_RETIMER_CPU0_PMSCL      A @T6G_MB_LIB.T6G(SCH_1):P0V9_RETIMER_CPU0_PMSCL
   2 P0V9_RETIMER_CPU0_PMSCL_R      B @T6G_MB_LIB.T6G(SCH_1):P0V9_RETIMER_CPU0_PMSCL_R

Q_RES_0402LF-0,5%,1/16W,CHIP,CS00002JB13  I95  R647
   1 P0V9_RETIMER_CPU0_PMSDA      A @T6G_MB_LIB.T6G(SCH_1):P0V9_RETIMER_CPU0_PMSDA
   2 P0V9_RETIMER_CPU0_PMSDA_R      B @T6G_MB_LIB.T6G(SCH_1):P0V9_RETIMER_CPU0_PMSDA_R

Q_RES_0402LF-0,5%,1/16W,CHIP,CS00002JB13  I105  PR6531
   1 P0V9_RETIMER_CPU0_SENSE_SH_P      A @T6G_MB_LIB.T6G(SCH_1):P0V9_RETIMER_CPU0_SENSE_SH_P
   2 P0V9_RETIMER_CPU0_SENSE_R_P      B @T6G_MB_LIB.T6G(SCH_1):P0V9_RETIMER_CPU0_SENSE_R_P

Q_CAP_0402-1000PF,50V,5%,EMPTY,TMP_QCH21006JB10  I118  C101
   1 PWRGD_P0V9_RETIMER_CPU0_R      A @T6G_MB_LIB.T6G(SCH_1):PWRGD_P0V9_RETIMER_CPU0_R
   2    GND      B @T6G_MB_LIB.T6G(SCH_1):GND

Q_RES_0402LF-0,5%,1/16W,CHIP,CS00002JB13  I119  R650
   1 PWRGD_P0V9_RETIMER_CPU0      A @T6G_MB_LIB.T6G(SCH_1):PWRGD_P0V9_RETIMER_CPU0
   2 PWRGD_P0V9_RETIMER_CPU0_R      B @T6G_MB_LIB.T6G(SCH_1):PWRGD_P0V9_RETIMER_CPU0_R

Q_RES_0402LF-0,5%,1/16W,CHIP,CS00002JB13  I120  R651
   1 P0V9_RETIMER_CPU0_EN      A @T6G_MB_LIB.T6G(SCH_1):P0V9_RETIMER_CPU0_EN
   2 P0V9_RETIMER_CPU0_EN0_R      B @T6G_MB_LIB.T6G(SCH_1):P0V9_RETIMER_CPU0_EN0_R

Q_CAP_0402-3300PF,50V,10%,X7R,TMP_QCH2336K1B12  I121  PC6540
   1 P0V9_RETIMER_CPU0_SENSE_R_P      A @T6G_MB_LIB.T6G(SCH_1):P0V9_RETIMER_CPU0_SENSE_R_P
   2 P0V9_RETIMER_CPU0_SENSE_SH_N      B @T6G_MB_LIB.T6G(SCH_1):P0V9_RETIMER_CPU0_SENSE_SH_N

Q_CAP_0402-0.1UF,25V,10%,X7R,CH4104K1B00  I123  PC6602
   1 P0V9_RETIMER_CPU0_VINSEN      A @T6G_MB_LIB.T6G(SCH_1):P0V9_RETIMER_CPU0_VINSEN
   2    GND      B @T6G_MB_LIB.T6G(SCH_1):GND

Q_RES_0402LF-1K,1%,1/16W,EMPTY,CS21002FB06  I125  PR6607
   1 P0V9_RETIMER_CPU0_VINSEN      A @T6G_MB_LIB.T6G(SCH_1):P0V9_RETIMER_CPU0_VINSEN
   2    GND      B @T6G_MB_LIB.T6G(SCH_1):GND

Q_RES_0402LF-1K,1%,1/16W,CHIP,CS21002FB06  I127  R655
   1 P3V3_AUX      A @T6G_MB_LIB.T6G(SCH_1):P3V3_AUX
   2 P0V9_RETIMER_CPU0_INALERT      B @T6G_MB_LIB.T6G(SCH_1):P0V9_RETIMER_CPU0_INALERT

Q_RES_0402LF-1K,1%,1/16W,CHIP,CS21002FB06  I128  R652
   1 P3V3_AUX      A @T6G_MB_LIB.T6G(SCH_1):P3V3_AUX
   2 P0V9_RETIMER_CPU0_CFP      B @T6G_MB_LIB.T6G(SCH_1):P0V9_RETIMER_CPU0_CFP

Q_RES_0402LF-1,1%,1/16W,CHIP,CS-1002FB04  I131  PR6608
   1 P0V9_RETIMER_CPU0_VCC      A @T6G_MB_LIB.T6G(SCH_1):P0V9_RETIMER_CPU0_VCC
   2 P3V3_AUX      B @T6G_MB_LIB.T6G(SCH_1):P3V3_AUX

Q_CAP_C0402-1UF,16V,10%,X6S,CH5103KEB01  I132  PC6604
   1 P0V9_RETIMER_CPU0_VCC      A @T6G_MB_LIB.T6G(SCH_1):P0V9_RETIMER_CPU0_VCC
   2    GND      B @T6G_MB_LIB.T6G(SCH_1):GND

Q_RES_0402LF-1K,1%,1/16W,CHIP,CS21002FB06  I135  PR6615
   1 P3V3_AUX      A @T6G_MB_LIB.T6G(SCH_1):P3V3_AUX
   2 TP_P0V9_RETIMER_CPU0_VRHOT      B @T6G_MB_LIB.T6G(SCH_1):TP_P0V9_RETIMER_CPU0_VRHOT

Q_RES_0402LF-0,5%,1/16W,CHIP,CS00002JB13  I136  PR6616
   1 P0V9_RETIMER_CPU0_VRHOT      A @T6G_MB_LIB.T6G(SCH_1):P0V9_RETIMER_CPU0_VRHOT
   2 TP_P0V9_RETIMER_CPU0_VRHOT      B @T6G_MB_LIB.T6G(SCH_1):TP_P0V9_RETIMER_CPU0_VRHOT

Q_RES_0402LF-10K,1%,1/16W,EMPTY,CS31002FB08  I138  PR6814
   1 P0V9_RETIMER_CPU0_TEMP0      A @T6G_MB_LIB.T6G(SCH_1):P0V9_RETIMER_CPU0_TEMP0
   2    GND      B @T6G_MB_LIB.T6G(SCH_1):GND

Q_CAP_C0402-100NF,50V,10%,X7R,CH4106K1B01  I144  PC6603
   1 P0V9_RETIMER_CPU0_VCC      A @T6G_MB_LIB.T6G(SCH_1):P0V9_RETIMER_CPU0_VCC
   2    GND      B @T6G_MB_LIB.T6G(SCH_1):GND

Q_CAP_C0402-10UF,6.3V,20%,X6S,CH6101MEB03  I145  PC6606
   1 PV09_RETIMER_CPU0_VCCS      A @T6G_MB_LIB.T6G(SCH_1):PV09_RETIMER_CPU0_VCCS
   2    GND      B @T6G_MB_LIB.T6G(SCH_1):GND

Q_CAP_C0402-1UF,16V,10%,X6S,CH5103KEB01  I146  PC6605
   1 PV09_RETIMER_CPU0_VCCS      A @T6G_MB_LIB.T6G(SCH_1):PV09_RETIMER_CPU0_VCCS
   2    GND      B @T6G_MB_LIB.T6G(SCH_1):GND

Q_CAP_0402-470PF,50V,10%,X7R,TMP_QCH14706KB18  I148  PC6607
   1 P0V9_RETIMER_CPU0_TEMP0      A @T6G_MB_LIB.T6G(SCH_1):P0V9_RETIMER_CPU0_TEMP0
   2    GND      B @T6G_MB_LIB.T6G(SCH_1):GND

Q_RES_0402LF-0,5%,1/16W,CHIP,CS00002JB13  I150  PR6605
   1 P0V9_RETIMER_CPU0_VMON      A @T6G_MB_LIB.T6G(SCH_1):P0V9_RETIMER_CPU0_VMON
   2    GND      B @T6G_MB_LIB.T6G(SCH_1):GND

Q_CAP_0402-0.1UF,25V,10%,EMPTY,CH4104K1B00  I151  PC6601
   1 P0V9_RETIMER_CPU0_VMON      A @T6G_MB_LIB.T6G(SCH_1):P0V9_RETIMER_CPU0_VMON
   2    GND      B @T6G_MB_LIB.T6G(SCH_1):GND

Q_RES_0402LF-0,5%,1/16W,EMPTY,CS00002JB13  I158  PR6807
   1 P12V_AUX      A @T6G_MB_LIB.T6G(SCH_1):P12V_AUX
   2 P0V9_RETIMER_CPU0_VMON      B @T6G_MB_LIB.T6G(SCH_1):P0V9_RETIMER_CPU0_VMON

Q_RES_0402LF-0,5%,1/16W,CHIP,CS00002JB13  I160  PR6606
   1 P12V_AUX      A @T6G_MB_LIB.T6G(SCH_1):P12V_AUX
   2 P0V9_RETIMER_CPU0_VINSEN      B @T6G_MB_LIB.T6G(SCH_1):P0V9_RETIMER_CPU0_VINSEN

Q_RES_0402LF-0,5%,1/16W,CHIP,CS00002JB13  I161  R6801
   1    GND      A @T6G_MB_LIB.T6G(SCH_1):GND
   2 P0V9_RETIMER_CPU0_EN1_R      B @T6G_MB_LIB.T6G(SCH_1):P0V9_RETIMER_CPU0_EN1_R

Q_RES_0402LF-0,5%,1/16W,CHIP,CS00002JB13  I165  PR6810
   1 P0V9_RETIMER_CPU0_SVID_CLK      A @T6G_MB_LIB.T6G(SCH_1):P0V9_RETIMER_CPU0_SVID_CLK
   2    GND      B @T6G_MB_LIB.T6G(SCH_1):GND

Q_RES_0402LF-1K,1%,1/16W,EMPTY,CS21002FB06  I166  PR6805
   1 P3V3_AUX      A @T6G_MB_LIB.T6G(SCH_1):P3V3_AUX
   2 P0V9_RETIMER_CPU0_SVID_CLK      B @T6G_MB_LIB.T6G(SCH_1):P0V9_RETIMER_CPU0_SVID_CLK

Q_RES_0402LF-1K,1%,1/16W,EMPTY,CS21002FB06  I167  PR6803
   1 P3V3_AUX      A @T6G_MB_LIB.T6G(SCH_1):P3V3_AUX
   2 P0V9_RETIMER_CPU0_SVID_SDA      B @T6G_MB_LIB.T6G(SCH_1):P0V9_RETIMER_CPU0_SVID_SDA

Q_RES_0402LF-0,5%,1/16W,CHIP,CS00002JB13  I168  PR6819
   1 P0V9_RETIMER_CPU0_SVID_SDA      A @T6G_MB_LIB.T6G(SCH_1):P0V9_RETIMER_CPU0_SVID_SDA
   2    GND      B @T6G_MB_LIB.T6G(SCH_1):GND

Q_RES_0402LF-1K,1%,1/16W,EMPTY,CS21002FB06  I169  PR6817
   1 P3V3_AUX      A @T6G_MB_LIB.T6G(SCH_1):P3V3_AUX
   2 TP_P0V9_RETIMER_CPU0_SVID_ALERT_N      B @T6G_MB_LIB.T6G(SCH_1):TP_P0V9_RETIMER_CPU0_SVID_ALERT_N

Q_RES_0402LF-5.36K,1%,1/16W,EMPTY,CS25362FB02  I178  PR6604
   1 P5V_AUX      A @T6G_MB_LIB.T6G(SCH_1):P5V_AUX
   2 P0V9_RETIMER_CPU0_VMON      B @T6G_MB_LIB.T6G(SCH_1):P0V9_RETIMER_CPU0_VMON

Q_RES_0402LF-0,5%,1/16W,CHIP,CS00002JB13  I183  PR6603
   1    GND      A @T6G_MB_LIB.T6G(SCH_1):GND
   2 P0V9_RETIMER_CPU0_ADDR      B @T6G_MB_LIB.T6G(SCH_1):P0V9_RETIMER_CPU0_ADDR

Q_RES_0402LF-0,5%,1/16W,CHIP,CS00002JB13  I188  PR6609
   1 NC_P0V9_RETIMER_CPU0_IMON3      A @T6G_MB_LIB.T6G(SCH_1):NC_P0V9_RETIMER_CPU0_IMON3
   2    GND      B @T6G_MB_LIB.T6G(SCH_1):GND

Q_RES_0402LF-0,5%,1/16W,CHIP,CS00002JB13  I190  PR6610
   1 NC_P0V9_RETIMER_CPU0_IMON4      A @T6G_MB_LIB.T6G(SCH_1):NC_P0V9_RETIMER_CPU0_IMON4
   2    GND      B @T6G_MB_LIB.T6G(SCH_1):GND

Q_RES_0402LF-0,5%,1/16W,CHIP,CS00002JB13  I191  PR6611
   1 NC_P0V9_RETIMER_CPU0_IMON5      A @T6G_MB_LIB.T6G(SCH_1):NC_P0V9_RETIMER_CPU0_IMON5
   2    GND      B @T6G_MB_LIB.T6G(SCH_1):GND

Q_RES_0402LF-0,5%,1/16W,CHIP,CS00002JB13  I192  PR6612
   1 NC_P0V9_RETIMER_CPU0_IMON6      A @T6G_MB_LIB.T6G(SCH_1):NC_P0V9_RETIMER_CPU0_IMON6
   2    GND      B @T6G_MB_LIB.T6G(SCH_1):GND

Q_RES_0402LF-0,5%,1/16W,CHIP,CS00002JB13  I193  PR6613
   1 NC_P0V9_RETIMER_CPU0_IMON7      A @T6G_MB_LIB.T6G(SCH_1):NC_P0V9_RETIMER_CPU0_IMON7
   2    GND      B @T6G_MB_LIB.T6G(SCH_1):GND

Q_RES_0402LF-0,5%,1/16W,CHIP,CS00002JB13  I198  PR6614
   1 NC_P0V9_RETIMER_CPU0_IMON8      A @T6G_MB_LIB.T6G(SCH_1):NC_P0V9_RETIMER_CPU0_IMON8
   2    GND      B @T6G_MB_LIB.T6G(SCH_1):GND

Q_RES_0402LF-0,5%,1/16W,CHIP,CS00002JB13  I204  PR6618
   1 P0V9_RETIMER_CPU0_TEMP1_R      A @T6G_MB_LIB.T6G(SCH_1):P0V9_RETIMER_CPU0_TEMP1_R
   2    GND      B @T6G_MB_LIB.T6G(SCH_1):GND

Q_RES_0402LF-4.7K,1%,1/16W,EMPTY,CS24702FB06  I207  R649
   1 P3V3_AUX      A @T6G_MB_LIB.T6G(SCH_1):P3V3_AUX
   2 TP_P0V9_RETIMER_CPU0_PMALERT      B @T6G_MB_LIB.T6G(SCH_1):TP_P0V9_RETIMER_CPU0_PMALERT

Q_RES_0402LF-1K,1%,1/16W,CHIP,CS21002FB06  I208  R6786
   1 P0V9_RETIMER_CPU0_EN0_R      A @T6G_MB_LIB.T6G(SCH_1):P0V9_RETIMER_CPU0_EN0_R
   2    GND      B @T6G_MB_LIB.T6G(SCH_1):GND

Q_RES_0402LF-0,5%,1/16W,EMPTY,CS00002JB13  I210  PR883
   1 TP_P0V9_RETIMER_CPU0_SVID_ALERT_N      A @T6G_MB_LIB.T6G(SCH_1):TP_P0V9_RETIMER_CPU0_SVID_ALERT_N
   2    GND      B @T6G_MB_LIB.T6G(SCH_1):GND

Q_RES_0402LF-1K,1%,1/16W,EMPTY,CS21002FB06  I212  R643
   1 P3V3_AUX      A @T6G_MB_LIB.T6G(SCH_1):P3V3_AUX
   2 PWRGD_P0V9_RETIMER_CPU0_R      B @T6G_MB_LIB.T6G(SCH_1):PWRGD_P0V9_RETIMER_CPU0_R

Q_RES_0402LF-1K,1%,1/16W,CHIP,CS21002FB06  I213  R6860
   1 P1V8_AUX      A @T6G_MB_LIB.T6G(SCH_1):P1V8_AUX
   2 PWRGD_P0V9_RETIMER_CPU0_R      B @T6G_MB_LIB.T6G(SCH_1):PWRGD_P0V9_RETIMER_CPU0_R

Q_SHORT_SM-EMPTY,SHORT16  I214  PJ09_P0_P
   1 P0V9_CPU0_RT_2D      1 @T6G_MB_LIB.T6G(SCH_1):P0V9_CPU0_RT_2D
   2 P0V9_RETIMER_CPU0_SENSE_SH_P      2 @T6G_MB_LIB.T6G(SCH_1):P0V9_RETIMER_CPU0_SENSE_SH_P

Q_SHORT_SM-EMPTY,SHORT16  I215  PJ09_P0_N
   1    GND      1 @T6G_MB_LIB.T6G(SCH_1):GND
   2 P0V9_RETIMER_CPU0_SENSE_SH_N      2 @T6G_MB_LIB.T6G(SCH_1):P0V9_RETIMER_CPU0_SENSE_SH_N


DRAWING: @T6G_MB_LIB.T6G(SCH_1):PAGE476 

Q_CAP_0402-3300PF,50V,10%,X7R,TMP_QCH2336K1B12  I6  PC6555_1
   1 SW_P12V_AUX_P0V9_RETIMER_CPU0_FLT      A @T6G_MB_LIB.T6G(SCH_1):SW_P12V_AUX_P0V9_RETIMER_CPU0_FLT
   2    GND      B @T6G_MB_LIB.T6G(SCH_1):GND

Q_CAP_C0805-22UF,16V,20%,X6S,CH6223MEA01  I21  PC6558_1
   1 SW_P12V_AUX_P0V9_RETIMER_CPU0_FLT      A @T6G_MB_LIB.T6G(SCH_1):SW_P12V_AUX_P0V9_RETIMER_CPU0_FLT
   2    GND      B @T6G_MB_LIB.T6G(SCH_1):GND

Q_CAP_C0805-22UF,16V,20%,X6S,CH6223MEA01  I24  PC6557_1
   1 SW_P12V_AUX_P0V9_RETIMER_CPU0_FLT      A @T6G_MB_LIB.T6G(SCH_1):SW_P12V_AUX_P0V9_RETIMER_CPU0_FLT
   2    GND      B @T6G_MB_LIB.T6G(SCH_1):GND

Q_CAP_C0805-22UF,16V,20%,X6S,CH6223MEA01  I27  PC6556_1
   1 SW_P12V_AUX_P0V9_RETIMER_CPU0_FLT      A @T6G_MB_LIB.T6G(SCH_1):SW_P12V_AUX_P0V9_RETIMER_CPU0_FLT
   2    GND      B @T6G_MB_LIB.T6G(SCH_1):GND

Q_CAP_C0402-1UF,25V,10%,X6S,CH5104KEB02  I29  PC6554_1
   1 SW_P12V_AUX_P0V9_RETIMER_CPU0_FLT      A @T6G_MB_LIB.T6G(SCH_1):SW_P12V_AUX_P0V9_RETIMER_CPU0_FLT
   2    GND      B @T6G_MB_LIB.T6G(SCH_1):GND

Q_CAP_C0402-100NF,50V,10%,X7R,CH4106K1B01  I30  PC6563
   1 SW_P0V9_RETIMER_CPU0_BOOT1_RC      A @T6G_MB_LIB.T6G(SCH_1):SW_P0V9_RETIMER_CPU0_BOOT1_RC
   2 SW_P0V9_RETIMER_CPU0_PH1      B @T6G_MB_LIB.T6G(SCH_1):SW_P0V9_RETIMER_CPU0_PH1

Q_CAP_C0402-100NF,50V,10%,X7R,CH4106K1B01  I33  PC6565
   1 P0V9_CPU0_RT_2D      A @T6G_MB_LIB.T6G(SCH_1):P0V9_CPU0_RT_2D
   2    GND      B @T6G_MB_LIB.T6G(SCH_1):GND

Q_INDUCTOR_SMLF-120NH/69A,IND,CV+12^0EZ03  I34  PL6505
   2 P0V9_CPU0_RT_2D      2 @T6G_MB_LIB.T6G(SCH_1):P0V9_CPU0_RT_2D
   1 SW_P0V9_RETIMER_CPU0_SW1      1 @T6G_MB_LIB.T6G(SCH_1):SW_P0V9_RETIMER_CPU0_SW1

Q_RES_0402LF-0,5%,1/16W,CHIP,CS00002JB13  I42  PR6556
   1 P0V9_RETIMER_CPU0_VOS1      A @T6G_MB_LIB.T6G(SCH_1):P0V9_RETIMER_CPU0_VOS1
   2 P0V9_CPU0_RT_2D      B @T6G_MB_LIB.T6G(SCH_1):P0V9_CPU0_RT_2D

Q_CAP_C0402-2.2UF,10V,10%,X6S,CH5222KEB01  I47  PC6550_09P0_1
   1 P0V9_RETIMER_CPU0_PVCC      A @T6G_MB_LIB.T6G(SCH_1):P0V9_RETIMER_CPU0_PVCC
   2    GND      B @T6G_MB_LIB.T6G(SCH_1):GND

Q_CAP_C0402-2.2UF,10V,10%,X6S,CH5222KEB01  I48  PC6552
   1 P0V9_RETIMER_CPU0_VCC1      A @T6G_MB_LIB.T6G(SCH_1):P0V9_RETIMER_CPU0_VCC1
   2    GND      B @T6G_MB_LIB.T6G(SCH_1):GND

ISL99390FRZTR5935-ISL99390FRZ-TR5935,SMLF,IC,AL099A  I53  PU6503
  34 P0V9_RETIMER_CPU0_PWM1    PWM @T6G_MB_LIB.T6G(SCH_1):P0V9_RETIMER_CPU0_PWM1
  39 PV09_RETIMER_CPU0_VCCS  REFIN @T6G_MB_LIB.T6G(SCH_1):PV09_RETIMER_CPU0_VCCS
   3 P0V9_RETIMER_CPU0_VCC1    VCC @T6G_MB_LIB.T6G(SCH_1):P0V9_RETIMER_CPU0_VCC1
   2    GND   AGND @T6G_MB_LIB.T6G(SCH_1):GND
  33 SW_P0V9_RETIMER_CPU0_BOOT1   BOOT @T6G_MB_LIB.T6G(SCH_1):SW_P0V9_RETIMER_CPU0_BOOT1
25_29 SW_P12V_AUX_P0V9_RETIMER_CPU0_FLT   VIN1 @T6G_MB_LIB.T6G(SCH_1):SW_P12V_AUX_P0V9_RETIMER_CPU0_FLT
  32 SW_P0V9_RETIMER_CPU0_PH1  PHASE @T6G_MB_LIB.T6G(SCH_1):SW_P0V9_RETIMER_CPU0_PH1
   4 P0V9_RETIMER_CPU0_PVCC   PVCC @T6G_MB_LIB.T6G(SCH_1):P0V9_RETIMER_CPU0_PVCC
  36 P0V9_RETIMER_CPU0_TEMP0 TOUT_FLT @T6G_MB_LIB.T6G(SCH_1):P0V9_RETIMER_CPU0_TEMP0
  38 P0V9_RETIMER_CPU0_IMON1   IOUT @T6G_MB_LIB.T6G(SCH_1):P0V9_RETIMER_CPU0_IMON1
  37 P0V9_RETIMER_CPU0_LSET1   LSET @T6G_MB_LIB.T6G(SCH_1):P0V9_RETIMER_CPU0_LSET1
10_19 SW_P0V9_RETIMER_CPU0_SW1     SW @T6G_MB_LIB.T6G(SCH_1):SW_P0V9_RETIMER_CPU0_SW1
   5    GND  PGND1 @T6G_MB_LIB.T6G(SCH_1):GND
  30 SW_P12V_AUX_P0V9_RETIMER_CPU0_FLT   VIN2 @T6G_MB_LIB.T6G(SCH_1):SW_P12V_AUX_P0V9_RETIMER_CPU0_FLT
   1 P0V9_RETIMER_CPU0_VOS1    VOS @T6G_MB_LIB.T6G(SCH_1):P0V9_RETIMER_CPU0_VOS1
  40    GND  PGND3 @T6G_MB_LIB.T6G(SCH_1):GND
  35 P0V9_RETIMER_CPU0_VCC1     EN @T6G_MB_LIB.T6G(SCH_1):P0V9_RETIMER_CPU0_VCC1
  31 NC_PV09_RETIMER_CPU0_DNC1    DNC @T6G_MB_LIB.T6G(SCH_1):NC_PV09_RETIMER_CPU0_DNC1
   6 NC_PV09_RETIMER_CPU0_GL1_1    GL1 @T6G_MB_LIB.T6G(SCH_1):NC_PV09_RETIMER_CPU0_GL1_1
  41 NC_PV09_RETIMER_CPU0_GL2_1    GL2 @T6G_MB_LIB.T6G(SCH_1):NC_PV09_RETIMER_CPU0_GL2_1
7_9-20_24    GND  PGND2 @T6G_MB_LIB.T6G(SCH_1):GND

Q_RES_0402LF-2.2,5%,1/16W,CHIP,TMP_QCS-2202JB25  I58  PR6552
   1 P0V9_RETIMER_CPU0_PVCC      A @T6G_MB_LIB.T6G(SCH_1):P0V9_RETIMER_CPU0_PVCC
   2 P0V9_RETIMER_CPU0_VCC1      B @T6G_MB_LIB.T6G(SCH_1):P0V9_RETIMER_CPU0_VCC1

Q_CAP_C0402-100NF,50V,10%,X7R,CH4106K1B01  I68  PC6553_1
   1 PV09_RETIMER_CPU0_VCCS      A @T6G_MB_LIB.T6G(SCH_1):PV09_RETIMER_CPU0_VCCS
   2    GND      B @T6G_MB_LIB.T6G(SCH_1):GND

Q_INDUCTOR_SMLF-100NH/16A,IND,CV+10G0MZ04  I182  PL6504
   2 P12V_AUX      2 @T6G_MB_LIB.T6G(SCH_1):P12V_AUX
   1 SW_P12V_AUX_P0V9_RETIMER_CPU0_FLT      1 @T6G_MB_LIB.T6G(SCH_1):SW_P12V_AUX_P0V9_RETIMER_CPU0_FLT

Q_RES_0402LF-0,5%,1/16W,CHIP,CS00002JB13  I183  PR6550
   1 P5V_AUX      A @T6G_MB_LIB.T6G(SCH_1):P5V_AUX
   2 P0V9_RETIMER_CPU0_PVCC      B @T6G_MB_LIB.T6G(SCH_1):P0V9_RETIMER_CPU0_PVCC

Q_RES_0402LF-0,5%,1/16W,EMPTY,CS00002JB13  I185  PR6551
   1 P3V3_AUX      A @T6G_MB_LIB.T6G(SCH_1):P3V3_AUX
   2 P0V9_RETIMER_CPU0_PVCC      B @T6G_MB_LIB.T6G(SCH_1):P0V9_RETIMER_CPU0_PVCC

Q_RES_0603LF-499,1%,1/10W,CHIP,CS14993F901  I187  PR6557
   1 P0V9_CPU0_RT_2D      A @T6G_MB_LIB.T6G(SCH_1):P0V9_CPU0_RT_2D
   2    GND      B @T6G_MB_LIB.T6G(SCH_1):GND

Q_CAP_C0805-22UF,4V,20%,X6S,CH622KMEA03  I202  PC6566_1
   1 P0V9_CPU0_RT_2D      A @T6G_MB_LIB.T6G(SCH_1):P0V9_CPU0_RT_2D
   2    GND      B @T6G_MB_LIB.T6G(SCH_1):GND

Q_CAPP_SMLF-100UF,16V,20%,OSCON,CC71003MZ30  I209  PC6561
   1 SW_P12V_AUX_P0V9_RETIMER_CPU0_FLT      A @T6G_MB_LIB.T6G(SCH_1):SW_P12V_AUX_P0V9_RETIMER_CPU0_FLT
   2    GND      B @T6G_MB_LIB.T6G(SCH_1):GND

Q_CAP_C0805-22UF,16V,20%,X6S,CH6223MEA01  I210  PC6559_1
   1 SW_P12V_AUX_P0V9_RETIMER_CPU0_FLT      A @T6G_MB_LIB.T6G(SCH_1):SW_P12V_AUX_P0V9_RETIMER_CPU0_FLT
   2    GND      B @T6G_MB_LIB.T6G(SCH_1):GND

Q_CAP_C0805-22UF,16V,20%,X6S,CH6223MEA01  I216  PC6816
   1 SW_P12V_AUX_P0V9_RETIMER_CPU0_FLT      A @T6G_MB_LIB.T6G(SCH_1):SW_P12V_AUX_P0V9_RETIMER_CPU0_FLT
   2    GND      B @T6G_MB_LIB.T6G(SCH_1):GND

Q_CAP_C0805-22UF,16V,20%,X6S,CH6223MEA01  I217  PC6560
   1 SW_P12V_AUX_P0V9_RETIMER_CPU0_FLT      A @T6G_MB_LIB.T6G(SCH_1):SW_P12V_AUX_P0V9_RETIMER_CPU0_FLT
   2    GND      B @T6G_MB_LIB.T6G(SCH_1):GND

Q_RES_0402LF-8.87K,1%,1/16W,EMPTY,CS28872FB01  I220  PR6553
   1 P0V9_RETIMER_CPU0_LSET1      A @T6G_MB_LIB.T6G(SCH_1):P0V9_RETIMER_CPU0_LSET1
   2    GND      B @T6G_MB_LIB.T6G(SCH_1):GND

Q_RES_0402LF-5.6,1%,1/16W,CHIP,CS-5602FB01  I221  PR6554
   1 SW_P0V9_RETIMER_CPU0_BOOT1      A @T6G_MB_LIB.T6G(SCH_1):SW_P0V9_RETIMER_CPU0_BOOT1
   2 SW_P0V9_RETIMER_CPU0_BOOT1_RC      B @T6G_MB_LIB.T6G(SCH_1):SW_P0V9_RETIMER_CPU0_BOOT1_RC

Q_CAPP_SMLF-390UF,2.5V,20%,ALUM,CC7390JMZ13  I222  PC6572
   1 P0V9_CPU0_RT_2D      A @T6G_MB_LIB.T6G(SCH_1):P0V9_CPU0_RT_2D
   2    GND      B @T6G_MB_LIB.T6G(SCH_1):GND

Q_CAP_C0805-22UF,4V,20%,X6S,CH622KMEA03  I223  PC6567_1
   1 P0V9_CPU0_RT_2D      A @T6G_MB_LIB.T6G(SCH_1):P0V9_CPU0_RT_2D
   2    GND      B @T6G_MB_LIB.T6G(SCH_1):GND

Q_CAPP_SMLF-470UF,2.5V,20%,SPCAP,CH747LM8818  I224  PC6568
   1 P0V9_CPU0_RT_2D      A @T6G_MB_LIB.T6G(SCH_1):P0V9_CPU0_RT_2D
   2    GND      B @T6G_MB_LIB.T6G(SCH_1):GND

Q_CAPP_SMLF-470UF,2.5V,20%,SPCAP,CH747LM8818  I225  PC6569
   1 P0V9_CPU0_RT_2D      A @T6G_MB_LIB.T6G(SCH_1):P0V9_CPU0_RT_2D
   2    GND      B @T6G_MB_LIB.T6G(SCH_1):GND

Q_CAPP_SMLF-470UF,2.5V,20%,SPCAP,CH747LM8818  I226  PC6570
   1 P0V9_CPU0_RT_2D      A @T6G_MB_LIB.T6G(SCH_1):P0V9_CPU0_RT_2D
   2    GND      B @T6G_MB_LIB.T6G(SCH_1):GND

Q_CAPP_SMLF-390UF,2.5V,20%,ALUM,CC7390JMZ13  I227  PC6571
   1 P0V9_CPU0_RT_2D      A @T6G_MB_LIB.T6G(SCH_1):P0V9_CPU0_RT_2D
   2    GND      B @T6G_MB_LIB.T6G(SCH_1):GND

Q_CAPP_SMLF-100UF,16V,20%,OSCON,CC71003MZ30  I231  PC6810
   1 SW_P12V_AUX_P0V9_RETIMER_CPU0_FLT      A @T6G_MB_LIB.T6G(SCH_1):SW_P12V_AUX_P0V9_RETIMER_CPU0_FLT
   2    GND      B @T6G_MB_LIB.T6G(SCH_1):GND

Q_CAP_C0805-22UF,16V,20%,X6S,CH6223MEA01  I232  PC6817
   1 SW_P12V_AUX_P0V9_RETIMER_CPU0_FLT      A @T6G_MB_LIB.T6G(SCH_1):SW_P12V_AUX_P0V9_RETIMER_CPU0_FLT
   2    GND      B @T6G_MB_LIB.T6G(SCH_1):GND

Q_CAPP_SMLF-390UF,2.5V,20%,ALUM,CC7390JMZ13  I236  PC6574
   1 P0V9_CPU0_RT_2D      A @T6G_MB_LIB.T6G(SCH_1):P0V9_CPU0_RT_2D
   2    GND      B @T6G_MB_LIB.T6G(SCH_1):GND

Q_CAPP_SMLF-390UF,2.5V,20%,ALUM,CC7390JMZ13  I238  PC6573
   1 P0V9_CPU0_RT_2D      A @T6G_MB_LIB.T6G(SCH_1):P0V9_CPU0_RT_2D
   2    GND      B @T6G_MB_LIB.T6G(SCH_1):GND

Q_CAPP_SMLF-470UF,2.5V,20%,SPCAP,CH747LM8818  I239  PC534
   1 P0V9_CPU0_RT_2D      A @T6G_MB_LIB.T6G(SCH_1):P0V9_CPU0_RT_2D
   2    GND      B @T6G_MB_LIB.T6G(SCH_1):GND

Q_CAP_C0805-22UF,16V,20%,X6S,CH6223MEA01  I241  PC6583
   1 SW_P12V_AUX_P0V9_RETIMER_CPU0_FLT      A @T6G_MB_LIB.T6G(SCH_1):SW_P12V_AUX_P0V9_RETIMER_CPU0_FLT
   2    GND      B @T6G_MB_LIB.T6G(SCH_1):GND

Q_CAP_C0805-22UF,16V,20%,X6S,CH6223MEA01  I242  PC6582_2
   1 SW_P12V_AUX_P0V9_RETIMER_CPU0_FLT      A @T6G_MB_LIB.T6G(SCH_1):SW_P12V_AUX_P0V9_RETIMER_CPU0_FLT
   2    GND      B @T6G_MB_LIB.T6G(SCH_1):GND

Q_CAP_C0805-22UF,16V,20%,X6S,CH6223MEA01  I243  PC6581_2
   1 SW_P12V_AUX_P0V9_RETIMER_CPU0_FLT      A @T6G_MB_LIB.T6G(SCH_1):SW_P12V_AUX_P0V9_RETIMER_CPU0_FLT
   2    GND      B @T6G_MB_LIB.T6G(SCH_1):GND

Q_CAP_C0805-22UF,16V,20%,X6S,CH6223MEA01  I244  PC6580_2
   1 SW_P12V_AUX_P0V9_RETIMER_CPU0_FLT      A @T6G_MB_LIB.T6G(SCH_1):SW_P12V_AUX_P0V9_RETIMER_CPU0_FLT
   2    GND      B @T6G_MB_LIB.T6G(SCH_1):GND

Q_CAP_C0805-22UF,16V,20%,X6S,CH6223MEA01  I245  PC6579_2
   1 SW_P12V_AUX_P0V9_RETIMER_CPU0_FLT      A @T6G_MB_LIB.T6G(SCH_1):SW_P12V_AUX_P0V9_RETIMER_CPU0_FLT
   2    GND      B @T6G_MB_LIB.T6G(SCH_1):GND

Q_CAPP_SMLF-470UF,2.5V,20%,SPCAP,CH747LM8818  I247  PC6811
   1 P0V9_CPU0_RT_2D      A @T6G_MB_LIB.T6G(SCH_1):P0V9_CPU0_RT_2D
   2    GND      B @T6G_MB_LIB.T6G(SCH_1):GND

Q_CAPP_SMLF-470UF,2.5V,20%,SPCAP,CH747LM8818  I248  PC6812
   1 P0V9_CPU0_RT_2D      A @T6G_MB_LIB.T6G(SCH_1):P0V9_CPU0_RT_2D
   2    GND      B @T6G_MB_LIB.T6G(SCH_1):GND

Q_CAP_C0805-22UF,4V,20%,X6S,CH622KMEA03  I250  PC6587_2
   1 P0V9_CPU0_RT_2D      A @T6G_MB_LIB.T6G(SCH_1):P0V9_CPU0_RT_2D
   2    GND      B @T6G_MB_LIB.T6G(SCH_1):GND

Q_CAP_C0805-22UF,4V,20%,X6S,CH622KMEA03  I251  PC6586_2
   1 P0V9_CPU0_RT_2D      A @T6G_MB_LIB.T6G(SCH_1):P0V9_CPU0_RT_2D
   2    GND      B @T6G_MB_LIB.T6G(SCH_1):GND

Q_CAP_C0402-100NF,50V,10%,X7R,CH4106K1B01  I253  PC6584
   1 SW_P0V9_RETIMER_CPU0_BOOT2_RC      A @T6G_MB_LIB.T6G(SCH_1):SW_P0V9_RETIMER_CPU0_BOOT2_RC
   2 SW_P0V9_RETIMER_CPU0_PH2      B @T6G_MB_LIB.T6G(SCH_1):SW_P0V9_RETIMER_CPU0_PH2

Q_CAP_C0402-100NF,50V,10%,X7R,CH4106K1B01  I255  PC6806
   1 P0V9_CPU0_RT_2D      A @T6G_MB_LIB.T6G(SCH_1):P0V9_CPU0_RT_2D
   2    GND      B @T6G_MB_LIB.T6G(SCH_1):GND

Q_INDUCTOR_SMLF-120NH/69A,IND,CV+12^0EZ03  I257  PL6506
   2 P0V9_CPU0_RT_2D      2 @T6G_MB_LIB.T6G(SCH_1):P0V9_CPU0_RT_2D
   1 SW_P0V9_RETIMER_CPU0_SW2      1 @T6G_MB_LIB.T6G(SCH_1):SW_P0V9_RETIMER_CPU0_SW2

Q_CAP_C0402-1UF,25V,10%,X6S,CH5104KEB02  I258  PC6577_2
   1 SW_P12V_AUX_P0V9_RETIMER_CPU0_FLT      A @T6G_MB_LIB.T6G(SCH_1):SW_P12V_AUX_P0V9_RETIMER_CPU0_FLT
   2    GND      B @T6G_MB_LIB.T6G(SCH_1):GND

Q_CAP_0402-3300PF,50V,10%,X7R,TMP_QCH2336K1B12  I259  PC6578_2
   1 SW_P12V_AUX_P0V9_RETIMER_CPU0_FLT      A @T6G_MB_LIB.T6G(SCH_1):SW_P12V_AUX_P0V9_RETIMER_CPU0_FLT
   2    GND      B @T6G_MB_LIB.T6G(SCH_1):GND

Q_RES_0402LF-5.6,1%,1/16W,CHIP,CS-5602FB01  I262  PR6562
   1 SW_P0V9_RETIMER_CPU0_BOOT2      A @T6G_MB_LIB.T6G(SCH_1):SW_P0V9_RETIMER_CPU0_BOOT2
   2 SW_P0V9_RETIMER_CPU0_BOOT2_RC      B @T6G_MB_LIB.T6G(SCH_1):SW_P0V9_RETIMER_CPU0_BOOT2_RC

Q_RES_0402LF-0,5%,1/16W,CHIP,CS00002JB13  I263  PR6564
   1 P0V9_RETIMER_CPU0_VOS2      A @T6G_MB_LIB.T6G(SCH_1):P0V9_RETIMER_CPU0_VOS2
   2 P0V9_CPU0_RT_2D      B @T6G_MB_LIB.T6G(SCH_1):P0V9_CPU0_RT_2D

Q_CAP_C0402-2.2UF,10V,10%,X6S,CH5222KEB01  I267  PC6551_09P0_2
   1 P0V9_RETIMER_CPU0_PVCC      A @T6G_MB_LIB.T6G(SCH_1):P0V9_RETIMER_CPU0_PVCC
   2    GND      B @T6G_MB_LIB.T6G(SCH_1):GND

Q_RES_0402LF-2.2,5%,1/16W,CHIP,TMP_QCS-2202JB25  I269  PR6560
   1 P0V9_RETIMER_CPU0_PVCC      A @T6G_MB_LIB.T6G(SCH_1):P0V9_RETIMER_CPU0_PVCC
   2 P0V9_RETIMER_CPU0_VCC2      B @T6G_MB_LIB.T6G(SCH_1):P0V9_RETIMER_CPU0_VCC2

ISL99390FRZTR5935-ISL99390FRZ-TR5935,SMLF,IC,AL099A  I270  PU6504
  34 P0V9_RETIMER_CPU0_PWM2    PWM @T6G_MB_LIB.T6G(SCH_1):P0V9_RETIMER_CPU0_PWM2
  39 PV09_RETIMER_CPU0_VCCS  REFIN @T6G_MB_LIB.T6G(SCH_1):PV09_RETIMER_CPU0_VCCS
   3 P0V9_RETIMER_CPU0_VCC2    VCC @T6G_MB_LIB.T6G(SCH_1):P0V9_RETIMER_CPU0_VCC2
   2    GND   AGND @T6G_MB_LIB.T6G(SCH_1):GND
  33 SW_P0V9_RETIMER_CPU0_BOOT2   BOOT @T6G_MB_LIB.T6G(SCH_1):SW_P0V9_RETIMER_CPU0_BOOT2
25_29 SW_P12V_AUX_P0V9_RETIMER_CPU0_FLT   VIN1 @T6G_MB_LIB.T6G(SCH_1):SW_P12V_AUX_P0V9_RETIMER_CPU0_FLT
  32 SW_P0V9_RETIMER_CPU0_PH2  PHASE @T6G_MB_LIB.T6G(SCH_1):SW_P0V9_RETIMER_CPU0_PH2
   4 P0V9_RETIMER_CPU0_PVCC   PVCC @T6G_MB_LIB.T6G(SCH_1):P0V9_RETIMER_CPU0_PVCC
  36 P0V9_RETIMER_CPU0_TEMP0 TOUT_FLT @T6G_MB_LIB.T6G(SCH_1):P0V9_RETIMER_CPU0_TEMP0
  38 P0V9_RETIMER_CPU0_IMON2   IOUT @T6G_MB_LIB.T6G(SCH_1):P0V9_RETIMER_CPU0_IMON2
  37 P0V9_RETIMER_CPU0_LSET2   LSET @T6G_MB_LIB.T6G(SCH_1):P0V9_RETIMER_CPU0_LSET2
10_19 SW_P0V9_RETIMER_CPU0_SW2     SW @T6G_MB_LIB.T6G(SCH_1):SW_P0V9_RETIMER_CPU0_SW2
   5    GND  PGND1 @T6G_MB_LIB.T6G(SCH_1):GND
  30 SW_P12V_AUX_P0V9_RETIMER_CPU0_FLT   VIN2 @T6G_MB_LIB.T6G(SCH_1):SW_P12V_AUX_P0V9_RETIMER_CPU0_FLT
   1 P0V9_RETIMER_CPU0_VOS2    VOS @T6G_MB_LIB.T6G(SCH_1):P0V9_RETIMER_CPU0_VOS2
  40    GND  PGND3 @T6G_MB_LIB.T6G(SCH_1):GND
  35 P0V9_RETIMER_CPU0_VCC2     EN @T6G_MB_LIB.T6G(SCH_1):P0V9_RETIMER_CPU0_VCC2
  31 NC_PV09_RETIMER_CPU0_DNC2    DNC @T6G_MB_LIB.T6G(SCH_1):NC_PV09_RETIMER_CPU0_DNC2
   6 NC_PV09_RETIMER_CPU0_GL1_2    GL1 @T6G_MB_LIB.T6G(SCH_1):NC_PV09_RETIMER_CPU0_GL1_2
  41 NC_PV09_RETIMER_CPU0_GL2_2    GL2 @T6G_MB_LIB.T6G(SCH_1):NC_PV09_RETIMER_CPU0_GL2_2
7_9-20_24    GND  PGND2 @T6G_MB_LIB.T6G(SCH_1):GND

Q_CAP_C0402-2.2UF,10V,10%,X6S,CH5222KEB01  I271  PC6575
   1 P0V9_RETIMER_CPU0_VCC2      A @T6G_MB_LIB.T6G(SCH_1):P0V9_RETIMER_CPU0_VCC2
   2    GND      B @T6G_MB_LIB.T6G(SCH_1):GND

Q_RES_0402LF-8.87K,1%,1/16W,EMPTY,CS28872FB01  I276  PR6561
   1 P0V9_RETIMER_CPU0_LSET2      A @T6G_MB_LIB.T6G(SCH_1):P0V9_RETIMER_CPU0_LSET2
   2    GND      B @T6G_MB_LIB.T6G(SCH_1):GND

Q_CAP_C0402-100NF,50V,10%,X7R,CH4106K1B01  I281  PC6576
   1 PV09_RETIMER_CPU0_VCCS      A @T6G_MB_LIB.T6G(SCH_1):PV09_RETIMER_CPU0_VCCS
   2    GND      B @T6G_MB_LIB.T6G(SCH_1):GND

Q_RES_0402LF-1.5,1%,1/8W,EMPTY,CS-1504FB00  I283  PR6555
   1 SW_P0V9_RETIMER_CPU0_SW1_RC      A @T6G_MB_LIB.T6G(SCH_1):SW_P0V9_RETIMER_CPU0_SW1_RC
   2    GND      B @T6G_MB_LIB.T6G(SCH_1):GND

Q_CAP_C0402-560PF,50V,10%,EMPTY,CH1566K1B09  I285  PC6564
   1 SW_P0V9_RETIMER_CPU0_SW1      A @T6G_MB_LIB.T6G(SCH_1):SW_P0V9_RETIMER_CPU0_SW1
   2 SW_P0V9_RETIMER_CPU0_SW1_RC      B @T6G_MB_LIB.T6G(SCH_1):SW_P0V9_RETIMER_CPU0_SW1_RC

Q_RES_0402LF-1.5,1%,1/8W,EMPTY,CS-1504FB00  I286  PR6563
   1 SW_P0V9_RETIMER_CPU0_SW2_RC      A @T6G_MB_LIB.T6G(SCH_1):SW_P0V9_RETIMER_CPU0_SW2_RC
   2    GND      B @T6G_MB_LIB.T6G(SCH_1):GND

Q_CAP_C0402-560PF,50V,10%,EMPTY,CH1566K1B09  I288  PC6585
   1 SW_P0V9_RETIMER_CPU0_SW2      A @T6G_MB_LIB.T6G(SCH_1):SW_P0V9_RETIMER_CPU0_SW2
   2 SW_P0V9_RETIMER_CPU0_SW2_RC      B @T6G_MB_LIB.T6G(SCH_1):SW_P0V9_RETIMER_CPU0_SW2_RC

Q_CAP_0402-0.1UF,25V,10%,X7R,CH4104K1B00  I291  PC6562
   1 P12V_AUX      A @T6G_MB_LIB.T6G(SCH_1):P12V_AUX
   2    GND      B @T6G_MB_LIB.T6G(SCH_1):GND


DRAWING: @T6G_MB_LIB.T6G(SCH_1):PAGE477 

Q_RES_0402LF-0,5%,1/16W,CHIP,CS00002JB13  I2  R6800
   1    GND      A @T6G_MB_LIB.T6G(SCH_1):GND
   2 P0V9_RETIMER_CPU1_EN1_R      B @T6G_MB_LIB.T6G(SCH_1):P0V9_RETIMER_CPU1_EN1_R

Q_RES_0402LF-0,5%,1/16W,CHIP,CS00002JB13  I3  PR6821
   1 P0V9_RETIMER_CPU1_VMON      A @T6G_MB_LIB.T6G(SCH_1):P0V9_RETIMER_CPU1_VMON
   2    GND      B @T6G_MB_LIB.T6G(SCH_1):GND

Q_CAP_0402-0.1UF,25V,10%,EMPTY,CH4104K1B00  I5  PC514
   1 P0V9_RETIMER_CPU1_VMON      A @T6G_MB_LIB.T6G(SCH_1):P0V9_RETIMER_CPU1_VMON
   2    GND      B @T6G_MB_LIB.T6G(SCH_1):GND

Q_RES_0402LF-5.36K,1%,1/16W,EMPTY,CS25362FB02  I7  PR885
   1 P5V_AUX      A @T6G_MB_LIB.T6G(SCH_1):P5V_AUX
   2 P0V9_RETIMER_CPU1_VMON      B @T6G_MB_LIB.T6G(SCH_1):P0V9_RETIMER_CPU1_VMON

Q_RES_0402LF-0,5%,1/16W,CHIP,CS00002JB13  I10  PR6809
   1 P12V_AUX      A @T6G_MB_LIB.T6G(SCH_1):P12V_AUX
   2 P0V9_RETIMER_CPU1_VINSEN      B @T6G_MB_LIB.T6G(SCH_1):P0V9_RETIMER_CPU1_VINSEN

Q_RES_0402LF-0,5%,1/16W,EMPTY,CS00002JB13  I11  PR6808
   1 P12V_AUX      A @T6G_MB_LIB.T6G(SCH_1):P12V_AUX
   2 P0V9_RETIMER_CPU1_VMON      B @T6G_MB_LIB.T6G(SCH_1):P0V9_RETIMER_CPU1_VMON

Q_RES_0402LF-22.1K,1%,1/16W,CHIP,CS32212FB02  I13  PR6533
   1    GND      A @T6G_MB_LIB.T6G(SCH_1):GND
   2 P0V9_RETIMER_CPU1_ADDR      B @T6G_MB_LIB.T6G(SCH_1):P0V9_RETIMER_CPU1_ADDR

Q_RES_0402LF-1K,1%,1/16W,CHIP,CS21002FB06  I14  R665
   1 P3V3_AUX      A @T6G_MB_LIB.T6G(SCH_1):P3V3_AUX
   2 P0V9_RETIMER_CPU1_INALERT      B @T6G_MB_LIB.T6G(SCH_1):P0V9_RETIMER_CPU1_INALERT

Q_RES_0402LF-1K,1%,1/16W,CHIP,CS21002FB06  I15  R663
   1 P3V3_AUX      A @T6G_MB_LIB.T6G(SCH_1):P3V3_AUX
   2 P0V9_RETIMER_CPU1_CFP      B @T6G_MB_LIB.T6G(SCH_1):P0V9_RETIMER_CPU1_CFP

Q_RES_0402LF-49.9,1%,1/16W,CHIP,CS04992FB07  I22  PR6602
   1 P0V9_RETIMER_CPU1_SENSE_SH_N      A @T6G_MB_LIB.T6G(SCH_1):P0V9_RETIMER_CPU1_SENSE_SH_N
   2    GND      B @T6G_MB_LIB.T6G(SCH_1):GND

Q_RES_0402LF-49.9,1%,1/16W,CHIP,CS04992FB07  I23  PR6600
   1 P0V9_RETIMER_CPU1_SENSE_SH_P      A @T6G_MB_LIB.T6G(SCH_1):P0V9_RETIMER_CPU1_SENSE_SH_P
   2 P0V9_CPU1_RT_2D      B @T6G_MB_LIB.T6G(SCH_1):P0V9_CPU1_RT_2D

Q_RES_0402LF-0,5%,1/16W,CHIP,CS00002JB13  I27  PR6601
   1 P0V9_RETIMER_CPU1_SENSE_SH_P      A @T6G_MB_LIB.T6G(SCH_1):P0V9_RETIMER_CPU1_SENSE_SH_P
   2 P0V9_RETIMER_CPU1_SENSE_R_P      B @T6G_MB_LIB.T6G(SCH_1):P0V9_RETIMER_CPU1_SENSE_R_P

Q_CAP_0402-3300PF,50V,10%,X7R,TMP_QCH2336K1B12  I28  PC6600
   1 P0V9_RETIMER_CPU1_SENSE_R_P      A @T6G_MB_LIB.T6G(SCH_1):P0V9_RETIMER_CPU1_SENSE_R_P
   2 P0V9_RETIMER_CPU1_SENSE_SH_N      B @T6G_MB_LIB.T6G(SCH_1):P0V9_RETIMER_CPU1_SENSE_SH_N

Q_RES_0402LF-0,5%,1/16W,CHIP,CS00002JB13  I31  R658
   1 P0V9_RETIMER_CPU1_PMSDA      A @T6G_MB_LIB.T6G(SCH_1):P0V9_RETIMER_CPU1_PMSDA
   2 P0V9_RETIMER_CPU1_PMSDA_R      B @T6G_MB_LIB.T6G(SCH_1):P0V9_RETIMER_CPU1_PMSDA_R

Q_RES_0402LF-1K,1%,1/16W,EMPTY,CS21002FB06  I32  PR6818
   1 P3V3_AUX      A @T6G_MB_LIB.T6G(SCH_1):P3V3_AUX
   2 TP_P0V9_RETIMER_CPU1_SVID_ALERT_N      B @T6G_MB_LIB.T6G(SCH_1):TP_P0V9_RETIMER_CPU1_SVID_ALERT_N

Q_RES_0402LF-0,5%,1/16W,CHIP,CS00002JB13  I33  R657
   1 P0V9_RETIMER_CPU1_PMSCL      A @T6G_MB_LIB.T6G(SCH_1):P0V9_RETIMER_CPU1_PMSCL
   2 P0V9_RETIMER_CPU1_PMSCL_R      B @T6G_MB_LIB.T6G(SCH_1):P0V9_RETIMER_CPU1_PMSCL_R

Q_RES_0402LF-1K,1%,1/16W,EMPTY,CS21002FB06  I36  PR6804
   1 P3V3_AUX      A @T6G_MB_LIB.T6G(SCH_1):P3V3_AUX
   2 P0V9_RETIMER_CPU1_SVID_SDA      B @T6G_MB_LIB.T6G(SCH_1):P0V9_RETIMER_CPU1_SVID_SDA

Q_RES_0402LF-1K,1%,1/16W,EMPTY,CS21002FB06  I37  PR6806
   1 P3V3_AUX      A @T6G_MB_LIB.T6G(SCH_1):P3V3_AUX
   2 P0V9_RETIMER_CPU1_SVID_CLK      B @T6G_MB_LIB.T6G(SCH_1):P0V9_RETIMER_CPU1_SVID_CLK

Q_RES_0402LF-0,5%,1/16W,CHIP,CS00002JB13  I38  R662
   1 P0V9_RETIMER_CPU1_EN      A @T6G_MB_LIB.T6G(SCH_1):P0V9_RETIMER_CPU1_EN
   2 P0V9_RETIMER_CPU1_EN0_R      B @T6G_MB_LIB.T6G(SCH_1):P0V9_RETIMER_CPU1_EN0_R

Q_RES_0402LF-0,5%,1/16W,CHIP,CS00002JB13  I39  R661
   1 PWRGD_P0V9_RETIMER_CPU1      A @T6G_MB_LIB.T6G(SCH_1):PWRGD_P0V9_RETIMER_CPU1
   2 PWRGD_P0V9_RETIMER_CPU1_R      B @T6G_MB_LIB.T6G(SCH_1):PWRGD_P0V9_RETIMER_CPU1_R

Q_RES_0402LF-0,5%,1/16W,CHIP,CS00002JB13  I42  PR6811
   1 P0V9_RETIMER_CPU1_SVID_CLK      A @T6G_MB_LIB.T6G(SCH_1):P0V9_RETIMER_CPU1_SVID_CLK
   2    GND      B @T6G_MB_LIB.T6G(SCH_1):GND

Q_RES_0402LF-0,5%,1/16W,CHIP,CS00002JB13  I43  PR6820
   1 P0V9_RETIMER_CPU1_SVID_SDA      A @T6G_MB_LIB.T6G(SCH_1):P0V9_RETIMER_CPU1_SVID_SDA
   2    GND      B @T6G_MB_LIB.T6G(SCH_1):GND

Q_RES_0402LF-0,5%,1/16W,EMPTY,CS00002JB13  I44  PR6802
   1 TP_P0V9_RETIMER_CPU1_SVID_ALERT_N      A @T6G_MB_LIB.T6G(SCH_1):TP_P0V9_RETIMER_CPU1_SVID_ALERT_N
   2    GND      B @T6G_MB_LIB.T6G(SCH_1):GND

Q_CAP_0402-1000PF,50V,5%,EMPTY,TMP_QCH21006JB10  I45  C107
   1 PWRGD_P0V9_RETIMER_CPU1_R      A @T6G_MB_LIB.T6G(SCH_1):PWRGD_P0V9_RETIMER_CPU1_R
   2    GND      B @T6G_MB_LIB.T6G(SCH_1):GND

Q_RES_0402LF-1K,1%,1/16W,EMPTY,CS21002FB06  I46  PR6813
   1 P0V9_RETIMER_CPU1_VINSEN      A @T6G_MB_LIB.T6G(SCH_1):P0V9_RETIMER_CPU1_VINSEN
   2    GND      B @T6G_MB_LIB.T6G(SCH_1):GND

Q_CAP_0402-0.1UF,25V,10%,X7R,CH4104K1B00  I48  PC819
   1 P0V9_RETIMER_CPU1_VINSEN      A @T6G_MB_LIB.T6G(SCH_1):P0V9_RETIMER_CPU1_VINSEN
   2    GND      B @T6G_MB_LIB.T6G(SCH_1):GND

Q_CAP_0402-470PF,50V,10%,X7R,TMP_QCH14706KB18  I51  PC523
   1 P0V9_RETIMER_CPU1_TEMP0      A @T6G_MB_LIB.T6G(SCH_1):P0V9_RETIMER_CPU1_TEMP0
   2    GND      B @T6G_MB_LIB.T6G(SCH_1):GND

Q_RES_0402LF-0,5%,1/16W,CHIP,CS00002JB13  I52  PR6548
   1 P0V9_RETIMER_CPU1_TEMP1_R      A @T6G_MB_LIB.T6G(SCH_1):P0V9_RETIMER_CPU1_TEMP1_R
   2    GND      B @T6G_MB_LIB.T6G(SCH_1):GND

Q_RES_0402LF-10K,1%,1/16W,EMPTY,CS31002FB08  I54  PR6815
   1 P0V9_RETIMER_CPU1_TEMP0      A @T6G_MB_LIB.T6G(SCH_1):P0V9_RETIMER_CPU1_TEMP0
   2    GND      B @T6G_MB_LIB.T6G(SCH_1):GND

Q_RES_0402LF-0,5%,1/16W,CHIP,CS00002JB13  I56  PR6816
   1 P0V9_RETIMER_CPU1_VRHOT      A @T6G_MB_LIB.T6G(SCH_1):P0V9_RETIMER_CPU1_VRHOT
   2 TP_P0V9_RETIMER_CPU1_VRHOT      B @T6G_MB_LIB.T6G(SCH_1):TP_P0V9_RETIMER_CPU1_VRHOT

Q_RES_0402LF-0,5%,1/16W,CHIP,CS00002JB13  I57  PR6544
   1 NC_P0V9_RETIMER_CPU1_IMON8      A @T6G_MB_LIB.T6G(SCH_1):NC_P0V9_RETIMER_CPU1_IMON8
   2    GND      B @T6G_MB_LIB.T6G(SCH_1):GND

Q_RES_0402LF-0,5%,1/16W,CHIP,CS00002JB13  I58  PR6543
   1 NC_P0V9_RETIMER_CPU1_IMON7      A @T6G_MB_LIB.T6G(SCH_1):NC_P0V9_RETIMER_CPU1_IMON7
   2    GND      B @T6G_MB_LIB.T6G(SCH_1):GND

Q_RES_0402LF-0,5%,1/16W,CHIP,CS00002JB13  I64  PR6542
   1 NC_P0V9_RETIMER_CPU1_IMON6      A @T6G_MB_LIB.T6G(SCH_1):NC_P0V9_RETIMER_CPU1_IMON6
   2    GND      B @T6G_MB_LIB.T6G(SCH_1):GND

Q_RES_0402LF-0,5%,1/16W,CHIP,CS00002JB13  I65  PR6541
   1 NC_P0V9_RETIMER_CPU1_IMON5      A @T6G_MB_LIB.T6G(SCH_1):NC_P0V9_RETIMER_CPU1_IMON5
   2    GND      B @T6G_MB_LIB.T6G(SCH_1):GND

Q_RES_0402LF-0,5%,1/16W,CHIP,CS00002JB13  I68  PR6540
   1 NC_P0V9_RETIMER_CPU1_IMON4      A @T6G_MB_LIB.T6G(SCH_1):NC_P0V9_RETIMER_CPU1_IMON4
   2    GND      B @T6G_MB_LIB.T6G(SCH_1):GND

Q_RES_0402LF-0,5%,1/16W,CHIP,CS00002JB13  I69  PR6539
   1 NC_P0V9_RETIMER_CPU1_IMON3      A @T6G_MB_LIB.T6G(SCH_1):NC_P0V9_RETIMER_CPU1_IMON3
   2    GND      B @T6G_MB_LIB.T6G(SCH_1):GND

Q_CAP_C0402-10UF,6.3V,20%,X6S,CH6101MEB03  I72  PC6546
   1 PV09_RETIMER_CPU1_VCCS      A @T6G_MB_LIB.T6G(SCH_1):PV09_RETIMER_CPU1_VCCS
   2    GND      B @T6G_MB_LIB.T6G(SCH_1):GND

Q_CAP_C0402-1UF,16V,10%,X6S,CH5103KEB01  I73  PC6545
   1 PV09_RETIMER_CPU1_VCCS      A @T6G_MB_LIB.T6G(SCH_1):PV09_RETIMER_CPU1_VCCS
   2    GND      B @T6G_MB_LIB.T6G(SCH_1):GND

Q_CAP_C0402-100NF,50V,10%,X7R,CH4106K1B01  I74  PC6543
   1 P0V9_RETIMER_CPU1_VCC      A @T6G_MB_LIB.T6G(SCH_1):P0V9_RETIMER_CPU1_VCC
   2    GND      B @T6G_MB_LIB.T6G(SCH_1):GND

Q_CAP_C0402-1UF,16V,10%,X6S,CH5103KEB01  I75  PC6544
   1 P0V9_RETIMER_CPU1_VCC      A @T6G_MB_LIB.T6G(SCH_1):P0V9_RETIMER_CPU1_VCC
   2    GND      B @T6G_MB_LIB.T6G(SCH_1):GND

Q_RES_0402LF-1,1%,1/16W,CHIP,CS-1002FB04  I83  PR6538
   1 P0V9_RETIMER_CPU1_VCC      A @T6G_MB_LIB.T6G(SCH_1):P0V9_RETIMER_CPU1_VCC
   2 P3V3_AUX      B @T6G_MB_LIB.T6G(SCH_1):P3V3_AUX

Q_RES_0402LF-1K,1%,1/16W,CHIP,CS21002FB06  I86  PR6812
   1 P3V3_AUX      A @T6G_MB_LIB.T6G(SCH_1):P3V3_AUX
   2 TP_P0V9_RETIMER_CPU1_VRHOT      B @T6G_MB_LIB.T6G(SCH_1):TP_P0V9_RETIMER_CPU1_VRHOT

ISL69260IRAZT-ISL69260IRAZ-T,SMLF,IC,AL069260000  I88  PU6510
  23 P0V9_RETIMER_CPU1_IMON1    CS7 @T6G_MB_LIB.T6G(SCH_1):P0V9_RETIMER_CPU1_IMON1
  39 P0V9_RETIMER_CPU1_VCC    VCC @T6G_MB_LIB.T6G(SCH_1):P0V9_RETIMER_CPU1_VCC
  20 P0V9_RETIMER_CPU1_EN1_R    EN1 @T6G_MB_LIB.T6G(SCH_1):P0V9_RETIMER_CPU1_EN1_R
  10 P0V9_RETIMER_CPU1_PMSCL_R  PMSCL @T6G_MB_LIB.T6G(SCH_1):P0V9_RETIMER_CPU1_PMSCL_R
  18 P0V9_RETIMER_CPU1_SVID_SDA SVDATA @T6G_MB_LIB.T6G(SCH_1):P0V9_RETIMER_CPU1_SVID_SDA
  24 P0V9_RETIMER_CPU1_IMON2    CS6 @T6G_MB_LIB.T6G(SCH_1):P0V9_RETIMER_CPU1_IMON2
  19 TP_P0V9_RETIMER_CPU1_SVID_ALERT_N NSVALERT# @T6G_MB_LIB.T6G(SCH_1):TP_P0V9_RETIMER_CPU1_SVID_ALERT_N
  14 P0V9_RETIMER_CPU1_VRHOT NVRHOT# @T6G_MB_LIB.T6G(SCH_1):P0V9_RETIMER_CPU1_VRHOT
  25 NC_P0V9_RETIMER_CPU1_IMON3    CS5 @T6G_MB_LIB.T6G(SCH_1):NC_P0V9_RETIMER_CPU1_IMON3
  26 NC_P0V9_RETIMER_CPU1_IMON4    CS4 @T6G_MB_LIB.T6G(SCH_1):NC_P0V9_RETIMER_CPU1_IMON4
  16 NC_P0V9_RETIMER_CPU1_PG1    PG1 @T6G_MB_LIB.T6G(SCH_1):NC_P0V9_RETIMER_CPU1_PG1
  17 P0V9_RETIMER_CPU1_SVID_CLK  SVCLK @T6G_MB_LIB.T6G(SCH_1):P0V9_RETIMER_CPU1_SVID_CLK
  11 TP_P0V9_RETIMER_CPU1_PMALERT NPMALERT# @T6G_MB_LIB.T6G(SCH_1):TP_P0V9_RETIMER_CPU1_PMALERT
  13 P0V9_RETIMER_CPU1_EN0_R    EN0 @T6G_MB_LIB.T6G(SCH_1):P0V9_RETIMER_CPU1_EN0_R
  22 P0V9_RETIMER_CPU1_SENSE_SH_N  RGND0 @T6G_MB_LIB.T6G(SCH_1):P0V9_RETIMER_CPU1_SENSE_SH_N
   9 P0V9_RETIMER_CPU1_PMSDA_R  PMSDA @T6G_MB_LIB.T6G(SCH_1):P0V9_RETIMER_CPU1_PMSDA_R
   5 NC_P0V9_RETIMER_CPU1_PWM4   PWM4 @T6G_MB_LIB.T6G(SCH_1):NC_P0V9_RETIMER_CPU1_PWM4
   6 NC_P0V9_RETIMER_CPU1_PWM3   PWM5 @T6G_MB_LIB.T6G(SCH_1):NC_P0V9_RETIMER_CPU1_PWM3
  21 P0V9_RETIMER_CPU1_SENSE_R_P  VSEN0 @T6G_MB_LIB.T6G(SCH_1):P0V9_RETIMER_CPU1_SENSE_R_P
   2 NC_P0V9_RETIMER_CPU1_PWM7   PWM1 @T6G_MB_LIB.T6G(SCH_1):NC_P0V9_RETIMER_CPU1_PWM7
  12 PWRGD_P0V9_RETIMER_CPU1_R    PG0 @T6G_MB_LIB.T6G(SCH_1):PWRGD_P0V9_RETIMER_CPU1_R
   7 P0V9_RETIMER_CPU1_PWM2   PWM6 @T6G_MB_LIB.T6G(SCH_1):P0V9_RETIMER_CPU1_PWM2
  40 PV09_RETIMER_CPU1_VCCS   VCCS @T6G_MB_LIB.T6G(SCH_1):PV09_RETIMER_CPU1_VCCS
  37 P0V9_RETIMER_CPU1_VMON VMON||IINSEN||VSYS||ISYS @T6G_MB_LIB.T6G(SCH_1):P0V9_RETIMER_CPU1_VMON
  38 P0V9_RETIMER_CPU1_VINSEN VINSEN||VSYS @T6G_MB_LIB.T6G(SCH_1):P0V9_RETIMER_CPU1_VINSEN
  36 P0V9_RETIMER_CPU1_TEMP1_R TEMP1||ISYS @T6G_MB_LIB.T6G(SCH_1):P0V9_RETIMER_CPU1_TEMP1_R
  15 P0V9_RETIMER_CPU1_INALERT NPINALERT#||NPSYSCRIT# @T6G_MB_LIB.T6G(SCH_1):P0V9_RETIMER_CPU1_INALERT
  32    GND  VSEN1 @T6G_MB_LIB.T6G(SCH_1):GND
  31    GND  RGND1 @T6G_MB_LIB.T6G(SCH_1):GND
  29 NC_P0V9_RETIMER_CPU1_IMON7    CS1 @T6G_MB_LIB.T6G(SCH_1):NC_P0V9_RETIMER_CPU1_IMON7
   8 P0V9_RETIMER_CPU1_PWM1   PWM7 @T6G_MB_LIB.T6G(SCH_1):P0V9_RETIMER_CPU1_PWM1
   4 NC_P0V9_RETIMER_CPU1_PWM5   PWM3 @T6G_MB_LIB.T6G(SCH_1):NC_P0V9_RETIMER_CPU1_PWM5
  27 NC_P0V9_RETIMER_CPU1_IMON5    CS3 @T6G_MB_LIB.T6G(SCH_1):NC_P0V9_RETIMER_CPU1_IMON5
   3 NC_P0V9_RETIMER_CPU1_PWM6   PWM2 @T6G_MB_LIB.T6G(SCH_1):NC_P0V9_RETIMER_CPU1_PWM6
  28 NC_P0V9_RETIMER_CPU1_IMON6    CS2 @T6G_MB_LIB.T6G(SCH_1):NC_P0V9_RETIMER_CPU1_IMON6
  33 P0V9_RETIMER_CPU1_CFP    CFP @T6G_MB_LIB.T6G(SCH_1):P0V9_RETIMER_CPU1_CFP
  TH    GND TH_GND @T6G_MB_LIB.T6G(SCH_1):GND
  34 P0V9_RETIMER_CPU1_ADDR ADDR_CFG @T6G_MB_LIB.T6G(SCH_1):P0V9_RETIMER_CPU1_ADDR
  35 P0V9_RETIMER_CPU1_TEMP0  TEMP0 @T6G_MB_LIB.T6G(SCH_1):P0V9_RETIMER_CPU1_TEMP0
   1 NC_P0V9_RETIMER_CPU1_PWM8   PWM0 @T6G_MB_LIB.T6G(SCH_1):NC_P0V9_RETIMER_CPU1_PWM8
  30 NC_P0V9_RETIMER_CPU1_IMON8    CS0 @T6G_MB_LIB.T6G(SCH_1):NC_P0V9_RETIMER_CPU1_IMON8

Q_RES_0402LF-4.7K,1%,1/16W,EMPTY,CS24702FB06  I89  R660
   1 P3V3_AUX      A @T6G_MB_LIB.T6G(SCH_1):P3V3_AUX
   2 TP_P0V9_RETIMER_CPU1_PMALERT      B @T6G_MB_LIB.T6G(SCH_1):TP_P0V9_RETIMER_CPU1_PMALERT

Q_RES_0402LF-1K,1%,1/16W,CHIP,CS21002FB06  I90  R6787
   1 P0V9_RETIMER_CPU1_EN0_R      A @T6G_MB_LIB.T6G(SCH_1):P0V9_RETIMER_CPU1_EN0_R
   2    GND      B @T6G_MB_LIB.T6G(SCH_1):GND

Q_RES_0402LF-1K,1%,1/16W,EMPTY,CS21002FB06  I92  R656
   1 P3V3_AUX      A @T6G_MB_LIB.T6G(SCH_1):P3V3_AUX
   2 PWRGD_P0V9_RETIMER_CPU1_R      B @T6G_MB_LIB.T6G(SCH_1):PWRGD_P0V9_RETIMER_CPU1_R

Q_RES_0402LF-1K,1%,1/16W,CHIP,CS21002FB06  I93  R6861
   1 P1V8_AUX      A @T6G_MB_LIB.T6G(SCH_1):P1V8_AUX
   2 PWRGD_P0V9_RETIMER_CPU1_R      B @T6G_MB_LIB.T6G(SCH_1):PWRGD_P0V9_RETIMER_CPU1_R

Q_SHORT_SM-EMPTY,SHORT16  I95  PJ09_P1_P
   1 P0V9_CPU1_RT_2D      1 @T6G_MB_LIB.T6G(SCH_1):P0V9_CPU1_RT_2D
   2 P0V9_RETIMER_CPU1_SENSE_SH_P      2 @T6G_MB_LIB.T6G(SCH_1):P0V9_RETIMER_CPU1_SENSE_SH_P

Q_SHORT_SM-EMPTY,SHORT16  I96  PJ09_P1_N
   1    GND      1 @T6G_MB_LIB.T6G(SCH_1):GND
   2 P0V9_RETIMER_CPU1_SENSE_SH_N      2 @T6G_MB_LIB.T6G(SCH_1):P0V9_RETIMER_CPU1_SENSE_SH_N


DRAWING: @T6G_MB_LIB.T6G(SCH_1):PAGE478 

Q_CAP_C0402-100NF,50V,10%,X7R,CH4106K1B01  I2  PC6646
   1 PV09_RETIMER_CPU1_VCCS      A @T6G_MB_LIB.T6G(SCH_1):PV09_RETIMER_CPU1_VCCS
   2    GND      B @T6G_MB_LIB.T6G(SCH_1):GND

Q_RES_0402LF-8.87K,1%,1/16W,EMPTY,CS28872FB01  I5  PR6628
   1 P0V9_RETIMER_CPU1_LSET2      A @T6G_MB_LIB.T6G(SCH_1):P0V9_RETIMER_CPU1_LSET2
   2    GND      B @T6G_MB_LIB.T6G(SCH_1):GND

Q_CAP_C0402-2.2UF,10V,10%,X6S,CH5222KEB01  I10  PC6645
   1 P0V9_RETIMER_CPU1_VCC2      A @T6G_MB_LIB.T6G(SCH_1):P0V9_RETIMER_CPU1_VCC2
   2    GND      B @T6G_MB_LIB.T6G(SCH_1):GND

Q_RES_0402LF-2.2,5%,1/16W,CHIP,TMP_QCS-2202JB25  I11  PR6627
   1 P0V9_RETIMER_CPU1_PVCC      A @T6G_MB_LIB.T6G(SCH_1):P0V9_RETIMER_CPU1_PVCC
   2 P0V9_RETIMER_CPU1_VCC2      B @T6G_MB_LIB.T6G(SCH_1):P0V9_RETIMER_CPU1_VCC2

ISL99390FRZTR5935-ISL99390FRZ-TR5935,SMLF,IC,AL099A  I12  PU6512
  34 P0V9_RETIMER_CPU1_PWM2    PWM @T6G_MB_LIB.T6G(SCH_1):P0V9_RETIMER_CPU1_PWM2
  39 PV09_RETIMER_CPU1_VCCS  REFIN @T6G_MB_LIB.T6G(SCH_1):PV09_RETIMER_CPU1_VCCS
   3 P0V9_RETIMER_CPU1_VCC2    VCC @T6G_MB_LIB.T6G(SCH_1):P0V9_RETIMER_CPU1_VCC2
   2    GND   AGND @T6G_MB_LIB.T6G(SCH_1):GND
  33 SW_P0V9_RETIMER_CPU1_BOOT2   BOOT @T6G_MB_LIB.T6G(SCH_1):SW_P0V9_RETIMER_CPU1_BOOT2
25_29 SW_P12V_AUX_P0V9_RETIMER_CPU1_FLT   VIN1 @T6G_MB_LIB.T6G(SCH_1):SW_P12V_AUX_P0V9_RETIMER_CPU1_FLT
  32 SW_P0V9_RETIMER_CPU1_PH2  PHASE @T6G_MB_LIB.T6G(SCH_1):SW_P0V9_RETIMER_CPU1_PH2
   4 P0V9_RETIMER_CPU1_PVCC   PVCC @T6G_MB_LIB.T6G(SCH_1):P0V9_RETIMER_CPU1_PVCC
  36 P0V9_RETIMER_CPU1_TEMP0 TOUT_FLT @T6G_MB_LIB.T6G(SCH_1):P0V9_RETIMER_CPU1_TEMP0
  38 P0V9_RETIMER_CPU1_IMON2   IOUT @T6G_MB_LIB.T6G(SCH_1):P0V9_RETIMER_CPU1_IMON2
  37 P0V9_RETIMER_CPU1_LSET2   LSET @T6G_MB_LIB.T6G(SCH_1):P0V9_RETIMER_CPU1_LSET2
10_19 SW_P0V9_RETIMER_CPU1_SW2     SW @T6G_MB_LIB.T6G(SCH_1):SW_P0V9_RETIMER_CPU1_SW2
   5    GND  PGND1 @T6G_MB_LIB.T6G(SCH_1):GND
  30 SW_P12V_AUX_P0V9_RETIMER_CPU1_FLT   VIN2 @T6G_MB_LIB.T6G(SCH_1):SW_P12V_AUX_P0V9_RETIMER_CPU1_FLT
   1 P0V9_RETIMER_CPU1_VOS2    VOS @T6G_MB_LIB.T6G(SCH_1):P0V9_RETIMER_CPU1_VOS2
  40    GND  PGND3 @T6G_MB_LIB.T6G(SCH_1):GND
  35 P0V9_RETIMER_CPU1_VCC2     EN @T6G_MB_LIB.T6G(SCH_1):P0V9_RETIMER_CPU1_VCC2
  31 NC_PV09_RETIMER_CPU1_DNC2    DNC @T6G_MB_LIB.T6G(SCH_1):NC_PV09_RETIMER_CPU1_DNC2
   6 NC_PV09_RETIMER_CPU1_GL1_2    GL1 @T6G_MB_LIB.T6G(SCH_1):NC_PV09_RETIMER_CPU1_GL1_2
  41 NC_PV09_RETIMER_CPU1_GL2_2    GL2 @T6G_MB_LIB.T6G(SCH_1):NC_PV09_RETIMER_CPU1_GL2_2
7_9-20_24    GND  PGND2 @T6G_MB_LIB.T6G(SCH_1):GND

Q_CAP_C0402-2.2UF,10V,10%,X6S,CH5222KEB01  I14  PC6644_09P1_2
   1 P0V9_RETIMER_CPU1_PVCC      A @T6G_MB_LIB.T6G(SCH_1):P0V9_RETIMER_CPU1_PVCC
   2    GND      B @T6G_MB_LIB.T6G(SCH_1):GND

Q_RES_0402LF-0,5%,1/16W,CHIP,CS00002JB13  I16  PR6631
   1 P0V9_RETIMER_CPU1_VOS2      A @T6G_MB_LIB.T6G(SCH_1):P0V9_RETIMER_CPU1_VOS2
   2 P0V9_CPU1_RT_2D      B @T6G_MB_LIB.T6G(SCH_1):P0V9_CPU1_RT_2D

Q_CAP_0402-3300PF,50V,10%,X7R,TMP_QCH2336K1B12  I18  PC6634_2
   1 SW_P12V_AUX_P0V9_RETIMER_CPU1_FLT      A @T6G_MB_LIB.T6G(SCH_1):SW_P12V_AUX_P0V9_RETIMER_CPU1_FLT
   2    GND      B @T6G_MB_LIB.T6G(SCH_1):GND

Q_RES_0402LF-5.6,1%,1/16W,CHIP,CS-5602FB01  I19  PR6629
   1 SW_P0V9_RETIMER_CPU1_BOOT2      A @T6G_MB_LIB.T6G(SCH_1):SW_P0V9_RETIMER_CPU1_BOOT2
   2 SW_P0V9_RETIMER_CPU1_BOOT2_RC      B @T6G_MB_LIB.T6G(SCH_1):SW_P0V9_RETIMER_CPU1_BOOT2_RC

Q_CAP_C0402-1UF,25V,10%,X6S,CH5104KEB02  I21  PC6633_2
   1 SW_P12V_AUX_P0V9_RETIMER_CPU1_FLT      A @T6G_MB_LIB.T6G(SCH_1):SW_P12V_AUX_P0V9_RETIMER_CPU1_FLT
   2    GND      B @T6G_MB_LIB.T6G(SCH_1):GND

Q_INDUCTOR_SMLF-120NH/69A,IND,CV+12^0EZ03  I22  PL6512
   2 P0V9_CPU1_RT_2D      2 @T6G_MB_LIB.T6G(SCH_1):P0V9_CPU1_RT_2D
   1 SW_P0V9_RETIMER_CPU1_SW2      1 @T6G_MB_LIB.T6G(SCH_1):SW_P0V9_RETIMER_CPU1_SW2

Q_CAP_C0402-100NF,50V,10%,X7R,CH4106K1B01  I23  PC6807
   1 P0V9_CPU1_RT_2D      A @T6G_MB_LIB.T6G(SCH_1):P0V9_CPU1_RT_2D
   2    GND      B @T6G_MB_LIB.T6G(SCH_1):GND

Q_CAP_C0805-22UF,16V,20%,X6S,CH6223MEA01  I25  PC6635_2
   1 SW_P12V_AUX_P0V9_RETIMER_CPU1_FLT      A @T6G_MB_LIB.T6G(SCH_1):SW_P12V_AUX_P0V9_RETIMER_CPU1_FLT
   2    GND      B @T6G_MB_LIB.T6G(SCH_1):GND

Q_CAP_C0402-100NF,50V,10%,X7R,CH4106K1B01  I26  PC6640
   1 SW_P0V9_RETIMER_CPU1_BOOT2_RC      A @T6G_MB_LIB.T6G(SCH_1):SW_P0V9_RETIMER_CPU1_BOOT2_RC
   2 SW_P0V9_RETIMER_CPU1_PH2      B @T6G_MB_LIB.T6G(SCH_1):SW_P0V9_RETIMER_CPU1_PH2

Q_CAP_C0805-22UF,16V,20%,X6S,CH6223MEA01  I28  PC6636_2
   1 SW_P12V_AUX_P0V9_RETIMER_CPU1_FLT      A @T6G_MB_LIB.T6G(SCH_1):SW_P12V_AUX_P0V9_RETIMER_CPU1_FLT
   2    GND      B @T6G_MB_LIB.T6G(SCH_1):GND

Q_CAP_C0805-22UF,4V,20%,X6S,CH622KMEA03  I29  PC6642_2
   1 P0V9_CPU1_RT_2D      A @T6G_MB_LIB.T6G(SCH_1):P0V9_CPU1_RT_2D
   2    GND      B @T6G_MB_LIB.T6G(SCH_1):GND

Q_CAP_C0805-22UF,4V,20%,X6S,CH622KMEA03  I30  PC6643_2
   1 P0V9_CPU1_RT_2D      A @T6G_MB_LIB.T6G(SCH_1):P0V9_CPU1_RT_2D
   2    GND      B @T6G_MB_LIB.T6G(SCH_1):GND

Q_CAPP_SMLF-470UF,2.5V,20%,SPCAP,CH747LM8818  I31  PC6813
   1 P0V9_CPU1_RT_2D      A @T6G_MB_LIB.T6G(SCH_1):P0V9_CPU1_RT_2D
   2    GND      B @T6G_MB_LIB.T6G(SCH_1):GND

Q_CAPP_SMLF-470UF,2.5V,20%,SPCAP,CH747LM8818  I32  PC6814
   1 P0V9_CPU1_RT_2D      A @T6G_MB_LIB.T6G(SCH_1):P0V9_CPU1_RT_2D
   2    GND      B @T6G_MB_LIB.T6G(SCH_1):GND

Q_CAP_C0805-22UF,16V,20%,X6S,CH6223MEA01  I35  PC6637_2
   1 SW_P12V_AUX_P0V9_RETIMER_CPU1_FLT      A @T6G_MB_LIB.T6G(SCH_1):SW_P12V_AUX_P0V9_RETIMER_CPU1_FLT
   2    GND      B @T6G_MB_LIB.T6G(SCH_1):GND

Q_CAP_C0805-22UF,16V,20%,X6S,CH6223MEA01  I36  PC6638_2
   1 SW_P12V_AUX_P0V9_RETIMER_CPU1_FLT      A @T6G_MB_LIB.T6G(SCH_1):SW_P12V_AUX_P0V9_RETIMER_CPU1_FLT
   2    GND      B @T6G_MB_LIB.T6G(SCH_1):GND

Q_CAP_C0805-22UF,16V,20%,X6S,CH6223MEA01  I38  PC6639
   1 SW_P12V_AUX_P0V9_RETIMER_CPU1_FLT      A @T6G_MB_LIB.T6G(SCH_1):SW_P12V_AUX_P0V9_RETIMER_CPU1_FLT
   2    GND      B @T6G_MB_LIB.T6G(SCH_1):GND

Q_CAP_C0402-100NF,50V,10%,X7R,CH4106K1B01  I39  PC6611_1
   1 PV09_RETIMER_CPU1_VCCS      A @T6G_MB_LIB.T6G(SCH_1):PV09_RETIMER_CPU1_VCCS
   2    GND      B @T6G_MB_LIB.T6G(SCH_1):GND

Q_RES_0402LF-0,5%,1/16W,CHIP,CS00002JB13  I42  PR6619
   1 P5V_AUX      A @T6G_MB_LIB.T6G(SCH_1):P5V_AUX
   2 P0V9_RETIMER_CPU1_PVCC      B @T6G_MB_LIB.T6G(SCH_1):P0V9_RETIMER_CPU1_PVCC

Q_RES_0402LF-8.87K,1%,1/16W,EMPTY,CS28872FB01  I46  PR6622
   1 P0V9_RETIMER_CPU1_LSET1      A @T6G_MB_LIB.T6G(SCH_1):P0V9_RETIMER_CPU1_LSET1
   2    GND      B @T6G_MB_LIB.T6G(SCH_1):GND

ISL99390FRZTR5935-ISL99390FRZ-TR5935,SMLF,IC,AL099A  I51  PU6511
  34 P0V9_RETIMER_CPU1_PWM1    PWM @T6G_MB_LIB.T6G(SCH_1):P0V9_RETIMER_CPU1_PWM1
  39 PV09_RETIMER_CPU1_VCCS  REFIN @T6G_MB_LIB.T6G(SCH_1):PV09_RETIMER_CPU1_VCCS
   3 P0V9_RETIMER_CPU1_VCC1    VCC @T6G_MB_LIB.T6G(SCH_1):P0V9_RETIMER_CPU1_VCC1
   2    GND   AGND @T6G_MB_LIB.T6G(SCH_1):GND
  33 SW_P0V9_RETIMER_CPU1_BOOT1   BOOT @T6G_MB_LIB.T6G(SCH_1):SW_P0V9_RETIMER_CPU1_BOOT1
25_29 SW_P12V_AUX_P0V9_RETIMER_CPU1_FLT   VIN1 @T6G_MB_LIB.T6G(SCH_1):SW_P12V_AUX_P0V9_RETIMER_CPU1_FLT
  32 SW_P0V9_RETIMER_CPU1_PH1  PHASE @T6G_MB_LIB.T6G(SCH_1):SW_P0V9_RETIMER_CPU1_PH1
   4 P0V9_RETIMER_CPU1_PVCC   PVCC @T6G_MB_LIB.T6G(SCH_1):P0V9_RETIMER_CPU1_PVCC
  36 P0V9_RETIMER_CPU1_TEMP0 TOUT_FLT @T6G_MB_LIB.T6G(SCH_1):P0V9_RETIMER_CPU1_TEMP0
  38 P0V9_RETIMER_CPU1_IMON1   IOUT @T6G_MB_LIB.T6G(SCH_1):P0V9_RETIMER_CPU1_IMON1
  37 P0V9_RETIMER_CPU1_LSET1   LSET @T6G_MB_LIB.T6G(SCH_1):P0V9_RETIMER_CPU1_LSET1
10_19 SW_P0V9_RETIMER_CPU1_SW1     SW @T6G_MB_LIB.T6G(SCH_1):SW_P0V9_RETIMER_CPU1_SW1
   5    GND  PGND1 @T6G_MB_LIB.T6G(SCH_1):GND
  30 SW_P12V_AUX_P0V9_RETIMER_CPU1_FLT   VIN2 @T6G_MB_LIB.T6G(SCH_1):SW_P12V_AUX_P0V9_RETIMER_CPU1_FLT
   1 P0V9_RETIMER_CPU1_VOS1    VOS @T6G_MB_LIB.T6G(SCH_1):P0V9_RETIMER_CPU1_VOS1
  40    GND  PGND3 @T6G_MB_LIB.T6G(SCH_1):GND
  35 P0V9_RETIMER_CPU1_VCC1     EN @T6G_MB_LIB.T6G(SCH_1):P0V9_RETIMER_CPU1_VCC1
  31 NC_PV09_RETIMER_CPU1_DNC1    DNC @T6G_MB_LIB.T6G(SCH_1):NC_PV09_RETIMER_CPU1_DNC1
   6 NC_PV09_RETIMER_CPU1_GL1_1    GL1 @T6G_MB_LIB.T6G(SCH_1):NC_PV09_RETIMER_CPU1_GL1_1
  41 NC_PV09_RETIMER_CPU1_GL2_1    GL2 @T6G_MB_LIB.T6G(SCH_1):NC_PV09_RETIMER_CPU1_GL2_1
7_9-20_24    GND  PGND2 @T6G_MB_LIB.T6G(SCH_1):GND

Q_CAP_C0402-2.2UF,10V,10%,X6S,CH5222KEB01  I52  PC6610
   1 P0V9_RETIMER_CPU1_VCC1      A @T6G_MB_LIB.T6G(SCH_1):P0V9_RETIMER_CPU1_VCC1
   2    GND      B @T6G_MB_LIB.T6G(SCH_1):GND

Q_RES_0402LF-2.2,5%,1/16W,CHIP,TMP_QCS-2202JB25  I53  PR6621
   1 P0V9_RETIMER_CPU1_PVCC      A @T6G_MB_LIB.T6G(SCH_1):P0V9_RETIMER_CPU1_PVCC
   2 P0V9_RETIMER_CPU1_VCC1      B @T6G_MB_LIB.T6G(SCH_1):P0V9_RETIMER_CPU1_VCC1

Q_CAP_C0402-2.2UF,10V,10%,X6S,CH5222KEB01  I55  PC6609_09P1_1
   1 P0V9_RETIMER_CPU1_PVCC      A @T6G_MB_LIB.T6G(SCH_1):P0V9_RETIMER_CPU1_PVCC
   2    GND      B @T6G_MB_LIB.T6G(SCH_1):GND

Q_RES_0402LF-0,5%,1/16W,EMPTY,CS00002JB13  I56  PR6620
   1 P3V3_AUX      A @T6G_MB_LIB.T6G(SCH_1):P3V3_AUX
   2 P0V9_RETIMER_CPU1_PVCC      B @T6G_MB_LIB.T6G(SCH_1):P0V9_RETIMER_CPU1_PVCC

Q_RES_0402LF-0,5%,1/16W,CHIP,CS00002JB13  I59  PR6626
   1 P0V9_RETIMER_CPU1_VOS1      A @T6G_MB_LIB.T6G(SCH_1):P0V9_RETIMER_CPU1_VOS1
   2 P0V9_CPU1_RT_2D      B @T6G_MB_LIB.T6G(SCH_1):P0V9_CPU1_RT_2D

Q_CAP_0402-3300PF,50V,10%,X7R,TMP_QCH2336K1B12  I61  PC6613_1
   1 SW_P12V_AUX_P0V9_RETIMER_CPU1_FLT      A @T6G_MB_LIB.T6G(SCH_1):SW_P12V_AUX_P0V9_RETIMER_CPU1_FLT
   2    GND      B @T6G_MB_LIB.T6G(SCH_1):GND

Q_RES_0402LF-5.6,1%,1/16W,CHIP,CS-5602FB01  I62  PR6623
   1 SW_P0V9_RETIMER_CPU1_BOOT1      A @T6G_MB_LIB.T6G(SCH_1):SW_P0V9_RETIMER_CPU1_BOOT1
   2 SW_P0V9_RETIMER_CPU1_BOOT1_RC      B @T6G_MB_LIB.T6G(SCH_1):SW_P0V9_RETIMER_CPU1_BOOT1_RC

Q_CAP_C0402-1UF,25V,10%,X6S,CH5104KEB02  I64  PC6612_1
   1 SW_P12V_AUX_P0V9_RETIMER_CPU1_FLT      A @T6G_MB_LIB.T6G(SCH_1):SW_P12V_AUX_P0V9_RETIMER_CPU1_FLT
   2    GND      B @T6G_MB_LIB.T6G(SCH_1):GND

Q_INDUCTOR_SMLF-120NH/69A,IND,CV+12^0EZ03  I65  PL6511
   2 P0V9_CPU1_RT_2D      2 @T6G_MB_LIB.T6G(SCH_1):P0V9_CPU1_RT_2D
   1 SW_P0V9_RETIMER_CPU1_SW1      1 @T6G_MB_LIB.T6G(SCH_1):SW_P0V9_RETIMER_CPU1_SW1

Q_CAP_C0402-100NF,50V,10%,X7R,CH4106K1B01  I66  PC6623
   1 P0V9_CPU1_RT_2D      A @T6G_MB_LIB.T6G(SCH_1):P0V9_CPU1_RT_2D
   2    GND      B @T6G_MB_LIB.T6G(SCH_1):GND

Q_CAP_C0805-22UF,4V,20%,X6S,CH622KMEA03  I67  PC6624_1
   1 P0V9_CPU1_RT_2D      A @T6G_MB_LIB.T6G(SCH_1):P0V9_CPU1_RT_2D
   2    GND      B @T6G_MB_LIB.T6G(SCH_1):GND

Q_CAP_C0805-22UF,4V,20%,X6S,CH622KMEA03  I68  PC6625_1
   1 P0V9_CPU1_RT_2D      A @T6G_MB_LIB.T6G(SCH_1):P0V9_CPU1_RT_2D
   2    GND      B @T6G_MB_LIB.T6G(SCH_1):GND

Q_CAPP_SMLF-470UF,2.5V,20%,SPCAP,CH747LM8818  I69  PC6626
   1 P0V9_CPU1_RT_2D      A @T6G_MB_LIB.T6G(SCH_1):P0V9_CPU1_RT_2D
   2    GND      B @T6G_MB_LIB.T6G(SCH_1):GND

Q_CAPP_SMLF-470UF,2.5V,20%,SPCAP,CH747LM8818  I70  PC6627
   1 P0V9_CPU1_RT_2D      A @T6G_MB_LIB.T6G(SCH_1):P0V9_CPU1_RT_2D
   2    GND      B @T6G_MB_LIB.T6G(SCH_1):GND

Q_CAP_C0805-22UF,16V,20%,X6S,CH6223MEA01  I72  PC6614_1
   1 SW_P12V_AUX_P0V9_RETIMER_CPU1_FLT      A @T6G_MB_LIB.T6G(SCH_1):SW_P12V_AUX_P0V9_RETIMER_CPU1_FLT
   2    GND      B @T6G_MB_LIB.T6G(SCH_1):GND

Q_CAP_C0805-22UF,16V,20%,X6S,CH6223MEA01  I74  PC6615_1
   1 SW_P12V_AUX_P0V9_RETIMER_CPU1_FLT      A @T6G_MB_LIB.T6G(SCH_1):SW_P12V_AUX_P0V9_RETIMER_CPU1_FLT
   2    GND      B @T6G_MB_LIB.T6G(SCH_1):GND

Q_CAP_C0402-100NF,50V,10%,X7R,CH4106K1B01  I76  PC6621
   1 SW_P0V9_RETIMER_CPU1_BOOT1_RC      A @T6G_MB_LIB.T6G(SCH_1):SW_P0V9_RETIMER_CPU1_BOOT1_RC
   2 SW_P0V9_RETIMER_CPU1_PH1      B @T6G_MB_LIB.T6G(SCH_1):SW_P0V9_RETIMER_CPU1_PH1

Q_CAP_C0805-22UF,16V,20%,X6S,CH6223MEA01  I77  PC6616_1
   1 SW_P12V_AUX_P0V9_RETIMER_CPU1_FLT      A @T6G_MB_LIB.T6G(SCH_1):SW_P12V_AUX_P0V9_RETIMER_CPU1_FLT
   2    GND      B @T6G_MB_LIB.T6G(SCH_1):GND

Q_CAP_C0805-22UF,16V,20%,X6S,CH6223MEA01  I79  PC6617_1
   1 SW_P12V_AUX_P0V9_RETIMER_CPU1_FLT      A @T6G_MB_LIB.T6G(SCH_1):SW_P12V_AUX_P0V9_RETIMER_CPU1_FLT
   2    GND      B @T6G_MB_LIB.T6G(SCH_1):GND

Q_CAP_C0805-22UF,16V,20%,X6S,CH6223MEA01  I80  PC6618
   1 SW_P12V_AUX_P0V9_RETIMER_CPU1_FLT      A @T6G_MB_LIB.T6G(SCH_1):SW_P12V_AUX_P0V9_RETIMER_CPU1_FLT
   2    GND      B @T6G_MB_LIB.T6G(SCH_1):GND

Q_CAPP_SMLF-470UF,2.5V,20%,SPCAP,CH747LM8818  I82  PC6815
   1 P0V9_CPU1_RT_2D      A @T6G_MB_LIB.T6G(SCH_1):P0V9_CPU1_RT_2D
   2    GND      B @T6G_MB_LIB.T6G(SCH_1):GND

Q_CAPP_SMLF-390UF,2.5V,20%,ALUM,CC7390JMZ13  I83  PC6631
   1 P0V9_CPU1_RT_2D      A @T6G_MB_LIB.T6G(SCH_1):P0V9_CPU1_RT_2D
   2    GND      B @T6G_MB_LIB.T6G(SCH_1):GND

Q_CAPP_SMLF-390UF,2.5V,20%,ALUM,CC7390JMZ13  I84  PC6632
   1 P0V9_CPU1_RT_2D      A @T6G_MB_LIB.T6G(SCH_1):P0V9_CPU1_RT_2D
   2    GND      B @T6G_MB_LIB.T6G(SCH_1):GND

Q_CAP_C0805-22UF,16V,20%,X6S,CH6223MEA01  I86  PC6818
   1 SW_P12V_AUX_P0V9_RETIMER_CPU1_FLT      A @T6G_MB_LIB.T6G(SCH_1):SW_P12V_AUX_P0V9_RETIMER_CPU1_FLT
   2    GND      B @T6G_MB_LIB.T6G(SCH_1):GND

Q_CAPP_SMLF-100UF,16V,20%,OSCON,CC71003MZ30  I88  PC473
   1 SW_P12V_AUX_P0V9_RETIMER_CPU1_FLT      A @T6G_MB_LIB.T6G(SCH_1):SW_P12V_AUX_P0V9_RETIMER_CPU1_FLT
   2    GND      B @T6G_MB_LIB.T6G(SCH_1):GND

Q_CAPP_SMLF-470UF,2.5V,20%,SPCAP,CH747LM8818  I93  PC6628
   1 P0V9_CPU1_RT_2D      A @T6G_MB_LIB.T6G(SCH_1):P0V9_CPU1_RT_2D
   2    GND      B @T6G_MB_LIB.T6G(SCH_1):GND

Q_CAPP_SMLF-390UF,2.5V,20%,ALUM,CC7390JMZ13  I94  PC6629
   1 P0V9_CPU1_RT_2D      A @T6G_MB_LIB.T6G(SCH_1):P0V9_CPU1_RT_2D
   2    GND      B @T6G_MB_LIB.T6G(SCH_1):GND

Q_CAPP_SMLF-390UF,2.5V,20%,ALUM,CC7390JMZ13  I95  PC6630
   1 P0V9_CPU1_RT_2D      A @T6G_MB_LIB.T6G(SCH_1):P0V9_CPU1_RT_2D
   2    GND      B @T6G_MB_LIB.T6G(SCH_1):GND

Q_RES_0603LF-499,1%,1/10W,CHIP,CS14993F901  I97  PR6625
   1 P0V9_CPU1_RT_2D      A @T6G_MB_LIB.T6G(SCH_1):P0V9_CPU1_RT_2D
   2    GND      B @T6G_MB_LIB.T6G(SCH_1):GND

Q_CAP_C0805-22UF,16V,20%,X6S,CH6223MEA01  I100  PC6819
   1 SW_P12V_AUX_P0V9_RETIMER_CPU1_FLT      A @T6G_MB_LIB.T6G(SCH_1):SW_P12V_AUX_P0V9_RETIMER_CPU1_FLT
   2    GND      B @T6G_MB_LIB.T6G(SCH_1):GND

Q_CAPP_SMLF-100UF,16V,20%,OSCON,CC71003MZ30  I102  PC6619
   1 SW_P12V_AUX_P0V9_RETIMER_CPU1_FLT      A @T6G_MB_LIB.T6G(SCH_1):SW_P12V_AUX_P0V9_RETIMER_CPU1_FLT
   2    GND      B @T6G_MB_LIB.T6G(SCH_1):GND

Q_INDUCTOR_SMLF-100NH/16A,IND,CV+10G0MZ04  I104  PL6510
   2 P12V_AUX      2 @T6G_MB_LIB.T6G(SCH_1):P12V_AUX
   1 SW_P12V_AUX_P0V9_RETIMER_CPU1_FLT      1 @T6G_MB_LIB.T6G(SCH_1):SW_P12V_AUX_P0V9_RETIMER_CPU1_FLT

Q_RES_0402LF-1.5,1%,1/8W,EMPTY,CS-1504FB00  I106  PR6624
   1 SW_P0V9_RETIMER_CPU1_SW1_RC      A @T6G_MB_LIB.T6G(SCH_1):SW_P0V9_RETIMER_CPU1_SW1_RC
   2    GND      B @T6G_MB_LIB.T6G(SCH_1):GND

Q_CAP_C0402-560PF,50V,10%,EMPTY,CH1566K1B09  I108  PC6622
   1 SW_P0V9_RETIMER_CPU1_SW1      A @T6G_MB_LIB.T6G(SCH_1):SW_P0V9_RETIMER_CPU1_SW1
   2 SW_P0V9_RETIMER_CPU1_SW1_RC      B @T6G_MB_LIB.T6G(SCH_1):SW_P0V9_RETIMER_CPU1_SW1_RC

Q_CAP_C0402-560PF,50V,10%,EMPTY,CH1566K1B09  I109  PC6641
   1 SW_P0V9_RETIMER_CPU1_SW2      A @T6G_MB_LIB.T6G(SCH_1):SW_P0V9_RETIMER_CPU1_SW2
   2 SW_P0V9_RETIMER_CPU1_SW2_RC      B @T6G_MB_LIB.T6G(SCH_1):SW_P0V9_RETIMER_CPU1_SW2_RC

Q_RES_0402LF-1.5,1%,1/8W,EMPTY,CS-1504FB00  I110  PR6630
   1 SW_P0V9_RETIMER_CPU1_SW2_RC      A @T6G_MB_LIB.T6G(SCH_1):SW_P0V9_RETIMER_CPU1_SW2_RC
   2    GND      B @T6G_MB_LIB.T6G(SCH_1):GND

Q_CAP_0402-0.1UF,25V,10%,X7R,CH4104K1B00  I114  PC6620
   1 P12V_AUX      A @T6G_MB_LIB.T6G(SCH_1):P12V_AUX
   2    GND      B @T6G_MB_LIB.T6G(SCH_1):GND


DRAWING: @T6G_MB_LIB.T6G(SCH_1):PAGE378 

TCA9548APWR-TCA9548APWR,SMLF,IC,AL009548K02  I1  U6020
   1 RT_SMB_MUX_ADDR0     A0 @T6G_MB_LIB.T6G(SCH_1):RT_SMB_MUX_ADDR0
   2 RT_SMB_MUX_ADDR1     A1 @T6G_MB_LIB.T6G(SCH_1):RT_SMB_MUX_ADDR1
   3 RST_SMB_RT_N RESET# @T6G_MB_LIB.T6G(SCH_1):RST_SMB_RT_N
   4 SMB_RT_CPU1_P0_SDA    SD0 @T6G_MB_LIB.T6G(SCH_1):SMB_RT_CPU1_P0_SDA
   5 SMB_RT_CPU1_P0_SCL    SC0 @T6G_MB_LIB.T6G(SCH_1):SMB_RT_CPU1_P0_SCL
   6 SMB_RT_CPU1_P1_SDA    SD1 @T6G_MB_LIB.T6G(SCH_1):SMB_RT_CPU1_P1_SDA
   7 SMB_RT_CPU1_P1_SCL    SC1 @T6G_MB_LIB.T6G(SCH_1):SMB_RT_CPU1_P1_SCL
   8 SMB_RT_CPU1_P3_SDA    SD2 @T6G_MB_LIB.T6G(SCH_1):SMB_RT_CPU1_P3_SDA
   9 SMB_RT_CPU1_P3_SCL    SC2 @T6G_MB_LIB.T6G(SCH_1):SMB_RT_CPU1_P3_SCL
  10 SMB_RT_CPU1_P2_SDA    SD3 @T6G_MB_LIB.T6G(SCH_1):SMB_RT_CPU1_P2_SDA
  11 SMB_RT_CPU1_P2_SCL    SC3 @T6G_MB_LIB.T6G(SCH_1):SMB_RT_CPU1_P2_SCL
  12    GND    GND @T6G_MB_LIB.T6G(SCH_1):GND
  24 P1V8_AUX    VCC @T6G_MB_LIB.T6G(SCH_1):P1V8_AUX
  23 SMB_MUX_RT_SDA    SDA @T6G_MB_LIB.T6G(SCH_1):SMB_MUX_RT_SDA
  22 SMB_MUX_RT_SCL    SCL @T6G_MB_LIB.T6G(SCH_1):SMB_MUX_RT_SCL
  21 RT_SMB_MUX_ADDR2     A2 @T6G_MB_LIB.T6G(SCH_1):RT_SMB_MUX_ADDR2
  20 SMB_RT_CPU0_P2_SCL    SC7 @T6G_MB_LIB.T6G(SCH_1):SMB_RT_CPU0_P2_SCL
  19 SMB_RT_CPU0_P2_SDA    SD7 @T6G_MB_LIB.T6G(SCH_1):SMB_RT_CPU0_P2_SDA
  18 SMB_RT_CPU0_P3_SCL    SC6 @T6G_MB_LIB.T6G(SCH_1):SMB_RT_CPU0_P3_SCL
  17 SMB_RT_CPU0_P3_SDA    SD6 @T6G_MB_LIB.T6G(SCH_1):SMB_RT_CPU0_P3_SDA
  16 SMB_RT_CPU0_P1_SCL    SC5 @T6G_MB_LIB.T6G(SCH_1):SMB_RT_CPU0_P1_SCL
  15 SMB_RT_CPU0_P1_SDA    SD5 @T6G_MB_LIB.T6G(SCH_1):SMB_RT_CPU0_P1_SDA
  14 SMB_RT_CPU0_P0_SCL    SC4 @T6G_MB_LIB.T6G(SCH_1):SMB_RT_CPU0_P0_SCL
  13 SMB_RT_CPU0_P0_SDA    SD4 @T6G_MB_LIB.T6G(SCH_1):SMB_RT_CPU0_P0_SDA

Q_RES_0201LF-0,5%,1/20W,CHIP,CS00001JE10  I6  R6810
   1 SMB_RT_CPU1_P0_R_SDA      A @T6G_MB_LIB.T6G(SCH_1):SMB_RT_CPU1_P0_R_SDA
   2 SMB_RT_CPU1_P0_SDA      B @T6G_MB_LIB.T6G(SCH_1):SMB_RT_CPU1_P0_SDA

Q_RES_0201LF-0,5%,1/20W,CHIP,CS00001JE10  I7  R6811
   1 SMB_RT_CPU1_P0_R_SCL      A @T6G_MB_LIB.T6G(SCH_1):SMB_RT_CPU1_P0_R_SCL
   2 SMB_RT_CPU1_P0_SCL      B @T6G_MB_LIB.T6G(SCH_1):SMB_RT_CPU1_P0_SCL

Q_RES_0201LF-1K,1%,1/20W,CHIP,CS21001FE07  I9  R6718
   1 P1V8_CPU1_RT_1D      A @T6G_MB_LIB.T6G(SCH_1):P1V8_CPU1_RT_1D
   2 SMB_RT_CPU1_P0_R_SDA      B @T6G_MB_LIB.T6G(SCH_1):SMB_RT_CPU1_P0_R_SDA

Q_RES_0201LF-1K,1%,1/20W,CHIP,CS21001FE07  I11  R6719
   1 P1V8_CPU1_RT_1D      A @T6G_MB_LIB.T6G(SCH_1):P1V8_CPU1_RT_1D
   2 SMB_RT_CPU1_P0_R_SCL      B @T6G_MB_LIB.T6G(SCH_1):SMB_RT_CPU1_P0_R_SCL

Q_RES_0201LF-0,5%,1/20W,CHIP,CS00001JE10  I13  R6736
   1 SMB_RT_CPU1_P1_R_SDA      A @T6G_MB_LIB.T6G(SCH_1):SMB_RT_CPU1_P1_R_SDA
   2 SMB_RT_CPU1_P1_SDA      B @T6G_MB_LIB.T6G(SCH_1):SMB_RT_CPU1_P1_SDA

Q_RES_0201LF-0,5%,1/20W,CHIP,CS00001JE10  I14  R6737
   1 SMB_RT_CPU1_P1_R_SCL      A @T6G_MB_LIB.T6G(SCH_1):SMB_RT_CPU1_P1_R_SCL
   2 SMB_RT_CPU1_P1_SCL      B @T6G_MB_LIB.T6G(SCH_1):SMB_RT_CPU1_P1_SCL

Q_RES_0201LF-1K,1%,1/20W,CHIP,CS21001FE07  I17  R6738
   1 P1V8_CPU1_RT_1D      A @T6G_MB_LIB.T6G(SCH_1):P1V8_CPU1_RT_1D
   2 SMB_RT_CPU1_P1_R_SDA      B @T6G_MB_LIB.T6G(SCH_1):SMB_RT_CPU1_P1_R_SDA

Q_RES_0201LF-1K,1%,1/20W,CHIP,CS21001FE07  I18  R6739
   1 P1V8_CPU1_RT_1D      A @T6G_MB_LIB.T6G(SCH_1):P1V8_CPU1_RT_1D
   2 SMB_RT_CPU1_P1_R_SCL      B @T6G_MB_LIB.T6G(SCH_1):SMB_RT_CPU1_P1_R_SCL

Q_RES_0201LF-0,5%,1/20W,CHIP,CS00001JE10  I21  R6747
   1 SMB_RT_CPU1_P3_R_SCL      A @T6G_MB_LIB.T6G(SCH_1):SMB_RT_CPU1_P3_R_SCL
   2 SMB_RT_CPU1_P3_SCL      B @T6G_MB_LIB.T6G(SCH_1):SMB_RT_CPU1_P3_SCL

Q_RES_0201LF-0,5%,1/20W,CHIP,CS00001JE10  I22  R6746
   1 SMB_RT_CPU1_P3_R_SDA      A @T6G_MB_LIB.T6G(SCH_1):SMB_RT_CPU1_P3_R_SDA
   2 SMB_RT_CPU1_P3_SDA      B @T6G_MB_LIB.T6G(SCH_1):SMB_RT_CPU1_P3_SDA

Q_RES_0201LF-0,5%,1/20W,CHIP,CS00001JE10  I25  R6749
   1 SMB_RT_CPU1_P2_R_SCL      A @T6G_MB_LIB.T6G(SCH_1):SMB_RT_CPU1_P2_R_SCL
   2 SMB_RT_CPU1_P2_SCL      B @T6G_MB_LIB.T6G(SCH_1):SMB_RT_CPU1_P2_SCL

Q_RES_0201LF-0,5%,1/20W,CHIP,CS00001JE10  I26  R6748
   1 SMB_RT_CPU1_P2_R_SDA      A @T6G_MB_LIB.T6G(SCH_1):SMB_RT_CPU1_P2_R_SDA
   2 SMB_RT_CPU1_P2_SDA      B @T6G_MB_LIB.T6G(SCH_1):SMB_RT_CPU1_P2_SDA

Q_RES_0201LF-1K,1%,1/20W,CHIP,CS21001FE07  I31  R6750
   1 P1V8_CPU1_RT_1D      A @T6G_MB_LIB.T6G(SCH_1):P1V8_CPU1_RT_1D
   2 SMB_RT_CPU1_P3_R_SDA      B @T6G_MB_LIB.T6G(SCH_1):SMB_RT_CPU1_P3_R_SDA

Q_RES_0201LF-1K,1%,1/20W,CHIP,CS21001FE07  I32  R6751
   1 P1V8_CPU1_RT_1D      A @T6G_MB_LIB.T6G(SCH_1):P1V8_CPU1_RT_1D
   2 SMB_RT_CPU1_P3_R_SCL      B @T6G_MB_LIB.T6G(SCH_1):SMB_RT_CPU1_P3_R_SCL

Q_RES_0201LF-1K,1%,1/20W,CHIP,CS21001FE07  I35  R6752
   1 P1V8_CPU1_RT_1D      A @T6G_MB_LIB.T6G(SCH_1):P1V8_CPU1_RT_1D
   2 SMB_RT_CPU1_P2_R_SDA      B @T6G_MB_LIB.T6G(SCH_1):SMB_RT_CPU1_P2_R_SDA

Q_RES_0201LF-1K,1%,1/20W,CHIP,CS21001FE07  I36  R6753
   1 P1V8_CPU1_RT_1D      A @T6G_MB_LIB.T6G(SCH_1):P1V8_CPU1_RT_1D
   2 SMB_RT_CPU1_P2_R_SCL      B @T6G_MB_LIB.T6G(SCH_1):SMB_RT_CPU1_P2_R_SCL

Q_RES_0201LF-0,5%,1/20W,CHIP,CS00001JE10  I53  R6754
   1 SMB_RT_CPU0_P0_SDA      A @T6G_MB_LIB.T6G(SCH_1):SMB_RT_CPU0_P0_SDA
   2 SMB_RT_CPU0_P0_R_SDA      B @T6G_MB_LIB.T6G(SCH_1):SMB_RT_CPU0_P0_R_SDA

Q_RES_0201LF-0,5%,1/20W,CHIP,CS00001JE10  I54  R6755
   1 SMB_RT_CPU0_P0_SCL      A @T6G_MB_LIB.T6G(SCH_1):SMB_RT_CPU0_P0_SCL
   2 SMB_RT_CPU0_P0_R_SCL      B @T6G_MB_LIB.T6G(SCH_1):SMB_RT_CPU0_P0_R_SCL

Q_RES_0201LF-0,5%,1/20W,CHIP,CS00001JE10  I55  R6758
   1 SMB_RT_CPU0_P3_SDA      A @T6G_MB_LIB.T6G(SCH_1):SMB_RT_CPU0_P3_SDA
   2 SMB_RT_CPU0_P3_R_SDA      B @T6G_MB_LIB.T6G(SCH_1):SMB_RT_CPU0_P3_R_SDA

Q_RES_0201LF-0,5%,1/20W,CHIP,CS00001JE10  I56  R6756
   1 SMB_RT_CPU0_P1_SDA      A @T6G_MB_LIB.T6G(SCH_1):SMB_RT_CPU0_P1_SDA
   2 SMB_RT_CPU0_P1_R_SDA      B @T6G_MB_LIB.T6G(SCH_1):SMB_RT_CPU0_P1_R_SDA

Q_RES_0201LF-0,5%,1/20W,CHIP,CS00001JE10  I57  R6757
   1 SMB_RT_CPU0_P1_SCL      A @T6G_MB_LIB.T6G(SCH_1):SMB_RT_CPU0_P1_SCL
   2 SMB_RT_CPU0_P1_R_SCL      B @T6G_MB_LIB.T6G(SCH_1):SMB_RT_CPU0_P1_R_SCL

Q_RES_0201LF-0,5%,1/20W,CHIP,CS00001JE10  I58  R6760
   1 SMB_RT_CPU0_P2_SDA      A @T6G_MB_LIB.T6G(SCH_1):SMB_RT_CPU0_P2_SDA
   2 SMB_RT_CPU0_P2_R_SDA      B @T6G_MB_LIB.T6G(SCH_1):SMB_RT_CPU0_P2_R_SDA

Q_RES_0201LF-0,5%,1/20W,CHIP,CS00001JE10  I59  R6759
   1 SMB_RT_CPU0_P3_SCL      A @T6G_MB_LIB.T6G(SCH_1):SMB_RT_CPU0_P3_SCL
   2 SMB_RT_CPU0_P3_R_SCL      B @T6G_MB_LIB.T6G(SCH_1):SMB_RT_CPU0_P3_R_SCL

Q_RES_0201LF-0,5%,1/20W,CHIP,CS00001JE10  I60  R6761
   1 SMB_RT_CPU0_P2_SCL      A @T6G_MB_LIB.T6G(SCH_1):SMB_RT_CPU0_P2_SCL
   2 SMB_RT_CPU0_P2_R_SCL      B @T6G_MB_LIB.T6G(SCH_1):SMB_RT_CPU0_P2_R_SCL

Q_RES_0201LF-1K,1%,1/20W,CHIP,CS21001FE07  I77  R6762
   1 P1V8_CPU0_RT_1D      A @T6G_MB_LIB.T6G(SCH_1):P1V8_CPU0_RT_1D
   2 SMB_RT_CPU0_P0_R_SDA      B @T6G_MB_LIB.T6G(SCH_1):SMB_RT_CPU0_P0_R_SDA

Q_RES_0201LF-1K,1%,1/20W,CHIP,CS21001FE07  I78  R6763
   1 P1V8_CPU0_RT_1D      A @T6G_MB_LIB.T6G(SCH_1):P1V8_CPU0_RT_1D
   2 SMB_RT_CPU0_P0_R_SCL      B @T6G_MB_LIB.T6G(SCH_1):SMB_RT_CPU0_P0_R_SCL

Q_RES_0201LF-1K,1%,1/20W,CHIP,CS21001FE07  I79  R6764
   1 P1V8_CPU0_RT_1D      A @T6G_MB_LIB.T6G(SCH_1):P1V8_CPU0_RT_1D
   2 SMB_RT_CPU0_P1_R_SDA      B @T6G_MB_LIB.T6G(SCH_1):SMB_RT_CPU0_P1_R_SDA

Q_RES_0201LF-1K,1%,1/20W,CHIP,CS21001FE07  I80  R6765
   1 P1V8_CPU0_RT_1D      A @T6G_MB_LIB.T6G(SCH_1):P1V8_CPU0_RT_1D
   2 SMB_RT_CPU0_P1_R_SCL      B @T6G_MB_LIB.T6G(SCH_1):SMB_RT_CPU0_P1_R_SCL

Q_RES_0201LF-1K,1%,1/20W,CHIP,CS21001FE07  I82  R6767
   1 P1V8_CPU0_RT_1D      A @T6G_MB_LIB.T6G(SCH_1):P1V8_CPU0_RT_1D
   2 SMB_RT_CPU0_P3_R_SCL      B @T6G_MB_LIB.T6G(SCH_1):SMB_RT_CPU0_P3_R_SCL

Q_RES_0201LF-1K,1%,1/20W,CHIP,CS21001FE07  I83  R6766
   1 P1V8_CPU0_RT_1D      A @T6G_MB_LIB.T6G(SCH_1):P1V8_CPU0_RT_1D
   2 SMB_RT_CPU0_P3_R_SDA      B @T6G_MB_LIB.T6G(SCH_1):SMB_RT_CPU0_P3_R_SDA

Q_RES_0201LF-1K,1%,1/20W,CHIP,CS21001FE07  I84  R6768
   1 P1V8_CPU0_RT_1D      A @T6G_MB_LIB.T6G(SCH_1):P1V8_CPU0_RT_1D
   2 SMB_RT_CPU0_P2_R_SDA      B @T6G_MB_LIB.T6G(SCH_1):SMB_RT_CPU0_P2_R_SDA

Q_RES_0201LF-1K,1%,1/20W,CHIP,CS21001FE07  I85  R6769
   1 P1V8_CPU0_RT_1D      A @T6G_MB_LIB.T6G(SCH_1):P1V8_CPU0_RT_1D
   2 SMB_RT_CPU0_P2_R_SCL      B @T6G_MB_LIB.T6G(SCH_1):SMB_RT_CPU0_P2_R_SCL

Q_CAP_C0201-0.1UF,10V,10%,X7S,CH4102K6E00  I88  C7500
   1 P1V8_AUX      A @T6G_MB_LIB.T6G(SCH_1):P1V8_AUX
   2    GND      B @T6G_MB_LIB.T6G(SCH_1):GND

Q_RES_0201LF-4.7K,5%,1/20W,CHIP,CS24701JE04  I94  R6773
   1 RT_SMB_MUX_ADDR2      A @T6G_MB_LIB.T6G(SCH_1):RT_SMB_MUX_ADDR2
   2    GND      B @T6G_MB_LIB.T6G(SCH_1):GND

Q_RES_0201LF-4.7K,5%,1/20W,CHIP,CS24701JE04  I95  R6774
   1 RT_SMB_MUX_ADDR1      A @T6G_MB_LIB.T6G(SCH_1):RT_SMB_MUX_ADDR1
   2    GND      B @T6G_MB_LIB.T6G(SCH_1):GND

Q_RES_0201LF-4.7K,5%,1/20W,EMPTY,CS24701JE04  I96  R6770
   1 P1V8_AUX      A @T6G_MB_LIB.T6G(SCH_1):P1V8_AUX
   2 RT_SMB_MUX_ADDR2      B @T6G_MB_LIB.T6G(SCH_1):RT_SMB_MUX_ADDR2

Q_RES_0201LF-4.7K,5%,1/20W,CHIP,CS24701JE04  I97  R6775
   1 RT_SMB_MUX_ADDR0      A @T6G_MB_LIB.T6G(SCH_1):RT_SMB_MUX_ADDR0
   2    GND      B @T6G_MB_LIB.T6G(SCH_1):GND

Q_RES_0201LF-4.7K,5%,1/20W,EMPTY,CS24701JE04  I98  R6772
   1 P1V8_AUX      A @T6G_MB_LIB.T6G(SCH_1):P1V8_AUX
   2 RT_SMB_MUX_ADDR0      B @T6G_MB_LIB.T6G(SCH_1):RT_SMB_MUX_ADDR0

Q_RES_0201LF-4.7K,5%,1/20W,EMPTY,CS24701JE04  I100  R6771
   1 P1V8_AUX      A @T6G_MB_LIB.T6G(SCH_1):P1V8_AUX
   2 RT_SMB_MUX_ADDR1      B @T6G_MB_LIB.T6G(SCH_1):RT_SMB_MUX_ADDR1

Q_RES_0201LF-0,5%,1/20W,CHIP,CS00001JE10  I104  R6776
   1 RST_SMB_RT_R1_N      A @T6G_MB_LIB.T6G(SCH_1):RST_SMB_RT_R1_N
   2 RST_SMB_RT_N      B @T6G_MB_LIB.T6G(SCH_1):RST_SMB_RT_N

Q_RES_0201LF-10K,1%,1/20W,CHIP,CS31001FE17  I107  R6778
   1 RST_SMB_RT_R1_N      A @T6G_MB_LIB.T6G(SCH_1):RST_SMB_RT_R1_N
   2    GND      B @T6G_MB_LIB.T6G(SCH_1):GND

CONN3_210HP1030BR1-CONN3_210-HP1-030BR1,THLF,IO,DFA  I116  JP6500
   3    GND      3 @T6G_MB_LIB.T6G(SCH_1):GND
   2 SMB_MUX_RT_R2_SDA      2 @T6G_MB_LIB.T6G(SCH_1):SMB_MUX_RT_R2_SDA
   1 SMB_MUX_RT_R2_SCL      1 @T6G_MB_LIB.T6G(SCH_1):SMB_MUX_RT_R2_SCL

Q_RES_0201LF-0,5%,1/20W,CHIP,CS00001JE10  I117  R1515
   1 SMB_MUX_RT_R1_SDA      A @T6G_MB_LIB.T6G(SCH_1):SMB_MUX_RT_R1_SDA
   2 SMB_MUX_RT_R2_SDA      B @T6G_MB_LIB.T6G(SCH_1):SMB_MUX_RT_R2_SDA

Q_RES_0201LF-0,5%,1/20W,CHIP,CS00001JE10  I118  R1514
   1 SMB_MUX_RT_R1_SCL      A @T6G_MB_LIB.T6G(SCH_1):SMB_MUX_RT_R1_SCL
   2 SMB_MUX_RT_R2_SCL      B @T6G_MB_LIB.T6G(SCH_1):SMB_MUX_RT_R2_SCL

Q_RES_0201LF-33.2,1%,1/20W,CHIP,CS03321FE09  I119  R6779
   1 SMB_MUX_RT_SDA      A @T6G_MB_LIB.T6G(SCH_1):SMB_MUX_RT_SDA
   2 SMB_MUX_RT_R1_SDA      B @T6G_MB_LIB.T6G(SCH_1):SMB_MUX_RT_R1_SDA

Q_RES_0201LF-33.2,1%,1/20W,CHIP,CS03321FE09  I120  R6780
   1 SMB_MUX_RT_SCL      A @T6G_MB_LIB.T6G(SCH_1):SMB_MUX_RT_SCL
   2 SMB_MUX_RT_R1_SCL      B @T6G_MB_LIB.T6G(SCH_1):SMB_MUX_RT_R1_SCL


DRAWING: @T6G_MB_LIB.T6G(SCH_1):PAGE408 

Q_RES_0201LF-0,5%,1/20W,CHIP,CS00001JE10  I15  R612
   1 CLK_100M_RETIMER_CPU0_P1_R_DN      A @T6G_MB_LIB.T6G(SCH_1):CLK_100M_RETIMER_CPU0_P1_R_DN
   2 CLK_100M_RETIMER_CPU0_P1_DN      B @T6G_MB_LIB.T6G(SCH_1):CLK_100M_RETIMER_CPU0_P1_DN

Q_RES_0201LF-51.1,1%,1/20W,EMPTY,CS05111FE00  I18  R629
   1 CLK_100M_RETIMER_CPU0_P1_DN      A @T6G_MB_LIB.T6G(SCH_1):CLK_100M_RETIMER_CPU0_P1_DN
   2    GND      B @T6G_MB_LIB.T6G(SCH_1):GND

Q_RES_0201LF-51.1,1%,1/20W,EMPTY,CS05111FE00  I19  R630
   1 CLK_100M_RETIMER_CPU0_P1_DP      A @T6G_MB_LIB.T6G(SCH_1):CLK_100M_RETIMER_CPU0_P1_DP
   2    GND      B @T6G_MB_LIB.T6G(SCH_1):GND

Q_RES_0201LF-0,5%,1/20W,CHIP,CS00001JE10  I20  R611
   1 CLK_100M_RETIMER_CPU0_P1_R_DP      A @T6G_MB_LIB.T6G(SCH_1):CLK_100M_RETIMER_CPU0_P1_R_DP
   2 CLK_100M_RETIMER_CPU0_P1_DP      B @T6G_MB_LIB.T6G(SCH_1):CLK_100M_RETIMER_CPU0_P1_DP

Q_RES_0201LF-4.7K,5%,1/20W,EMPTY,CS24701JE04  I5  R1021
   1 P1V8_CPU0_RT_1D      A @T6G_MB_LIB.T6G(SCH_1):P1V8_CPU0_RT_1D
   2 RT_CPU0_P1_SCAN_MODE      B @T6G_MB_LIB.T6G(SCH_1):RT_CPU0_P1_SCAN_MODE

Q_RES_0201LF-10K,1%,1/20W,CHIP,CS31001FE17  I7  R1028
   1 GPIO2_RT_CPU0_P1      A @T6G_MB_LIB.T6G(SCH_1):GPIO2_RT_CPU0_P1
   2    GND      B @T6G_MB_LIB.T6G(SCH_1):GND

Q_RES_0201LF-10K,1%,1/20W,CHIP,CS31001FE17  I8  R1029
   1 GPIO3_RT_CPU0_P1      A @T6G_MB_LIB.T6G(SCH_1):GPIO3_RT_CPU0_P1
   2    GND      B @T6G_MB_LIB.T6G(SCH_1):GND

Q_RES_0201LF-4.7K,5%,1/20W,CHIP,CS24701JE04  I9  R1031
   1 TEST0_RT_CPU0_P1      A @T6G_MB_LIB.T6G(SCH_1):TEST0_RT_CPU0_P1
   2    GND      B @T6G_MB_LIB.T6G(SCH_1):GND

Q_RES_0201LF-4.7K,5%,1/20W,EMPTY,CS24701JE04  I10  R1027
   1 P1V8_CPU0_RT_1D      A @T6G_MB_LIB.T6G(SCH_1):P1V8_CPU0_RT_1D
   2 GPIO2_RT_CPU0_P1      B @T6G_MB_LIB.T6G(SCH_1):GPIO2_RT_CPU0_P1

Q_RES_0201LF-4.7K,5%,1/20W,EMPTY,CS24701JE04  I11  R1030
   1 P1V8_CPU0_RT_1D      A @T6G_MB_LIB.T6G(SCH_1):P1V8_CPU0_RT_1D
   2 TEST0_RT_CPU0_P1      B @T6G_MB_LIB.T6G(SCH_1):TEST0_RT_CPU0_P1

Q_RES_0201LF-49.9,1%,1/20W,CHIP,CS04991FE06  I21  R677
   1 SMB_RT_CPU0_P1_ROM_MUX_1D_SDA      A @T6G_MB_LIB.T6G(SCH_1):SMB_RT_CPU0_P1_ROM_MUX_1D_SDA
   2 SMB_RT_CPU0_P1_ROM_MUX_1D_R_SDA      B @T6G_MB_LIB.T6G(SCH_1):SMB_RT_CPU0_P1_ROM_MUX_1D_R_SDA

Q_RES_0201LF-49.9,1%,1/20W,CHIP,CS04991FE06  I22  R676
   1 SMB_RT_CPU0_P1_ROM_MUX_1D_SCL      A @T6G_MB_LIB.T6G(SCH_1):SMB_RT_CPU0_P1_ROM_MUX_1D_SCL
   2 SMB_RT_CPU0_P1_ROM_MUX_1D_R_SCL      B @T6G_MB_LIB.T6G(SCH_1):SMB_RT_CPU0_P1_ROM_MUX_1D_R_SCL

Q_RES_0201LF-0,5%,1/20W,CHIP,CS00001JE10  I29  R1026
   1 SMB_RT_CPU0_P1_R_SDA      A @T6G_MB_LIB.T6G(SCH_1):SMB_RT_CPU0_P1_R_SDA
   2 SMB_RT_CPU0_P1_R2_SDA      B @T6G_MB_LIB.T6G(SCH_1):SMB_RT_CPU0_P1_R2_SDA

Q_RES_0201LF-0,5%,1/20W,CHIP,CS00001JE10  I30  R1025
   1 SMB_RT_CPU0_P1_R_SCL      A @T6G_MB_LIB.T6G(SCH_1):SMB_RT_CPU0_P1_R_SCL
   2 SMB_RT_CPU0_P1_R2_SCL      B @T6G_MB_LIB.T6G(SCH_1):SMB_RT_CPU0_P1_R2_SCL

Q_RES_0201LF-4.7K,5%,1/20W,CHIP,CS24701JE04  I36  R1033
   1 TEST1_RT_CPU0_P1      A @T6G_MB_LIB.T6G(SCH_1):TEST1_RT_CPU0_P1
   2    GND      B @T6G_MB_LIB.T6G(SCH_1):GND

Q_RES_0201LF-4.7K,5%,1/20W,CHIP,CS24701JE04  I37  R1035
   1 TEST2_RT_CPU0_P1      A @T6G_MB_LIB.T6G(SCH_1):TEST2_RT_CPU0_P1
   2    GND      B @T6G_MB_LIB.T6G(SCH_1):GND

Q_RES_0201LF-4.7K,5%,1/20W,CHIP,CS24701JE04  I39  R1037
   1 JTAG_TEST_MODE_RT_CPU0_P1      A @T6G_MB_LIB.T6G(SCH_1):JTAG_TEST_MODE_RT_CPU0_P1
   2    GND      B @T6G_MB_LIB.T6G(SCH_1):GND

Q_RES_0201LF-4.7K,5%,1/20W,EMPTY,CS24701JE04  I40  R1032
   1 P1V8_CPU0_RT_1D      A @T6G_MB_LIB.T6G(SCH_1):P1V8_CPU0_RT_1D
   2 TEST1_RT_CPU0_P1      B @T6G_MB_LIB.T6G(SCH_1):TEST1_RT_CPU0_P1

Q_RES_0201LF-4.7K,5%,1/20W,EMPTY,CS24701JE04  I41  R1034
   1 P1V8_CPU0_RT_1D      A @T6G_MB_LIB.T6G(SCH_1):P1V8_CPU0_RT_1D
   2 TEST2_RT_CPU0_P1      B @T6G_MB_LIB.T6G(SCH_1):TEST2_RT_CPU0_P1

Q_RES_0201LF-4.7K,5%,1/20W,EMPTY,CS24701JE04  I42  R1024
   1 P1V8_CPU0_RT_1D      A @T6G_MB_LIB.T6G(SCH_1):P1V8_CPU0_RT_1D
   2 JTAG_TEST_MODE_RT_CPU0_P1      B @T6G_MB_LIB.T6G(SCH_1):JTAG_TEST_MODE_RT_CPU0_P1

Q_RES_0201LF-4.7K,5%,1/20W,EMPTY,CS24701JE04  I50  R1006
   1 MODE_RT_CPU0_P1      A @T6G_MB_LIB.T6G(SCH_1):MODE_RT_CPU0_P1
   2    GND      B @T6G_MB_LIB.T6G(SCH_1):GND

Q_RES_0201LF-4.7K,5%,1/20W,CHIP,CS24701JE04  I51  R1039
   1 P1V8_CPU0_RT_1D      A @T6G_MB_LIB.T6G(SCH_1):P1V8_CPU0_RT_1D
   2 MODE_RT_CPU0_P1      B @T6G_MB_LIB.T6G(SCH_1):MODE_RT_CPU0_P1

Q_RES_0201LF-0,5%,1/20W,CHIP,CS00001JE10  I55  R1012
   1 RST_RT_CPU0_P1_RESET_N      A @T6G_MB_LIB.T6G(SCH_1):RST_RT_CPU0_P1_RESET_N
   2 RST_RT_CPU0_P1_RESET_R_N      B @T6G_MB_LIB.T6G(SCH_1):RST_RT_CPU0_P1_RESET_R_N

Q_RES_0201LF-0,5%,1/20W,CHIP,CS00001JE10  I56  R1004
   1 RST_RT_CPU0_P1_PERST_N      A @T6G_MB_LIB.T6G(SCH_1):RST_RT_CPU0_P1_PERST_N
   2 RST_RT_CPU0_P1_PERST_R_N      B @T6G_MB_LIB.T6G(SCH_1):RST_RT_CPU0_P1_PERST_R_N

Q_RES_0201LF-1K,1%,1/20W,EMPTY,CS21001FE07  I64  R1014
   1 RT_CPU0_P1_ADDR3      A @T6G_MB_LIB.T6G(SCH_1):RT_CPU0_P1_ADDR3
   2    GND      B @T6G_MB_LIB.T6G(SCH_1):GND

Q_RES_0201LF-20K,1%,1/20W,CHIP,CS32001FE00  I65  R1016
   1 RT_CPU0_P1_ADDR2      A @T6G_MB_LIB.T6G(SCH_1):RT_CPU0_P1_ADDR2
   2    GND      B @T6G_MB_LIB.T6G(SCH_1):GND

Q_RES_0201LF-1K,1%,1/20W,CHIP,CS21001FE07  I66  R1013
   1 P1V8_CPU0_RT_1D      A @T6G_MB_LIB.T6G(SCH_1):P1V8_CPU0_RT_1D
   2 RT_CPU0_P1_ADDR3      B @T6G_MB_LIB.T6G(SCH_1):RT_CPU0_P1_ADDR3

Q_RES_0201LF-1K,1%,1/20W,EMPTY,CS21001FE07  I67  R1015
   1 P1V8_CPU0_RT_1D      A @T6G_MB_LIB.T6G(SCH_1):P1V8_CPU0_RT_1D
   2 RT_CPU0_P1_ADDR2      B @T6G_MB_LIB.T6G(SCH_1):RT_CPU0_P1_ADDR2

Q_RES_0201LF-1K,1%,1/20W,CHIP,CS21001FE07  I68  R1018
   1 RT_CPU0_P1_ADDR1      A @T6G_MB_LIB.T6G(SCH_1):RT_CPU0_P1_ADDR1
   2    GND      B @T6G_MB_LIB.T6G(SCH_1):GND

Q_RES_0201LF-1K,1%,1/20W,EMPTY,CS21001FE07  I69  R1017
   1 P1V8_CPU0_RT_1D      A @T6G_MB_LIB.T6G(SCH_1):P1V8_CPU0_RT_1D
   2 RT_CPU0_P1_ADDR1      B @T6G_MB_LIB.T6G(SCH_1):RT_CPU0_P1_ADDR1

Q_RES_0201LF-10K,1%,1/20W,CHIP,CS31001FE17  I73  R1019
   1 RST_RT_CPU0_P1_PERST_R_N      A @T6G_MB_LIB.T6G(SCH_1):RST_RT_CPU0_P1_PERST_R_N
   2    GND      B @T6G_MB_LIB.T6G(SCH_1):GND

Q_RES_0201LF-10K,1%,1/20W,CHIP,CS31001FE17  I74  R1020
   1 RST_RT_CPU0_P1_RESET_R_N      A @T6G_MB_LIB.T6G(SCH_1):RST_RT_CPU0_P1_RESET_R_N
   2    GND      B @T6G_MB_LIB.T6G(SCH_1):GND

Q_RES_0201LF-4.7K,5%,1/20W,EMPTY,CS24701JE04  I78  R1023
   1 P1V8_CPU0_RT_1D      A @T6G_MB_LIB.T6G(SCH_1):P1V8_CPU0_RT_1D
   2 RST_RT_CPU0_P1_RESET_R_N      B @T6G_MB_LIB.T6G(SCH_1):RST_RT_CPU0_P1_RESET_R_N

PT5161LRS-PT5161LRS,SMLF,IC,AJ051610U03  I83  U6011
 FJ6     NC  GPIO0     NC
FJ23     NC  GPIO1     NC
FJ25 GPIO2_RT_CPU0_P1  GPIO2 @T6G_MB_LIB.T6G(SCH_1):GPIO2_RT_CPU0_P1
FJ28 GPIO3_RT_CPU0_P1  GPIO3 @T6G_MB_LIB.T6G(SCH_1):GPIO3_RT_CPU0_P1
FJ31     NC  INT_N     NC
  B3 JTAG_TCK_RT_CPU0_P1 JTAG_TCK @T6G_MB_LIB.T6G(SCH_1):JTAG_TCK_RT_CPU0_P1
  B6 JTAG_TDI_RT_CPU0_P1 JTAG_TDI @T6G_MB_LIB.T6G(SCH_1):JTAG_TDI_RT_CPU0_P1
  B9 JTAG_TDO_RT_CPU0_P1 JTAG_TDO @T6G_MB_LIB.T6G(SCH_1):JTAG_TDO_RT_CPU0_P1
 FF8 JTAG_TEST_MODE_RT_CPU0_P1 JTAG_TEST_MODE @T6G_MB_LIB.T6G(SCH_1):JTAG_TEST_MODE_RT_CPU0_P1
 B12 JTAG_TMS_RT_CPU0_P1 JTAG_TMS @T6G_MB_LIB.T6G(SCH_1):JTAG_TMS_RT_CPU0_P1
  E8 JTAG_TRST_RT_CPU0_P1_N JTAG_TRST_N @T6G_MB_LIB.T6G(SCH_1):JTAG_TRST_RT_CPU0_P1_N
 FJ9 MODE_RT_CPU0_P1   MODE @T6G_MB_LIB.T6G(SCH_1):MODE_RT_CPU0_P1
  F2 RST_RT_CPU0_P1_PERST_N PERST_N @T6G_MB_LIB.T6G(SCH_1):RST_RT_CPU0_P1_PERST_N
 E18     NC REFCLK_OUTN     NC
 B16     NC REFCLK_OUTP     NC
FF18 CLK_100M_RETIMER_CPU0_P1_DN REFCLKN @T6G_MB_LIB.T6G(SCH_1):CLK_100M_RETIMER_CPU0_P1_DN
FJ16 CLK_100M_RETIMER_CPU0_P1_DP REFCLKP @T6G_MB_LIB.T6G(SCH_1):CLK_100M_RETIMER_CPU0_P1_DP
FF11 RST_RT_CPU0_P1_RESET_N RESET_N @T6G_MB_LIB.T6G(SCH_1):RST_RT_CPU0_P1_RESET_N
 E11 RXDET_BYP_RT_CPU0_P1 RXDET_BYP @T6G_MB_LIB.T6G(SCH_1):RXDET_BYP_RT_CPU0_P1
FF33 RT_CPU0_P1_SCAN_MODE SCAN_MODE @T6G_MB_LIB.T6G(SCH_1):RT_CPU0_P1_SCAN_MODE
 F34 RT_CPU0_P1_ADDR1 SMB_ADDR1 @T6G_MB_LIB.T6G(SCH_1):RT_CPU0_P1_ADDR1
 B23 RT_CPU0_P1_ADDR2 SMB_ADDR2 @T6G_MB_LIB.T6G(SCH_1):RT_CPU0_P1_ADDR2
 B25 RT_CPU0_P1_ADDR3 SMB_ADDR3 @T6G_MB_LIB.T6G(SCH_1):RT_CPU0_P1_ADDR3
 B31 SMB_RT_CPU0_P1_R2_SCL SMBCLK @T6G_MB_LIB.T6G(SCH_1):SMB_RT_CPU0_P1_R2_SCL
 B28 SMB_RT_CPU0_P1_R2_SDA SMBDAT @T6G_MB_LIB.T6G(SCH_1):SMB_RT_CPU0_P1_R2_SDA
 E30    GND T_SENSE @T6G_MB_LIB.T6G(SCH_1):GND
FF24 TEST0_RT_CPU0_P1  TEST0 @T6G_MB_LIB.T6G(SCH_1):TEST0_RT_CPU0_P1
FF27 TEST1_RT_CPU0_P1  TEST1 @T6G_MB_LIB.T6G(SCH_1):TEST1_RT_CPU0_P1
FF30 TEST2_RT_CPU0_P1  TEST2 @T6G_MB_LIB.T6G(SCH_1):TEST2_RT_CPU0_P1
 G35 CLKREQ_RT_CPU0_P1_N CLKREQ_N @T6G_MB_LIB.T6G(SCH_1):CLKREQ_RT_CPU0_P1_N
 FF5 SMB_RT_CPU0_P1_ROM_MUX_1D_R_SCL EE_CLK @T6G_MB_LIB.T6G(SCH_1):SMB_RT_CPU0_P1_ROM_MUX_1D_R_SCL
 FJ3 SMB_RT_CPU0_P1_ROM_MUX_1D_R_SDA EE_DAT @T6G_MB_LIB.T6G(SCH_1):SMB_RT_CPU0_P1_ROM_MUX_1D_R_SDA

Q_RES_0201LF-1K,1%,1/20W,CHIP,CS21001FE07  I84  R1391
   1 JTAG_TRST_RT_CPU0_P1_N      A @T6G_MB_LIB.T6G(SCH_1):JTAG_TRST_RT_CPU0_P1_N
   2    GND      B @T6G_MB_LIB.T6G(SCH_1):GND

Q_RES_0201LF-4.7K,5%,1/20W,CHIP,CS24701JE04  I94  R1395
   1 CLKREQ_RT_CPU0_P1_N      A @T6G_MB_LIB.T6G(SCH_1):CLKREQ_RT_CPU0_P1_N
   2    GND      B @T6G_MB_LIB.T6G(SCH_1):GND

Q_RES_0201LF-10K,1%,1/20W,CHIP,CS31001FE17  I98  R1398
   1 RXDET_BYP_RT_CPU0_P1      A @T6G_MB_LIB.T6G(SCH_1):RXDET_BYP_RT_CPU0_P1
   2    GND      B @T6G_MB_LIB.T6G(SCH_1):GND

Q_RES_0201LF-1K,1%,1/20W,EMPTY,CS21001FE07  I99  R1397
   1 P1V8_CPU0_RT_1D      A @T6G_MB_LIB.T6G(SCH_1):P1V8_CPU0_RT_1D
   2 RXDET_BYP_RT_CPU0_P1      B @T6G_MB_LIB.T6G(SCH_1):RXDET_BYP_RT_CPU0_P1

Q_RES_0201LF-200,1%,1/20W,CHIP,CS12001FE12  I102  R1022
   1 RT_CPU0_P1_SCAN_MODE      A @T6G_MB_LIB.T6G(SCH_1):RT_CPU0_P1_SCAN_MODE
   2    GND      B @T6G_MB_LIB.T6G(SCH_1):GND

Q_RES_0201LF-4.7K,5%,1/20W,EMPTY,CS24701JE04  I115  R1470
   1 P1V8_CPU0_RT_1D      A @T6G_MB_LIB.T6G(SCH_1):P1V8_CPU0_RT_1D
   2 JTAG_TDI_RT_CPU0_P1      B @T6G_MB_LIB.T6G(SCH_1):JTAG_TDI_RT_CPU0_P1

Q_RES_0201LF-4.7K,5%,1/20W,EMPTY,CS24701JE04  I116  R1471
   1 P1V8_CPU0_RT_1D      A @T6G_MB_LIB.T6G(SCH_1):P1V8_CPU0_RT_1D
   2 JTAG_TMS_RT_CPU0_P1      B @T6G_MB_LIB.T6G(SCH_1):JTAG_TMS_RT_CPU0_P1

Q_RES_0201LF-4.7K,5%,1/20W,CHIP,CS24701JE04  I119  R1392
   1 JTAG_TCK_RT_CPU0_P1      A @T6G_MB_LIB.T6G(SCH_1):JTAG_TCK_RT_CPU0_P1
   2    GND      B @T6G_MB_LIB.T6G(SCH_1):GND

Q_RES_0201LF-1K,1%,1/20W,EMPTY,CS21001FE07  I121  R1472
   1 P1V8_CPU0_RT_1D      A @T6G_MB_LIB.T6G(SCH_1):P1V8_CPU0_RT_1D
   2 JTAG_TDO_RT_CPU0_P1      B @T6G_MB_LIB.T6G(SCH_1):JTAG_TDO_RT_CPU0_P1

Q_RES_0201LF-4.7K,5%,1/20W,EMPTY,CS24701JE04  I122  R1473
   1 P1V8_CPU0_RT_1D      A @T6G_MB_LIB.T6G(SCH_1):P1V8_CPU0_RT_1D
   2 JTAG_TCK_RT_CPU0_P1      B @T6G_MB_LIB.T6G(SCH_1):JTAG_TCK_RT_CPU0_P1


DRAWING: @T6G_MB_LIB.T6G(SCH_1):PAGE156 

CONN2_AAABAT029Y19-CONN2_AAA-BAT-029-Y19,THLF,IO,DA  I86  BT2
   1 P3V_BAT      1 @T6G_MB_LIB.T6G(SCH_1):P3V_BAT
   2    GND      2 @T6G_MB_LIB.T6G(SCH_1):GND

TPS71715DCKR-TPS71715DCKR,SMLF,EMPTY,AL071715001  I91  U9
   2    GND    GND @T6G_MB_LIB.T6G(SCH_1):GND
   3 BAT_LDO_EN     EN @T6G_MB_LIB.T6G(SCH_1):BAT_LDO_EN
   1 P1V5_BAT_IN     IN @T6G_MB_LIB.T6G(SCH_1):P1V5_BAT_IN
   4  U9_NR NR||FB @T6G_MB_LIB.T6G(SCH_1):U9_NR
   5 P1V5_BAT_OUT    OUT @T6G_MB_LIB.T6G(SCH_1):P1V5_BAT_OUT

Q_RES_0402LF-1K,1%,1/16W,CHIP,CS21002FB06  I94  R1776
   1 CLR_CMOS      A @T6G_MB_LIB.T6G(SCH_1):CLR_CMOS
   2    GND      B @T6G_MB_LIB.T6G(SCH_1):GND

Q_CAP_C0402-0.1UF,16V,10%,X7R,CH4103K1B08  I95  C1563
   1 CLR_CMOS      A @T6G_MB_LIB.T6G(SCH_1):CLR_CMOS
   2    GND      B @T6G_MB_LIB.T6G(SCH_1):GND

Q_RES_0402LF-10K,5%,1/16W,CHIP,CS31002JB08  I97  R5101
   1 P3V3_AUX      A @T6G_MB_LIB.T6G(SCH_1):P3V3_AUX
   2 P3V3_STBY_R      B @T6G_MB_LIB.T6G(SCH_1):P3V3_STBY_R

SCHOTTKY_DUAL_12A_3C-BAT54CW,SMLF,IC,BCBAT54CZ13  I99  U166
   2 P3V_BAT_R      A @T6G_MB_LIB.T6G(SCH_1):P3V_BAT_R
   1 P3V3_STBY_R      B @T6G_MB_LIB.T6G(SCH_1):P3V3_STBY_R
   3 P3V3_RTC_AUX      C @T6G_MB_LIB.T6G(SCH_1):P3V3_RTC_AUX

Q_RES_0402LF-0,5%,1/16W,CHIP,CS00002JB13  I100  R5052
   1 P3V3_RTC_AUX_R      A @T6G_MB_LIB.T6G(SCH_1):P3V3_RTC_AUX_R
   2 P3V3_RTC_AUX      B @T6G_MB_LIB.T6G(SCH_1):P3V3_RTC_AUX

Q_RES_0402LF-0,5%,1/16W,EMPTY,CS00002JB13  I101  R5051
   1 P3V3_RTC_AUX      A @T6G_MB_LIB.T6G(SCH_1):P3V3_RTC_AUX
   2 P1V5_BAT_IN      B @T6G_MB_LIB.T6G(SCH_1):P1V5_BAT_IN

MOSFET_DUAL_6P-2N7002KDW,SMLF,IC,BAM70020047  I104  Q8
   2 CLR_CMOS     G1 @T6G_MB_LIB.T6G(SCH_1):CLR_CMOS
   5 CLR_CMOS     G2 @T6G_MB_LIB.T6G(SCH_1):CLR_CMOS
   1    GND     S1 @T6G_MB_LIB.T6G(SCH_1):GND
   4    GND     S2 @T6G_MB_LIB.T6G(SCH_1):GND
   6 CLR_CMOS_N     D1 @T6G_MB_LIB.T6G(SCH_1):CLR_CMOS_N
   3 BAT_LDO_EN     D2 @T6G_MB_LIB.T6G(SCH_1):BAT_LDO_EN

Q_CAP_C0402-1UF,25V,10%,X6S,CH5104KEB02  I107  C45
   1 P1V5_BAT_IN      A @T6G_MB_LIB.T6G(SCH_1):P1V5_BAT_IN
   2    GND      B @T6G_MB_LIB.T6G(SCH_1):GND

Q_CAP_C0402-100NF,50V,10%,X7R,CH4106K1B01  I108  C193
   1 P1V5_BAT_IN      A @T6G_MB_LIB.T6G(SCH_1):P1V5_BAT_IN
   2    GND      B @T6G_MB_LIB.T6G(SCH_1):GND

Q_CAP_C0402-0.01UF,50V,10%,EMPTY,CH31006KB18  I113  C22
   1  U9_NR      A @T6G_MB_LIB.T6G(SCH_1):U9_NR
   2    GND      B @T6G_MB_LIB.T6G(SCH_1):GND

Q_RES_0402LF-100,1%,1/16W,CHIP,CS11002FB07  I116  R1779
   1 CLR_CMOS_N      A @T6G_MB_LIB.T6G(SCH_1):CLR_CMOS_N
   2 P1V5_BAT      B @T6G_MB_LIB.T6G(SCH_1):P1V5_BAT

Q_CAP_C0402-1UF,25V,10%,X6S,CH5104KEB02  I118  C1564
   1 P1V5_BAT_OUT      A @T6G_MB_LIB.T6G(SCH_1):P1V5_BAT_OUT
   2    GND      B @T6G_MB_LIB.T6G(SCH_1):GND

Q_RES_0402LF-1K,1%,1/16W,EMPTY,CS21002FB06  I120  R5053
   1 P1V5_BAT_OUT      A @T6G_MB_LIB.T6G(SCH_1):P1V5_BAT_OUT
   2 P1V5_BAT_OUT_R      B @T6G_MB_LIB.T6G(SCH_1):P1V5_BAT_OUT_R

Q_RES_0402LF-0,5%,1/16W,CHIP,CS00002JB13  I122  R5054
   1 P3V3_RTC_AUX_R      A @T6G_MB_LIB.T6G(SCH_1):P3V3_RTC_AUX_R
   2 P1V5_BAT_OUT_R      B @T6G_MB_LIB.T6G(SCH_1):P1V5_BAT_OUT_R

Q_CAP_C0402-1UF,25V,10%,X6S,CH5104KEB02  I125  C1567
   1 P1V5_BAT      A @T6G_MB_LIB.T6G(SCH_1):P1V5_BAT
   2    GND      B @T6G_MB_LIB.T6G(SCH_1):GND

Q_CAP_C0805-10UF,25V,10%,X6S,CH6104KEA00  I126  C5032
   1 P1V5_BAT      A @T6G_MB_LIB.T6G(SCH_1):P1V5_BAT
   2    GND      B @T6G_MB_LIB.T6G(SCH_1):GND

CONN3_210HP1030BR1-CONN3_210-HP1-030BR1,THLF,IO,DFA  I128  JP12
   3    GND      3 @T6G_MB_LIB.T6G(SCH_1):GND
   2 P1V5_BAT      2 @T6G_MB_LIB.T6G(SCH_1):P1V5_BAT
   1 P1V5_BAT_OUT_R      1 @T6G_MB_LIB.T6G(SCH_1):P1V5_BAT_OUT_R

Q_RES_0402LF-1K,1%,1/16W,CHIP,CS21002FB06  I129  R1777
   1 P1V5_BAT_IN      A @T6G_MB_LIB.T6G(SCH_1):P1V5_BAT_IN
   2 BAT_LDO_EN      B @T6G_MB_LIB.T6G(SCH_1):BAT_LDO_EN

NCP698SQ15T1G-NCP698SQ15T1G,SMLF,EMPTY,AL000698000  I130  U167
   1    GND    GND @T6G_MB_LIB.T6G(SCH_1):GND
   3 P1V5_BAT_OUT   VOUT @T6G_MB_LIB.T6G(SCH_1):P1V5_BAT_OUT
   2 P1V5_BAT_IN    VIN @T6G_MB_LIB.T6G(SCH_1):P1V5_BAT_IN
   4 BAT_LDO_EN     EN @T6G_MB_LIB.T6G(SCH_1):BAT_LDO_EN

Q_RES_0402LF-1K,1%,1/16W,CHIP,CS21002FB06  I131  R1775
   1 P3V_BAT      A @T6G_MB_LIB.T6G(SCH_1):P3V_BAT
   2 P3V_BAT_R      B @T6G_MB_LIB.T6G(SCH_1):P3V_BAT_R


DRAWING: @T6G_MB_LIB.T6G(SCH_1):PAGE391 

PT5161LRS-PT5161LRS,SMLF,IC,AJ051610U03  I5  U6015
  G1 RT_CPU1_P1_VQPS   VQPS @T6G_MB_LIB.T6G(SCH_1):RT_CPU1_P1_VQPS
BV20 P1V8_CPU1_RT1_1A PWR_1A_1 @T6G_MB_LIB.T6G(SCH_1):P1V8_CPU1_RT1_1A
CE17 P1V8_CPU1_RT1_1A PWR_1A_2 @T6G_MB_LIB.T6G(SCH_1):P1V8_CPU1_RT1_1A
CE20 P1V8_CPU1_RT1_1A PWR_1A_3 @T6G_MB_LIB.T6G(SCH_1):P1V8_CPU1_RT1_1A
CM17 P1V8_CPU1_RT1_1A PWR_1A_4 @T6G_MB_LIB.T6G(SCH_1):P1V8_CPU1_RT1_1A
CM20 P1V8_CPU1_RT1_1A PWR_1A_5 @T6G_MB_LIB.T6G(SCH_1):P1V8_CPU1_RT1_1A
BL17 P0V9_CPU1_RT_2D PWR_2D_1 @T6G_MB_LIB.T6G(SCH_1):P0V9_CPU1_RT_2D
BL20 P0V9_CPU1_RT_2D PWR_2D_2 @T6G_MB_LIB.T6G(SCH_1):P0V9_CPU1_RT_2D
CW17 P0V9_CPU1_RT_2D PWR_2D_3 @T6G_MB_LIB.T6G(SCH_1):P0V9_CPU1_RT_2D
CW20 P0V9_CPU1_RT_2D PWR_2D_4 @T6G_MB_LIB.T6G(SCH_1):P0V9_CPU1_RT_2D
BV17 P1V8_CPU1_RT1_1A_1D PWR_1D @T6G_MB_LIB.T6G(SCH_1):P1V8_CPU1_RT1_1A_1D
AC17 P0V9_CPU1_RT1_2A PWR_2A_1 @T6G_MB_LIB.T6G(SCH_1):P0V9_CPU1_RT1_2A
AC20 P0V9_CPU1_RT1_2A PWR_2A_2 @T6G_MB_LIB.T6G(SCH_1):P0V9_CPU1_RT1_2A
AK17 P0V9_CPU1_RT1_2A PWR_2A_3 @T6G_MB_LIB.T6G(SCH_1):P0V9_CPU1_RT1_2A
AK20 P0V9_CPU1_RT1_2A PWR_2A_4 @T6G_MB_LIB.T6G(SCH_1):P0V9_CPU1_RT1_2A
AU17 P0V9_CPU1_RT1_2A PWR_2A_5 @T6G_MB_LIB.T6G(SCH_1):P0V9_CPU1_RT1_2A
AU20 P0V9_CPU1_RT1_2A PWR_2A_6 @T6G_MB_LIB.T6G(SCH_1):P0V9_CPU1_RT1_2A
BD17 P0V9_CPU1_RT1_2A_2D PWR_2A_7 @T6G_MB_LIB.T6G(SCH_1):P0V9_CPU1_RT1_2A_2D
BD20 P0V9_CPU1_RT1_2A_2D PWR_2A_8 @T6G_MB_LIB.T6G(SCH_1):P0V9_CPU1_RT1_2A_2D
DF17 P0V9_CPU1_RT1_2A_2D PWR_2A_9 @T6G_MB_LIB.T6G(SCH_1):P0V9_CPU1_RT1_2A_2D
DF20 P0V9_CPU1_RT1_2A_2D PWR_2A_10 @T6G_MB_LIB.T6G(SCH_1):P0V9_CPU1_RT1_2A_2D
DN17 P0V9_CPU1_RT1_2A PWR_2A_11 @T6G_MB_LIB.T6G(SCH_1):P0V9_CPU1_RT1_2A
DN20 P0V9_CPU1_RT1_2A PWR_2A_12 @T6G_MB_LIB.T6G(SCH_1):P0V9_CPU1_RT1_2A
DY17 P0V9_CPU1_RT1_2A PWR_2A_13 @T6G_MB_LIB.T6G(SCH_1):P0V9_CPU1_RT1_2A
DY20 P0V9_CPU1_RT1_2A PWR_2A_14 @T6G_MB_LIB.T6G(SCH_1):P0V9_CPU1_RT1_2A
EG17 P0V9_CPU1_RT1_2A PWR_2A_15 @T6G_MB_LIB.T6G(SCH_1):P0V9_CPU1_RT1_2A
EG20 P0V9_CPU1_RT1_2A PWR_2A_16 @T6G_MB_LIB.T6G(SCH_1):P0V9_CPU1_RT1_2A
EP17 P0V9_CPU1_RT1_2A PWR_2A_17 @T6G_MB_LIB.T6G(SCH_1):P0V9_CPU1_RT1_2A
EP20 P0V9_CPU1_RT1_2A PWR_2A_18 @T6G_MB_LIB.T6G(SCH_1):P0V9_CPU1_RT1_2A
 T17 P0V9_CPU1_RT1_2A PWR_2A_19 @T6G_MB_LIB.T6G(SCH_1):P0V9_CPU1_RT1_2A
 T20 P0V9_CPU1_RT1_2A PWR_2A_20 @T6G_MB_LIB.T6G(SCH_1):P0V9_CPU1_RT1_2A

Q_RES_0201LF-0,5%,1/20W,CHIP,CS00001JE10  I15  R6733
   1 NCF_CPU1_P1_GND      A @T6G_MB_LIB.T6G(SCH_1):NCF_CPU1_P1_GND
   2    GND      B @T6G_MB_LIB.T6G(SCH_1):GND

Q_RES_0201LF-0,5%,1/20W,CHIP,CS00001JE10  I16  R6732
   1 NCF_A1_CPU1_P1_GND      A @T6G_MB_LIB.T6G(SCH_1):NCF_A1_CPU1_P1_GND
   2    GND      B @T6G_MB_LIB.T6G(SCH_1):GND

PT5161LRS-PT5161LRS,SMLF,IC,AJ051610U03  I19  U6015
AC13    GND   GND1 @T6G_MB_LIB.T6G(SCH_1):GND
AC22    GND   GND2 @T6G_MB_LIB.T6G(SCH_1):GND
AC32    GND   GND3 @T6G_MB_LIB.T6G(SCH_1):GND
 AC4    GND   GND4 @T6G_MB_LIB.T6G(SCH_1):GND
 AD2    GND   GND5 @T6G_MB_LIB.T6G(SCH_1):GND
AD34    GND   GND6 @T6G_MB_LIB.T6G(SCH_1):GND
 AE1    GND   GND7 @T6G_MB_LIB.T6G(SCH_1):GND
AE35    GND   GND8 @T6G_MB_LIB.T6G(SCH_1):GND
AK13    GND   GND9 @T6G_MB_LIB.T6G(SCH_1):GND
AK22    GND  GND10 @T6G_MB_LIB.T6G(SCH_1):GND
AK32    GND  GND11 @T6G_MB_LIB.T6G(SCH_1):GND
 AK4    GND  GND12 @T6G_MB_LIB.T6G(SCH_1):GND
 AL2    GND  GND13 @T6G_MB_LIB.T6G(SCH_1):GND
AL34    GND  GND14 @T6G_MB_LIB.T6G(SCH_1):GND
 AM1    GND  GND15 @T6G_MB_LIB.T6G(SCH_1):GND
AM35    GND  GND16 @T6G_MB_LIB.T6G(SCH_1):GND
AU13    GND  GND17 @T6G_MB_LIB.T6G(SCH_1):GND
AU22    GND  GND18 @T6G_MB_LIB.T6G(SCH_1):GND
AU32    GND  GND19 @T6G_MB_LIB.T6G(SCH_1):GND
 AU4    GND  GND20 @T6G_MB_LIB.T6G(SCH_1):GND
 AV2    GND  GND21 @T6G_MB_LIB.T6G(SCH_1):GND
AV34    GND  GND22 @T6G_MB_LIB.T6G(SCH_1):GND
 AW1    GND  GND23 @T6G_MB_LIB.T6G(SCH_1):GND
AW35    GND  GND24 @T6G_MB_LIB.T6G(SCH_1):GND
 B19    GND  GND25 @T6G_MB_LIB.T6G(SCH_1):GND
BD13    GND  GND26 @T6G_MB_LIB.T6G(SCH_1):GND
BD22    GND  GND27 @T6G_MB_LIB.T6G(SCH_1):GND
BD32    GND  GND28 @T6G_MB_LIB.T6G(SCH_1):GND
 BD4    GND  GND29 @T6G_MB_LIB.T6G(SCH_1):GND
 BE2    GND  GND30 @T6G_MB_LIB.T6G(SCH_1):GND
BE34    GND  GND31 @T6G_MB_LIB.T6G(SCH_1):GND
 BF1    GND  GND32 @T6G_MB_LIB.T6G(SCH_1):GND
BF35    GND  GND33 @T6G_MB_LIB.T6G(SCH_1):GND
BL13    GND  GND34 @T6G_MB_LIB.T6G(SCH_1):GND
BL22    GND  GND35 @T6G_MB_LIB.T6G(SCH_1):GND
BL32    GND  GND36 @T6G_MB_LIB.T6G(SCH_1):GND
 BL4    GND  GND37 @T6G_MB_LIB.T6G(SCH_1):GND
 BM2    GND  GND38 @T6G_MB_LIB.T6G(SCH_1):GND
BM34    GND  GND39 @T6G_MB_LIB.T6G(SCH_1):GND
 BN1    GND  GND40 @T6G_MB_LIB.T6G(SCH_1):GND
BN35    GND  GND41 @T6G_MB_LIB.T6G(SCH_1):GND
BV13    GND  GND42 @T6G_MB_LIB.T6G(SCH_1):GND
BV22    GND  GND43 @T6G_MB_LIB.T6G(SCH_1):GND
BV32    GND  GND44 @T6G_MB_LIB.T6G(SCH_1):GND
 BV4    GND  GND45 @T6G_MB_LIB.T6G(SCH_1):GND
 BW2    GND  GND46 @T6G_MB_LIB.T6G(SCH_1):GND
BW34    GND  GND47 @T6G_MB_LIB.T6G(SCH_1):GND
 BY1    GND  GND48 @T6G_MB_LIB.T6G(SCH_1):GND
BY35    GND  GND49 @T6G_MB_LIB.T6G(SCH_1):GND
CE13    GND  GND50 @T6G_MB_LIB.T6G(SCH_1):GND
CE22    GND  GND51 @T6G_MB_LIB.T6G(SCH_1):GND
CE32    GND  GND52 @T6G_MB_LIB.T6G(SCH_1):GND
 CE4    GND  GND53 @T6G_MB_LIB.T6G(SCH_1):GND
 CF2    GND  GND54 @T6G_MB_LIB.T6G(SCH_1):GND
CF34    GND  GND55 @T6G_MB_LIB.T6G(SCH_1):GND
 CG1    GND  GND56 @T6G_MB_LIB.T6G(SCH_1):GND
CG35    GND  GND57 @T6G_MB_LIB.T6G(SCH_1):GND
CM13    GND  GND58 @T6G_MB_LIB.T6G(SCH_1):GND
CM22    GND  GND59 @T6G_MB_LIB.T6G(SCH_1):GND
CM32    GND  GND60 @T6G_MB_LIB.T6G(SCH_1):GND
 CM4    GND  GND61 @T6G_MB_LIB.T6G(SCH_1):GND
 CN2    GND  GND62 @T6G_MB_LIB.T6G(SCH_1):GND
CN34    GND  GND63 @T6G_MB_LIB.T6G(SCH_1):GND
 CP1    GND  GND64 @T6G_MB_LIB.T6G(SCH_1):GND
CP35    GND  GND65 @T6G_MB_LIB.T6G(SCH_1):GND
CW13    GND  GND66 @T6G_MB_LIB.T6G(SCH_1):GND
CW22    GND  GND67 @T6G_MB_LIB.T6G(SCH_1):GND
CW32    GND  GND68 @T6G_MB_LIB.T6G(SCH_1):GND
 CW4    GND  GND69 @T6G_MB_LIB.T6G(SCH_1):GND
 CY2    GND  GND70 @T6G_MB_LIB.T6G(SCH_1):GND
CY34    GND  GND71 @T6G_MB_LIB.T6G(SCH_1):GND
 DA1    GND  GND72 @T6G_MB_LIB.T6G(SCH_1):GND
DA35    GND  GND73 @T6G_MB_LIB.T6G(SCH_1):GND
DF13    GND  GND74 @T6G_MB_LIB.T6G(SCH_1):GND
DF22    GND  GND75 @T6G_MB_LIB.T6G(SCH_1):GND
DF32    GND  GND76 @T6G_MB_LIB.T6G(SCH_1):GND
 DF4    GND  GND77 @T6G_MB_LIB.T6G(SCH_1):GND
 DG2    GND  GND78 @T6G_MB_LIB.T6G(SCH_1):GND
DG34    GND  GND79 @T6G_MB_LIB.T6G(SCH_1):GND
 DH1    GND  GND80 @T6G_MB_LIB.T6G(SCH_1):GND
DH35    GND  GND81 @T6G_MB_LIB.T6G(SCH_1):GND
DN13    GND  GND82 @T6G_MB_LIB.T6G(SCH_1):GND
  A1 NCF_A1_CPU1_P1_GND NCF_GND1 @T6G_MB_LIB.T6G(SCH_1):NCF_A1_CPU1_P1_GND
 A35 NCF_CPU1_P1_GND NCF_GND2 @T6G_MB_LIB.T6G(SCH_1):NCF_CPU1_P1_GND
  C2 NCF_CPU1_P1_GND NCF_GND3 @T6G_MB_LIB.T6G(SCH_1):NCF_CPU1_P1_GND
 C34 NCF_CPU1_P1_GND NCF_GND4 @T6G_MB_LIB.T6G(SCH_1):NCF_CPU1_P1_GND
  D1 NCF_CPU1_P1_GND NCF_GND5 @T6G_MB_LIB.T6G(SCH_1):NCF_CPU1_P1_GND
 D35 NCF_CPU1_P1_GND NCF_GND6 @T6G_MB_LIB.T6G(SCH_1):NCF_CPU1_P1_GND
 FE2 NCF_CPU1_P1_GND NCF_GND7 @T6G_MB_LIB.T6G(SCH_1):NCF_CPU1_P1_GND
FE34 NCF_CPU1_P1_GND NCF_GND8 @T6G_MB_LIB.T6G(SCH_1):NCF_CPU1_P1_GND
 FG1 NCF_CPU1_P1_GND NCF_GND9 @T6G_MB_LIB.T6G(SCH_1):NCF_CPU1_P1_GND
FG35 NCF_CPU1_P1_GND NCF_GND10 @T6G_MB_LIB.T6G(SCH_1):NCF_CPU1_P1_GND
 FH2 NCF_CPU1_P1_GND NCF_GND11 @T6G_MB_LIB.T6G(SCH_1):NCF_CPU1_P1_GND
FH34 NCF_CPU1_P1_GND NCF_GND12 @T6G_MB_LIB.T6G(SCH_1):NCF_CPU1_P1_GND
DN22    GND  GND83 @T6G_MB_LIB.T6G(SCH_1):GND
DN32    GND  GND84 @T6G_MB_LIB.T6G(SCH_1):GND
 DN4    GND  GND85 @T6G_MB_LIB.T6G(SCH_1):GND
 DP2    GND  GND86 @T6G_MB_LIB.T6G(SCH_1):GND
DP34    GND  GND87 @T6G_MB_LIB.T6G(SCH_1):GND
 DR1    GND  GND88 @T6G_MB_LIB.T6G(SCH_1):GND
DR35    GND  GND89 @T6G_MB_LIB.T6G(SCH_1):GND
DY13    GND  GND90 @T6G_MB_LIB.T6G(SCH_1):GND
DY22    GND  GND91 @T6G_MB_LIB.T6G(SCH_1):GND
DY32    GND  GND92 @T6G_MB_LIB.T6G(SCH_1):GND
 DY4    GND  GND93 @T6G_MB_LIB.T6G(SCH_1):GND
 E14    GND  GND94 @T6G_MB_LIB.T6G(SCH_1):GND
 E27    GND  GND95 @T6G_MB_LIB.T6G(SCH_1):GND
 E33    GND  GND96 @T6G_MB_LIB.T6G(SCH_1):GND
 EA2    GND  GND97 @T6G_MB_LIB.T6G(SCH_1):GND
EA34    GND  GND98 @T6G_MB_LIB.T6G(SCH_1):GND
 EB1    GND  GND99 @T6G_MB_LIB.T6G(SCH_1):GND
EB35    GND GND100 @T6G_MB_LIB.T6G(SCH_1):GND
EG13    GND GND101 @T6G_MB_LIB.T6G(SCH_1):GND
EG22    GND GND102 @T6G_MB_LIB.T6G(SCH_1):GND
EG32    GND GND103 @T6G_MB_LIB.T6G(SCH_1):GND
 EG4    GND GND104 @T6G_MB_LIB.T6G(SCH_1):GND
 EH2    GND GND105 @T6G_MB_LIB.T6G(SCH_1):GND
EH34    GND GND106 @T6G_MB_LIB.T6G(SCH_1):GND
 EJ1    GND GND107 @T6G_MB_LIB.T6G(SCH_1):GND
EJ35    GND GND108 @T6G_MB_LIB.T6G(SCH_1):GND
EP13    GND GND109 @T6G_MB_LIB.T6G(SCH_1):GND
EP22    GND GND110 @T6G_MB_LIB.T6G(SCH_1):GND
EP32    GND GND111 @T6G_MB_LIB.T6G(SCH_1):GND
 EP4    GND GND112 @T6G_MB_LIB.T6G(SCH_1):GND
 ER2    GND GND113 @T6G_MB_LIB.T6G(SCH_1):GND
ER34    GND GND114 @T6G_MB_LIB.T6G(SCH_1):GND
 ET1    GND GND115 @T6G_MB_LIB.T6G(SCH_1):GND
ET35    GND GND116 @T6G_MB_LIB.T6G(SCH_1):GND
FA15    GND GND117 @T6G_MB_LIB.T6G(SCH_1):GND
FA32    GND GND118 @T6G_MB_LIB.T6G(SCH_1):GND
 FB2    GND GND119 @T6G_MB_LIB.T6G(SCH_1):GND
FB34    GND GND120 @T6G_MB_LIB.T6G(SCH_1):GND
FC19    GND GND121 @T6G_MB_LIB.T6G(SCH_1):GND
FC23    GND GND122 @T6G_MB_LIB.T6G(SCH_1):GND
FC25    GND GND123 @T6G_MB_LIB.T6G(SCH_1):GND
FC28    GND GND124 @T6G_MB_LIB.T6G(SCH_1):GND
 FC3    GND GND125 @T6G_MB_LIB.T6G(SCH_1):GND
 FC6    GND GND126 @T6G_MB_LIB.T6G(SCH_1):GND
 FC9    GND GND127 @T6G_MB_LIB.T6G(SCH_1):GND
 FD1    GND GND128 @T6G_MB_LIB.T6G(SCH_1):GND
FD35    GND GND129 @T6G_MB_LIB.T6G(SCH_1):GND
FF14    GND GND130 @T6G_MB_LIB.T6G(SCH_1):GND
FF21    GND GND131 @T6G_MB_LIB.T6G(SCH_1):GND
FJ12    GND GND132 @T6G_MB_LIB.T6G(SCH_1):GND
FJ19    GND GND133 @T6G_MB_LIB.T6G(SCH_1):GND
 H12    GND GND134 @T6G_MB_LIB.T6G(SCH_1):GND
 H16    GND GND135 @T6G_MB_LIB.T6G(SCH_1):GND
 H19    GND GND136 @T6G_MB_LIB.T6G(SCH_1):GND
 H31    GND GND137 @T6G_MB_LIB.T6G(SCH_1):GND
 J22    GND GND138 @T6G_MB_LIB.T6G(SCH_1):GND
  J4    GND GND139 @T6G_MB_LIB.T6G(SCH_1):GND
  K2    GND GND140 @T6G_MB_LIB.T6G(SCH_1):GND
 K34    GND GND141 @T6G_MB_LIB.T6G(SCH_1):GND
  L1    GND GND142 @T6G_MB_LIB.T6G(SCH_1):GND
 L35    GND GND143 @T6G_MB_LIB.T6G(SCH_1):GND
 T13    GND GND144 @T6G_MB_LIB.T6G(SCH_1):GND
 T22    GND GND145 @T6G_MB_LIB.T6G(SCH_1):GND
 T32    GND GND146 @T6G_MB_LIB.T6G(SCH_1):GND
  T4    GND GND147 @T6G_MB_LIB.T6G(SCH_1):GND
  U2    GND GND148 @T6G_MB_LIB.T6G(SCH_1):GND
 U34    GND GND149 @T6G_MB_LIB.T6G(SCH_1):GND
  V1    GND GND150 @T6G_MB_LIB.T6G(SCH_1):GND
 V35    GND GND151 @T6G_MB_LIB.T6G(SCH_1):GND

Q_RES_0201LF-200,1%,1/20W,CHIP,CS12001FE12  I20  R6731
   1 RT_CPU1_P1_VQPS      A @T6G_MB_LIB.T6G(SCH_1):RT_CPU1_P1_VQPS
   2    GND      B @T6G_MB_LIB.T6G(SCH_1):GND

Q_RES_0201LF-1K,1%,1/20W,EMPTY,CS21001FE07  I21  R6730
   1 P1V8_CPU1_RT_1D      A @T6G_MB_LIB.T6G(SCH_1):P1V8_CPU1_RT_1D
   2 RT_CPU1_P1_VQPS      B @T6G_MB_LIB.T6G(SCH_1):RT_CPU1_P1_VQPS


DRAWING: @T6G_MB_LIB.T6G(SCH_1):PAGE443 

Q_RES_0402LF-0,5%,1/16W,EMPTY,CS00002JB13  I4  R664
   1 P1V8_CPU1_RT1_1A_1D      A @T6G_MB_LIB.T6G(SCH_1):P1V8_CPU1_RT1_1A_1D
   2 P1V8_CPU1_RT1_1A      B @T6G_MB_LIB.T6G(SCH_1):P1V8_CPU1_RT1_1A

Q_RES_0402LF-0,5%,1/16W,EMPTY,CS00002JB13  I5  R653
   1 P1V8_CPU1_RT1_1A_1D      A @T6G_MB_LIB.T6G(SCH_1):P1V8_CPU1_RT1_1A_1D
   2 P1V8_CPU1_RT1_1A      B @T6G_MB_LIB.T6G(SCH_1):P1V8_CPU1_RT1_1A

Q_CAP_0201-1UF,4V,20%,X6S,CH-10KMEE00  I8  C203
   1 P1V8_CPU1_RT1_1A_1D      A @T6G_MB_LIB.T6G(SCH_1):P1V8_CPU1_RT1_1A_1D
   2    GND      B @T6G_MB_LIB.T6G(SCH_1):GND

Q_CAP_C0201-0.1UF,10V,10%,X7S,CH4102K6E00  I9  C206
   1 P1V8_CPU1_RT1_1A_1D      A @T6G_MB_LIB.T6G(SCH_1):P1V8_CPU1_RT1_1A_1D
   2    GND      B @T6G_MB_LIB.T6G(SCH_1):GND

Q_RES_0603LF-0,5%,1/4W,EMPTY,CS00006J900  I10  R705
   1 P0V9_CPU1_RT_2D      A @T6G_MB_LIB.T6G(SCH_1):P0V9_CPU1_RT_2D
   2 P0V9_CPU1_RT1_2A_2D      B @T6G_MB_LIB.T6G(SCH_1):P0V9_CPU1_RT1_2A_2D

Q_RES_0603LF-0,5%,1/4W,CHIP,CS00006J900  I11  R712
   1 P0V9_CPU1_RT1_2A_2D      A @T6G_MB_LIB.T6G(SCH_1):P0V9_CPU1_RT1_2A_2D
   2 P0V9_CPU1_RT1_2A      B @T6G_MB_LIB.T6G(SCH_1):P0V9_CPU1_RT1_2A

Q_INDUCTOR_SMLF-BLM21SN300SN1D/5A,IND,CX300SN1000  I12  L5
   2 P1V8_CPU1_RT1_1A      2 @T6G_MB_LIB.T6G(SCH_1):P1V8_CPU1_RT1_1A
   1 P1V8_CPU1_RT_1D      1 @T6G_MB_LIB.T6G(SCH_1):P1V8_CPU1_RT_1D

Q_CAP_C0805-100UF,4V,20%,X6S,CH710KMEA01  I13  C103
   1 P1V8_CPU1_RT1_1A      A @T6G_MB_LIB.T6G(SCH_1):P1V8_CPU1_RT1_1A
   2    GND      B @T6G_MB_LIB.T6G(SCH_1):GND

Q_CAP_C0402-22UF,4V,20%,X6S,CH622KMEB02  I14  C111
   1 P1V8_CPU1_RT1_1A      A @T6G_MB_LIB.T6G(SCH_1):P1V8_CPU1_RT1_1A
   2    GND      B @T6G_MB_LIB.T6G(SCH_1):GND

Q_CAP_C0805-100UF,4V,20%,X6S,CH710KMEA01  I16  C102
   1 P1V8_CPU1_RT_1D      A @T6G_MB_LIB.T6G(SCH_1):P1V8_CPU1_RT_1D
   2    GND      B @T6G_MB_LIB.T6G(SCH_1):GND

Q_CAP_C0402-10UF,6.3V,20%,X6S,CH6101MEB01  I17  C199
   1 P1V8_CPU1_RT1_1A      A @T6G_MB_LIB.T6G(SCH_1):P1V8_CPU1_RT1_1A
   2    GND      B @T6G_MB_LIB.T6G(SCH_1):GND

Q_CAP_0402-4.7UF,6.3V,20%,X6S,CH5471MEB01  I18  C195
   1 P1V8_CPU1_RT1_1A      A @T6G_MB_LIB.T6G(SCH_1):P1V8_CPU1_RT1_1A
   2    GND      B @T6G_MB_LIB.T6G(SCH_1):GND

Q_CAP_0201-1UF,4V,20%,X6S,CH-10KMEE00  I20  C202
   1 P1V8_CPU1_RT1_1A      A @T6G_MB_LIB.T6G(SCH_1):P1V8_CPU1_RT1_1A
   2    GND      B @T6G_MB_LIB.T6G(SCH_1):GND

Q_CAP_0201-1UF,4V,20%,X6S,CH-10KMEE00  I22  C204
   1 P1V8_CPU1_RT1_1A      A @T6G_MB_LIB.T6G(SCH_1):P1V8_CPU1_RT1_1A
   2    GND      B @T6G_MB_LIB.T6G(SCH_1):GND

Q_CAP_C0201-0.1UF,10V,10%,X7S,CH4102K6E00  I23  C205
   1 P1V8_CPU1_RT1_1A      A @T6G_MB_LIB.T6G(SCH_1):P1V8_CPU1_RT1_1A
   2    GND      B @T6G_MB_LIB.T6G(SCH_1):GND

Q_CAP_C0402-22UF,4V,20%,X6S,CH622KMEB02  I24  C110
   1 P1V8_CPU1_RT_1D      A @T6G_MB_LIB.T6G(SCH_1):P1V8_CPU1_RT_1D
   2    GND      B @T6G_MB_LIB.T6G(SCH_1):GND

Q_CAP_C0402-10UF,6.3V,20%,X6S,CH6101MEB01  I25  C127
   1 P1V8_CPU1_RT_1D      A @T6G_MB_LIB.T6G(SCH_1):P1V8_CPU1_RT_1D
   2    GND      B @T6G_MB_LIB.T6G(SCH_1):GND

Q_CAP_0402-4.7UF,6.3V,20%,X6S,CH5471MEB01  I26  C200
   1 P1V8_CPU1_RT_1D      A @T6G_MB_LIB.T6G(SCH_1):P1V8_CPU1_RT_1D
   2    GND      B @T6G_MB_LIB.T6G(SCH_1):GND

Q_CAP_C0201-0.1UF,10V,10%,X7S,CH4102K6E00  I27  C217
   1 P1V8_CPU1_RT1_1A      A @T6G_MB_LIB.T6G(SCH_1):P1V8_CPU1_RT1_1A
   2    GND      B @T6G_MB_LIB.T6G(SCH_1):GND

Q_CAP_C0201-0.1UF,10V,10%,X7S,CH4102K6E00  I28  C287
   1 P1V8_CPU1_RT1_1A      A @T6G_MB_LIB.T6G(SCH_1):P1V8_CPU1_RT1_1A
   2    GND      B @T6G_MB_LIB.T6G(SCH_1):GND

Q_CAP_C0201-0.1UF,10V,10%,X7S,CH4102K6E00  I29  C288
   1 P1V8_CPU1_RT1_1A      A @T6G_MB_LIB.T6G(SCH_1):P1V8_CPU1_RT1_1A
   2    GND      B @T6G_MB_LIB.T6G(SCH_1):GND

Q_INDUCTOR_SMLF-100NH/16A,IND,CV+10G0MZ04  I30  L6
   2 P0V9_CPU1_RT1_2A      2 @T6G_MB_LIB.T6G(SCH_1):P0V9_CPU1_RT1_2A
   1 P0V9_CPU1_RT_2D      1 @T6G_MB_LIB.T6G(SCH_1):P0V9_CPU1_RT_2D

Q_CAP_C0201-0.1UF,10V,10%,X7S,CH4102K6E00  I34  C313
   1 P0V9_CPU1_RT1_2A_2D      A @T6G_MB_LIB.T6G(SCH_1):P0V9_CPU1_RT1_2A_2D
   2    GND      B @T6G_MB_LIB.T6G(SCH_1):GND

Q_CAP_C0201-0.1UF,10V,10%,X7S,CH4102K6E00  I37  C316
   1 P0V9_CPU1_RT1_2A_2D      A @T6G_MB_LIB.T6G(SCH_1):P0V9_CPU1_RT1_2A_2D
   2    GND      B @T6G_MB_LIB.T6G(SCH_1):GND

Q_CAP_C0201-0.1UF,10V,10%,X7S,CH4102K6E00  I38  C340
   1 P0V9_CPU1_RT1_2A      A @T6G_MB_LIB.T6G(SCH_1):P0V9_CPU1_RT1_2A
   2    GND      B @T6G_MB_LIB.T6G(SCH_1):GND

Q_CAP_C0201-0.1UF,10V,10%,X7S,CH4102K6E00  I39  C344
   1 P0V9_CPU1_RT1_2A      A @T6G_MB_LIB.T6G(SCH_1):P0V9_CPU1_RT1_2A
   2    GND      B @T6G_MB_LIB.T6G(SCH_1):GND

Q_CAP_0201-1UF,4V,20%,X6S,CH-10KMEE00  I40  C294
   1 P0V9_CPU1_RT1_2A      A @T6G_MB_LIB.T6G(SCH_1):P0V9_CPU1_RT1_2A
   2    GND      B @T6G_MB_LIB.T6G(SCH_1):GND

Q_CAP_C0402-10UF,6.3V,20%,X6S,CH6101MEB01  I41  C332
   1 P0V9_CPU1_RT1_2A      A @T6G_MB_LIB.T6G(SCH_1):P0V9_CPU1_RT1_2A
   2    GND      B @T6G_MB_LIB.T6G(SCH_1):GND

Q_CAP_0201-1UF,4V,20%,X6S,CH-10KMEE00  I42  C307
   1 P0V9_CPU1_RT1_2A      A @T6G_MB_LIB.T6G(SCH_1):P0V9_CPU1_RT1_2A
   2    GND      B @T6G_MB_LIB.T6G(SCH_1):GND

Q_CAP_0201-1UF,4V,20%,X6S,CH-10KMEE00  I43  C326
   1 P0V9_CPU1_RT1_2A      A @T6G_MB_LIB.T6G(SCH_1):P0V9_CPU1_RT1_2A
   2    GND      B @T6G_MB_LIB.T6G(SCH_1):GND

Q_CAP_C0402-10UF,6.3V,20%,X6S,CH6101MEB01  I44  C321
   1 P0V9_CPU1_RT1_2A      A @T6G_MB_LIB.T6G(SCH_1):P0V9_CPU1_RT1_2A
   2    GND      B @T6G_MB_LIB.T6G(SCH_1):GND

Q_CAP_0402-4.7UF,6.3V,20%,X6S,CH5471MEB01  I45  C325
   1 P0V9_CPU1_RT1_2A      A @T6G_MB_LIB.T6G(SCH_1):P0V9_CPU1_RT1_2A
   2    GND      B @T6G_MB_LIB.T6G(SCH_1):GND

Q_CAP_0402-4.7UF,6.3V,20%,X6S,CH5471MEB01  I46  C331
   1 P0V9_CPU1_RT1_2A      A @T6G_MB_LIB.T6G(SCH_1):P0V9_CPU1_RT1_2A
   2    GND      B @T6G_MB_LIB.T6G(SCH_1):GND

Q_CAP_0201-1UF,4V,20%,X6S,CH-10KMEE00  I47  C330
   1 P0V9_CPU1_RT1_2A      A @T6G_MB_LIB.T6G(SCH_1):P0V9_CPU1_RT1_2A
   2    GND      B @T6G_MB_LIB.T6G(SCH_1):GND

Q_CAP_C0201-0.1UF,10V,10%,X7S,CH4102K6E00  I48  C312
   1 P0V9_CPU1_RT1_2A      A @T6G_MB_LIB.T6G(SCH_1):P0V9_CPU1_RT1_2A
   2    GND      B @T6G_MB_LIB.T6G(SCH_1):GND

Q_CAP_C0201-0.1UF,10V,10%,X7S,CH4102K6E00  I49  C349
   1 P0V9_CPU1_RT1_2A      A @T6G_MB_LIB.T6G(SCH_1):P0V9_CPU1_RT1_2A
   2    GND      B @T6G_MB_LIB.T6G(SCH_1):GND

Q_CAP_C0201-0.1UF,10V,10%,X7S,CH4102K6E00  I50  C291
   1 P0V9_CPU1_RT1_2A      A @T6G_MB_LIB.T6G(SCH_1):P0V9_CPU1_RT1_2A
   2    GND      B @T6G_MB_LIB.T6G(SCH_1):GND

Q_CAP_C0201-0.1UF,10V,10%,X7S,CH4102K6E00  I51  C319
   1 P0V9_CPU1_RT1_2A      A @T6G_MB_LIB.T6G(SCH_1):P0V9_CPU1_RT1_2A
   2    GND      B @T6G_MB_LIB.T6G(SCH_1):GND

Q_CAP_0201-1UF,4V,20%,X6S,CH-10KMEE00  I52  C314
   1 P0V9_CPU1_RT1_2A      A @T6G_MB_LIB.T6G(SCH_1):P0V9_CPU1_RT1_2A
   2    GND      B @T6G_MB_LIB.T6G(SCH_1):GND

Q_CAP_0201-1UF,4V,20%,X6S,CH-10KMEE00  I53  C337
   1 P0V9_CPU1_RT1_2A      A @T6G_MB_LIB.T6G(SCH_1):P0V9_CPU1_RT1_2A
   2    GND      B @T6G_MB_LIB.T6G(SCH_1):GND

Q_CAP_0402-4.7UF,6.3V,20%,X6S,CH5471MEB01  I54  C343
   1 P0V9_CPU1_RT1_2A      A @T6G_MB_LIB.T6G(SCH_1):P0V9_CPU1_RT1_2A
   2    GND      B @T6G_MB_LIB.T6G(SCH_1):GND

Q_CAP_0402-4.7UF,6.3V,20%,X6S,CH5471MEB01  I55  C336
   1 P0V9_CPU1_RT1_2A      A @T6G_MB_LIB.T6G(SCH_1):P0V9_CPU1_RT1_2A
   2    GND      B @T6G_MB_LIB.T6G(SCH_1):GND

Q_CAP_0201-1UF,4V,20%,X6S,CH-10KMEE00  I57  C346
   1 P0V9_CPU1_RT1_2A      A @T6G_MB_LIB.T6G(SCH_1):P0V9_CPU1_RT1_2A
   2    GND      B @T6G_MB_LIB.T6G(SCH_1):GND

Q_CAP_0201-1UF,4V,20%,X6S,CH-10KMEE00  I58  C293
   1 P0V9_CPU1_RT1_2A      A @T6G_MB_LIB.T6G(SCH_1):P0V9_CPU1_RT1_2A
   2    GND      B @T6G_MB_LIB.T6G(SCH_1):GND

Q_CAP_0201-1UF,4V,20%,X6S,CH-10KMEE00  I59  C301
   1 P0V9_CPU1_RT1_2A      A @T6G_MB_LIB.T6G(SCH_1):P0V9_CPU1_RT1_2A
   2    GND      B @T6G_MB_LIB.T6G(SCH_1):GND

Q_CAP_C0201-0.1UF,10V,10%,X7S,CH4102K6E00  I60  C322
   1 P0V9_CPU1_RT1_2A      A @T6G_MB_LIB.T6G(SCH_1):P0V9_CPU1_RT1_2A
   2    GND      B @T6G_MB_LIB.T6G(SCH_1):GND

Q_CAP_C0201-0.1UF,10V,10%,X7S,CH4102K6E00  I62  C334
   1 P0V9_CPU1_RT1_2A      A @T6G_MB_LIB.T6G(SCH_1):P0V9_CPU1_RT1_2A
   2    GND      B @T6G_MB_LIB.T6G(SCH_1):GND

Q_CAP_0201-1UF,4V,20%,X6S,CH-10KMEE00  I65  C289
   1 P0V9_CPU1_RT1_2A      A @T6G_MB_LIB.T6G(SCH_1):P0V9_CPU1_RT1_2A
   2    GND      B @T6G_MB_LIB.T6G(SCH_1):GND

Q_CAP_0201-1UF,4V,20%,X6S,CH-10KMEE00  I66  C353
   1 P0V9_CPU1_RT1_2A      A @T6G_MB_LIB.T6G(SCH_1):P0V9_CPU1_RT1_2A
   2    GND      B @T6G_MB_LIB.T6G(SCH_1):GND

Q_CAP_C0805-100UF,4V,20%,X6S,CH710KMEA01  I67  C317
   1 P0V9_CPU1_RT1_2A      A @T6G_MB_LIB.T6G(SCH_1):P0V9_CPU1_RT1_2A
   2    GND      B @T6G_MB_LIB.T6G(SCH_1):GND

Q_CAP_C0805-100UF,4V,20%,X6S,CH710KMEA01  I69  C320
   1 P0V9_CPU1_RT1_2A      A @T6G_MB_LIB.T6G(SCH_1):P0V9_CPU1_RT1_2A
   2    GND      B @T6G_MB_LIB.T6G(SCH_1):GND

Q_CAP_C0805-100UF,4V,20%,X6S,CH710KMEA01  I70  C324
   1 P0V9_CPU1_RT1_2A      A @T6G_MB_LIB.T6G(SCH_1):P0V9_CPU1_RT1_2A
   2    GND      B @T6G_MB_LIB.T6G(SCH_1):GND

Q_CAP_C0805-100UF,4V,20%,X6S,CH710KMEA01  I71  C328
   1 P0V9_CPU1_RT1_2A      A @T6G_MB_LIB.T6G(SCH_1):P0V9_CPU1_RT1_2A
   2    GND      B @T6G_MB_LIB.T6G(SCH_1):GND

Q_CAP_C0805-100UF,4V,20%,X6S,CH710KMEA01  I72  C323
   1 P0V9_CPU1_RT_2D      A @T6G_MB_LIB.T6G(SCH_1):P0V9_CPU1_RT_2D
   2    GND      B @T6G_MB_LIB.T6G(SCH_1):GND

Q_CAP_C0402-22UF,4V,20%,X6S,CH622KMEB02  I73  C327
   1 P0V9_CPU1_RT_2D      A @T6G_MB_LIB.T6G(SCH_1):P0V9_CPU1_RT_2D
   2    GND      B @T6G_MB_LIB.T6G(SCH_1):GND

Q_CAP_C0402-22UF,4V,20%,X6S,CH622KMEB02  I74  C329
   1 P0V9_CPU1_RT1_2A      A @T6G_MB_LIB.T6G(SCH_1):P0V9_CPU1_RT1_2A
   2    GND      B @T6G_MB_LIB.T6G(SCH_1):GND

Q_CAP_C0402-22UF,4V,20%,X6S,CH622KMEB02  I75  C335
   1 P0V9_CPU1_RT1_2A      A @T6G_MB_LIB.T6G(SCH_1):P0V9_CPU1_RT1_2A
   2    GND      B @T6G_MB_LIB.T6G(SCH_1):GND

Q_CAP_C0402-22UF,4V,20%,X6S,CH622KMEB02  I76  C351
   1 P0V9_CPU1_RT1_2A      A @T6G_MB_LIB.T6G(SCH_1):P0V9_CPU1_RT1_2A
   2    GND      B @T6G_MB_LIB.T6G(SCH_1):GND

Q_CAP_C0402-22UF,4V,20%,X6S,CH622KMEB02  I77  C318
   1 P0V9_CPU1_RT1_2A      A @T6G_MB_LIB.T6G(SCH_1):P0V9_CPU1_RT1_2A
   2    GND      B @T6G_MB_LIB.T6G(SCH_1):GND

Q_CAP_0402-4.7UF,6.3V,20%,X6S,CH5471MEB01  I78  C338
   1 P0V9_CPU1_RT_2D      A @T6G_MB_LIB.T6G(SCH_1):P0V9_CPU1_RT_2D
   2    GND      B @T6G_MB_LIB.T6G(SCH_1):GND

Q_CAP_0201-1UF,4V,20%,X6S,CH-10KMEE00  I79  C342
   1 P0V9_CPU1_RT_2D      A @T6G_MB_LIB.T6G(SCH_1):P0V9_CPU1_RT_2D
   2    GND      B @T6G_MB_LIB.T6G(SCH_1):GND

Q_CAP_C0402-10UF,6.3V,20%,X6S,CH6101MEB01  I80  C339
   1 P0V9_CPU1_RT1_2A      A @T6G_MB_LIB.T6G(SCH_1):P0V9_CPU1_RT1_2A
   2    GND      B @T6G_MB_LIB.T6G(SCH_1):GND

Q_CAP_C0402-10UF,6.3V,20%,X6S,CH6101MEB01  I81  C354
   1 P0V9_CPU1_RT1_2A      A @T6G_MB_LIB.T6G(SCH_1):P0V9_CPU1_RT1_2A
   2    GND      B @T6G_MB_LIB.T6G(SCH_1):GND

Q_CAP_C0201-0.1UF,10V,10%,X7S,CH4102K6E00  I82  C300
   1 P0V9_CPU1_RT_2D      A @T6G_MB_LIB.T6G(SCH_1):P0V9_CPU1_RT_2D
   2    GND      B @T6G_MB_LIB.T6G(SCH_1):GND

Q_CAP_C0201-0.1UF,10V,10%,X7S,CH4102K6E00  I84  C311
   1 P0V9_CPU1_RT_2D      A @T6G_MB_LIB.T6G(SCH_1):P0V9_CPU1_RT_2D
   2    GND      B @T6G_MB_LIB.T6G(SCH_1):GND

Q_CAP_C0201-0.1UF,10V,10%,X7S,CH4102K6E00  I85  C292
   1 P0V9_CPU1_RT_2D      A @T6G_MB_LIB.T6G(SCH_1):P0V9_CPU1_RT_2D
   2    GND      B @T6G_MB_LIB.T6G(SCH_1):GND

Q_CAP_C0201-0.1UF,10V,10%,X7S,CH4102K6E00  I86  C290
   1 P0V9_CPU1_RT_2D      A @T6G_MB_LIB.T6G(SCH_1):P0V9_CPU1_RT_2D
   2    GND      B @T6G_MB_LIB.T6G(SCH_1):GND

Q_CAP_C0402-10UF,6.3V,20%,X6S,CH6101MEB01  I87  C333
   1 P0V9_CPU1_RT_2D      A @T6G_MB_LIB.T6G(SCH_1):P0V9_CPU1_RT_2D
   2    GND      B @T6G_MB_LIB.T6G(SCH_1):GND

Q_INDUCTOR_SMLF-BLM15PD121SN1D/1300MA,IND,CX5PD121A  I88  L31
   2 P1V8_CPU1_RT1_1A_1D      2 @T6G_MB_LIB.T6G(SCH_1):P1V8_CPU1_RT1_1A_1D
   1 P1V8_CPU1_RT_1D      1 @T6G_MB_LIB.T6G(SCH_1):P1V8_CPU1_RT_1D

Q_RES_0402LF-0,5%,1/16W,EMPTY,CS00002JB13  I89  R704
   1 P1V8_CPU1_RT_1D      A @T6G_MB_LIB.T6G(SCH_1):P1V8_CPU1_RT_1D
   2 P1V8_CPU1_RT1_1A_1D      B @T6G_MB_LIB.T6G(SCH_1):P1V8_CPU1_RT1_1A_1D

Q_CAP_0201-1UF,4V,20%,X6S,CH-10KMEE00  I90  C306
   1 P0V9_CPU1_RT1_2A_2D      A @T6G_MB_LIB.T6G(SCH_1):P0V9_CPU1_RT1_2A_2D
   2    GND      B @T6G_MB_LIB.T6G(SCH_1):GND

Q_CAP_0201-1UF,4V,20%,X6S,CH-10KMEE00  I91  C315
   1 P0V9_CPU1_RT1_2A_2D      A @T6G_MB_LIB.T6G(SCH_1):P0V9_CPU1_RT1_2A_2D
   2    GND      B @T6G_MB_LIB.T6G(SCH_1):GND

Q_CAP_C0201-0.1UF,10V,10%,X7S,CH4102K6E00  I92  C341
   1 P0V9_CPU1_RT1_2A      A @T6G_MB_LIB.T6G(SCH_1):P0V9_CPU1_RT1_2A
   2    GND      B @T6G_MB_LIB.T6G(SCH_1):GND

Q_CAP_C0201-0.1UF,10V,10%,X7S,CH4102K6E00  I93  C350
   1 P0V9_CPU1_RT1_2A      A @T6G_MB_LIB.T6G(SCH_1):P0V9_CPU1_RT1_2A
   2    GND      B @T6G_MB_LIB.T6G(SCH_1):GND

Q_CAPP_SMLF-470UF,2.5V,20%,SPCAP,CH747LM8818  I94  C7023
   1 P0V9_CPU1_RT1_2A      A @T6G_MB_LIB.T6G(SCH_1):P0V9_CPU1_RT1_2A
   2    GND      B @T6G_MB_LIB.T6G(SCH_1):GND

Q_CAPP_SMLF-470UF,2.5V,20%,SPCAP,CH747LM8818  I95  C7024
   1 P0V9_CPU1_RT1_2A      A @T6G_MB_LIB.T6G(SCH_1):P0V9_CPU1_RT1_2A
   2    GND      B @T6G_MB_LIB.T6G(SCH_1):GND

Q_CAP_C0805-100UF,4V,20%,X6S,CH710KMEA01  I96  C7025
   1 P0V9_CPU1_RT1_2A      A @T6G_MB_LIB.T6G(SCH_1):P0V9_CPU1_RT1_2A
   2    GND      B @T6G_MB_LIB.T6G(SCH_1):GND


DRAWING: @T6G_MB_LIB.T6G(SCH_1):PAGE392 

Q_RES_0201LF-4.7K,5%,1/20W,EMPTY,CS24701JE04  I19  R755
   1 P1V8_CPU1_RT_1D      A @T6G_MB_LIB.T6G(SCH_1):P1V8_CPU1_RT_1D
   2 RT_CPU1_P1_SCAN_MODE      B @T6G_MB_LIB.T6G(SCH_1):RT_CPU1_P1_SCAN_MODE

Q_RES_0201LF-10K,1%,1/20W,CHIP,CS31001FE17  I21  R782
   1 GPIO2_RT_CPU1_P1      A @T6G_MB_LIB.T6G(SCH_1):GPIO2_RT_CPU1_P1
   2    GND      B @T6G_MB_LIB.T6G(SCH_1):GND

Q_RES_0201LF-10K,1%,1/20W,CHIP,CS31001FE17  I22  R783
   1 GPIO3_RT_CPU1_P1      A @T6G_MB_LIB.T6G(SCH_1):GPIO3_RT_CPU1_P1
   2    GND      B @T6G_MB_LIB.T6G(SCH_1):GND

Q_RES_0201LF-4.7K,5%,1/20W,CHIP,CS24701JE04  I23  R785
   1 TEST0_RT_CPU1_P1      A @T6G_MB_LIB.T6G(SCH_1):TEST0_RT_CPU1_P1
   2    GND      B @T6G_MB_LIB.T6G(SCH_1):GND

Q_RES_0201LF-4.7K,5%,1/20W,EMPTY,CS24701JE04  I24  R781
   1 P1V8_CPU1_RT_1D      A @T6G_MB_LIB.T6G(SCH_1):P1V8_CPU1_RT_1D
   2 GPIO2_RT_CPU1_P1      B @T6G_MB_LIB.T6G(SCH_1):GPIO2_RT_CPU1_P1

Q_RES_0201LF-4.7K,5%,1/20W,EMPTY,CS24701JE04  I25  R784
   1 P1V8_CPU1_RT_1D      A @T6G_MB_LIB.T6G(SCH_1):P1V8_CPU1_RT_1D
   2 TEST0_RT_CPU1_P1      B @T6G_MB_LIB.T6G(SCH_1):TEST0_RT_CPU1_P1

Q_RES_0201LF-51.1,1%,1/20W,EMPTY,CS05111FE00  I31  R625
   1 CLK_100M_RETIMER_CPU1_P1_DN      A @T6G_MB_LIB.T6G(SCH_1):CLK_100M_RETIMER_CPU1_P1_DN
   2    GND      B @T6G_MB_LIB.T6G(SCH_1):GND

Q_RES_0201LF-51.1,1%,1/20W,EMPTY,CS05111FE00  I32  R626
   1 CLK_100M_RETIMER_CPU1_P1_DP      A @T6G_MB_LIB.T6G(SCH_1):CLK_100M_RETIMER_CPU1_P1_DP
   2    GND      B @T6G_MB_LIB.T6G(SCH_1):GND

Q_RES_0201LF-0,5%,1/20W,CHIP,CS00001JE10  I33  R597
   1 CLK_100M_RETIMER_CPU1_P1_R_DP      A @T6G_MB_LIB.T6G(SCH_1):CLK_100M_RETIMER_CPU1_P1_R_DP
   2 CLK_100M_RETIMER_CPU1_P1_DP      B @T6G_MB_LIB.T6G(SCH_1):CLK_100M_RETIMER_CPU1_P1_DP

Q_RES_0201LF-0,5%,1/20W,CHIP,CS00001JE10  I34  R598
   1 CLK_100M_RETIMER_CPU1_P1_R_DN      A @T6G_MB_LIB.T6G(SCH_1):CLK_100M_RETIMER_CPU1_P1_R_DN
   2 CLK_100M_RETIMER_CPU1_P1_DN      B @T6G_MB_LIB.T6G(SCH_1):CLK_100M_RETIMER_CPU1_P1_DN

Q_RES_0201LF-49.9,1%,1/20W,CHIP,CS04991FE06  I35  R671
   1 SMB_RT_CPU1_P1_ROM_MUX_1D_SDA      A @T6G_MB_LIB.T6G(SCH_1):SMB_RT_CPU1_P1_ROM_MUX_1D_SDA
   2 SMB_RT_CPU1_P1_ROM_MUX_1D_R_SDA      B @T6G_MB_LIB.T6G(SCH_1):SMB_RT_CPU1_P1_ROM_MUX_1D_R_SDA

Q_RES_0201LF-49.9,1%,1/20W,CHIP,CS04991FE06  I36  R670
   1 SMB_RT_CPU1_P1_ROM_MUX_1D_SCL      A @T6G_MB_LIB.T6G(SCH_1):SMB_RT_CPU1_P1_ROM_MUX_1D_SCL
   2 SMB_RT_CPU1_P1_ROM_MUX_1D_R_SCL      B @T6G_MB_LIB.T6G(SCH_1):SMB_RT_CPU1_P1_ROM_MUX_1D_R_SCL

Q_RES_0201LF-0,5%,1/20W,CHIP,CS00001JE10  I43  R780
   1 SMB_RT_CPU1_P1_R_SDA      A @T6G_MB_LIB.T6G(SCH_1):SMB_RT_CPU1_P1_R_SDA
   2 SMB_RT_CPU1_P1_R2_SDA      B @T6G_MB_LIB.T6G(SCH_1):SMB_RT_CPU1_P1_R2_SDA

Q_RES_0201LF-0,5%,1/20W,CHIP,CS00001JE10  I44  R779
   1 SMB_RT_CPU1_P1_R_SCL      A @T6G_MB_LIB.T6G(SCH_1):SMB_RT_CPU1_P1_R_SCL
   2 SMB_RT_CPU1_P1_R2_SCL      B @T6G_MB_LIB.T6G(SCH_1):SMB_RT_CPU1_P1_R2_SCL

PT5161LRS-PT5161LRS,SMLF,IC,AJ051610U03  I47  U6015
 FJ6     NC  GPIO0     NC
FJ23     NC  GPIO1     NC
FJ25 GPIO2_RT_CPU1_P1  GPIO2 @T6G_MB_LIB.T6G(SCH_1):GPIO2_RT_CPU1_P1
FJ28 GPIO3_RT_CPU1_P1  GPIO3 @T6G_MB_LIB.T6G(SCH_1):GPIO3_RT_CPU1_P1
FJ31     NC  INT_N     NC
  B3 JTAG_TCK_RT_CPU1_P1 JTAG_TCK @T6G_MB_LIB.T6G(SCH_1):JTAG_TCK_RT_CPU1_P1
  B6 JTAG_TDI_RT_CPU1_P1 JTAG_TDI @T6G_MB_LIB.T6G(SCH_1):JTAG_TDI_RT_CPU1_P1
  B9 JTAG_TDO_RT_CPU1_P1 JTAG_TDO @T6G_MB_LIB.T6G(SCH_1):JTAG_TDO_RT_CPU1_P1
 FF8 JTAG_TEST_MODE_RT_CPU1_P1 JTAG_TEST_MODE @T6G_MB_LIB.T6G(SCH_1):JTAG_TEST_MODE_RT_CPU1_P1
 B12 JTAG_TMS_RT_CPU1_P1 JTAG_TMS @T6G_MB_LIB.T6G(SCH_1):JTAG_TMS_RT_CPU1_P1
  E8 JTAG_TRST_RT_CPU1_P1_N JTAG_TRST_N @T6G_MB_LIB.T6G(SCH_1):JTAG_TRST_RT_CPU1_P1_N
 FJ9 MODE_RT_CPU1_P1   MODE @T6G_MB_LIB.T6G(SCH_1):MODE_RT_CPU1_P1
  F2 RST_RT_CPU1_P1_PERST_N PERST_N @T6G_MB_LIB.T6G(SCH_1):RST_RT_CPU1_P1_PERST_N
 E18     NC REFCLK_OUTN     NC
 B16     NC REFCLK_OUTP     NC
FF18 CLK_100M_RETIMER_CPU1_P1_DN REFCLKN @T6G_MB_LIB.T6G(SCH_1):CLK_100M_RETIMER_CPU1_P1_DN
FJ16 CLK_100M_RETIMER_CPU1_P1_DP REFCLKP @T6G_MB_LIB.T6G(SCH_1):CLK_100M_RETIMER_CPU1_P1_DP
FF11 RST_RT_CPU1_P1_RESET_N RESET_N @T6G_MB_LIB.T6G(SCH_1):RST_RT_CPU1_P1_RESET_N
 E11 RXDET_BYP_RT_CPU1_P1 RXDET_BYP @T6G_MB_LIB.T6G(SCH_1):RXDET_BYP_RT_CPU1_P1
FF33 RT_CPU1_P1_SCAN_MODE SCAN_MODE @T6G_MB_LIB.T6G(SCH_1):RT_CPU1_P1_SCAN_MODE
 F34 RT_CPU1_P1_ADDR1 SMB_ADDR1 @T6G_MB_LIB.T6G(SCH_1):RT_CPU1_P1_ADDR1
 B23 RT_CPU1_P1_ADDR2 SMB_ADDR2 @T6G_MB_LIB.T6G(SCH_1):RT_CPU1_P1_ADDR2
 B25 RT_CPU1_P1_ADDR3 SMB_ADDR3 @T6G_MB_LIB.T6G(SCH_1):RT_CPU1_P1_ADDR3
 B31 SMB_RT_CPU1_P1_R2_SCL SMBCLK @T6G_MB_LIB.T6G(SCH_1):SMB_RT_CPU1_P1_R2_SCL
 B28 SMB_RT_CPU1_P1_R2_SDA SMBDAT @T6G_MB_LIB.T6G(SCH_1):SMB_RT_CPU1_P1_R2_SDA
 E30    GND T_SENSE @T6G_MB_LIB.T6G(SCH_1):GND
FF24 TEST0_RT_CPU1_P1  TEST0 @T6G_MB_LIB.T6G(SCH_1):TEST0_RT_CPU1_P1
FF27 TEST1_RT_CPU1_P1  TEST1 @T6G_MB_LIB.T6G(SCH_1):TEST1_RT_CPU1_P1
FF30 TEST2_RT_CPU1_P1  TEST2 @T6G_MB_LIB.T6G(SCH_1):TEST2_RT_CPU1_P1
 G35 CLKREQ_RT_CPU1_P1_N CLKREQ_N @T6G_MB_LIB.T6G(SCH_1):CLKREQ_RT_CPU1_P1_N
 FF5 SMB_RT_CPU1_P1_ROM_MUX_1D_R_SCL EE_CLK @T6G_MB_LIB.T6G(SCH_1):SMB_RT_CPU1_P1_ROM_MUX_1D_R_SCL
 FJ3 SMB_RT_CPU1_P1_ROM_MUX_1D_R_SDA EE_DAT @T6G_MB_LIB.T6G(SCH_1):SMB_RT_CPU1_P1_ROM_MUX_1D_R_SDA

Q_RES_0201LF-4.7K,5%,1/20W,CHIP,CS24701JE04  I51  R787
   1 TEST1_RT_CPU1_P1      A @T6G_MB_LIB.T6G(SCH_1):TEST1_RT_CPU1_P1
   2    GND      B @T6G_MB_LIB.T6G(SCH_1):GND

Q_RES_0201LF-4.7K,5%,1/20W,CHIP,CS24701JE04  I52  R791
   1 TEST2_RT_CPU1_P1      A @T6G_MB_LIB.T6G(SCH_1):TEST2_RT_CPU1_P1
   2    GND      B @T6G_MB_LIB.T6G(SCH_1):GND

Q_RES_0201LF-4.7K,5%,1/20W,CHIP,CS24701JE04  I54  R792
   1 JTAG_TEST_MODE_RT_CPU1_P1      A @T6G_MB_LIB.T6G(SCH_1):JTAG_TEST_MODE_RT_CPU1_P1
   2    GND      B @T6G_MB_LIB.T6G(SCH_1):GND

Q_RES_0201LF-4.7K,5%,1/20W,EMPTY,CS24701JE04  I55  R786
   1 P1V8_CPU1_RT_1D      A @T6G_MB_LIB.T6G(SCH_1):P1V8_CPU1_RT_1D
   2 TEST1_RT_CPU1_P1      B @T6G_MB_LIB.T6G(SCH_1):TEST1_RT_CPU1_P1

Q_RES_0201LF-4.7K,5%,1/20W,EMPTY,CS24701JE04  I56  R788
   1 P1V8_CPU1_RT_1D      A @T6G_MB_LIB.T6G(SCH_1):P1V8_CPU1_RT_1D
   2 TEST2_RT_CPU1_P1      B @T6G_MB_LIB.T6G(SCH_1):TEST2_RT_CPU1_P1

Q_RES_0201LF-4.7K,5%,1/20W,EMPTY,CS24701JE04  I57  R759
   1 P1V8_CPU1_RT_1D      A @T6G_MB_LIB.T6G(SCH_1):P1V8_CPU1_RT_1D
   2 JTAG_TEST_MODE_RT_CPU1_P1      B @T6G_MB_LIB.T6G(SCH_1):JTAG_TEST_MODE_RT_CPU1_P1

Q_RES_0201LF-4.7K,5%,1/20W,EMPTY,CS24701JE04  I65  R794
   1 MODE_RT_CPU1_P1      A @T6G_MB_LIB.T6G(SCH_1):MODE_RT_CPU1_P1
   2    GND      B @T6G_MB_LIB.T6G(SCH_1):GND

Q_RES_0201LF-4.7K,5%,1/20W,CHIP,CS24701JE04  I66  R793
   1 P1V8_CPU1_RT_1D      A @T6G_MB_LIB.T6G(SCH_1):P1V8_CPU1_RT_1D
   2 MODE_RT_CPU1_P1      B @T6G_MB_LIB.T6G(SCH_1):MODE_RT_CPU1_P1

Q_RES_0201LF-0,5%,1/20W,CHIP,CS00001JE10  I70  R731
   1 RST_RT_CPU1_P1_PERST_N      A @T6G_MB_LIB.T6G(SCH_1):RST_RT_CPU1_P1_PERST_N
   2 RST_RT_CPU1_P1_PERST_R_N      B @T6G_MB_LIB.T6G(SCH_1):RST_RT_CPU1_P1_PERST_R_N

Q_RES_0201LF-0,5%,1/20W,CHIP,CS00001JE10  I71  R732
   1 RST_RT_CPU1_P1_RESET_N      A @T6G_MB_LIB.T6G(SCH_1):RST_RT_CPU1_P1_RESET_N
   2 RST_RT_CPU1_P1_RESET_R_N      B @T6G_MB_LIB.T6G(SCH_1):RST_RT_CPU1_P1_RESET_R_N

Q_RES_0201LF-10K,1%,1/20W,CHIP,CS31001FE17  I92  R752
   1 RST_RT_CPU1_P1_RESET_R_N      A @T6G_MB_LIB.T6G(SCH_1):RST_RT_CPU1_P1_RESET_R_N
   2    GND      B @T6G_MB_LIB.T6G(SCH_1):GND

Q_RES_0201LF-10K,1%,1/20W,CHIP,CS31001FE17  I93  R749
   1 RST_RT_CPU1_P1_PERST_R_N      A @T6G_MB_LIB.T6G(SCH_1):RST_RT_CPU1_P1_PERST_R_N
   2    GND      B @T6G_MB_LIB.T6G(SCH_1):GND

Q_RES_0201LF-4.7K,5%,1/20W,EMPTY,CS24701JE04  I94  R758
   1 P1V8_CPU1_RT_1D      A @T6G_MB_LIB.T6G(SCH_1):P1V8_CPU1_RT_1D
   2 RST_RT_CPU1_P1_RESET_R_N      B @T6G_MB_LIB.T6G(SCH_1):RST_RT_CPU1_P1_RESET_R_N

Q_RES_0201LF-1K,1%,1/20W,EMPTY,CS21001FE07  I101  R741
   1 RT_CPU1_P1_ADDR3      A @T6G_MB_LIB.T6G(SCH_1):RT_CPU1_P1_ADDR3
   2    GND      B @T6G_MB_LIB.T6G(SCH_1):GND

Q_RES_0201LF-20K,1%,1/20W,CHIP,CS32001FE00  I102  R746
   1 RT_CPU1_P1_ADDR2      A @T6G_MB_LIB.T6G(SCH_1):RT_CPU1_P1_ADDR2
   2    GND      B @T6G_MB_LIB.T6G(SCH_1):GND

Q_RES_0201LF-1K,1%,1/20W,CHIP,CS21001FE07  I103  R735
   1 P1V8_CPU1_RT_1D      A @T6G_MB_LIB.T6G(SCH_1):P1V8_CPU1_RT_1D
   2 RT_CPU1_P1_ADDR3      B @T6G_MB_LIB.T6G(SCH_1):RT_CPU1_P1_ADDR3

Q_RES_0201LF-1K,1%,1/20W,EMPTY,CS21001FE07  I104  R745
   1 P1V8_CPU1_RT_1D      A @T6G_MB_LIB.T6G(SCH_1):P1V8_CPU1_RT_1D
   2 RT_CPU1_P1_ADDR2      B @T6G_MB_LIB.T6G(SCH_1):RT_CPU1_P1_ADDR2

Q_RES_0201LF-1K,1%,1/20W,CHIP,CS21001FE07  I105  R796
   1 RT_CPU1_P1_ADDR1      A @T6G_MB_LIB.T6G(SCH_1):RT_CPU1_P1_ADDR1
   2    GND      B @T6G_MB_LIB.T6G(SCH_1):GND

Q_RES_0201LF-1K,1%,1/20W,EMPTY,CS21001FE07  I110  R795
   1 P1V8_CPU1_RT_1D      A @T6G_MB_LIB.T6G(SCH_1):P1V8_CPU1_RT_1D
   2 RT_CPU1_P1_ADDR1      B @T6G_MB_LIB.T6G(SCH_1):RT_CPU1_P1_ADDR1

Q_RES_0201LF-4.7K,5%,1/20W,CHIP,CS24701JE04  I111  R1376
   1 CLKREQ_RT_CPU1_P1_N      A @T6G_MB_LIB.T6G(SCH_1):CLKREQ_RT_CPU1_P1_N
   2    GND      B @T6G_MB_LIB.T6G(SCH_1):GND

Q_RES_0201LF-1K,1%,1/20W,CHIP,CS21001FE07  I115  R1372
   1 JTAG_TRST_RT_CPU1_P1_N      A @T6G_MB_LIB.T6G(SCH_1):JTAG_TRST_RT_CPU1_P1_N
   2    GND      B @T6G_MB_LIB.T6G(SCH_1):GND

Q_RES_0201LF-1K,1%,1/20W,EMPTY,CS21001FE07  I125  R1377
   1 P1V8_CPU1_RT_1D      A @T6G_MB_LIB.T6G(SCH_1):P1V8_CPU1_RT_1D
   2 RXDET_BYP_RT_CPU1_P1      B @T6G_MB_LIB.T6G(SCH_1):RXDET_BYP_RT_CPU1_P1

Q_RES_0201LF-10K,1%,1/20W,CHIP,CS31001FE17  I126  R1378
   1 RXDET_BYP_RT_CPU1_P1      A @T6G_MB_LIB.T6G(SCH_1):RXDET_BYP_RT_CPU1_P1
   2    GND      B @T6G_MB_LIB.T6G(SCH_1):GND

Q_RES_0201LF-200,1%,1/20W,CHIP,CS12001FE12  I132  R756
   1 RT_CPU1_P1_SCAN_MODE      A @T6G_MB_LIB.T6G(SCH_1):RT_CPU1_P1_SCAN_MODE
   2    GND      B @T6G_MB_LIB.T6G(SCH_1):GND

Q_RES_0201LF-4.7K,5%,1/20W,EMPTY,CS24701JE04  I145  R1454
   1 P1V8_CPU1_RT_1D      A @T6G_MB_LIB.T6G(SCH_1):P1V8_CPU1_RT_1D
   2 JTAG_TDI_RT_CPU1_P1      B @T6G_MB_LIB.T6G(SCH_1):JTAG_TDI_RT_CPU1_P1

Q_RES_0201LF-4.7K,5%,1/20W,EMPTY,CS24701JE04  I146  R1455
   1 P1V8_CPU1_RT_1D      A @T6G_MB_LIB.T6G(SCH_1):P1V8_CPU1_RT_1D
   2 JTAG_TMS_RT_CPU1_P1      B @T6G_MB_LIB.T6G(SCH_1):JTAG_TMS_RT_CPU1_P1

Q_RES_0201LF-4.7K,5%,1/20W,CHIP,CS24701JE04  I150  R1373
   1 JTAG_TCK_RT_CPU1_P1      A @T6G_MB_LIB.T6G(SCH_1):JTAG_TCK_RT_CPU1_P1
   2    GND      B @T6G_MB_LIB.T6G(SCH_1):GND

Q_RES_0201LF-4.7K,5%,1/20W,EMPTY,CS24701JE04  I151  R1461
   1 P1V8_CPU1_RT_1D      A @T6G_MB_LIB.T6G(SCH_1):P1V8_CPU1_RT_1D
   2 JTAG_TCK_RT_CPU1_P1      B @T6G_MB_LIB.T6G(SCH_1):JTAG_TCK_RT_CPU1_P1

Q_RES_0201LF-1K,1%,1/20W,EMPTY,CS21001FE07  I153  R1456
   1 P1V8_CPU1_RT_1D      A @T6G_MB_LIB.T6G(SCH_1):P1V8_CPU1_RT_1D
   2 JTAG_TDO_RT_CPU1_P1      B @T6G_MB_LIB.T6G(SCH_1):JTAG_TDO_RT_CPU1_P1


DRAWING: @T6G_MB_LIB.T6G(SCH_1):PAGE467 

Q_RES_0402LF-1K,1%,1/16W,CHIP,CS21002FB06  I2  R6744
   1 RT_BOARD_ID_ID1      A @T6G_MB_LIB.T6G(SCH_1):RT_BOARD_ID_ID1
   2    GND      B @T6G_MB_LIB.T6G(SCH_1):GND

Q_RES_0402LF-1K,1%,1/16W,CHIP,CS21002FB06  I4  R6745
   1 RT_BOARD_ID_ID0      A @T6G_MB_LIB.T6G(SCH_1):RT_BOARD_ID_ID0
   2    GND      B @T6G_MB_LIB.T6G(SCH_1):GND

Q_RES_0402LF-1K,1%,1/16W,EMPTY,CS21002FB06  I5  R6742
   1 P1V8_AUX      A @T6G_MB_LIB.T6G(SCH_1):P1V8_AUX
   2 RT_BOARD_ID_ID1      B @T6G_MB_LIB.T6G(SCH_1):RT_BOARD_ID_ID1

Q_RES_0402LF-1K,1%,1/16W,EMPTY,CS21002FB06  I6  R6743
   1 P1V8_AUX      A @T6G_MB_LIB.T6G(SCH_1):P1V8_AUX
   2 RT_BOARD_ID_ID0      B @T6G_MB_LIB.T6G(SCH_1):RT_BOARD_ID_ID0


DRAWING: @T6G_MB_LIB.T6G(SCH_1):PAGE377 

Q_RES_0201LF-4.7K,5%,1/20W,CHIP,CS24701JE04  I2  R845
   1 RT_ROM_SMB_MUX_ADDR2      A @T6G_MB_LIB.T6G(SCH_1):RT_ROM_SMB_MUX_ADDR2
   2    GND      B @T6G_MB_LIB.T6G(SCH_1):GND

Q_RES_0201LF-4.7K,5%,1/20W,CHIP,CS24701JE04  I3  R846
   1 RT_ROM_SMB_MUX_ADDR1      A @T6G_MB_LIB.T6G(SCH_1):RT_ROM_SMB_MUX_ADDR1
   2    GND      B @T6G_MB_LIB.T6G(SCH_1):GND

Q_RES_0201LF-4.7K,5%,1/20W,EMPTY,CS24701JE04  I4  R842
   1 P1V8_AUX      A @T6G_MB_LIB.T6G(SCH_1):P1V8_AUX
   2 RT_ROM_SMB_MUX_ADDR2      B @T6G_MB_LIB.T6G(SCH_1):RT_ROM_SMB_MUX_ADDR2

Q_RES_0201LF-4.7K,5%,1/20W,EMPTY,CS24701JE04  I5  R843
   1 P1V8_AUX      A @T6G_MB_LIB.T6G(SCH_1):P1V8_AUX
   2 RT_ROM_SMB_MUX_ADDR1      B @T6G_MB_LIB.T6G(SCH_1):RT_ROM_SMB_MUX_ADDR1

Q_RES_0201LF-4.7K,5%,1/20W,CHIP,CS24701JE04  I8  R847
   1 RT_ROM_SMB_MUX_ADDR0      A @T6G_MB_LIB.T6G(SCH_1):RT_ROM_SMB_MUX_ADDR0
   2    GND      B @T6G_MB_LIB.T6G(SCH_1):GND

Q_RES_0201LF-4.7K,5%,1/20W,EMPTY,CS24701JE04  I9  R844
   1 P1V8_AUX      A @T6G_MB_LIB.T6G(SCH_1):P1V8_AUX
   2 RT_ROM_SMB_MUX_ADDR0      B @T6G_MB_LIB.T6G(SCH_1):RT_ROM_SMB_MUX_ADDR0

Q_RES_0201LF-10K,1%,1/20W,CHIP,CS31001FE17  I16  R849
   1 RST_SMB_RT_ROM_R1_N      A @T6G_MB_LIB.T6G(SCH_1):RST_SMB_RT_ROM_R1_N
   2    GND      B @T6G_MB_LIB.T6G(SCH_1):GND

Q_RES_0201LF-1K,1%,1/20W,CHIP,CS21001FE07  I17  R841
   1 P1V8_CPU0_RT_1D      A @T6G_MB_LIB.T6G(SCH_1):P1V8_CPU0_RT_1D
   2 SMB_RT_CPU0_P2_ROM_R_SCL      B @T6G_MB_LIB.T6G(SCH_1):SMB_RT_CPU0_P2_ROM_R_SCL

Q_RES_0201LF-1K,1%,1/20W,CHIP,CS21001FE07  I18  R840
   1 P1V8_CPU0_RT_1D      A @T6G_MB_LIB.T6G(SCH_1):P1V8_CPU0_RT_1D
   2 SMB_RT_CPU0_P2_ROM_R_SDA      B @T6G_MB_LIB.T6G(SCH_1):SMB_RT_CPU0_P2_ROM_R_SDA

Q_RES_0201LF-1K,1%,1/20W,CHIP,CS21001FE07  I19  R838
   1 P1V8_CPU0_RT_1D      A @T6G_MB_LIB.T6G(SCH_1):P1V8_CPU0_RT_1D
   2 SMB_RT_CPU0_P3_ROM_R_SDA      B @T6G_MB_LIB.T6G(SCH_1):SMB_RT_CPU0_P3_ROM_R_SDA

Q_RES_0201LF-1K,1%,1/20W,CHIP,CS21001FE07  I20  R839
   1 P1V8_CPU0_RT_1D      A @T6G_MB_LIB.T6G(SCH_1):P1V8_CPU0_RT_1D
   2 SMB_RT_CPU0_P3_ROM_R_SCL      B @T6G_MB_LIB.T6G(SCH_1):SMB_RT_CPU0_P3_ROM_R_SCL

Q_RES_0201LF-1K,1%,1/20W,CHIP,CS21001FE07  I21  R837
   1 P1V8_CPU0_RT_1D      A @T6G_MB_LIB.T6G(SCH_1):P1V8_CPU0_RT_1D
   2 SMB_RT_CPU0_P1_ROM_R_SCL      B @T6G_MB_LIB.T6G(SCH_1):SMB_RT_CPU0_P1_ROM_R_SCL

Q_RES_0201LF-1K,1%,1/20W,CHIP,CS21001FE07  I22  R836
   1 P1V8_CPU0_RT_1D      A @T6G_MB_LIB.T6G(SCH_1):P1V8_CPU0_RT_1D
   2 SMB_RT_CPU0_P1_ROM_R_SDA      B @T6G_MB_LIB.T6G(SCH_1):SMB_RT_CPU0_P1_ROM_R_SDA

Q_RES_0201LF-1K,1%,1/20W,CHIP,CS21001FE07  I23  R835
   1 P1V8_CPU0_RT_1D      A @T6G_MB_LIB.T6G(SCH_1):P1V8_CPU0_RT_1D
   2 SMB_RT_CPU0_P0_ROM_R_SCL      B @T6G_MB_LIB.T6G(SCH_1):SMB_RT_CPU0_P0_ROM_R_SCL

Q_RES_0201LF-1K,1%,1/20W,CHIP,CS21001FE07  I24  R834
   1 P1V8_CPU0_RT_1D      A @T6G_MB_LIB.T6G(SCH_1):P1V8_CPU0_RT_1D
   2 SMB_RT_CPU0_P0_ROM_R_SDA      B @T6G_MB_LIB.T6G(SCH_1):SMB_RT_CPU0_P0_ROM_R_SDA

Q_RES_0201LF-0,5%,1/20W,CHIP,CS00001JE10  I42  R848
   1 RST_SMB_RT_ROM_R1_N      A @T6G_MB_LIB.T6G(SCH_1):RST_SMB_RT_ROM_R1_N
   2 RST_SMB_RT_ROM_N      B @T6G_MB_LIB.T6G(SCH_1):RST_SMB_RT_ROM_N

Q_RES_0201LF-0,5%,1/20W,CHIP,CS00001JE10  I43  R807
   1 SMB_RT_CPU1_P3_ROM_MUX_2D_SCL      A @T6G_MB_LIB.T6G(SCH_1):SMB_RT_CPU1_P3_ROM_MUX_2D_SCL
   2 SMB_RT_CPU1_P3_ROM_MUX_2D_R_SCL      B @T6G_MB_LIB.T6G(SCH_1):SMB_RT_CPU1_P3_ROM_MUX_2D_R_SCL

Q_RES_0201LF-0,5%,1/20W,CHIP,CS00001JE10  I44  R809
   1 SMB_RT_CPU1_P2_ROM_MUX_2D_SCL      A @T6G_MB_LIB.T6G(SCH_1):SMB_RT_CPU1_P2_ROM_MUX_2D_SCL
   2 SMB_RT_CPU1_P2_ROM_MUX_2D_R_SCL      B @T6G_MB_LIB.T6G(SCH_1):SMB_RT_CPU1_P2_ROM_MUX_2D_R_SCL

Q_RES_0201LF-0,5%,1/20W,CHIP,CS00001JE10  I45  R808
   1 SMB_RT_CPU1_P2_ROM_MUX_2D_SDA      A @T6G_MB_LIB.T6G(SCH_1):SMB_RT_CPU1_P2_ROM_MUX_2D_SDA
   2 SMB_RT_CPU1_P2_ROM_MUX_2D_R_SDA      B @T6G_MB_LIB.T6G(SCH_1):SMB_RT_CPU1_P2_ROM_MUX_2D_R_SDA

Q_RES_0201LF-0,5%,1/20W,CHIP,CS00001JE10  I46  R805
   1 SMB_RT_CPU1_P1_ROM_MUX_2D_SCL      A @T6G_MB_LIB.T6G(SCH_1):SMB_RT_CPU1_P1_ROM_MUX_2D_SCL
   2 SMB_RT_CPU1_P1_ROM_MUX_2D_R_SCL      B @T6G_MB_LIB.T6G(SCH_1):SMB_RT_CPU1_P1_ROM_MUX_2D_R_SCL

Q_RES_0201LF-0,5%,1/20W,CHIP,CS00001JE10  I47  R806
   1 SMB_RT_CPU1_P3_ROM_MUX_2D_SDA      A @T6G_MB_LIB.T6G(SCH_1):SMB_RT_CPU1_P3_ROM_MUX_2D_SDA
   2 SMB_RT_CPU1_P3_ROM_MUX_2D_R_SDA      B @T6G_MB_LIB.T6G(SCH_1):SMB_RT_CPU1_P3_ROM_MUX_2D_R_SDA

Q_RES_0201LF-0,5%,1/20W,CHIP,CS00001JE10  I48  R803
   1 SMB_RT_CPU1_P1_ROM_MUX_2D_SDA      A @T6G_MB_LIB.T6G(SCH_1):SMB_RT_CPU1_P1_ROM_MUX_2D_SDA
   2 SMB_RT_CPU1_P1_ROM_MUX_2D_R_SDA      B @T6G_MB_LIB.T6G(SCH_1):SMB_RT_CPU1_P1_ROM_MUX_2D_R_SDA

Q_RES_0201LF-0,5%,1/20W,CHIP,CS00001JE10  I49  R801
   1 SMB_RT_CPU1_P0_ROM_MUX_2D_SDA      A @T6G_MB_LIB.T6G(SCH_1):SMB_RT_CPU1_P0_ROM_MUX_2D_SDA
   2 SMB_RT_CPU1_P0_ROM_MUX_2D_R_SDA      B @T6G_MB_LIB.T6G(SCH_1):SMB_RT_CPU1_P0_ROM_MUX_2D_R_SDA

Q_RES_0201LF-0,5%,1/20W,CHIP,CS00001JE10  I50  R802
   1 SMB_RT_CPU1_P0_ROM_MUX_2D_SCL      A @T6G_MB_LIB.T6G(SCH_1):SMB_RT_CPU1_P0_ROM_MUX_2D_SCL
   2 SMB_RT_CPU1_P0_ROM_MUX_2D_R_SCL      B @T6G_MB_LIB.T6G(SCH_1):SMB_RT_CPU1_P0_ROM_MUX_2D_R_SCL

Q_CAP_C0201-0.1UF,10V,10%,X7S,CH4102K6E00  I55  C365
   1 P1V8_AUX      A @T6G_MB_LIB.T6G(SCH_1):P1V8_AUX
   2    GND      B @T6G_MB_LIB.T6G(SCH_1):GND

Q_RES_0201LF-1K,1%,1/20W,CHIP,CS21001FE07  I58  R827
   1 P1V8_CPU1_RT_1D      A @T6G_MB_LIB.T6G(SCH_1):P1V8_CPU1_RT_1D
   2 SMB_RT_CPU1_P2_ROM_R_SCL      B @T6G_MB_LIB.T6G(SCH_1):SMB_RT_CPU1_P2_ROM_R_SCL

Q_RES_0201LF-1K,1%,1/20W,CHIP,CS21001FE07  I59  R826
   1 P1V8_CPU1_RT_1D      A @T6G_MB_LIB.T6G(SCH_1):P1V8_CPU1_RT_1D
   2 SMB_RT_CPU1_P2_ROM_R_SDA      B @T6G_MB_LIB.T6G(SCH_1):SMB_RT_CPU1_P2_ROM_R_SDA

Q_RES_0201LF-1K,1%,1/20W,CHIP,CS21001FE07  I60  R812
   1 P1V8_CPU1_RT_1D      A @T6G_MB_LIB.T6G(SCH_1):P1V8_CPU1_RT_1D
   2 SMB_RT_CPU1_P3_ROM_R_SCL      B @T6G_MB_LIB.T6G(SCH_1):SMB_RT_CPU1_P3_ROM_R_SCL

Q_RES_0201LF-1K,1%,1/20W,CHIP,CS21001FE07  I61  R810
   1 P1V8_CPU1_RT_1D      A @T6G_MB_LIB.T6G(SCH_1):P1V8_CPU1_RT_1D
   2 SMB_RT_CPU1_P3_ROM_R_SDA      B @T6G_MB_LIB.T6G(SCH_1):SMB_RT_CPU1_P3_ROM_R_SDA

Q_RES_0201LF-1K,1%,1/20W,CHIP,CS21001FE07  I62  R6734
   1 P1V8_CPU1_RT_1D      A @T6G_MB_LIB.T6G(SCH_1):P1V8_CPU1_RT_1D
   2 SMB_RT_CPU1_P1_ROM_R_SCL      B @T6G_MB_LIB.T6G(SCH_1):SMB_RT_CPU1_P1_ROM_R_SCL

Q_RES_0201LF-1K,1%,1/20W,CHIP,CS21001FE07  I63  R6735
   1 P1V8_CPU1_RT_1D      A @T6G_MB_LIB.T6G(SCH_1):P1V8_CPU1_RT_1D
   2 SMB_RT_CPU1_P1_ROM_R_SDA      B @T6G_MB_LIB.T6G(SCH_1):SMB_RT_CPU1_P1_ROM_R_SDA

Q_RES_0201LF-1K,1%,1/20W,CHIP,CS21001FE07  I64  R6707
   1 P1V8_CPU1_RT_1D      A @T6G_MB_LIB.T6G(SCH_1):P1V8_CPU1_RT_1D
   2 SMB_RT_CPU1_P0_ROM_R_SDA      B @T6G_MB_LIB.T6G(SCH_1):SMB_RT_CPU1_P0_ROM_R_SDA

Q_RES_0201LF-1K,1%,1/20W,CHIP,CS21001FE07  I65  R6706
   1 P1V8_CPU1_RT_1D      A @T6G_MB_LIB.T6G(SCH_1):P1V8_CPU1_RT_1D
   2 SMB_RT_CPU1_P0_ROM_R_SCL      B @T6G_MB_LIB.T6G(SCH_1):SMB_RT_CPU1_P0_ROM_R_SCL

Q_RES_0201LF-0,5%,1/20W,CHIP,CS00001JE10  I73  R833
   1 SMB_RT_CPU0_P2_ROM_MUX_2D_R_SCL      A @T6G_MB_LIB.T6G(SCH_1):SMB_RT_CPU0_P2_ROM_MUX_2D_R_SCL
   2 SMB_RT_CPU0_P2_ROM_MUX_2D_SCL      B @T6G_MB_LIB.T6G(SCH_1):SMB_RT_CPU0_P2_ROM_MUX_2D_SCL

Q_RES_0201LF-0,5%,1/20W,CHIP,CS00001JE10  I74  R831
   1 SMB_RT_CPU0_P3_ROM_MUX_2D_R_SCL      A @T6G_MB_LIB.T6G(SCH_1):SMB_RT_CPU0_P3_ROM_MUX_2D_R_SCL
   2 SMB_RT_CPU0_P3_ROM_MUX_2D_SCL      B @T6G_MB_LIB.T6G(SCH_1):SMB_RT_CPU0_P3_ROM_MUX_2D_SCL

Q_RES_0201LF-0,5%,1/20W,CHIP,CS00001JE10  I75  R832
   1 SMB_RT_CPU0_P2_ROM_MUX_2D_R_SDA      A @T6G_MB_LIB.T6G(SCH_1):SMB_RT_CPU0_P2_ROM_MUX_2D_R_SDA
   2 SMB_RT_CPU0_P2_ROM_MUX_2D_SDA      B @T6G_MB_LIB.T6G(SCH_1):SMB_RT_CPU0_P2_ROM_MUX_2D_SDA

Q_RES_0201LF-0,5%,1/20W,CHIP,CS00001JE10  I76  R828
   1 SMB_RT_CPU0_P1_ROM_MUX_2D_R_SDA      A @T6G_MB_LIB.T6G(SCH_1):SMB_RT_CPU0_P1_ROM_MUX_2D_R_SDA
   2 SMB_RT_CPU0_P1_ROM_MUX_2D_SDA      B @T6G_MB_LIB.T6G(SCH_1):SMB_RT_CPU0_P1_ROM_MUX_2D_SDA

Q_RES_0201LF-0,5%,1/20W,CHIP,CS00001JE10  I77  R829
   1 SMB_RT_CPU0_P1_ROM_MUX_2D_R_SCL      A @T6G_MB_LIB.T6G(SCH_1):SMB_RT_CPU0_P1_ROM_MUX_2D_R_SCL
   2 SMB_RT_CPU0_P1_ROM_MUX_2D_SCL      B @T6G_MB_LIB.T6G(SCH_1):SMB_RT_CPU0_P1_ROM_MUX_2D_SCL

Q_RES_0201LF-0,5%,1/20W,CHIP,CS00001JE10  I78  R830
   1 SMB_RT_CPU0_P3_ROM_MUX_2D_R_SDA      A @T6G_MB_LIB.T6G(SCH_1):SMB_RT_CPU0_P3_ROM_MUX_2D_R_SDA
   2 SMB_RT_CPU0_P3_ROM_MUX_2D_SDA      B @T6G_MB_LIB.T6G(SCH_1):SMB_RT_CPU0_P3_ROM_MUX_2D_SDA

Q_RES_0201LF-0,5%,1/20W,CHIP,CS00001JE10  I79  R799
   1 SMB_RT_CPU0_P0_ROM_MUX_2D_R_SCL      A @T6G_MB_LIB.T6G(SCH_1):SMB_RT_CPU0_P0_ROM_MUX_2D_R_SCL
   2 SMB_RT_CPU0_P0_ROM_MUX_2D_SCL      B @T6G_MB_LIB.T6G(SCH_1):SMB_RT_CPU0_P0_ROM_MUX_2D_SCL

Q_RES_0201LF-0,5%,1/20W,CHIP,CS00001JE10  I80  R797
   1 SMB_RT_CPU0_P0_ROM_MUX_2D_R_SDA      A @T6G_MB_LIB.T6G(SCH_1):SMB_RT_CPU0_P0_ROM_MUX_2D_R_SDA
   2 SMB_RT_CPU0_P0_ROM_MUX_2D_SDA      B @T6G_MB_LIB.T6G(SCH_1):SMB_RT_CPU0_P0_ROM_MUX_2D_SDA

Q_RES_0201LF-0,5%,1/20W,CHIP,CS00001JE10  I81  R850
   1 SMB_MUX_RT_ROM_SDA      A @T6G_MB_LIB.T6G(SCH_1):SMB_MUX_RT_ROM_SDA
   2 SMB_MUX_RT_ROM_R1_SDA      B @T6G_MB_LIB.T6G(SCH_1):SMB_MUX_RT_ROM_R1_SDA

Q_RES_0201LF-0,5%,1/20W,CHIP,CS00001JE10  I82  R851
   1 SMB_MUX_RT_ROM_SCL      A @T6G_MB_LIB.T6G(SCH_1):SMB_MUX_RT_ROM_SCL
   2 SMB_MUX_RT_ROM_R1_SCL      B @T6G_MB_LIB.T6G(SCH_1):SMB_MUX_RT_ROM_R1_SCL

TCA9548APWR-TCA9548APWR,SMLF,IC,AL009548K02  I94  U22
   1 RT_ROM_SMB_MUX_ADDR0     A0 @T6G_MB_LIB.T6G(SCH_1):RT_ROM_SMB_MUX_ADDR0
   2 RT_ROM_SMB_MUX_ADDR1     A1 @T6G_MB_LIB.T6G(SCH_1):RT_ROM_SMB_MUX_ADDR1
   3 RST_SMB_RT_ROM_N RESET# @T6G_MB_LIB.T6G(SCH_1):RST_SMB_RT_ROM_N
   4 SMB_RT_CPU1_P0_ROM_MUX_2D_R_SDA    SD0 @T6G_MB_LIB.T6G(SCH_1):SMB_RT_CPU1_P0_ROM_MUX_2D_R_SDA
   5 SMB_RT_CPU1_P0_ROM_MUX_2D_R_SCL    SC0 @T6G_MB_LIB.T6G(SCH_1):SMB_RT_CPU1_P0_ROM_MUX_2D_R_SCL
   6 SMB_RT_CPU1_P1_ROM_MUX_2D_R_SDA    SD1 @T6G_MB_LIB.T6G(SCH_1):SMB_RT_CPU1_P1_ROM_MUX_2D_R_SDA
   7 SMB_RT_CPU1_P1_ROM_MUX_2D_R_SCL    SC1 @T6G_MB_LIB.T6G(SCH_1):SMB_RT_CPU1_P1_ROM_MUX_2D_R_SCL
   8 SMB_RT_CPU1_P3_ROM_MUX_2D_R_SDA    SD2 @T6G_MB_LIB.T6G(SCH_1):SMB_RT_CPU1_P3_ROM_MUX_2D_R_SDA
   9 SMB_RT_CPU1_P3_ROM_MUX_2D_R_SCL    SC2 @T6G_MB_LIB.T6G(SCH_1):SMB_RT_CPU1_P3_ROM_MUX_2D_R_SCL
  10 SMB_RT_CPU1_P2_ROM_MUX_2D_R_SDA    SD3 @T6G_MB_LIB.T6G(SCH_1):SMB_RT_CPU1_P2_ROM_MUX_2D_R_SDA
  11 SMB_RT_CPU1_P2_ROM_MUX_2D_R_SCL    SC3 @T6G_MB_LIB.T6G(SCH_1):SMB_RT_CPU1_P2_ROM_MUX_2D_R_SCL
  12    GND    GND @T6G_MB_LIB.T6G(SCH_1):GND
  24 P1V8_AUX    VCC @T6G_MB_LIB.T6G(SCH_1):P1V8_AUX
  23 SMB_MUX_RT_ROM_SDA    SDA @T6G_MB_LIB.T6G(SCH_1):SMB_MUX_RT_ROM_SDA
  22 SMB_MUX_RT_ROM_SCL    SCL @T6G_MB_LIB.T6G(SCH_1):SMB_MUX_RT_ROM_SCL
  21 RT_ROM_SMB_MUX_ADDR2     A2 @T6G_MB_LIB.T6G(SCH_1):RT_ROM_SMB_MUX_ADDR2
  20 SMB_RT_CPU0_P2_ROM_MUX_2D_R_SCL    SC7 @T6G_MB_LIB.T6G(SCH_1):SMB_RT_CPU0_P2_ROM_MUX_2D_R_SCL
  19 SMB_RT_CPU0_P2_ROM_MUX_2D_R_SDA    SD7 @T6G_MB_LIB.T6G(SCH_1):SMB_RT_CPU0_P2_ROM_MUX_2D_R_SDA
  18 SMB_RT_CPU0_P3_ROM_MUX_2D_R_SCL    SC6 @T6G_MB_LIB.T6G(SCH_1):SMB_RT_CPU0_P3_ROM_MUX_2D_R_SCL
  17 SMB_RT_CPU0_P3_ROM_MUX_2D_R_SDA    SD6 @T6G_MB_LIB.T6G(SCH_1):SMB_RT_CPU0_P3_ROM_MUX_2D_R_SDA
  16 SMB_RT_CPU0_P1_ROM_MUX_2D_R_SCL    SC5 @T6G_MB_LIB.T6G(SCH_1):SMB_RT_CPU0_P1_ROM_MUX_2D_R_SCL
  15 SMB_RT_CPU0_P1_ROM_MUX_2D_R_SDA    SD5 @T6G_MB_LIB.T6G(SCH_1):SMB_RT_CPU0_P1_ROM_MUX_2D_R_SDA
  14 SMB_RT_CPU0_P0_ROM_MUX_2D_R_SCL    SC4 @T6G_MB_LIB.T6G(SCH_1):SMB_RT_CPU0_P0_ROM_MUX_2D_R_SCL
  13 SMB_RT_CPU0_P0_ROM_MUX_2D_R_SDA    SD4 @T6G_MB_LIB.T6G(SCH_1):SMB_RT_CPU0_P0_ROM_MUX_2D_R_SDA

Q_RES_0201LF-4.7K,5%,1/20W,CHIP,CS24701JE04  I104  R1361
   1 P1V8_CPU1_RT_1D      A @T6G_MB_LIB.T6G(SCH_1):P1V8_CPU1_RT_1D
   2 SMB_RT_CPU1_P0_ROM_MUX_2D_R_SDA      B @T6G_MB_LIB.T6G(SCH_1):SMB_RT_CPU1_P0_ROM_MUX_2D_R_SDA

Q_RES_0201LF-4.7K,5%,1/20W,CHIP,CS24701JE04  I105  R1390
   1 P1V8_CPU1_RT_1D      A @T6G_MB_LIB.T6G(SCH_1):P1V8_CPU1_RT_1D
   2 SMB_RT_CPU1_P0_ROM_MUX_2D_R_SCL      B @T6G_MB_LIB.T6G(SCH_1):SMB_RT_CPU1_P0_ROM_MUX_2D_R_SCL

Q_RES_0201LF-4.7K,5%,1/20W,CHIP,CS24701JE04  I106  R1393
   1 P1V8_CPU1_RT_1D      A @T6G_MB_LIB.T6G(SCH_1):P1V8_CPU1_RT_1D
   2 SMB_RT_CPU1_P1_ROM_MUX_2D_R_SDA      B @T6G_MB_LIB.T6G(SCH_1):SMB_RT_CPU1_P1_ROM_MUX_2D_R_SDA

Q_RES_0201LF-4.7K,5%,1/20W,CHIP,CS24701JE04  I107  R1394
   1 P1V8_CPU1_RT_1D      A @T6G_MB_LIB.T6G(SCH_1):P1V8_CPU1_RT_1D
   2 SMB_RT_CPU1_P1_ROM_MUX_2D_R_SCL      B @T6G_MB_LIB.T6G(SCH_1):SMB_RT_CPU1_P1_ROM_MUX_2D_R_SCL

Q_RES_0201LF-4.7K,5%,1/20W,CHIP,CS24701JE04  I108  R1399
   1 P1V8_CPU1_RT_1D      A @T6G_MB_LIB.T6G(SCH_1):P1V8_CPU1_RT_1D
   2 SMB_RT_CPU1_P3_ROM_MUX_2D_R_SDA      B @T6G_MB_LIB.T6G(SCH_1):SMB_RT_CPU1_P3_ROM_MUX_2D_R_SDA

Q_RES_0201LF-4.7K,5%,1/20W,CHIP,CS24701JE04  I109  R1402
   1 P1V8_CPU1_RT_1D      A @T6G_MB_LIB.T6G(SCH_1):P1V8_CPU1_RT_1D
   2 SMB_RT_CPU1_P3_ROM_MUX_2D_R_SCL      B @T6G_MB_LIB.T6G(SCH_1):SMB_RT_CPU1_P3_ROM_MUX_2D_R_SCL

Q_RES_0201LF-4.7K,5%,1/20W,CHIP,CS24701JE04  I110  R1403
   1 P1V8_CPU1_RT_1D      A @T6G_MB_LIB.T6G(SCH_1):P1V8_CPU1_RT_1D
   2 SMB_RT_CPU1_P2_ROM_MUX_2D_R_SDA      B @T6G_MB_LIB.T6G(SCH_1):SMB_RT_CPU1_P2_ROM_MUX_2D_R_SDA

Q_RES_0201LF-4.7K,5%,1/20W,CHIP,CS24701JE04  I111  R1407
   1 P1V8_CPU1_RT_1D      A @T6G_MB_LIB.T6G(SCH_1):P1V8_CPU1_RT_1D
   2 SMB_RT_CPU1_P2_ROM_MUX_2D_R_SCL      B @T6G_MB_LIB.T6G(SCH_1):SMB_RT_CPU1_P2_ROM_MUX_2D_R_SCL

Q_RES_0201LF-4.7K,5%,1/20W,CHIP,CS24701JE04  I121  R1367
   1 P1V8_CPU0_RT_1D      A @T6G_MB_LIB.T6G(SCH_1):P1V8_CPU0_RT_1D
   2 SMB_RT_CPU0_P0_ROM_MUX_2D_R_SCL      B @T6G_MB_LIB.T6G(SCH_1):SMB_RT_CPU0_P0_ROM_MUX_2D_R_SCL

Q_RES_0201LF-4.7K,5%,1/20W,CHIP,CS24701JE04  I122  R1366
   1 P1V8_CPU0_RT_1D      A @T6G_MB_LIB.T6G(SCH_1):P1V8_CPU0_RT_1D
   2 SMB_RT_CPU0_P0_ROM_MUX_2D_R_SDA      B @T6G_MB_LIB.T6G(SCH_1):SMB_RT_CPU0_P0_ROM_MUX_2D_R_SDA

Q_RES_0201LF-4.7K,5%,1/20W,CHIP,CS24701JE04  I123  R1374
   1 P1V8_CPU0_RT_1D      A @T6G_MB_LIB.T6G(SCH_1):P1V8_CPU0_RT_1D
   2 SMB_RT_CPU0_P1_ROM_MUX_2D_R_SCL      B @T6G_MB_LIB.T6G(SCH_1):SMB_RT_CPU0_P1_ROM_MUX_2D_R_SCL

Q_RES_0201LF-4.7K,5%,1/20W,CHIP,CS24701JE04  I124  R1371
   1 P1V8_CPU0_RT_1D      A @T6G_MB_LIB.T6G(SCH_1):P1V8_CPU0_RT_1D
   2 SMB_RT_CPU0_P1_ROM_MUX_2D_R_SDA      B @T6G_MB_LIB.T6G(SCH_1):SMB_RT_CPU0_P1_ROM_MUX_2D_R_SDA

Q_RES_0201LF-4.7K,5%,1/20W,CHIP,CS24701JE04  I125  R1375
   1 P1V8_CPU0_RT_1D      A @T6G_MB_LIB.T6G(SCH_1):P1V8_CPU0_RT_1D
   2 SMB_RT_CPU0_P3_ROM_MUX_2D_R_SDA      B @T6G_MB_LIB.T6G(SCH_1):SMB_RT_CPU0_P3_ROM_MUX_2D_R_SDA

Q_RES_0201LF-4.7K,5%,1/20W,CHIP,CS24701JE04  I126  R1379
   1 P1V8_CPU0_RT_1D      A @T6G_MB_LIB.T6G(SCH_1):P1V8_CPU0_RT_1D
   2 SMB_RT_CPU0_P3_ROM_MUX_2D_R_SCL      B @T6G_MB_LIB.T6G(SCH_1):SMB_RT_CPU0_P3_ROM_MUX_2D_R_SCL

Q_RES_0201LF-4.7K,5%,1/20W,CHIP,CS24701JE04  I127  R1382
   1 P1V8_CPU0_RT_1D      A @T6G_MB_LIB.T6G(SCH_1):P1V8_CPU0_RT_1D
   2 SMB_RT_CPU0_P2_ROM_MUX_2D_R_SDA      B @T6G_MB_LIB.T6G(SCH_1):SMB_RT_CPU0_P2_ROM_MUX_2D_R_SDA

Q_RES_0201LF-4.7K,5%,1/20W,CHIP,CS24701JE04  I128  R1383
   1 P1V8_CPU0_RT_1D      A @T6G_MB_LIB.T6G(SCH_1):P1V8_CPU0_RT_1D
   2 SMB_RT_CPU0_P2_ROM_MUX_2D_R_SCL      B @T6G_MB_LIB.T6G(SCH_1):SMB_RT_CPU0_P2_ROM_MUX_2D_R_SCL

Q_RES_0201LF-1K,1%,1/20W,CHIP,CS21001FE07  I164  R1410
   1 P1V8_CPU0_RT_1D      A @T6G_MB_LIB.T6G(SCH_1):P1V8_CPU0_RT_1D
   2 SMB_RT_CPU0_P0_ROM_MUX_1D_SDA      B @T6G_MB_LIB.T6G(SCH_1):SMB_RT_CPU0_P0_ROM_MUX_1D_SDA

Q_RES_0201LF-1K,1%,1/20W,CHIP,CS21001FE07  I165  R1411
   1 P1V8_CPU0_RT_1D      A @T6G_MB_LIB.T6G(SCH_1):P1V8_CPU0_RT_1D
   2 SMB_RT_CPU0_P0_ROM_MUX_1D_SCL      B @T6G_MB_LIB.T6G(SCH_1):SMB_RT_CPU0_P0_ROM_MUX_1D_SCL

Q_RES_0201LF-1K,1%,1/20W,CHIP,CS21001FE07  I166  R1415
   1 P1V8_CPU0_RT_1D      A @T6G_MB_LIB.T6G(SCH_1):P1V8_CPU0_RT_1D
   2 SMB_RT_CPU0_P1_ROM_MUX_1D_SDA      B @T6G_MB_LIB.T6G(SCH_1):SMB_RT_CPU0_P1_ROM_MUX_1D_SDA

Q_RES_0201LF-1K,1%,1/20W,CHIP,CS21001FE07  I167  R1418
   1 P1V8_CPU0_RT_1D      A @T6G_MB_LIB.T6G(SCH_1):P1V8_CPU0_RT_1D
   2 SMB_RT_CPU0_P1_ROM_MUX_1D_SCL      B @T6G_MB_LIB.T6G(SCH_1):SMB_RT_CPU0_P1_ROM_MUX_1D_SCL

Q_RES_0201LF-1K,1%,1/20W,CHIP,CS21001FE07  I168  R1420
   1 P1V8_CPU0_RT_1D      A @T6G_MB_LIB.T6G(SCH_1):P1V8_CPU0_RT_1D
   2 SMB_RT_CPU0_P3_ROM_MUX_1D_SDA      B @T6G_MB_LIB.T6G(SCH_1):SMB_RT_CPU0_P3_ROM_MUX_1D_SDA

Q_RES_0201LF-1K,1%,1/20W,CHIP,CS21001FE07  I169  R1428
   1 P1V8_CPU0_RT_1D      A @T6G_MB_LIB.T6G(SCH_1):P1V8_CPU0_RT_1D
   2 SMB_RT_CPU0_P3_ROM_MUX_1D_SCL      B @T6G_MB_LIB.T6G(SCH_1):SMB_RT_CPU0_P3_ROM_MUX_1D_SCL

Q_RES_0201LF-1K,1%,1/20W,CHIP,CS21001FE07  I170  R1431
   1 P1V8_CPU0_RT_1D      A @T6G_MB_LIB.T6G(SCH_1):P1V8_CPU0_RT_1D
   2 SMB_RT_CPU0_P2_ROM_MUX_1D_SDA      B @T6G_MB_LIB.T6G(SCH_1):SMB_RT_CPU0_P2_ROM_MUX_1D_SDA

Q_RES_0201LF-1K,1%,1/20W,CHIP,CS21001FE07  I171  R1432
   1 P1V8_CPU0_RT_1D      A @T6G_MB_LIB.T6G(SCH_1):P1V8_CPU0_RT_1D
   2 SMB_RT_CPU0_P2_ROM_MUX_1D_SCL      B @T6G_MB_LIB.T6G(SCH_1):SMB_RT_CPU0_P2_ROM_MUX_1D_SCL

Q_RES_0201LF-1K,1%,1/20W,CHIP,CS21001FE07  I172  R1437
   1 P1V8_CPU1_RT_1D      A @T6G_MB_LIB.T6G(SCH_1):P1V8_CPU1_RT_1D
   2 SMB_RT_CPU1_P0_ROM_MUX_1D_SCL      B @T6G_MB_LIB.T6G(SCH_1):SMB_RT_CPU1_P0_ROM_MUX_1D_SCL

Q_RES_0201LF-1K,1%,1/20W,CHIP,CS21001FE07  I173  R1436
   1 P1V8_CPU1_RT_1D      A @T6G_MB_LIB.T6G(SCH_1):P1V8_CPU1_RT_1D
   2 SMB_RT_CPU1_P0_ROM_MUX_1D_SDA      B @T6G_MB_LIB.T6G(SCH_1):SMB_RT_CPU1_P0_ROM_MUX_1D_SDA

Q_RES_0201LF-1K,1%,1/20W,CHIP,CS21001FE07  I174  R1448
   1 P1V8_CPU1_RT_1D      A @T6G_MB_LIB.T6G(SCH_1):P1V8_CPU1_RT_1D
   2 SMB_RT_CPU1_P1_ROM_MUX_1D_SDA      B @T6G_MB_LIB.T6G(SCH_1):SMB_RT_CPU1_P1_ROM_MUX_1D_SDA

Q_RES_0201LF-1K,1%,1/20W,CHIP,CS21001FE07  I175  R1451
   1 P1V8_CPU1_RT_1D      A @T6G_MB_LIB.T6G(SCH_1):P1V8_CPU1_RT_1D
   2 SMB_RT_CPU1_P1_ROM_MUX_1D_SCL      B @T6G_MB_LIB.T6G(SCH_1):SMB_RT_CPU1_P1_ROM_MUX_1D_SCL

Q_RES_0201LF-1K,1%,1/20W,CHIP,CS21001FE07  I176  R1462
   1 P1V8_CPU1_RT_1D      A @T6G_MB_LIB.T6G(SCH_1):P1V8_CPU1_RT_1D
   2 SMB_RT_CPU1_P3_ROM_MUX_1D_SDA      B @T6G_MB_LIB.T6G(SCH_1):SMB_RT_CPU1_P3_ROM_MUX_1D_SDA

Q_RES_0201LF-1K,1%,1/20W,CHIP,CS21001FE07  I177  R1463
   1 P1V8_CPU1_RT_1D      A @T6G_MB_LIB.T6G(SCH_1):P1V8_CPU1_RT_1D
   2 SMB_RT_CPU1_P3_ROM_MUX_1D_SCL      B @T6G_MB_LIB.T6G(SCH_1):SMB_RT_CPU1_P3_ROM_MUX_1D_SCL

Q_RES_0201LF-1K,1%,1/20W,CHIP,CS21001FE07  I178  R1468
   1 P1V8_CPU1_RT_1D      A @T6G_MB_LIB.T6G(SCH_1):P1V8_CPU1_RT_1D
   2 SMB_RT_CPU1_P2_ROM_MUX_1D_SDA      B @T6G_MB_LIB.T6G(SCH_1):SMB_RT_CPU1_P2_ROM_MUX_1D_SDA

Q_RES_0201LF-1K,1%,1/20W,CHIP,CS21001FE07  I179  R1469
   1 P1V8_CPU1_RT_1D      A @T6G_MB_LIB.T6G(SCH_1):P1V8_CPU1_RT_1D
   2 SMB_RT_CPU1_P2_ROM_MUX_1D_SCL      B @T6G_MB_LIB.T6G(SCH_1):SMB_RT_CPU1_P2_ROM_MUX_1D_SCL


DRAWING: @T6G_MB_LIB.T6G(SCH_1):PAGE451 

Q_RES_0201LF-4.7K,5%,1/20W,EMPTY,CS24701JE04  I17  R868
   1 P1V8_CPU1_RT_1D      A @T6G_MB_LIB.T6G(SCH_1):P1V8_CPU1_RT_1D
   2 RT_CPU1_P2_SCAN_MODE      B @T6G_MB_LIB.T6G(SCH_1):RT_CPU1_P2_SCAN_MODE

Q_RES_0201LF-10K,1%,1/20W,CHIP,CS31001FE17  I19  R875
   1 GPIO2_RT_CPU1_P2      A @T6G_MB_LIB.T6G(SCH_1):GPIO2_RT_CPU1_P2
   2    GND      B @T6G_MB_LIB.T6G(SCH_1):GND

Q_RES_0201LF-10K,1%,1/20W,CHIP,CS31001FE17  I20  R876
   1 GPIO3_RT_CPU1_P2      A @T6G_MB_LIB.T6G(SCH_1):GPIO3_RT_CPU1_P2
   2    GND      B @T6G_MB_LIB.T6G(SCH_1):GND

Q_RES_0201LF-4.7K,5%,1/20W,EMPTY,CS24701JE04  I21  R874
   1 P1V8_CPU1_RT_1D      A @T6G_MB_LIB.T6G(SCH_1):P1V8_CPU1_RT_1D
   2 GPIO2_RT_CPU1_P2      B @T6G_MB_LIB.T6G(SCH_1):GPIO2_RT_CPU1_P2

Q_RES_0201LF-0,5%,1/20W,CHIP,CS00001JE10  I27  R620
   1 CLK_100M_RETIMER_CPU1_P2_R_DN      A @T6G_MB_LIB.T6G(SCH_1):CLK_100M_RETIMER_CPU1_P2_R_DN
   2 CLK_100M_RETIMER_CPU1_P2_DN      B @T6G_MB_LIB.T6G(SCH_1):CLK_100M_RETIMER_CPU1_P2_DN

Q_RES_0201LF-0,5%,1/20W,CHIP,CS00001JE10  I28  R619
   1 CLK_100M_RETIMER_CPU1_P2_R_DP      A @T6G_MB_LIB.T6G(SCH_1):CLK_100M_RETIMER_CPU1_P2_R_DP
   2 CLK_100M_RETIMER_CPU1_P2_DP      B @T6G_MB_LIB.T6G(SCH_1):CLK_100M_RETIMER_CPU1_P2_DP

Q_RES_0201LF-49.9,1%,1/20W,CHIP,CS04991FE06  I29  R692
   1 SMB_RT_CPU1_P2_ROM_MUX_1D_SDA      A @T6G_MB_LIB.T6G(SCH_1):SMB_RT_CPU1_P2_ROM_MUX_1D_SDA
   2 SMB_RT_CPU1_P2_ROM_MUX_1D_R_SDA      B @T6G_MB_LIB.T6G(SCH_1):SMB_RT_CPU1_P2_ROM_MUX_1D_R_SDA

Q_RES_0201LF-49.9,1%,1/20W,CHIP,CS04991FE06  I30  R691
   1 SMB_RT_CPU1_P2_ROM_MUX_1D_SCL      A @T6G_MB_LIB.T6G(SCH_1):SMB_RT_CPU1_P2_ROM_MUX_1D_SCL
   2 SMB_RT_CPU1_P2_ROM_MUX_1D_R_SCL      B @T6G_MB_LIB.T6G(SCH_1):SMB_RT_CPU1_P2_ROM_MUX_1D_R_SCL

Q_RES_0201LF-0,5%,1/20W,CHIP,CS00001JE10  I34  R872
   1 SMB_RT_CPU1_P2_R_SCL      A @T6G_MB_LIB.T6G(SCH_1):SMB_RT_CPU1_P2_R_SCL
   2 SMB_RT_CPU1_P2_R2_SCL      B @T6G_MB_LIB.T6G(SCH_1):SMB_RT_CPU1_P2_R2_SCL

Q_RES_0201LF-0,5%,1/20W,CHIP,CS00001JE10  I35  R873
   1 SMB_RT_CPU1_P2_R_SDA      A @T6G_MB_LIB.T6G(SCH_1):SMB_RT_CPU1_P2_R_SDA
   2 SMB_RT_CPU1_P2_R2_SDA      B @T6G_MB_LIB.T6G(SCH_1):SMB_RT_CPU1_P2_R2_SDA

Q_RES_0201LF-51.1,1%,1/20W,EMPTY,CS05111FE00  I36  R640
   1 CLK_100M_RETIMER_CPU1_P2_DP      A @T6G_MB_LIB.T6G(SCH_1):CLK_100M_RETIMER_CPU1_P2_DP
   2    GND      B @T6G_MB_LIB.T6G(SCH_1):GND

Q_RES_0201LF-4.7K,5%,1/20W,CHIP,CS24701JE04  I42  R879
   1 TEST0_RT_CPU1_P2      A @T6G_MB_LIB.T6G(SCH_1):TEST0_RT_CPU1_P2
   2    GND      B @T6G_MB_LIB.T6G(SCH_1):GND

Q_RES_0201LF-4.7K,5%,1/20W,CHIP,CS24701JE04  I43  R881
   1 TEST1_RT_CPU1_P2      A @T6G_MB_LIB.T6G(SCH_1):TEST1_RT_CPU1_P2
   2    GND      B @T6G_MB_LIB.T6G(SCH_1):GND

Q_RES_0201LF-4.7K,5%,1/20W,CHIP,CS24701JE04  I45  R883
   1 TEST2_RT_CPU1_P2      A @T6G_MB_LIB.T6G(SCH_1):TEST2_RT_CPU1_P2
   2    GND      B @T6G_MB_LIB.T6G(SCH_1):GND

Q_RES_0201LF-4.7K,5%,1/20W,CHIP,CS24701JE04  I46  R884
   1 JTAG_TEST_MODE_RT_CPU1_P2      A @T6G_MB_LIB.T6G(SCH_1):JTAG_TEST_MODE_RT_CPU1_P2
   2    GND      B @T6G_MB_LIB.T6G(SCH_1):GND

Q_RES_0201LF-4.7K,5%,1/20W,EMPTY,CS24701JE04  I47  R878
   1 P1V8_CPU1_RT_1D      A @T6G_MB_LIB.T6G(SCH_1):P1V8_CPU1_RT_1D
   2 TEST0_RT_CPU1_P2      B @T6G_MB_LIB.T6G(SCH_1):TEST0_RT_CPU1_P2

Q_RES_0201LF-4.7K,5%,1/20W,EMPTY,CS24701JE04  I48  R880
   1 P1V8_CPU1_RT_1D      A @T6G_MB_LIB.T6G(SCH_1):P1V8_CPU1_RT_1D
   2 TEST1_RT_CPU1_P2      B @T6G_MB_LIB.T6G(SCH_1):TEST1_RT_CPU1_P2

Q_RES_0201LF-4.7K,5%,1/20W,EMPTY,CS24701JE04  I49  R882
   1 P1V8_CPU1_RT_1D      A @T6G_MB_LIB.T6G(SCH_1):P1V8_CPU1_RT_1D
   2 TEST2_RT_CPU1_P2      B @T6G_MB_LIB.T6G(SCH_1):TEST2_RT_CPU1_P2

Q_RES_0201LF-4.7K,5%,1/20W,EMPTY,CS24701JE04  I50  R871
   1 P1V8_CPU1_RT_1D      A @T6G_MB_LIB.T6G(SCH_1):P1V8_CPU1_RT_1D
   2 JTAG_TEST_MODE_RT_CPU1_P2      B @T6G_MB_LIB.T6G(SCH_1):JTAG_TEST_MODE_RT_CPU1_P2

Q_RES_0201LF-4.7K,5%,1/20W,EMPTY,CS24701JE04  I58  R886
   1 MODE_RT_CPU1_P2      A @T6G_MB_LIB.T6G(SCH_1):MODE_RT_CPU1_P2
   2    GND      B @T6G_MB_LIB.T6G(SCH_1):GND

Q_RES_0201LF-4.7K,5%,1/20W,CHIP,CS24701JE04  I59  R885
   1 P1V8_CPU1_RT_1D      A @T6G_MB_LIB.T6G(SCH_1):P1V8_CPU1_RT_1D
   2 MODE_RT_CPU1_P2      B @T6G_MB_LIB.T6G(SCH_1):MODE_RT_CPU1_P2

Q_RES_0201LF-0,5%,1/20W,CHIP,CS00001JE10  I62  R860
   1 RST_RT_CPU1_P2_RESET_N      A @T6G_MB_LIB.T6G(SCH_1):RST_RT_CPU1_P2_RESET_N
   2 RST_RT_CPU1_P2_RESET_R_N      B @T6G_MB_LIB.T6G(SCH_1):RST_RT_CPU1_P2_RESET_R_N

Q_RES_0201LF-0,5%,1/20W,CHIP,CS00001JE10  I63  R854
   1 RST_RT_CPU1_P2_PERST_N      A @T6G_MB_LIB.T6G(SCH_1):RST_RT_CPU1_P2_PERST_N
   2 RST_RT_CPU1_P2_PERST_R_N      B @T6G_MB_LIB.T6G(SCH_1):RST_RT_CPU1_P2_PERST_R_N

Q_RES_0201LF-1K,1%,1/20W,EMPTY,CS21001FE07  I71  R863
   1 RT_CPU1_P2_ADDR3      A @T6G_MB_LIB.T6G(SCH_1):RT_CPU1_P2_ADDR3
   2    GND      B @T6G_MB_LIB.T6G(SCH_1):GND

Q_RES_0201LF-20K,1%,1/20W,CHIP,CS32001FE00  I72  R865
   1 RT_CPU1_P2_ADDR2      A @T6G_MB_LIB.T6G(SCH_1):RT_CPU1_P2_ADDR2
   2    GND      B @T6G_MB_LIB.T6G(SCH_1):GND

Q_RES_0201LF-1K,1%,1/20W,CHIP,CS21001FE07  I74  R861
   1 P1V8_CPU1_RT_1D      A @T6G_MB_LIB.T6G(SCH_1):P1V8_CPU1_RT_1D
   2 RT_CPU1_P2_ADDR3      B @T6G_MB_LIB.T6G(SCH_1):RT_CPU1_P2_ADDR3

Q_RES_0201LF-1K,1%,1/20W,EMPTY,CS21001FE07  I75  R864
   1 P1V8_CPU1_RT_1D      A @T6G_MB_LIB.T6G(SCH_1):P1V8_CPU1_RT_1D
   2 RT_CPU1_P2_ADDR2      B @T6G_MB_LIB.T6G(SCH_1):RT_CPU1_P2_ADDR2

Q_RES_0201LF-1K,1%,1/20W,CHIP,CS21001FE07  I76  R892
   1 RT_CPU1_P2_ADDR1      A @T6G_MB_LIB.T6G(SCH_1):RT_CPU1_P2_ADDR1
   2    GND      B @T6G_MB_LIB.T6G(SCH_1):GND

Q_RES_0201LF-1K,1%,1/20W,EMPTY,CS21001FE07  I77  R887
   1 P1V8_CPU1_RT_1D      A @T6G_MB_LIB.T6G(SCH_1):P1V8_CPU1_RT_1D
   2 RT_CPU1_P2_ADDR1      B @T6G_MB_LIB.T6G(SCH_1):RT_CPU1_P2_ADDR1

Q_RES_0201LF-10K,1%,1/20W,CHIP,CS31001FE17  I80  R867
   1 RST_RT_CPU1_P2_RESET_R_N      A @T6G_MB_LIB.T6G(SCH_1):RST_RT_CPU1_P2_RESET_R_N
   2    GND      B @T6G_MB_LIB.T6G(SCH_1):GND

Q_RES_0201LF-10K,1%,1/20W,CHIP,CS31001FE17  I82  R866
   1 RST_RT_CPU1_P2_PERST_R_N      A @T6G_MB_LIB.T6G(SCH_1):RST_RT_CPU1_P2_PERST_R_N
   2    GND      B @T6G_MB_LIB.T6G(SCH_1):GND

Q_RES_0201LF-4.7K,5%,1/20W,EMPTY,CS24701JE04  I86  R870
   1 P1V8_CPU1_RT_1D      A @T6G_MB_LIB.T6G(SCH_1):P1V8_CPU1_RT_1D
   2 RST_RT_CPU1_P2_RESET_R_N      B @T6G_MB_LIB.T6G(SCH_1):RST_RT_CPU1_P2_RESET_R_N

Q_RES_0201LF-51.1,1%,1/20W,EMPTY,CS05111FE00  I92  R637
   1 CLK_100M_RETIMER_CPU1_P2_DN      A @T6G_MB_LIB.T6G(SCH_1):CLK_100M_RETIMER_CPU1_P2_DN
   2    GND      B @T6G_MB_LIB.T6G(SCH_1):GND

PT5161LRS-PT5161LRS,SMLF,IC,AJ051610U03  I97  U6016
 FJ6     NC  GPIO0     NC
FJ23     NC  GPIO1     NC
FJ25 GPIO2_RT_CPU1_P2  GPIO2 @T6G_MB_LIB.T6G(SCH_1):GPIO2_RT_CPU1_P2
FJ28 GPIO3_RT_CPU1_P2  GPIO3 @T6G_MB_LIB.T6G(SCH_1):GPIO3_RT_CPU1_P2
FJ31     NC  INT_N     NC
  B3 JTAG_TCK_RT_CPU1_P2 JTAG_TCK @T6G_MB_LIB.T6G(SCH_1):JTAG_TCK_RT_CPU1_P2
  B6 JTAG_TDI_RT_CPU1_P2 JTAG_TDI @T6G_MB_LIB.T6G(SCH_1):JTAG_TDI_RT_CPU1_P2
  B9 JTAG_TDO_RT_CPU1_P2 JTAG_TDO @T6G_MB_LIB.T6G(SCH_1):JTAG_TDO_RT_CPU1_P2
 FF8 JTAG_TEST_MODE_RT_CPU1_P2 JTAG_TEST_MODE @T6G_MB_LIB.T6G(SCH_1):JTAG_TEST_MODE_RT_CPU1_P2
 B12 JTAG_TMS_RT_CPU1_P2 JTAG_TMS @T6G_MB_LIB.T6G(SCH_1):JTAG_TMS_RT_CPU1_P2
  E8 JTAG_TRST_RT_CPU1_P2_N JTAG_TRST_N @T6G_MB_LIB.T6G(SCH_1):JTAG_TRST_RT_CPU1_P2_N
 FJ9 MODE_RT_CPU1_P2   MODE @T6G_MB_LIB.T6G(SCH_1):MODE_RT_CPU1_P2
  F2 RST_RT_CPU1_P2_PERST_N PERST_N @T6G_MB_LIB.T6G(SCH_1):RST_RT_CPU1_P2_PERST_N
 E18     NC REFCLK_OUTN     NC
 B16     NC REFCLK_OUTP     NC
FF18 CLK_100M_RETIMER_CPU1_P2_DN REFCLKN @T6G_MB_LIB.T6G(SCH_1):CLK_100M_RETIMER_CPU1_P2_DN
FJ16 CLK_100M_RETIMER_CPU1_P2_DP REFCLKP @T6G_MB_LIB.T6G(SCH_1):CLK_100M_RETIMER_CPU1_P2_DP
FF11 RST_RT_CPU1_P2_RESET_N RESET_N @T6G_MB_LIB.T6G(SCH_1):RST_RT_CPU1_P2_RESET_N
 E11 RXDET_BYP_RT_CPU1_P2 RXDET_BYP @T6G_MB_LIB.T6G(SCH_1):RXDET_BYP_RT_CPU1_P2
FF33 RT_CPU1_P2_SCAN_MODE SCAN_MODE @T6G_MB_LIB.T6G(SCH_1):RT_CPU1_P2_SCAN_MODE
 F34 RT_CPU1_P2_ADDR1 SMB_ADDR1 @T6G_MB_LIB.T6G(SCH_1):RT_CPU1_P2_ADDR1
 B23 RT_CPU1_P2_ADDR2 SMB_ADDR2 @T6G_MB_LIB.T6G(SCH_1):RT_CPU1_P2_ADDR2
 B25 RT_CPU1_P2_ADDR3 SMB_ADDR3 @T6G_MB_LIB.T6G(SCH_1):RT_CPU1_P2_ADDR3
 B31 SMB_RT_CPU1_P2_R2_SCL SMBCLK @T6G_MB_LIB.T6G(SCH_1):SMB_RT_CPU1_P2_R2_SCL
 B28 SMB_RT_CPU1_P2_R2_SDA SMBDAT @T6G_MB_LIB.T6G(SCH_1):SMB_RT_CPU1_P2_R2_SDA
 E30    GND T_SENSE @T6G_MB_LIB.T6G(SCH_1):GND
FF24 TEST0_RT_CPU1_P2  TEST0 @T6G_MB_LIB.T6G(SCH_1):TEST0_RT_CPU1_P2
FF27 TEST1_RT_CPU1_P2  TEST1 @T6G_MB_LIB.T6G(SCH_1):TEST1_RT_CPU1_P2
FF30 TEST2_RT_CPU1_P2  TEST2 @T6G_MB_LIB.T6G(SCH_1):TEST2_RT_CPU1_P2
 G35 CLKREQ_RT_CPU1_P2_N CLKREQ_N @T6G_MB_LIB.T6G(SCH_1):CLKREQ_RT_CPU1_P2_N
 FF5 SMB_RT_CPU1_P2_ROM_MUX_1D_R_SCL EE_CLK @T6G_MB_LIB.T6G(SCH_1):SMB_RT_CPU1_P2_ROM_MUX_1D_R_SCL
 FJ3 SMB_RT_CPU1_P2_ROM_MUX_1D_R_SDA EE_DAT @T6G_MB_LIB.T6G(SCH_1):SMB_RT_CPU1_P2_ROM_MUX_1D_R_SDA

Q_RES_0201LF-4.7K,5%,1/20W,CHIP,CS24701JE04  I98  R1421
   1 CLKREQ_RT_CPU1_P2_N      A @T6G_MB_LIB.T6G(SCH_1):CLKREQ_RT_CPU1_P2_N
   2    GND      B @T6G_MB_LIB.T6G(SCH_1):GND

Q_RES_0201LF-1K,1%,1/20W,CHIP,CS21001FE07  I102  R1416
   1 JTAG_TRST_RT_CPU1_P2_N      A @T6G_MB_LIB.T6G(SCH_1):JTAG_TRST_RT_CPU1_P2_N
   2    GND      B @T6G_MB_LIB.T6G(SCH_1):GND

Q_RES_0201LF-10K,1%,1/20W,CHIP,CS31001FE17  I113  R1427
   1 RXDET_BYP_RT_CPU1_P2      A @T6G_MB_LIB.T6G(SCH_1):RXDET_BYP_RT_CPU1_P2
   2    GND      B @T6G_MB_LIB.T6G(SCH_1):GND

Q_RES_0201LF-1K,1%,1/20W,EMPTY,CS21001FE07  I114  R1426
   1 P1V8_CPU1_RT_1D      A @T6G_MB_LIB.T6G(SCH_1):P1V8_CPU1_RT_1D
   2 RXDET_BYP_RT_CPU1_P2      B @T6G_MB_LIB.T6G(SCH_1):RXDET_BYP_RT_CPU1_P2

Q_RES_0201LF-200,1%,1/20W,CHIP,CS12001FE12  I119  R869
   1 RT_CPU1_P2_SCAN_MODE      A @T6G_MB_LIB.T6G(SCH_1):RT_CPU1_P2_SCAN_MODE
   2    GND      B @T6G_MB_LIB.T6G(SCH_1):GND

Q_RES_0201LF-4.7K,5%,1/20W,EMPTY,CS24701JE04  I132  R1488
   1 P1V8_CPU1_RT_1D      A @T6G_MB_LIB.T6G(SCH_1):P1V8_CPU1_RT_1D
   2 JTAG_TDI_RT_CPU1_P2      B @T6G_MB_LIB.T6G(SCH_1):JTAG_TDI_RT_CPU1_P2

Q_RES_0201LF-4.7K,5%,1/20W,CHIP,CS24701JE04  I136  R1417
   1 JTAG_TCK_RT_CPU1_P2      A @T6G_MB_LIB.T6G(SCH_1):JTAG_TCK_RT_CPU1_P2
   2    GND      B @T6G_MB_LIB.T6G(SCH_1):GND

Q_RES_0201LF-4.7K,5%,1/20W,EMPTY,CS24701JE04  I137  R1499
   1 P1V8_CPU1_RT_1D      A @T6G_MB_LIB.T6G(SCH_1):P1V8_CPU1_RT_1D
   2 JTAG_TCK_RT_CPU1_P2      B @T6G_MB_LIB.T6G(SCH_1):JTAG_TCK_RT_CPU1_P2

Q_RES_0201LF-1K,1%,1/20W,EMPTY,CS21001FE07  I139  R1490
   1 P1V8_CPU1_RT_1D      A @T6G_MB_LIB.T6G(SCH_1):P1V8_CPU1_RT_1D
   2 JTAG_TDO_RT_CPU1_P2      B @T6G_MB_LIB.T6G(SCH_1):JTAG_TDO_RT_CPU1_P2

Q_RES_0201LF-4.7K,5%,1/20W,EMPTY,CS24701JE04  I140  R1489
   1 P1V8_CPU1_RT_1D      A @T6G_MB_LIB.T6G(SCH_1):P1V8_CPU1_RT_1D
   2 JTAG_TMS_RT_CPU1_P2      B @T6G_MB_LIB.T6G(SCH_1):JTAG_TMS_RT_CPU1_P2


DRAWING: @T6G_MB_LIB.T6G(SCH_1):PAGE452 

PT5161LRS-PT5161LRS,SMLF,IC,AJ051610U03  I7  U6016
  G1 RT_CPU1_P2_VQPS   VQPS @T6G_MB_LIB.T6G(SCH_1):RT_CPU1_P2_VQPS
BV20 P1V8_CPU1_RT2_1A PWR_1A_1 @T6G_MB_LIB.T6G(SCH_1):P1V8_CPU1_RT2_1A
CE17 P1V8_CPU1_RT2_1A PWR_1A_2 @T6G_MB_LIB.T6G(SCH_1):P1V8_CPU1_RT2_1A
CE20 P1V8_CPU1_RT2_1A PWR_1A_3 @T6G_MB_LIB.T6G(SCH_1):P1V8_CPU1_RT2_1A
CM17 P1V8_CPU1_RT2_1A PWR_1A_4 @T6G_MB_LIB.T6G(SCH_1):P1V8_CPU1_RT2_1A
CM20 P1V8_CPU1_RT2_1A PWR_1A_5 @T6G_MB_LIB.T6G(SCH_1):P1V8_CPU1_RT2_1A
BL17 P0V9_CPU1_RT_2D PWR_2D_1 @T6G_MB_LIB.T6G(SCH_1):P0V9_CPU1_RT_2D
BL20 P0V9_CPU1_RT_2D PWR_2D_2 @T6G_MB_LIB.T6G(SCH_1):P0V9_CPU1_RT_2D
CW17 P0V9_CPU1_RT_2D PWR_2D_3 @T6G_MB_LIB.T6G(SCH_1):P0V9_CPU1_RT_2D
CW20 P0V9_CPU1_RT_2D PWR_2D_4 @T6G_MB_LIB.T6G(SCH_1):P0V9_CPU1_RT_2D
BV17 P1V8_CPU1_RT2_1A_1D PWR_1D @T6G_MB_LIB.T6G(SCH_1):P1V8_CPU1_RT2_1A_1D
AC17 P0V9_CPU1_RT2_2A PWR_2A_1 @T6G_MB_LIB.T6G(SCH_1):P0V9_CPU1_RT2_2A
AC20 P0V9_CPU1_RT2_2A PWR_2A_2 @T6G_MB_LIB.T6G(SCH_1):P0V9_CPU1_RT2_2A
AK17 P0V9_CPU1_RT2_2A PWR_2A_3 @T6G_MB_LIB.T6G(SCH_1):P0V9_CPU1_RT2_2A
AK20 P0V9_CPU1_RT2_2A PWR_2A_4 @T6G_MB_LIB.T6G(SCH_1):P0V9_CPU1_RT2_2A
AU17 P0V9_CPU1_RT2_2A PWR_2A_5 @T6G_MB_LIB.T6G(SCH_1):P0V9_CPU1_RT2_2A
AU20 P0V9_CPU1_RT2_2A PWR_2A_6 @T6G_MB_LIB.T6G(SCH_1):P0V9_CPU1_RT2_2A
BD17 P0V9_CPU1_RT2_2A_2D PWR_2A_7 @T6G_MB_LIB.T6G(SCH_1):P0V9_CPU1_RT2_2A_2D
BD20 P0V9_CPU1_RT2_2A_2D PWR_2A_8 @T6G_MB_LIB.T6G(SCH_1):P0V9_CPU1_RT2_2A_2D
DF17 P0V9_CPU1_RT2_2A_2D PWR_2A_9 @T6G_MB_LIB.T6G(SCH_1):P0V9_CPU1_RT2_2A_2D
DF20 P0V9_CPU1_RT2_2A_2D PWR_2A_10 @T6G_MB_LIB.T6G(SCH_1):P0V9_CPU1_RT2_2A_2D
DN17 P0V9_CPU1_RT2_2A PWR_2A_11 @T6G_MB_LIB.T6G(SCH_1):P0V9_CPU1_RT2_2A
DN20 P0V9_CPU1_RT2_2A PWR_2A_12 @T6G_MB_LIB.T6G(SCH_1):P0V9_CPU1_RT2_2A
DY17 P0V9_CPU1_RT2_2A PWR_2A_13 @T6G_MB_LIB.T6G(SCH_1):P0V9_CPU1_RT2_2A
DY20 P0V9_CPU1_RT2_2A PWR_2A_14 @T6G_MB_LIB.T6G(SCH_1):P0V9_CPU1_RT2_2A
EG17 P0V9_CPU1_RT2_2A PWR_2A_15 @T6G_MB_LIB.T6G(SCH_1):P0V9_CPU1_RT2_2A
EG20 P0V9_CPU1_RT2_2A PWR_2A_16 @T6G_MB_LIB.T6G(SCH_1):P0V9_CPU1_RT2_2A
EP17 P0V9_CPU1_RT2_2A PWR_2A_17 @T6G_MB_LIB.T6G(SCH_1):P0V9_CPU1_RT2_2A
EP20 P0V9_CPU1_RT2_2A PWR_2A_18 @T6G_MB_LIB.T6G(SCH_1):P0V9_CPU1_RT2_2A
 T17 P0V9_CPU1_RT2_2A PWR_2A_19 @T6G_MB_LIB.T6G(SCH_1):P0V9_CPU1_RT2_2A
 T20 P0V9_CPU1_RT2_2A PWR_2A_20 @T6G_MB_LIB.T6G(SCH_1):P0V9_CPU1_RT2_2A

Q_RES_0201LF-0,5%,1/20W,CHIP,CS00001JE10  I15  R6797
   1 NCF_CPU1_P2_GND      A @T6G_MB_LIB.T6G(SCH_1):NCF_CPU1_P2_GND
   2    GND      B @T6G_MB_LIB.T6G(SCH_1):GND

Q_RES_0201LF-0,5%,1/20W,CHIP,CS00001JE10  I18  R6796
   1 NCF_A1_CPU1_P2_GND      A @T6G_MB_LIB.T6G(SCH_1):NCF_A1_CPU1_P2_GND
   2    GND      B @T6G_MB_LIB.T6G(SCH_1):GND

PT5161LRS-PT5161LRS,SMLF,IC,AJ051610U03  I19  U6016
AC13    GND   GND1 @T6G_MB_LIB.T6G(SCH_1):GND
AC22    GND   GND2 @T6G_MB_LIB.T6G(SCH_1):GND
AC32    GND   GND3 @T6G_MB_LIB.T6G(SCH_1):GND
 AC4    GND   GND4 @T6G_MB_LIB.T6G(SCH_1):GND
 AD2    GND   GND5 @T6G_MB_LIB.T6G(SCH_1):GND
AD34    GND   GND6 @T6G_MB_LIB.T6G(SCH_1):GND
 AE1    GND   GND7 @T6G_MB_LIB.T6G(SCH_1):GND
AE35    GND   GND8 @T6G_MB_LIB.T6G(SCH_1):GND
AK13    GND   GND9 @T6G_MB_LIB.T6G(SCH_1):GND
AK22    GND  GND10 @T6G_MB_LIB.T6G(SCH_1):GND
AK32    GND  GND11 @T6G_MB_LIB.T6G(SCH_1):GND
 AK4    GND  GND12 @T6G_MB_LIB.T6G(SCH_1):GND
 AL2    GND  GND13 @T6G_MB_LIB.T6G(SCH_1):GND
AL34    GND  GND14 @T6G_MB_LIB.T6G(SCH_1):GND
 AM1    GND  GND15 @T6G_MB_LIB.T6G(SCH_1):GND
AM35    GND  GND16 @T6G_MB_LIB.T6G(SCH_1):GND
AU13    GND  GND17 @T6G_MB_LIB.T6G(SCH_1):GND
AU22    GND  GND18 @T6G_MB_LIB.T6G(SCH_1):GND
AU32    GND  GND19 @T6G_MB_LIB.T6G(SCH_1):GND
 AU4    GND  GND20 @T6G_MB_LIB.T6G(SCH_1):GND
 AV2    GND  GND21 @T6G_MB_LIB.T6G(SCH_1):GND
AV34    GND  GND22 @T6G_MB_LIB.T6G(SCH_1):GND
 AW1    GND  GND23 @T6G_MB_LIB.T6G(SCH_1):GND
AW35    GND  GND24 @T6G_MB_LIB.T6G(SCH_1):GND
 B19    GND  GND25 @T6G_MB_LIB.T6G(SCH_1):GND
BD13    GND  GND26 @T6G_MB_LIB.T6G(SCH_1):GND
BD22    GND  GND27 @T6G_MB_LIB.T6G(SCH_1):GND
BD32    GND  GND28 @T6G_MB_LIB.T6G(SCH_1):GND
 BD4    GND  GND29 @T6G_MB_LIB.T6G(SCH_1):GND
 BE2    GND  GND30 @T6G_MB_LIB.T6G(SCH_1):GND
BE34    GND  GND31 @T6G_MB_LIB.T6G(SCH_1):GND
 BF1    GND  GND32 @T6G_MB_LIB.T6G(SCH_1):GND
BF35    GND  GND33 @T6G_MB_LIB.T6G(SCH_1):GND
BL13    GND  GND34 @T6G_MB_LIB.T6G(SCH_1):GND
BL22    GND  GND35 @T6G_MB_LIB.T6G(SCH_1):GND
BL32    GND  GND36 @T6G_MB_LIB.T6G(SCH_1):GND
 BL4    GND  GND37 @T6G_MB_LIB.T6G(SCH_1):GND
 BM2    GND  GND38 @T6G_MB_LIB.T6G(SCH_1):GND
BM34    GND  GND39 @T6G_MB_LIB.T6G(SCH_1):GND
 BN1    GND  GND40 @T6G_MB_LIB.T6G(SCH_1):GND
BN35    GND  GND41 @T6G_MB_LIB.T6G(SCH_1):GND
BV13    GND  GND42 @T6G_MB_LIB.T6G(SCH_1):GND
BV22    GND  GND43 @T6G_MB_LIB.T6G(SCH_1):GND
BV32    GND  GND44 @T6G_MB_LIB.T6G(SCH_1):GND
 BV4    GND  GND45 @T6G_MB_LIB.T6G(SCH_1):GND
 BW2    GND  GND46 @T6G_MB_LIB.T6G(SCH_1):GND
BW34    GND  GND47 @T6G_MB_LIB.T6G(SCH_1):GND
 BY1    GND  GND48 @T6G_MB_LIB.T6G(SCH_1):GND
BY35    GND  GND49 @T6G_MB_LIB.T6G(SCH_1):GND
CE13    GND  GND50 @T6G_MB_LIB.T6G(SCH_1):GND
CE22    GND  GND51 @T6G_MB_LIB.T6G(SCH_1):GND
CE32    GND  GND52 @T6G_MB_LIB.T6G(SCH_1):GND
 CE4    GND  GND53 @T6G_MB_LIB.T6G(SCH_1):GND
 CF2    GND  GND54 @T6G_MB_LIB.T6G(SCH_1):GND
CF34    GND  GND55 @T6G_MB_LIB.T6G(SCH_1):GND
 CG1    GND  GND56 @T6G_MB_LIB.T6G(SCH_1):GND
CG35    GND  GND57 @T6G_MB_LIB.T6G(SCH_1):GND
CM13    GND  GND58 @T6G_MB_LIB.T6G(SCH_1):GND
CM22    GND  GND59 @T6G_MB_LIB.T6G(SCH_1):GND
CM32    GND  GND60 @T6G_MB_LIB.T6G(SCH_1):GND
 CM4    GND  GND61 @T6G_MB_LIB.T6G(SCH_1):GND
 CN2    GND  GND62 @T6G_MB_LIB.T6G(SCH_1):GND
CN34    GND  GND63 @T6G_MB_LIB.T6G(SCH_1):GND
 CP1    GND  GND64 @T6G_MB_LIB.T6G(SCH_1):GND
CP35    GND  GND65 @T6G_MB_LIB.T6G(SCH_1):GND
CW13    GND  GND66 @T6G_MB_LIB.T6G(SCH_1):GND
CW22    GND  GND67 @T6G_MB_LIB.T6G(SCH_1):GND
CW32    GND  GND68 @T6G_MB_LIB.T6G(SCH_1):GND
 CW4    GND  GND69 @T6G_MB_LIB.T6G(SCH_1):GND
 CY2    GND  GND70 @T6G_MB_LIB.T6G(SCH_1):GND
CY34    GND  GND71 @T6G_MB_LIB.T6G(SCH_1):GND
 DA1    GND  GND72 @T6G_MB_LIB.T6G(SCH_1):GND
DA35    GND  GND73 @T6G_MB_LIB.T6G(SCH_1):GND
DF13    GND  GND74 @T6G_MB_LIB.T6G(SCH_1):GND
DF22    GND  GND75 @T6G_MB_LIB.T6G(SCH_1):GND
DF32    GND  GND76 @T6G_MB_LIB.T6G(SCH_1):GND
 DF4    GND  GND77 @T6G_MB_LIB.T6G(SCH_1):GND
 DG2    GND  GND78 @T6G_MB_LIB.T6G(SCH_1):GND
DG34    GND  GND79 @T6G_MB_LIB.T6G(SCH_1):GND
 DH1    GND  GND80 @T6G_MB_LIB.T6G(SCH_1):GND
DH35    GND  GND81 @T6G_MB_LIB.T6G(SCH_1):GND
DN13    GND  GND82 @T6G_MB_LIB.T6G(SCH_1):GND
  A1 NCF_A1_CPU1_P2_GND NCF_GND1 @T6G_MB_LIB.T6G(SCH_1):NCF_A1_CPU1_P2_GND
 A35 NCF_CPU1_P2_GND NCF_GND2 @T6G_MB_LIB.T6G(SCH_1):NCF_CPU1_P2_GND
  C2 NCF_CPU1_P2_GND NCF_GND3 @T6G_MB_LIB.T6G(SCH_1):NCF_CPU1_P2_GND
 C34 NCF_CPU1_P2_GND NCF_GND4 @T6G_MB_LIB.T6G(SCH_1):NCF_CPU1_P2_GND
  D1 NCF_CPU1_P2_GND NCF_GND5 @T6G_MB_LIB.T6G(SCH_1):NCF_CPU1_P2_GND
 D35 NCF_CPU1_P2_GND NCF_GND6 @T6G_MB_LIB.T6G(SCH_1):NCF_CPU1_P2_GND
 FE2 NCF_CPU1_P2_GND NCF_GND7 @T6G_MB_LIB.T6G(SCH_1):NCF_CPU1_P2_GND
FE34 NCF_CPU1_P2_GND NCF_GND8 @T6G_MB_LIB.T6G(SCH_1):NCF_CPU1_P2_GND
 FG1 NCF_CPU1_P2_GND NCF_GND9 @T6G_MB_LIB.T6G(SCH_1):NCF_CPU1_P2_GND
FG35 NCF_CPU1_P2_GND NCF_GND10 @T6G_MB_LIB.T6G(SCH_1):NCF_CPU1_P2_GND
 FH2 NCF_CPU1_P2_GND NCF_GND11 @T6G_MB_LIB.T6G(SCH_1):NCF_CPU1_P2_GND
FH34 NCF_CPU1_P2_GND NCF_GND12 @T6G_MB_LIB.T6G(SCH_1):NCF_CPU1_P2_GND
DN22    GND  GND83 @T6G_MB_LIB.T6G(SCH_1):GND
DN32    GND  GND84 @T6G_MB_LIB.T6G(SCH_1):GND
 DN4    GND  GND85 @T6G_MB_LIB.T6G(SCH_1):GND
 DP2    GND  GND86 @T6G_MB_LIB.T6G(SCH_1):GND
DP34    GND  GND87 @T6G_MB_LIB.T6G(SCH_1):GND
 DR1    GND  GND88 @T6G_MB_LIB.T6G(SCH_1):GND
DR35    GND  GND89 @T6G_MB_LIB.T6G(SCH_1):GND
DY13    GND  GND90 @T6G_MB_LIB.T6G(SCH_1):GND
DY22    GND  GND91 @T6G_MB_LIB.T6G(SCH_1):GND
DY32    GND  GND92 @T6G_MB_LIB.T6G(SCH_1):GND
 DY4    GND  GND93 @T6G_MB_LIB.T6G(SCH_1):GND
 E14    GND  GND94 @T6G_MB_LIB.T6G(SCH_1):GND
 E27    GND  GND95 @T6G_MB_LIB.T6G(SCH_1):GND
 E33    GND  GND96 @T6G_MB_LIB.T6G(SCH_1):GND
 EA2    GND  GND97 @T6G_MB_LIB.T6G(SCH_1):GND
EA34    GND  GND98 @T6G_MB_LIB.T6G(SCH_1):GND
 EB1    GND  GND99 @T6G_MB_LIB.T6G(SCH_1):GND
EB35    GND GND100 @T6G_MB_LIB.T6G(SCH_1):GND
EG13    GND GND101 @T6G_MB_LIB.T6G(SCH_1):GND
EG22    GND GND102 @T6G_MB_LIB.T6G(SCH_1):GND
EG32    GND GND103 @T6G_MB_LIB.T6G(SCH_1):GND
 EG4    GND GND104 @T6G_MB_LIB.T6G(SCH_1):GND
 EH2    GND GND105 @T6G_MB_LIB.T6G(SCH_1):GND
EH34    GND GND106 @T6G_MB_LIB.T6G(SCH_1):GND
 EJ1    GND GND107 @T6G_MB_LIB.T6G(SCH_1):GND
EJ35    GND GND108 @T6G_MB_LIB.T6G(SCH_1):GND
EP13    GND GND109 @T6G_MB_LIB.T6G(SCH_1):GND
EP22    GND GND110 @T6G_MB_LIB.T6G(SCH_1):GND
EP32    GND GND111 @T6G_MB_LIB.T6G(SCH_1):GND
 EP4    GND GND112 @T6G_MB_LIB.T6G(SCH_1):GND
 ER2    GND GND113 @T6G_MB_LIB.T6G(SCH_1):GND
ER34    GND GND114 @T6G_MB_LIB.T6G(SCH_1):GND
 ET1    GND GND115 @T6G_MB_LIB.T6G(SCH_1):GND
ET35    GND GND116 @T6G_MB_LIB.T6G(SCH_1):GND
FA15    GND GND117 @T6G_MB_LIB.T6G(SCH_1):GND
FA32    GND GND118 @T6G_MB_LIB.T6G(SCH_1):GND
 FB2    GND GND119 @T6G_MB_LIB.T6G(SCH_1):GND
FB34    GND GND120 @T6G_MB_LIB.T6G(SCH_1):GND
FC19    GND GND121 @T6G_MB_LIB.T6G(SCH_1):GND
FC23    GND GND122 @T6G_MB_LIB.T6G(SCH_1):GND
FC25    GND GND123 @T6G_MB_LIB.T6G(SCH_1):GND
FC28    GND GND124 @T6G_MB_LIB.T6G(SCH_1):GND
 FC3    GND GND125 @T6G_MB_LIB.T6G(SCH_1):GND
 FC6    GND GND126 @T6G_MB_LIB.T6G(SCH_1):GND
 FC9    GND GND127 @T6G_MB_LIB.T6G(SCH_1):GND
 FD1    GND GND128 @T6G_MB_LIB.T6G(SCH_1):GND
FD35    GND GND129 @T6G_MB_LIB.T6G(SCH_1):GND
FF14    GND GND130 @T6G_MB_LIB.T6G(SCH_1):GND
FF21    GND GND131 @T6G_MB_LIB.T6G(SCH_1):GND
FJ12    GND GND132 @T6G_MB_LIB.T6G(SCH_1):GND
FJ19    GND GND133 @T6G_MB_LIB.T6G(SCH_1):GND
 H12    GND GND134 @T6G_MB_LIB.T6G(SCH_1):GND
 H16    GND GND135 @T6G_MB_LIB.T6G(SCH_1):GND
 H19    GND GND136 @T6G_MB_LIB.T6G(SCH_1):GND
 H31    GND GND137 @T6G_MB_LIB.T6G(SCH_1):GND
 J22    GND GND138 @T6G_MB_LIB.T6G(SCH_1):GND
  J4    GND GND139 @T6G_MB_LIB.T6G(SCH_1):GND
  K2    GND GND140 @T6G_MB_LIB.T6G(SCH_1):GND
 K34    GND GND141 @T6G_MB_LIB.T6G(SCH_1):GND
  L1    GND GND142 @T6G_MB_LIB.T6G(SCH_1):GND
 L35    GND GND143 @T6G_MB_LIB.T6G(SCH_1):GND
 T13    GND GND144 @T6G_MB_LIB.T6G(SCH_1):GND
 T22    GND GND145 @T6G_MB_LIB.T6G(SCH_1):GND
 T32    GND GND146 @T6G_MB_LIB.T6G(SCH_1):GND
  T4    GND GND147 @T6G_MB_LIB.T6G(SCH_1):GND
  U2    GND GND148 @T6G_MB_LIB.T6G(SCH_1):GND
 U34    GND GND149 @T6G_MB_LIB.T6G(SCH_1):GND
  V1    GND GND150 @T6G_MB_LIB.T6G(SCH_1):GND
 V35    GND GND151 @T6G_MB_LIB.T6G(SCH_1):GND

Q_RES_0201LF-200,1%,1/20W,CHIP,CS12001FE12  I20  R6795
   1 RT_CPU1_P2_VQPS      A @T6G_MB_LIB.T6G(SCH_1):RT_CPU1_P2_VQPS
   2    GND      B @T6G_MB_LIB.T6G(SCH_1):GND

Q_RES_0201LF-1K,1%,1/20W,EMPTY,CS21001FE07  I21  R6794
   1 P1V8_CPU1_RT_1D      A @T6G_MB_LIB.T6G(SCH_1):P1V8_CPU1_RT_1D
   2 RT_CPU1_P2_VQPS      B @T6G_MB_LIB.T6G(SCH_1):RT_CPU1_P2_VQPS


DRAWING: @T6G_MB_LIB.T6G(SCH_1):PAGE454 

Q_RES_0402LF-0,5%,1/16W,EMPTY,CS00002JB13  I2  R852
   1 P1V8_CPU1_RT2_1A_1D      A @T6G_MB_LIB.T6G(SCH_1):P1V8_CPU1_RT2_1A_1D
   2 P1V8_CPU1_RT2_1A      B @T6G_MB_LIB.T6G(SCH_1):P1V8_CPU1_RT2_1A

Q_RES_0402LF-0,5%,1/16W,EMPTY,CS00002JB13  I3  R853
   1 P1V8_CPU1_RT2_1A_1D      A @T6G_MB_LIB.T6G(SCH_1):P1V8_CPU1_RT2_1A_1D
   2 P1V8_CPU1_RT2_1A      B @T6G_MB_LIB.T6G(SCH_1):P1V8_CPU1_RT2_1A

Q_CAP_C0805-100UF,4V,20%,X6S,CH710KMEA01  I5  C367
   1 P1V8_CPU1_RT2_1A      A @T6G_MB_LIB.T6G(SCH_1):P1V8_CPU1_RT2_1A
   2    GND      B @T6G_MB_LIB.T6G(SCH_1):GND

Q_CAP_0201-1UF,4V,20%,X6S,CH-10KMEE00  I6  C375
   1 P1V8_CPU1_RT2_1A_1D      A @T6G_MB_LIB.T6G(SCH_1):P1V8_CPU1_RT2_1A_1D
   2    GND      B @T6G_MB_LIB.T6G(SCH_1):GND

Q_CAP_C0201-0.1UF,10V,10%,X7S,CH4102K6E00  I8  C378
   1 P1V8_CPU1_RT2_1A_1D      A @T6G_MB_LIB.T6G(SCH_1):P1V8_CPU1_RT2_1A_1D
   2    GND      B @T6G_MB_LIB.T6G(SCH_1):GND

Q_CAP_C0402-22UF,4V,20%,X6S,CH622KMEB02  I10  C369
   1 P1V8_CPU1_RT2_1A      A @T6G_MB_LIB.T6G(SCH_1):P1V8_CPU1_RT2_1A
   2    GND      B @T6G_MB_LIB.T6G(SCH_1):GND

Q_CAP_C0402-10UF,6.3V,20%,X6S,CH6101MEB01  I11  C372
   1 P1V8_CPU1_RT2_1A      A @T6G_MB_LIB.T6G(SCH_1):P1V8_CPU1_RT2_1A
   2    GND      B @T6G_MB_LIB.T6G(SCH_1):GND

Q_CAP_0402-4.7UF,6.3V,20%,X6S,CH5471MEB01  I12  C371
   1 P1V8_CPU1_RT2_1A      A @T6G_MB_LIB.T6G(SCH_1):P1V8_CPU1_RT2_1A
   2    GND      B @T6G_MB_LIB.T6G(SCH_1):GND

Q_CAP_0201-1UF,4V,20%,X6S,CH-10KMEE00  I13  C374
   1 P1V8_CPU1_RT2_1A      A @T6G_MB_LIB.T6G(SCH_1):P1V8_CPU1_RT2_1A
   2    GND      B @T6G_MB_LIB.T6G(SCH_1):GND

Q_CAP_0201-1UF,4V,20%,X6S,CH-10KMEE00  I15  C376
   1 P1V8_CPU1_RT2_1A      A @T6G_MB_LIB.T6G(SCH_1):P1V8_CPU1_RT2_1A
   2    GND      B @T6G_MB_LIB.T6G(SCH_1):GND

Q_CAP_C0201-0.1UF,10V,10%,X7S,CH4102K6E00  I16  C377
   1 P1V8_CPU1_RT2_1A      A @T6G_MB_LIB.T6G(SCH_1):P1V8_CPU1_RT2_1A
   2    GND      B @T6G_MB_LIB.T6G(SCH_1):GND

Q_CAP_C0201-0.1UF,10V,10%,X7S,CH4102K6E00  I17  C379
   1 P1V8_CPU1_RT2_1A      A @T6G_MB_LIB.T6G(SCH_1):P1V8_CPU1_RT2_1A
   2    GND      B @T6G_MB_LIB.T6G(SCH_1):GND

Q_CAP_C0201-0.1UF,10V,10%,X7S,CH4102K6E00  I18  C380
   1 P1V8_CPU1_RT2_1A      A @T6G_MB_LIB.T6G(SCH_1):P1V8_CPU1_RT2_1A
   2    GND      B @T6G_MB_LIB.T6G(SCH_1):GND

Q_CAP_C0201-0.1UF,10V,10%,X7S,CH4102K6E00  I19  C381
   1 P1V8_CPU1_RT2_1A      A @T6G_MB_LIB.T6G(SCH_1):P1V8_CPU1_RT2_1A
   2    GND      B @T6G_MB_LIB.T6G(SCH_1):GND

Q_RES_0603LF-0,5%,1/4W,EMPTY,CS00006J900  I20  R858
   1 P0V9_CPU1_RT_2D      A @T6G_MB_LIB.T6G(SCH_1):P0V9_CPU1_RT_2D
   2 P0V9_CPU1_RT2_2A_2D      B @T6G_MB_LIB.T6G(SCH_1):P0V9_CPU1_RT2_2A_2D

Q_INDUCTOR_SMLF-BLM21SN300SN1D/5A,IND,CX300SN1000  I21  L7
   2 P1V8_CPU1_RT2_1A      2 @T6G_MB_LIB.T6G(SCH_1):P1V8_CPU1_RT2_1A
   1 P1V8_CPU1_RT_1D      1 @T6G_MB_LIB.T6G(SCH_1):P1V8_CPU1_RT_1D

Q_CAP_C0805-100UF,4V,20%,X6S,CH710KMEA01  I24  C366
   1 P1V8_CPU1_RT_1D      A @T6G_MB_LIB.T6G(SCH_1):P1V8_CPU1_RT_1D
   2    GND      B @T6G_MB_LIB.T6G(SCH_1):GND

Q_CAP_C0402-22UF,4V,20%,X6S,CH622KMEB02  I25  C368
   1 P1V8_CPU1_RT_1D      A @T6G_MB_LIB.T6G(SCH_1):P1V8_CPU1_RT_1D
   2    GND      B @T6G_MB_LIB.T6G(SCH_1):GND

Q_CAP_C0402-10UF,6.3V,20%,X6S,CH6101MEB01  I27  C370
   1 P1V8_CPU1_RT_1D      A @T6G_MB_LIB.T6G(SCH_1):P1V8_CPU1_RT_1D
   2    GND      B @T6G_MB_LIB.T6G(SCH_1):GND

Q_CAP_0402-4.7UF,6.3V,20%,X6S,CH5471MEB01  I28  C373
   1 P1V8_CPU1_RT_1D      A @T6G_MB_LIB.T6G(SCH_1):P1V8_CPU1_RT_1D
   2    GND      B @T6G_MB_LIB.T6G(SCH_1):GND

Q_CAP_C0201-0.1UF,10V,10%,X7S,CH4102K6E00  I31  C421
   1 P0V9_CPU1_RT2_2A      A @T6G_MB_LIB.T6G(SCH_1):P0V9_CPU1_RT2_2A
   2    GND      B @T6G_MB_LIB.T6G(SCH_1):GND

Q_CAP_C0201-0.1UF,10V,10%,X7S,CH4102K6E00  I35  C396
   1 P0V9_CPU1_RT2_2A_2D      A @T6G_MB_LIB.T6G(SCH_1):P0V9_CPU1_RT2_2A_2D
   2    GND      B @T6G_MB_LIB.T6G(SCH_1):GND

Q_CAP_C0201-0.1UF,10V,10%,X7S,CH4102K6E00  I36  C397
   1 P0V9_CPU1_RT2_2A_2D      A @T6G_MB_LIB.T6G(SCH_1):P0V9_CPU1_RT2_2A_2D
   2    GND      B @T6G_MB_LIB.T6G(SCH_1):GND

Q_CAP_C0201-0.1UF,10V,10%,X7S,CH4102K6E00  I37  C427
   1 P0V9_CPU1_RT2_2A      A @T6G_MB_LIB.T6G(SCH_1):P0V9_CPU1_RT2_2A
   2    GND      B @T6G_MB_LIB.T6G(SCH_1):GND

Q_CAP_C0201-0.1UF,10V,10%,X7S,CH4102K6E00  I38  C393
   1 P0V9_CPU1_RT2_2A      A @T6G_MB_LIB.T6G(SCH_1):P0V9_CPU1_RT2_2A
   2    GND      B @T6G_MB_LIB.T6G(SCH_1):GND

Q_CAP_C0201-0.1UF,10V,10%,X7S,CH4102K6E00  I39  C430
   1 P0V9_CPU1_RT2_2A      A @T6G_MB_LIB.T6G(SCH_1):P0V9_CPU1_RT2_2A
   2    GND      B @T6G_MB_LIB.T6G(SCH_1):GND

Q_CAP_C0201-0.1UF,10V,10%,X7S,CH4102K6E00  I40  C400
   1 P0V9_CPU1_RT2_2A      A @T6G_MB_LIB.T6G(SCH_1):P0V9_CPU1_RT2_2A
   2    GND      B @T6G_MB_LIB.T6G(SCH_1):GND

Q_RES_0603LF-0,5%,1/4W,CHIP,CS00006J900  I41  R859
   1 P0V9_CPU1_RT2_2A_2D      A @T6G_MB_LIB.T6G(SCH_1):P0V9_CPU1_RT2_2A_2D
   2 P0V9_CPU1_RT2_2A      B @T6G_MB_LIB.T6G(SCH_1):P0V9_CPU1_RT2_2A

Q_CAP_0201-1UF,4V,20%,X6S,CH-10KMEE00  I42  C384
   1 P0V9_CPU1_RT2_2A      A @T6G_MB_LIB.T6G(SCH_1):P0V9_CPU1_RT2_2A
   2    GND      B @T6G_MB_LIB.T6G(SCH_1):GND

Q_CAP_0201-1UF,4V,20%,X6S,CH-10KMEE00  I43  C387
   1 P0V9_CPU1_RT2_2A      A @T6G_MB_LIB.T6G(SCH_1):P0V9_CPU1_RT2_2A
   2    GND      B @T6G_MB_LIB.T6G(SCH_1):GND

Q_CAP_C0402-10UF,6.3V,20%,X6S,CH6101MEB01  I44  C410
   1 P0V9_CPU1_RT2_2A      A @T6G_MB_LIB.T6G(SCH_1):P0V9_CPU1_RT2_2A
   2    GND      B @T6G_MB_LIB.T6G(SCH_1):GND

Q_CAP_C0402-10UF,6.3V,20%,X6S,CH6101MEB01  I45  C420
   1 P0V9_CPU1_RT2_2A      A @T6G_MB_LIB.T6G(SCH_1):P0V9_CPU1_RT2_2A
   2    GND      B @T6G_MB_LIB.T6G(SCH_1):GND

Q_CAP_C0805-100UF,4V,20%,X6S,CH710KMEA01  I46  C398
   1 P0V9_CPU1_RT2_2A      A @T6G_MB_LIB.T6G(SCH_1):P0V9_CPU1_RT2_2A
   2    GND      B @T6G_MB_LIB.T6G(SCH_1):GND

Q_CAP_C0805-100UF,4V,20%,X6S,CH710KMEA01  I47  C401
   1 P0V9_CPU1_RT2_2A      A @T6G_MB_LIB.T6G(SCH_1):P0V9_CPU1_RT2_2A
   2    GND      B @T6G_MB_LIB.T6G(SCH_1):GND

Q_CAP_0402-4.7UF,6.3V,20%,X6S,CH5471MEB01  I48  C406
   1 P0V9_CPU1_RT2_2A      A @T6G_MB_LIB.T6G(SCH_1):P0V9_CPU1_RT2_2A
   2    GND      B @T6G_MB_LIB.T6G(SCH_1):GND

Q_CAP_0201-1UF,4V,20%,X6S,CH-10KMEE00  I49  C407
   1 P0V9_CPU1_RT2_2A      A @T6G_MB_LIB.T6G(SCH_1):P0V9_CPU1_RT2_2A
   2    GND      B @T6G_MB_LIB.T6G(SCH_1):GND

Q_CAP_0201-1UF,4V,20%,X6S,CH-10KMEE00  I50  C391
   1 P0V9_CPU1_RT2_2A      A @T6G_MB_LIB.T6G(SCH_1):P0V9_CPU1_RT2_2A
   2    GND      B @T6G_MB_LIB.T6G(SCH_1):GND

Q_CAP_0201-1UF,4V,20%,X6S,CH-10KMEE00  I51  C415
   1 P0V9_CPU1_RT2_2A      A @T6G_MB_LIB.T6G(SCH_1):P0V9_CPU1_RT2_2A
   2    GND      B @T6G_MB_LIB.T6G(SCH_1):GND

Q_CAP_0201-1UF,4V,20%,X6S,CH-10KMEE00  I52  C418
   1 P0V9_CPU1_RT2_2A      A @T6G_MB_LIB.T6G(SCH_1):P0V9_CPU1_RT2_2A
   2    GND      B @T6G_MB_LIB.T6G(SCH_1):GND

Q_CAP_0201-1UF,4V,20%,X6S,CH-10KMEE00  I53  C422
   1 P0V9_CPU1_RT2_2A      A @T6G_MB_LIB.T6G(SCH_1):P0V9_CPU1_RT2_2A
   2    GND      B @T6G_MB_LIB.T6G(SCH_1):GND

Q_CAP_0402-4.7UF,6.3V,20%,X6S,CH5471MEB01  I54  C416
   1 P0V9_CPU1_RT2_2A      A @T6G_MB_LIB.T6G(SCH_1):P0V9_CPU1_RT2_2A
   2    GND      B @T6G_MB_LIB.T6G(SCH_1):GND

Q_CAP_0402-4.7UF,6.3V,20%,X6S,CH5471MEB01  I55  C413
   1 P0V9_CPU1_RT2_2A      A @T6G_MB_LIB.T6G(SCH_1):P0V9_CPU1_RT2_2A
   2    GND      B @T6G_MB_LIB.T6G(SCH_1):GND

Q_CAP_C0402-22UF,4V,20%,X6S,CH622KMEB02  I56  C417
   1 P0V9_CPU1_RT2_2A      A @T6G_MB_LIB.T6G(SCH_1):P0V9_CPU1_RT2_2A
   2    GND      B @T6G_MB_LIB.T6G(SCH_1):GND

Q_CAP_0402-4.7UF,6.3V,20%,X6S,CH5471MEB01  I57  C412
   1 P0V9_CPU1_RT2_2A      A @T6G_MB_LIB.T6G(SCH_1):P0V9_CPU1_RT2_2A
   2    GND      B @T6G_MB_LIB.T6G(SCH_1):GND

Q_CAP_0201-1UF,4V,20%,X6S,CH-10KMEE00  I58  C386
   1 P0V9_CPU1_RT2_2A      A @T6G_MB_LIB.T6G(SCH_1):P0V9_CPU1_RT2_2A
   2    GND      B @T6G_MB_LIB.T6G(SCH_1):GND

Q_CAP_C0402-22UF,4V,20%,X6S,CH622KMEB02  I59  C399
   1 P0V9_CPU1_RT2_2A      A @T6G_MB_LIB.T6G(SCH_1):P0V9_CPU1_RT2_2A
   2    GND      B @T6G_MB_LIB.T6G(SCH_1):GND

Q_CAP_C0402-22UF,4V,20%,X6S,CH622KMEB02  I60  C402
   1 P0V9_CPU1_RT2_2A      A @T6G_MB_LIB.T6G(SCH_1):P0V9_CPU1_RT2_2A
   2    GND      B @T6G_MB_LIB.T6G(SCH_1):GND

Q_CAP_C0201-0.1UF,10V,10%,X7S,CH4102K6E00  I61  C403
   1 P0V9_CPU1_RT2_2A      A @T6G_MB_LIB.T6G(SCH_1):P0V9_CPU1_RT2_2A
   2    GND      B @T6G_MB_LIB.T6G(SCH_1):GND

Q_CAP_C0201-0.1UF,10V,10%,X7S,CH4102K6E00  I62  C411
   1 P0V9_CPU1_RT2_2A      A @T6G_MB_LIB.T6G(SCH_1):P0V9_CPU1_RT2_2A
   2    GND      B @T6G_MB_LIB.T6G(SCH_1):GND

Q_CAP_C0201-0.1UF,10V,10%,X7S,CH4102K6E00  I64  C395
   1 P0V9_CPU1_RT2_2A      A @T6G_MB_LIB.T6G(SCH_1):P0V9_CPU1_RT2_2A
   2    GND      B @T6G_MB_LIB.T6G(SCH_1):GND

Q_CAP_0201-1UF,4V,20%,X6S,CH-10KMEE00  I67  C425
   1 P0V9_CPU1_RT2_2A      A @T6G_MB_LIB.T6G(SCH_1):P0V9_CPU1_RT2_2A
   2    GND      B @T6G_MB_LIB.T6G(SCH_1):GND

Q_CAP_0201-1UF,4V,20%,X6S,CH-10KMEE00  I68  C389
   1 P0V9_CPU1_RT2_2A      A @T6G_MB_LIB.T6G(SCH_1):P0V9_CPU1_RT2_2A
   2    GND      B @T6G_MB_LIB.T6G(SCH_1):GND

Q_CAP_C0402-22UF,4V,20%,X6S,CH622KMEB02  I69  C424
   1 P0V9_CPU1_RT2_2A      A @T6G_MB_LIB.T6G(SCH_1):P0V9_CPU1_RT2_2A
   2    GND      B @T6G_MB_LIB.T6G(SCH_1):GND

Q_CAP_C0402-10UF,6.3V,20%,X6S,CH6101MEB01  I70  C429
   1 P0V9_CPU1_RT2_2A      A @T6G_MB_LIB.T6G(SCH_1):P0V9_CPU1_RT2_2A
   2    GND      B @T6G_MB_LIB.T6G(SCH_1):GND

Q_CAP_0201-1UF,4V,20%,X6S,CH-10KMEE00  I71  C382
   1 P0V9_CPU1_RT2_2A      A @T6G_MB_LIB.T6G(SCH_1):P0V9_CPU1_RT2_2A
   2    GND      B @T6G_MB_LIB.T6G(SCH_1):GND

Q_CAP_C0402-10UF,6.3V,20%,X6S,CH6101MEB01  I72  C431
   1 P0V9_CPU1_RT2_2A      A @T6G_MB_LIB.T6G(SCH_1):P0V9_CPU1_RT2_2A
   2    GND      B @T6G_MB_LIB.T6G(SCH_1):GND

Q_INDUCTOR_SMLF-100NH/16A,IND,CV+10G0MZ04  I74  L8
   2 P0V9_CPU1_RT2_2A      2 @T6G_MB_LIB.T6G(SCH_1):P0V9_CPU1_RT2_2A
   1 P0V9_CPU1_RT_2D      1 @T6G_MB_LIB.T6G(SCH_1):P0V9_CPU1_RT_2D

Q_CAP_C0805-100UF,4V,20%,X6S,CH710KMEA01  I76  C404
   1 P0V9_CPU1_RT_2D      A @T6G_MB_LIB.T6G(SCH_1):P0V9_CPU1_RT_2D
   2    GND      B @T6G_MB_LIB.T6G(SCH_1):GND

Q_CAP_C0402-22UF,4V,20%,X6S,CH622KMEB02  I77  C408
   1 P0V9_CPU1_RT_2D      A @T6G_MB_LIB.T6G(SCH_1):P0V9_CPU1_RT_2D
   2    GND      B @T6G_MB_LIB.T6G(SCH_1):GND

Q_CAP_C0402-10UF,6.3V,20%,X6S,CH6101MEB01  I78  C414
   1 P0V9_CPU1_RT_2D      A @T6G_MB_LIB.T6G(SCH_1):P0V9_CPU1_RT_2D
   2    GND      B @T6G_MB_LIB.T6G(SCH_1):GND

Q_CAP_0402-4.7UF,6.3V,20%,X6S,CH5471MEB01  I79  C419
   1 P0V9_CPU1_RT_2D      A @T6G_MB_LIB.T6G(SCH_1):P0V9_CPU1_RT_2D
   2    GND      B @T6G_MB_LIB.T6G(SCH_1):GND

Q_CAP_0201-1UF,4V,20%,X6S,CH-10KMEE00  I80  C423
   1 P0V9_CPU1_RT_2D      A @T6G_MB_LIB.T6G(SCH_1):P0V9_CPU1_RT_2D
   2    GND      B @T6G_MB_LIB.T6G(SCH_1):GND

Q_CAP_C0201-0.1UF,10V,10%,X7S,CH4102K6E00  I82  C383
   1 P0V9_CPU1_RT_2D      A @T6G_MB_LIB.T6G(SCH_1):P0V9_CPU1_RT_2D
   2    GND      B @T6G_MB_LIB.T6G(SCH_1):GND

Q_CAP_C0201-0.1UF,10V,10%,X7S,CH4102K6E00  I83  C385
   1 P0V9_CPU1_RT_2D      A @T6G_MB_LIB.T6G(SCH_1):P0V9_CPU1_RT_2D
   2    GND      B @T6G_MB_LIB.T6G(SCH_1):GND

Q_CAP_C0201-0.1UF,10V,10%,X7S,CH4102K6E00  I84  C388
   1 P0V9_CPU1_RT_2D      A @T6G_MB_LIB.T6G(SCH_1):P0V9_CPU1_RT_2D
   2    GND      B @T6G_MB_LIB.T6G(SCH_1):GND

Q_CAP_C0201-0.1UF,10V,10%,X7S,CH4102K6E00  I85  C392
   1 P0V9_CPU1_RT_2D      A @T6G_MB_LIB.T6G(SCH_1):P0V9_CPU1_RT_2D
   2    GND      B @T6G_MB_LIB.T6G(SCH_1):GND

Q_CAP_C0805-100UF,4V,20%,X6S,CH710KMEA01  I86  C405
   1 P0V9_CPU1_RT2_2A      A @T6G_MB_LIB.T6G(SCH_1):P0V9_CPU1_RT2_2A
   2    GND      B @T6G_MB_LIB.T6G(SCH_1):GND

Q_CAP_C0805-100UF,4V,20%,X6S,CH710KMEA01  I87  C409
   1 P0V9_CPU1_RT2_2A      A @T6G_MB_LIB.T6G(SCH_1):P0V9_CPU1_RT2_2A
   2    GND      B @T6G_MB_LIB.T6G(SCH_1):GND

Q_INDUCTOR_SMLF-BLM15PD121SN1D/1300MA,IND,CX5PD121A  I88  L32
   2 P1V8_CPU1_RT2_1A_1D      2 @T6G_MB_LIB.T6G(SCH_1):P1V8_CPU1_RT2_1A_1D
   1 P1V8_CPU1_RT_1D      1 @T6G_MB_LIB.T6G(SCH_1):P1V8_CPU1_RT_1D

Q_RES_0402LF-0,5%,1/16W,EMPTY,CS00002JB13  I89  R857
   1 P1V8_CPU1_RT_1D      A @T6G_MB_LIB.T6G(SCH_1):P1V8_CPU1_RT_1D
   2 P1V8_CPU1_RT2_1A_1D      B @T6G_MB_LIB.T6G(SCH_1):P1V8_CPU1_RT2_1A_1D

Q_CAP_0201-1UF,4V,20%,X6S,CH-10KMEE00  I90  C390
   1 P0V9_CPU1_RT2_2A_2D      A @T6G_MB_LIB.T6G(SCH_1):P0V9_CPU1_RT2_2A_2D
   2    GND      B @T6G_MB_LIB.T6G(SCH_1):GND

Q_CAP_0201-1UF,4V,20%,X6S,CH-10KMEE00  I91  C394
   1 P0V9_CPU1_RT2_2A_2D      A @T6G_MB_LIB.T6G(SCH_1):P0V9_CPU1_RT2_2A_2D
   2    GND      B @T6G_MB_LIB.T6G(SCH_1):GND

Q_CAP_C0201-0.1UF,10V,10%,X7S,CH4102K6E00  I92  C426
   1 P0V9_CPU1_RT2_2A      A @T6G_MB_LIB.T6G(SCH_1):P0V9_CPU1_RT2_2A
   2    GND      B @T6G_MB_LIB.T6G(SCH_1):GND

Q_CAP_C0201-0.1UF,10V,10%,X7S,CH4102K6E00  I93  C428
   1 P0V9_CPU1_RT2_2A      A @T6G_MB_LIB.T6G(SCH_1):P0V9_CPU1_RT2_2A
   2    GND      B @T6G_MB_LIB.T6G(SCH_1):GND

Q_CAPP_SMLF-470UF,2.5V,20%,SPCAP,CH747LM8818  I94  C7004
   1 P0V9_CPU1_RT_2D      A @T6G_MB_LIB.T6G(SCH_1):P0V9_CPU1_RT_2D
   2    GND      B @T6G_MB_LIB.T6G(SCH_1):GND

Q_CAPP_SMLF-470UF,2.5V,20%,SPCAP,CH747LM8818  I95  C7005
   1 P0V9_CPU1_RT_2D      A @T6G_MB_LIB.T6G(SCH_1):P0V9_CPU1_RT_2D
   2    GND      B @T6G_MB_LIB.T6G(SCH_1):GND

Q_CAP_C0805-47UF,4V,20%,X6S,CH647KMEA04  I96  C7006
   1 P0V9_CPU1_RT_2D      A @T6G_MB_LIB.T6G(SCH_1):P0V9_CPU1_RT_2D
   2    GND      B @T6G_MB_LIB.T6G(SCH_1):GND

Q_CAP_C0805-47UF,4V,20%,X6S,CH647KMEA04  I97  C7007
   1 P0V9_CPU1_RT_2D      A @T6G_MB_LIB.T6G(SCH_1):P0V9_CPU1_RT_2D
   2    GND      B @T6G_MB_LIB.T6G(SCH_1):GND

Q_CAPP_SMLF-470UF,2.5V,20%,SPCAP,CH747LM8818  I98  C7026
   1 P0V9_CPU1_RT2_2A      A @T6G_MB_LIB.T6G(SCH_1):P0V9_CPU1_RT2_2A
   2    GND      B @T6G_MB_LIB.T6G(SCH_1):GND

Q_CAPP_SMLF-470UF,2.5V,20%,SPCAP,CH747LM8818  I99  C7027
   1 P0V9_CPU1_RT2_2A      A @T6G_MB_LIB.T6G(SCH_1):P0V9_CPU1_RT2_2A
   2    GND      B @T6G_MB_LIB.T6G(SCH_1):GND

Q_CAP_C0805-100UF,4V,20%,X6S,CH710KMEA01  I100  C7028
   1 P0V9_CPU1_RT2_2A      A @T6G_MB_LIB.T6G(SCH_1):P0V9_CPU1_RT2_2A
   2    GND      B @T6G_MB_LIB.T6G(SCH_1):GND

Q_CAPP_SMLF-470UF,2.5V,20%,SPCAP,CH747LM8818  I101  C7037
   1 P0V9_CPU1_RT_2D      A @T6G_MB_LIB.T6G(SCH_1):P0V9_CPU1_RT_2D
   2    GND      B @T6G_MB_LIB.T6G(SCH_1):GND

Q_CAP_C0805-47UF,4V,20%,X6S,CH647KMEA04  I102  C7038
   1 P0V9_CPU1_RT_2D      A @T6G_MB_LIB.T6G(SCH_1):P0V9_CPU1_RT_2D
   2    GND      B @T6G_MB_LIB.T6G(SCH_1):GND

Q_CAP_C0805-47UF,4V,20%,X6S,CH647KMEA04  I103  C7039
   1 P0V9_CPU1_RT_2D      A @T6G_MB_LIB.T6G(SCH_1):P0V9_CPU1_RT_2D
   2    GND      B @T6G_MB_LIB.T6G(SCH_1):GND

Q_CAP_C0805-47UF,4V,20%,X6S,CH647KMEA04  I104  C7040
   1 P0V9_CPU1_RT_2D      A @T6G_MB_LIB.T6G(SCH_1):P0V9_CPU1_RT_2D
   2    GND      B @T6G_MB_LIB.T6G(SCH_1):GND

Q_CAP_C0805-47UF,4V,20%,X6S,CH647KMEA04  I105  C7041
   1 P0V9_CPU1_RT_2D      A @T6G_MB_LIB.T6G(SCH_1):P0V9_CPU1_RT_2D
   2    GND      B @T6G_MB_LIB.T6G(SCH_1):GND


DRAWING: @T6G_MB_LIB.T6G(SCH_1):PAGE462 

Q_RES_0201LF-4.7K,5%,1/20W,EMPTY,CS24701JE04  I17  R909
   1 P1V8_CPU1_RT_1D      A @T6G_MB_LIB.T6G(SCH_1):P1V8_CPU1_RT_1D
   2 RT_CPU1_P3_SCAN_MODE      B @T6G_MB_LIB.T6G(SCH_1):RT_CPU1_P3_SCAN_MODE

Q_RES_0201LF-10K,1%,1/20W,CHIP,CS31001FE17  I19  R916
   1 GPIO2_RT_CPU1_P3      A @T6G_MB_LIB.T6G(SCH_1):GPIO2_RT_CPU1_P3
   2    GND      B @T6G_MB_LIB.T6G(SCH_1):GND

Q_RES_0201LF-10K,1%,1/20W,CHIP,CS31001FE17  I20  R917
   1 GPIO3_RT_CPU1_P3      A @T6G_MB_LIB.T6G(SCH_1):GPIO3_RT_CPU1_P3
   2    GND      B @T6G_MB_LIB.T6G(SCH_1):GND

Q_RES_0201LF-4.7K,5%,1/20W,CHIP,CS24701JE04  I21  R919
   1 TEST0_RT_CPU1_P3      A @T6G_MB_LIB.T6G(SCH_1):TEST0_RT_CPU1_P3
   2    GND      B @T6G_MB_LIB.T6G(SCH_1):GND

Q_RES_0201LF-4.7K,5%,1/20W,EMPTY,CS24701JE04  I22  R915
   1 P1V8_CPU1_RT_1D      A @T6G_MB_LIB.T6G(SCH_1):P1V8_CPU1_RT_1D
   2 GPIO2_RT_CPU1_P3      B @T6G_MB_LIB.T6G(SCH_1):GPIO2_RT_CPU1_P3

Q_RES_0201LF-4.7K,5%,1/20W,EMPTY,CS24701JE04  I23  R918
   1 P1V8_CPU1_RT_1D      A @T6G_MB_LIB.T6G(SCH_1):P1V8_CPU1_RT_1D
   2 TEST0_RT_CPU1_P3      B @T6G_MB_LIB.T6G(SCH_1):TEST0_RT_CPU1_P3

Q_RES_0201LF-51.1,1%,1/20W,EMPTY,CS05111FE00  I30  R641
   1 CLK_100M_RETIMER_CPU1_P3_DN      A @T6G_MB_LIB.T6G(SCH_1):CLK_100M_RETIMER_CPU1_P3_DN
   2    GND      B @T6G_MB_LIB.T6G(SCH_1):GND

Q_RES_0201LF-0,5%,1/20W,CHIP,CS00001JE10  I31  R622
   1 CLK_100M_RETIMER_CPU1_P3_R_DN      A @T6G_MB_LIB.T6G(SCH_1):CLK_100M_RETIMER_CPU1_P3_R_DN
   2 CLK_100M_RETIMER_CPU1_P3_DN      B @T6G_MB_LIB.T6G(SCH_1):CLK_100M_RETIMER_CPU1_P3_DN

Q_RES_0201LF-0,5%,1/20W,CHIP,CS00001JE10  I32  R621
   1 CLK_100M_RETIMER_CPU1_P3_R_DP      A @T6G_MB_LIB.T6G(SCH_1):CLK_100M_RETIMER_CPU1_P3_R_DP
   2 CLK_100M_RETIMER_CPU1_P3_DP      B @T6G_MB_LIB.T6G(SCH_1):CLK_100M_RETIMER_CPU1_P3_DP

Q_RES_0201LF-49.9,1%,1/20W,CHIP,CS04991FE06  I33  R696
   1 SMB_RT_CPU1_P3_ROM_MUX_1D_SDA      A @T6G_MB_LIB.T6G(SCH_1):SMB_RT_CPU1_P3_ROM_MUX_1D_SDA
   2 SMB_RT_CPU1_P3_ROM_MUX_1D_R_SDA      B @T6G_MB_LIB.T6G(SCH_1):SMB_RT_CPU1_P3_ROM_MUX_1D_R_SDA

Q_RES_0201LF-0,5%,1/20W,CHIP,CS00001JE10  I41  R914
   1 SMB_RT_CPU1_P3_R_SDA      A @T6G_MB_LIB.T6G(SCH_1):SMB_RT_CPU1_P3_R_SDA
   2 SMB_RT_CPU1_P3_R2_SDA      B @T6G_MB_LIB.T6G(SCH_1):SMB_RT_CPU1_P3_R2_SDA

Q_RES_0201LF-0,5%,1/20W,CHIP,CS00001JE10  I42  R913
   1 SMB_RT_CPU1_P3_R_SCL      A @T6G_MB_LIB.T6G(SCH_1):SMB_RT_CPU1_P3_R_SCL
   2 SMB_RT_CPU1_P3_R2_SCL      B @T6G_MB_LIB.T6G(SCH_1):SMB_RT_CPU1_P3_R2_SCL

Q_RES_0201LF-51.1,1%,1/20W,EMPTY,CS05111FE00  I46  R642
   1 CLK_100M_RETIMER_CPU1_P3_DP      A @T6G_MB_LIB.T6G(SCH_1):CLK_100M_RETIMER_CPU1_P3_DP
   2    GND      B @T6G_MB_LIB.T6G(SCH_1):GND

Q_RES_0201LF-4.7K,5%,1/20W,CHIP,CS24701JE04  I50  R921
   1 TEST1_RT_CPU1_P3      A @T6G_MB_LIB.T6G(SCH_1):TEST1_RT_CPU1_P3
   2    GND      B @T6G_MB_LIB.T6G(SCH_1):GND

Q_RES_0201LF-4.7K,5%,1/20W,CHIP,CS24701JE04  I51  R923
   1 TEST2_RT_CPU1_P3      A @T6G_MB_LIB.T6G(SCH_1):TEST2_RT_CPU1_P3
   2    GND      B @T6G_MB_LIB.T6G(SCH_1):GND

Q_RES_0201LF-4.7K,5%,1/20W,CHIP,CS24701JE04  I53  R924
   1 JTAG_TEST_MODE_RT_CPU1_P3      A @T6G_MB_LIB.T6G(SCH_1):JTAG_TEST_MODE_RT_CPU1_P3
   2    GND      B @T6G_MB_LIB.T6G(SCH_1):GND

Q_RES_0201LF-4.7K,5%,1/20W,EMPTY,CS24701JE04  I54  R920
   1 P1V8_CPU1_RT_1D      A @T6G_MB_LIB.T6G(SCH_1):P1V8_CPU1_RT_1D
   2 TEST1_RT_CPU1_P3      B @T6G_MB_LIB.T6G(SCH_1):TEST1_RT_CPU1_P3

Q_RES_0201LF-4.7K,5%,1/20W,EMPTY,CS24701JE04  I55  R922
   1 P1V8_CPU1_RT_1D      A @T6G_MB_LIB.T6G(SCH_1):P1V8_CPU1_RT_1D
   2 TEST2_RT_CPU1_P3      B @T6G_MB_LIB.T6G(SCH_1):TEST2_RT_CPU1_P3

Q_RES_0201LF-4.7K,5%,1/20W,EMPTY,CS24701JE04  I56  R912
   1 P1V8_CPU1_RT_1D      A @T6G_MB_LIB.T6G(SCH_1):P1V8_CPU1_RT_1D
   2 JTAG_TEST_MODE_RT_CPU1_P3      B @T6G_MB_LIB.T6G(SCH_1):JTAG_TEST_MODE_RT_CPU1_P3

Q_RES_0201LF-4.7K,5%,1/20W,EMPTY,CS24701JE04  I64  R926
   1 MODE_RT_CPU1_P3      A @T6G_MB_LIB.T6G(SCH_1):MODE_RT_CPU1_P3
   2    GND      B @T6G_MB_LIB.T6G(SCH_1):GND

Q_RES_0201LF-4.7K,5%,1/20W,CHIP,CS24701JE04  I65  R925
   1 P1V8_CPU1_RT_1D      A @T6G_MB_LIB.T6G(SCH_1):P1V8_CPU1_RT_1D
   2 MODE_RT_CPU1_P3      B @T6G_MB_LIB.T6G(SCH_1):MODE_RT_CPU1_P3

Q_RES_0201LF-0,5%,1/20W,CHIP,CS00001JE10  I69  R895
   1 RST_RT_CPU1_P3_PERST_N      A @T6G_MB_LIB.T6G(SCH_1):RST_RT_CPU1_P3_PERST_N
   2 RST_RT_CPU1_P3_PERST_R_N      B @T6G_MB_LIB.T6G(SCH_1):RST_RT_CPU1_P3_PERST_R_N

Q_RES_0201LF-0,5%,1/20W,CHIP,CS00001JE10  I70  R901
   1 RST_RT_CPU1_P3_RESET_N      A @T6G_MB_LIB.T6G(SCH_1):RST_RT_CPU1_P3_RESET_N
   2 RST_RT_CPU1_P3_RESET_R_N      B @T6G_MB_LIB.T6G(SCH_1):RST_RT_CPU1_P3_RESET_R_N

Q_RES_0201LF-1K,1%,1/20W,EMPTY,CS21001FE07  I79  R903
   1 RT_CPU1_P3_ADDR3      A @T6G_MB_LIB.T6G(SCH_1):RT_CPU1_P3_ADDR3
   2    GND      B @T6G_MB_LIB.T6G(SCH_1):GND

Q_RES_0201LF-1K,1%,1/20W,CHIP,CS21001FE07  I80  R902
   1 P1V8_CPU1_RT_1D      A @T6G_MB_LIB.T6G(SCH_1):P1V8_CPU1_RT_1D
   2 RT_CPU1_P3_ADDR3      B @T6G_MB_LIB.T6G(SCH_1):RT_CPU1_P3_ADDR3

Q_RES_0201LF-20K,1%,1/20W,CHIP,CS32001FE00  I81  R906
   1 RT_CPU1_P3_ADDR2      A @T6G_MB_LIB.T6G(SCH_1):RT_CPU1_P3_ADDR2
   2    GND      B @T6G_MB_LIB.T6G(SCH_1):GND

Q_RES_0201LF-1K,1%,1/20W,EMPTY,CS21001FE07  I82  R904
   1 P1V8_CPU1_RT_1D      A @T6G_MB_LIB.T6G(SCH_1):P1V8_CPU1_RT_1D
   2 RT_CPU1_P3_ADDR2      B @T6G_MB_LIB.T6G(SCH_1):RT_CPU1_P3_ADDR2

Q_RES_0201LF-1K,1%,1/20W,CHIP,CS21001FE07  I83  R949
   1 RT_CPU1_P3_ADDR1      A @T6G_MB_LIB.T6G(SCH_1):RT_CPU1_P3_ADDR1
   2    GND      B @T6G_MB_LIB.T6G(SCH_1):GND

Q_RES_0201LF-1K,1%,1/20W,EMPTY,CS21001FE07  I84  R927
   1 P1V8_CPU1_RT_1D      A @T6G_MB_LIB.T6G(SCH_1):P1V8_CPU1_RT_1D
   2 RT_CPU1_P3_ADDR1      B @T6G_MB_LIB.T6G(SCH_1):RT_CPU1_P3_ADDR1

Q_RES_0201LF-10K,1%,1/20W,CHIP,CS31001FE17  I90  R908
   1 RST_RT_CPU1_P3_RESET_R_N      A @T6G_MB_LIB.T6G(SCH_1):RST_RT_CPU1_P3_RESET_R_N
   2    GND      B @T6G_MB_LIB.T6G(SCH_1):GND

Q_RES_0201LF-10K,1%,1/20W,CHIP,CS31001FE17  I92  R907
   1 RST_RT_CPU1_P3_PERST_R_N      A @T6G_MB_LIB.T6G(SCH_1):RST_RT_CPU1_P3_PERST_R_N
   2    GND      B @T6G_MB_LIB.T6G(SCH_1):GND

Q_RES_0201LF-4.7K,5%,1/20W,EMPTY,CS24701JE04  I93  R911
   1 P1V8_CPU1_RT_1D      A @T6G_MB_LIB.T6G(SCH_1):P1V8_CPU1_RT_1D
   2 RST_RT_CPU1_P3_RESET_R_N      B @T6G_MB_LIB.T6G(SCH_1):RST_RT_CPU1_P3_RESET_R_N

PT5161LRS-PT5161LRS,SMLF,IC,AJ051610U03  I97  U6017
 FJ6     NC  GPIO0     NC
FJ23     NC  GPIO1     NC
FJ25 GPIO2_RT_CPU1_P3  GPIO2 @T6G_MB_LIB.T6G(SCH_1):GPIO2_RT_CPU1_P3
FJ28 GPIO3_RT_CPU1_P3  GPIO3 @T6G_MB_LIB.T6G(SCH_1):GPIO3_RT_CPU1_P3
FJ31     NC  INT_N     NC
  B3 JTAG_TCK_RT_CPU1_P3 JTAG_TCK @T6G_MB_LIB.T6G(SCH_1):JTAG_TCK_RT_CPU1_P3
  B6 JTAG_TDI_RT_CPU1_P3 JTAG_TDI @T6G_MB_LIB.T6G(SCH_1):JTAG_TDI_RT_CPU1_P3
  B9 JTAG_TDO_RT_CPU1_P3 JTAG_TDO @T6G_MB_LIB.T6G(SCH_1):JTAG_TDO_RT_CPU1_P3
 FF8 JTAG_TEST_MODE_RT_CPU1_P3 JTAG_TEST_MODE @T6G_MB_LIB.T6G(SCH_1):JTAG_TEST_MODE_RT_CPU1_P3
 B12 JTAG_TMS_RT_CPU1_P3 JTAG_TMS @T6G_MB_LIB.T6G(SCH_1):JTAG_TMS_RT_CPU1_P3
  E8 JTAG_TRST_RT_CPU1_P3_N JTAG_TRST_N @T6G_MB_LIB.T6G(SCH_1):JTAG_TRST_RT_CPU1_P3_N
 FJ9 MODE_RT_CPU1_P3   MODE @T6G_MB_LIB.T6G(SCH_1):MODE_RT_CPU1_P3
  F2 RST_RT_CPU1_P3_PERST_N PERST_N @T6G_MB_LIB.T6G(SCH_1):RST_RT_CPU1_P3_PERST_N
 E18     NC REFCLK_OUTN     NC
 B16     NC REFCLK_OUTP     NC
FF18 CLK_100M_RETIMER_CPU1_P3_DN REFCLKN @T6G_MB_LIB.T6G(SCH_1):CLK_100M_RETIMER_CPU1_P3_DN
FJ16 CLK_100M_RETIMER_CPU1_P3_DP REFCLKP @T6G_MB_LIB.T6G(SCH_1):CLK_100M_RETIMER_CPU1_P3_DP
FF11 RST_RT_CPU1_P3_RESET_N RESET_N @T6G_MB_LIB.T6G(SCH_1):RST_RT_CPU1_P3_RESET_N
 E11 RXDET_BYP_RT_CPU1_P3 RXDET_BYP @T6G_MB_LIB.T6G(SCH_1):RXDET_BYP_RT_CPU1_P3
FF33 RT_CPU1_P3_SCAN_MODE SCAN_MODE @T6G_MB_LIB.T6G(SCH_1):RT_CPU1_P3_SCAN_MODE
 F34 RT_CPU1_P3_ADDR1 SMB_ADDR1 @T6G_MB_LIB.T6G(SCH_1):RT_CPU1_P3_ADDR1
 B23 RT_CPU1_P3_ADDR2 SMB_ADDR2 @T6G_MB_LIB.T6G(SCH_1):RT_CPU1_P3_ADDR2
 B25 RT_CPU1_P3_ADDR3 SMB_ADDR3 @T6G_MB_LIB.T6G(SCH_1):RT_CPU1_P3_ADDR3
 B31 SMB_RT_CPU1_P3_R2_SCL SMBCLK @T6G_MB_LIB.T6G(SCH_1):SMB_RT_CPU1_P3_R2_SCL
 B28 SMB_RT_CPU1_P3_R2_SDA SMBDAT @T6G_MB_LIB.T6G(SCH_1):SMB_RT_CPU1_P3_R2_SDA
 E30    GND T_SENSE @T6G_MB_LIB.T6G(SCH_1):GND
FF24 TEST0_RT_CPU1_P3  TEST0 @T6G_MB_LIB.T6G(SCH_1):TEST0_RT_CPU1_P3
FF27 TEST1_RT_CPU1_P3  TEST1 @T6G_MB_LIB.T6G(SCH_1):TEST1_RT_CPU1_P3
FF30 TEST2_RT_CPU1_P3  TEST2 @T6G_MB_LIB.T6G(SCH_1):TEST2_RT_CPU1_P3
 G35 CLKREQ_RT_CPU1_P3_N CLKREQ_N @T6G_MB_LIB.T6G(SCH_1):CLKREQ_RT_CPU1_P3_N
 FF5 SMB_RT_CPU1_P3_ROM_MUX_1D_R_SCL EE_CLK @T6G_MB_LIB.T6G(SCH_1):SMB_RT_CPU1_P3_ROM_MUX_1D_R_SCL
 FJ3 SMB_RT_CPU1_P3_ROM_MUX_1D_R_SDA EE_DAT @T6G_MB_LIB.T6G(SCH_1):SMB_RT_CPU1_P3_ROM_MUX_1D_R_SDA

Q_RES_0201LF-4.7K,5%,1/20W,CHIP,CS24701JE04  I98  R1433
   1 CLKREQ_RT_CPU1_P3_N      A @T6G_MB_LIB.T6G(SCH_1):CLKREQ_RT_CPU1_P3_N
   2    GND      B @T6G_MB_LIB.T6G(SCH_1):GND

Q_RES_0201LF-1K,1%,1/20W,CHIP,CS21001FE07  I103  R1429
   1 JTAG_TRST_RT_CPU1_P3_N      A @T6G_MB_LIB.T6G(SCH_1):JTAG_TRST_RT_CPU1_P3_N
   2    GND      B @T6G_MB_LIB.T6G(SCH_1):GND

Q_RES_0201LF-10K,1%,1/20W,CHIP,CS31001FE17  I114  R1435
   1 RXDET_BYP_RT_CPU1_P3      A @T6G_MB_LIB.T6G(SCH_1):RXDET_BYP_RT_CPU1_P3
   2    GND      B @T6G_MB_LIB.T6G(SCH_1):GND

Q_RES_0201LF-1K,1%,1/20W,EMPTY,CS21001FE07  I115  R1434
   1 P1V8_CPU1_RT_1D      A @T6G_MB_LIB.T6G(SCH_1):P1V8_CPU1_RT_1D
   2 RXDET_BYP_RT_CPU1_P3      B @T6G_MB_LIB.T6G(SCH_1):RXDET_BYP_RT_CPU1_P3

Q_RES_0201LF-200,1%,1/20W,CHIP,CS12001FE12  I119  R910
   1 RT_CPU1_P3_SCAN_MODE      A @T6G_MB_LIB.T6G(SCH_1):RT_CPU1_P3_SCAN_MODE
   2    GND      B @T6G_MB_LIB.T6G(SCH_1):GND

Q_RES_0201LF-4.7K,5%,1/20W,EMPTY,CS24701JE04  I132  R1511
   1 P1V8_CPU1_RT_1D      A @T6G_MB_LIB.T6G(SCH_1):P1V8_CPU1_RT_1D
   2 JTAG_TMS_RT_CPU1_P3      B @T6G_MB_LIB.T6G(SCH_1):JTAG_TMS_RT_CPU1_P3

Q_RES_0201LF-4.7K,5%,1/20W,CHIP,CS24701JE04  I136  R1430
   1 JTAG_TCK_RT_CPU1_P3      A @T6G_MB_LIB.T6G(SCH_1):JTAG_TCK_RT_CPU1_P3
   2    GND      B @T6G_MB_LIB.T6G(SCH_1):GND

Q_RES_0201LF-4.7K,5%,1/20W,EMPTY,CS24701JE04  I137  R1513
   1 P1V8_CPU1_RT_1D      A @T6G_MB_LIB.T6G(SCH_1):P1V8_CPU1_RT_1D
   2 JTAG_TCK_RT_CPU1_P3      B @T6G_MB_LIB.T6G(SCH_1):JTAG_TCK_RT_CPU1_P3

Q_RES_0201LF-4.7K,5%,1/20W,EMPTY,CS24701JE04  I139  R1510
   1 P1V8_CPU1_RT_1D      A @T6G_MB_LIB.T6G(SCH_1):P1V8_CPU1_RT_1D
   2 JTAG_TDI_RT_CPU1_P3      B @T6G_MB_LIB.T6G(SCH_1):JTAG_TDI_RT_CPU1_P3

Q_RES_0201LF-1K,1%,1/20W,EMPTY,CS21001FE07  I140  R1512
   1 P1V8_CPU1_RT_1D      A @T6G_MB_LIB.T6G(SCH_1):P1V8_CPU1_RT_1D
   2 JTAG_TDO_RT_CPU1_P3      B @T6G_MB_LIB.T6G(SCH_1):JTAG_TDO_RT_CPU1_P3

Q_RES_0201LF-22,1%,1/20W,CHIP,CS02201FE11  I146  R695
   1 SMB_RT_CPU1_P3_ROM_MUX_1D_SCL      A @T6G_MB_LIB.T6G(SCH_1):SMB_RT_CPU1_P3_ROM_MUX_1D_SCL
   2 SMB_RT_CPU1_P3_ROM_MUX_1D_R_SCL      B @T6G_MB_LIB.T6G(SCH_1):SMB_RT_CPU1_P3_ROM_MUX_1D_R_SCL


DRAWING: @T6G_MB_LIB.T6G(SCH_1):PAGE463 

PT5161LRS-PT5161LRS,SMLF,IC,AJ051610U03  I5  U6017
  G1 RT_CPU1_P3_VQPS   VQPS @T6G_MB_LIB.T6G(SCH_1):RT_CPU1_P3_VQPS
BV20 P1V8_CPU1_RT3_1A PWR_1A_1 @T6G_MB_LIB.T6G(SCH_1):P1V8_CPU1_RT3_1A
CE17 P1V8_CPU1_RT3_1A PWR_1A_2 @T6G_MB_LIB.T6G(SCH_1):P1V8_CPU1_RT3_1A
CE20 P1V8_CPU1_RT3_1A PWR_1A_3 @T6G_MB_LIB.T6G(SCH_1):P1V8_CPU1_RT3_1A
CM17 P1V8_CPU1_RT3_1A PWR_1A_4 @T6G_MB_LIB.T6G(SCH_1):P1V8_CPU1_RT3_1A
CM20 P1V8_CPU1_RT3_1A PWR_1A_5 @T6G_MB_LIB.T6G(SCH_1):P1V8_CPU1_RT3_1A
BL17 P0V9_CPU1_RT_2D PWR_2D_1 @T6G_MB_LIB.T6G(SCH_1):P0V9_CPU1_RT_2D
BL20 P0V9_CPU1_RT_2D PWR_2D_2 @T6G_MB_LIB.T6G(SCH_1):P0V9_CPU1_RT_2D
CW17 P0V9_CPU1_RT_2D PWR_2D_3 @T6G_MB_LIB.T6G(SCH_1):P0V9_CPU1_RT_2D
CW20 P0V9_CPU1_RT_2D PWR_2D_4 @T6G_MB_LIB.T6G(SCH_1):P0V9_CPU1_RT_2D
BV17 P1V8_CPU1_RT3_1A_1D PWR_1D @T6G_MB_LIB.T6G(SCH_1):P1V8_CPU1_RT3_1A_1D
AC17 P0V9_CPU1_RT3_2A PWR_2A_1 @T6G_MB_LIB.T6G(SCH_1):P0V9_CPU1_RT3_2A
AC20 P0V9_CPU1_RT3_2A PWR_2A_2 @T6G_MB_LIB.T6G(SCH_1):P0V9_CPU1_RT3_2A
AK17 P0V9_CPU1_RT3_2A PWR_2A_3 @T6G_MB_LIB.T6G(SCH_1):P0V9_CPU1_RT3_2A
AK20 P0V9_CPU1_RT3_2A PWR_2A_4 @T6G_MB_LIB.T6G(SCH_1):P0V9_CPU1_RT3_2A
AU17 P0V9_CPU1_RT3_2A PWR_2A_5 @T6G_MB_LIB.T6G(SCH_1):P0V9_CPU1_RT3_2A
AU20 P0V9_CPU1_RT3_2A PWR_2A_6 @T6G_MB_LIB.T6G(SCH_1):P0V9_CPU1_RT3_2A
BD17 P0V9_CPU1_RT3_2A_2D PWR_2A_7 @T6G_MB_LIB.T6G(SCH_1):P0V9_CPU1_RT3_2A_2D
BD20 P0V9_CPU1_RT3_2A_2D PWR_2A_8 @T6G_MB_LIB.T6G(SCH_1):P0V9_CPU1_RT3_2A_2D
DF17 P0V9_CPU1_RT3_2A_2D PWR_2A_9 @T6G_MB_LIB.T6G(SCH_1):P0V9_CPU1_RT3_2A_2D
DF20 P0V9_CPU1_RT3_2A_2D PWR_2A_10 @T6G_MB_LIB.T6G(SCH_1):P0V9_CPU1_RT3_2A_2D
DN17 P0V9_CPU1_RT3_2A PWR_2A_11 @T6G_MB_LIB.T6G(SCH_1):P0V9_CPU1_RT3_2A
DN20 P0V9_CPU1_RT3_2A PWR_2A_12 @T6G_MB_LIB.T6G(SCH_1):P0V9_CPU1_RT3_2A
DY17 P0V9_CPU1_RT3_2A PWR_2A_13 @T6G_MB_LIB.T6G(SCH_1):P0V9_CPU1_RT3_2A
DY20 P0V9_CPU1_RT3_2A PWR_2A_14 @T6G_MB_LIB.T6G(SCH_1):P0V9_CPU1_RT3_2A
EG17 P0V9_CPU1_RT3_2A PWR_2A_15 @T6G_MB_LIB.T6G(SCH_1):P0V9_CPU1_RT3_2A
EG20 P0V9_CPU1_RT3_2A PWR_2A_16 @T6G_MB_LIB.T6G(SCH_1):P0V9_CPU1_RT3_2A
EP17 P0V9_CPU1_RT3_2A PWR_2A_17 @T6G_MB_LIB.T6G(SCH_1):P0V9_CPU1_RT3_2A
EP20 P0V9_CPU1_RT3_2A PWR_2A_18 @T6G_MB_LIB.T6G(SCH_1):P0V9_CPU1_RT3_2A
 T17 P0V9_CPU1_RT3_2A PWR_2A_19 @T6G_MB_LIB.T6G(SCH_1):P0V9_CPU1_RT3_2A
 T20 P0V9_CPU1_RT3_2A PWR_2A_20 @T6G_MB_LIB.T6G(SCH_1):P0V9_CPU1_RT3_2A

Q_RES_0201LF-0,5%,1/20W,CHIP,CS00001JE10  I13  R6903
   1 NCF_CPU1_P3_GND      A @T6G_MB_LIB.T6G(SCH_1):NCF_CPU1_P3_GND
   2    GND      B @T6G_MB_LIB.T6G(SCH_1):GND

Q_RES_0201LF-0,5%,1/20W,CHIP,CS00001JE10  I15  R6902
   1 NCF_A1_CPU1_P3_GND      A @T6G_MB_LIB.T6G(SCH_1):NCF_A1_CPU1_P3_GND
   2    GND      B @T6G_MB_LIB.T6G(SCH_1):GND

PT5161LRS-PT5161LRS,SMLF,IC,AJ051610U03  I17  U6017
AC13    GND   GND1 @T6G_MB_LIB.T6G(SCH_1):GND
AC22    GND   GND2 @T6G_MB_LIB.T6G(SCH_1):GND
AC32    GND   GND3 @T6G_MB_LIB.T6G(SCH_1):GND
 AC4    GND   GND4 @T6G_MB_LIB.T6G(SCH_1):GND
 AD2    GND   GND5 @T6G_MB_LIB.T6G(SCH_1):GND
AD34    GND   GND6 @T6G_MB_LIB.T6G(SCH_1):GND
 AE1    GND   GND7 @T6G_MB_LIB.T6G(SCH_1):GND
AE35    GND   GND8 @T6G_MB_LIB.T6G(SCH_1):GND
AK13    GND   GND9 @T6G_MB_LIB.T6G(SCH_1):GND
AK22    GND  GND10 @T6G_MB_LIB.T6G(SCH_1):GND
AK32    GND  GND11 @T6G_MB_LIB.T6G(SCH_1):GND
 AK4    GND  GND12 @T6G_MB_LIB.T6G(SCH_1):GND
 AL2    GND  GND13 @T6G_MB_LIB.T6G(SCH_1):GND
AL34    GND  GND14 @T6G_MB_LIB.T6G(SCH_1):GND
 AM1    GND  GND15 @T6G_MB_LIB.T6G(SCH_1):GND
AM35    GND  GND16 @T6G_MB_LIB.T6G(SCH_1):GND
AU13    GND  GND17 @T6G_MB_LIB.T6G(SCH_1):GND
AU22    GND  GND18 @T6G_MB_LIB.T6G(SCH_1):GND
AU32    GND  GND19 @T6G_MB_LIB.T6G(SCH_1):GND
 AU4    GND  GND20 @T6G_MB_LIB.T6G(SCH_1):GND
 AV2    GND  GND21 @T6G_MB_LIB.T6G(SCH_1):GND
AV34    GND  GND22 @T6G_MB_LIB.T6G(SCH_1):GND
 AW1    GND  GND23 @T6G_MB_LIB.T6G(SCH_1):GND
AW35    GND  GND24 @T6G_MB_LIB.T6G(SCH_1):GND
 B19    GND  GND25 @T6G_MB_LIB.T6G(SCH_1):GND
BD13    GND  GND26 @T6G_MB_LIB.T6G(SCH_1):GND
BD22    GND  GND27 @T6G_MB_LIB.T6G(SCH_1):GND
BD32    GND  GND28 @T6G_MB_LIB.T6G(SCH_1):GND
 BD4    GND  GND29 @T6G_MB_LIB.T6G(SCH_1):GND
 BE2    GND  GND30 @T6G_MB_LIB.T6G(SCH_1):GND
BE34    GND  GND31 @T6G_MB_LIB.T6G(SCH_1):GND
 BF1    GND  GND32 @T6G_MB_LIB.T6G(SCH_1):GND
BF35    GND  GND33 @T6G_MB_LIB.T6G(SCH_1):GND
BL13    GND  GND34 @T6G_MB_LIB.T6G(SCH_1):GND
BL22    GND  GND35 @T6G_MB_LIB.T6G(SCH_1):GND
BL32    GND  GND36 @T6G_MB_LIB.T6G(SCH_1):GND
 BL4    GND  GND37 @T6G_MB_LIB.T6G(SCH_1):GND
 BM2    GND  GND38 @T6G_MB_LIB.T6G(SCH_1):GND
BM34    GND  GND39 @T6G_MB_LIB.T6G(SCH_1):GND
 BN1    GND  GND40 @T6G_MB_LIB.T6G(SCH_1):GND
BN35    GND  GND41 @T6G_MB_LIB.T6G(SCH_1):GND
BV13    GND  GND42 @T6G_MB_LIB.T6G(SCH_1):GND
BV22    GND  GND43 @T6G_MB_LIB.T6G(SCH_1):GND
BV32    GND  GND44 @T6G_MB_LIB.T6G(SCH_1):GND
 BV4    GND  GND45 @T6G_MB_LIB.T6G(SCH_1):GND
 BW2    GND  GND46 @T6G_MB_LIB.T6G(SCH_1):GND
BW34    GND  GND47 @T6G_MB_LIB.T6G(SCH_1):GND
 BY1    GND  GND48 @T6G_MB_LIB.T6G(SCH_1):GND
BY35    GND  GND49 @T6G_MB_LIB.T6G(SCH_1):GND
CE13    GND  GND50 @T6G_MB_LIB.T6G(SCH_1):GND
CE22    GND  GND51 @T6G_MB_LIB.T6G(SCH_1):GND
CE32    GND  GND52 @T6G_MB_LIB.T6G(SCH_1):GND
 CE4    GND  GND53 @T6G_MB_LIB.T6G(SCH_1):GND
 CF2    GND  GND54 @T6G_MB_LIB.T6G(SCH_1):GND
CF34    GND  GND55 @T6G_MB_LIB.T6G(SCH_1):GND
 CG1    GND  GND56 @T6G_MB_LIB.T6G(SCH_1):GND
CG35    GND  GND57 @T6G_MB_LIB.T6G(SCH_1):GND
CM13    GND  GND58 @T6G_MB_LIB.T6G(SCH_1):GND
CM22    GND  GND59 @T6G_MB_LIB.T6G(SCH_1):GND
CM32    GND  GND60 @T6G_MB_LIB.T6G(SCH_1):GND
 CM4    GND  GND61 @T6G_MB_LIB.T6G(SCH_1):GND
 CN2    GND  GND62 @T6G_MB_LIB.T6G(SCH_1):GND
CN34    GND  GND63 @T6G_MB_LIB.T6G(SCH_1):GND
 CP1    GND  GND64 @T6G_MB_LIB.T6G(SCH_1):GND
CP35    GND  GND65 @T6G_MB_LIB.T6G(SCH_1):GND
CW13    GND  GND66 @T6G_MB_LIB.T6G(SCH_1):GND
CW22    GND  GND67 @T6G_MB_LIB.T6G(SCH_1):GND
CW32    GND  GND68 @T6G_MB_LIB.T6G(SCH_1):GND
 CW4    GND  GND69 @T6G_MB_LIB.T6G(SCH_1):GND
 CY2    GND  GND70 @T6G_MB_LIB.T6G(SCH_1):GND
CY34    GND  GND71 @T6G_MB_LIB.T6G(SCH_1):GND
 DA1    GND  GND72 @T6G_MB_LIB.T6G(SCH_1):GND
DA35    GND  GND73 @T6G_MB_LIB.T6G(SCH_1):GND
DF13    GND  GND74 @T6G_MB_LIB.T6G(SCH_1):GND
DF22    GND  GND75 @T6G_MB_LIB.T6G(SCH_1):GND
DF32    GND  GND76 @T6G_MB_LIB.T6G(SCH_1):GND
 DF4    GND  GND77 @T6G_MB_LIB.T6G(SCH_1):GND
 DG2    GND  GND78 @T6G_MB_LIB.T6G(SCH_1):GND
DG34    GND  GND79 @T6G_MB_LIB.T6G(SCH_1):GND
 DH1    GND  GND80 @T6G_MB_LIB.T6G(SCH_1):GND
DH35    GND  GND81 @T6G_MB_LIB.T6G(SCH_1):GND
DN13    GND  GND82 @T6G_MB_LIB.T6G(SCH_1):GND
  A1 NCF_A1_CPU1_P3_GND NCF_GND1 @T6G_MB_LIB.T6G(SCH_1):NCF_A1_CPU1_P3_GND
 A35 NCF_CPU1_P3_GND NCF_GND2 @T6G_MB_LIB.T6G(SCH_1):NCF_CPU1_P3_GND
  C2 NCF_CPU1_P3_GND NCF_GND3 @T6G_MB_LIB.T6G(SCH_1):NCF_CPU1_P3_GND
 C34 NCF_CPU1_P3_GND NCF_GND4 @T6G_MB_LIB.T6G(SCH_1):NCF_CPU1_P3_GND
  D1 NCF_CPU1_P3_GND NCF_GND5 @T6G_MB_LIB.T6G(SCH_1):NCF_CPU1_P3_GND
 D35 NCF_CPU1_P3_GND NCF_GND6 @T6G_MB_LIB.T6G(SCH_1):NCF_CPU1_P3_GND
 FE2 NCF_CPU1_P3_GND NCF_GND7 @T6G_MB_LIB.T6G(SCH_1):NCF_CPU1_P3_GND
FE34 NCF_CPU1_P3_GND NCF_GND8 @T6G_MB_LIB.T6G(SCH_1):NCF_CPU1_P3_GND
 FG1 NCF_CPU1_P3_GND NCF_GND9 @T6G_MB_LIB.T6G(SCH_1):NCF_CPU1_P3_GND
FG35 NCF_CPU1_P3_GND NCF_GND10 @T6G_MB_LIB.T6G(SCH_1):NCF_CPU1_P3_GND
 FH2 NCF_CPU1_P3_GND NCF_GND11 @T6G_MB_LIB.T6G(SCH_1):NCF_CPU1_P3_GND
FH34 NCF_CPU1_P3_GND NCF_GND12 @T6G_MB_LIB.T6G(SCH_1):NCF_CPU1_P3_GND
DN22    GND  GND83 @T6G_MB_LIB.T6G(SCH_1):GND
DN32    GND  GND84 @T6G_MB_LIB.T6G(SCH_1):GND
 DN4    GND  GND85 @T6G_MB_LIB.T6G(SCH_1):GND
 DP2    GND  GND86 @T6G_MB_LIB.T6G(SCH_1):GND
DP34    GND  GND87 @T6G_MB_LIB.T6G(SCH_1):GND
 DR1    GND  GND88 @T6G_MB_LIB.T6G(SCH_1):GND
DR35    GND  GND89 @T6G_MB_LIB.T6G(SCH_1):GND
DY13    GND  GND90 @T6G_MB_LIB.T6G(SCH_1):GND
DY22    GND  GND91 @T6G_MB_LIB.T6G(SCH_1):GND
DY32    GND  GND92 @T6G_MB_LIB.T6G(SCH_1):GND
 DY4    GND  GND93 @T6G_MB_LIB.T6G(SCH_1):GND
 E14    GND  GND94 @T6G_MB_LIB.T6G(SCH_1):GND
 E27    GND  GND95 @T6G_MB_LIB.T6G(SCH_1):GND
 E33    GND  GND96 @T6G_MB_LIB.T6G(SCH_1):GND
 EA2    GND  GND97 @T6G_MB_LIB.T6G(SCH_1):GND
EA34    GND  GND98 @T6G_MB_LIB.T6G(SCH_1):GND
 EB1    GND  GND99 @T6G_MB_LIB.T6G(SCH_1):GND
EB35    GND GND100 @T6G_MB_LIB.T6G(SCH_1):GND
EG13    GND GND101 @T6G_MB_LIB.T6G(SCH_1):GND
EG22    GND GND102 @T6G_MB_LIB.T6G(SCH_1):GND
EG32    GND GND103 @T6G_MB_LIB.T6G(SCH_1):GND
 EG4    GND GND104 @T6G_MB_LIB.T6G(SCH_1):GND
 EH2    GND GND105 @T6G_MB_LIB.T6G(SCH_1):GND
EH34    GND GND106 @T6G_MB_LIB.T6G(SCH_1):GND
 EJ1    GND GND107 @T6G_MB_LIB.T6G(SCH_1):GND
EJ35    GND GND108 @T6G_MB_LIB.T6G(SCH_1):GND
EP13    GND GND109 @T6G_MB_LIB.T6G(SCH_1):GND
EP22    GND GND110 @T6G_MB_LIB.T6G(SCH_1):GND
EP32    GND GND111 @T6G_MB_LIB.T6G(SCH_1):GND
 EP4    GND GND112 @T6G_MB_LIB.T6G(SCH_1):GND
 ER2    GND GND113 @T6G_MB_LIB.T6G(SCH_1):GND
ER34    GND GND114 @T6G_MB_LIB.T6G(SCH_1):GND
 ET1    GND GND115 @T6G_MB_LIB.T6G(SCH_1):GND
ET35    GND GND116 @T6G_MB_LIB.T6G(SCH_1):GND
FA15    GND GND117 @T6G_MB_LIB.T6G(SCH_1):GND
FA32    GND GND118 @T6G_MB_LIB.T6G(SCH_1):GND
 FB2    GND GND119 @T6G_MB_LIB.T6G(SCH_1):GND
FB34    GND GND120 @T6G_MB_LIB.T6G(SCH_1):GND
FC19    GND GND121 @T6G_MB_LIB.T6G(SCH_1):GND
FC23    GND GND122 @T6G_MB_LIB.T6G(SCH_1):GND
FC25    GND GND123 @T6G_MB_LIB.T6G(SCH_1):GND
FC28    GND GND124 @T6G_MB_LIB.T6G(SCH_1):GND
 FC3    GND GND125 @T6G_MB_LIB.T6G(SCH_1):GND
 FC6    GND GND126 @T6G_MB_LIB.T6G(SCH_1):GND
 FC9    GND GND127 @T6G_MB_LIB.T6G(SCH_1):GND
 FD1    GND GND128 @T6G_MB_LIB.T6G(SCH_1):GND
FD35    GND GND129 @T6G_MB_LIB.T6G(SCH_1):GND
FF14    GND GND130 @T6G_MB_LIB.T6G(SCH_1):GND
FF21    GND GND131 @T6G_MB_LIB.T6G(SCH_1):GND
FJ12    GND GND132 @T6G_MB_LIB.T6G(SCH_1):GND
FJ19    GND GND133 @T6G_MB_LIB.T6G(SCH_1):GND
 H12    GND GND134 @T6G_MB_LIB.T6G(SCH_1):GND
 H16    GND GND135 @T6G_MB_LIB.T6G(SCH_1):GND
 H19    GND GND136 @T6G_MB_LIB.T6G(SCH_1):GND
 H31    GND GND137 @T6G_MB_LIB.T6G(SCH_1):GND
 J22    GND GND138 @T6G_MB_LIB.T6G(SCH_1):GND
  J4    GND GND139 @T6G_MB_LIB.T6G(SCH_1):GND
  K2    GND GND140 @T6G_MB_LIB.T6G(SCH_1):GND
 K34    GND GND141 @T6G_MB_LIB.T6G(SCH_1):GND
  L1    GND GND142 @T6G_MB_LIB.T6G(SCH_1):GND
 L35    GND GND143 @T6G_MB_LIB.T6G(SCH_1):GND
 T13    GND GND144 @T6G_MB_LIB.T6G(SCH_1):GND
 T22    GND GND145 @T6G_MB_LIB.T6G(SCH_1):GND
 T32    GND GND146 @T6G_MB_LIB.T6G(SCH_1):GND
  T4    GND GND147 @T6G_MB_LIB.T6G(SCH_1):GND
  U2    GND GND148 @T6G_MB_LIB.T6G(SCH_1):GND
 U34    GND GND149 @T6G_MB_LIB.T6G(SCH_1):GND
  V1    GND GND150 @T6G_MB_LIB.T6G(SCH_1):GND
 V35    GND GND151 @T6G_MB_LIB.T6G(SCH_1):GND

Q_RES_0201LF-200,1%,1/20W,CHIP,CS12001FE12  I18  R6901
   1 RT_CPU1_P3_VQPS      A @T6G_MB_LIB.T6G(SCH_1):RT_CPU1_P3_VQPS
   2    GND      B @T6G_MB_LIB.T6G(SCH_1):GND

Q_RES_0201LF-1K,1%,1/20W,EMPTY,CS21001FE07  I19  R6900
   1 P1V8_CPU1_RT_1D      A @T6G_MB_LIB.T6G(SCH_1):P1V8_CPU1_RT_1D
   2 RT_CPU1_P3_VQPS      B @T6G_MB_LIB.T6G(SCH_1):RT_CPU1_P3_VQPS


DRAWING: @T6G_MB_LIB.T6G(SCH_1):PAGE465 

Q_RES_0402LF-0,5%,1/16W,EMPTY,CS00002JB13  I1  R894
   1 P1V8_CPU1_RT3_1A_1D      A @T6G_MB_LIB.T6G(SCH_1):P1V8_CPU1_RT3_1A_1D
   2 P1V8_CPU1_RT3_1A      B @T6G_MB_LIB.T6G(SCH_1):P1V8_CPU1_RT3_1A

Q_RES_0402LF-0,5%,1/16W,EMPTY,CS00002JB13  I2  R893
   1 P1V8_CPU1_RT3_1A_1D      A @T6G_MB_LIB.T6G(SCH_1):P1V8_CPU1_RT3_1A_1D
   2 P1V8_CPU1_RT3_1A      B @T6G_MB_LIB.T6G(SCH_1):P1V8_CPU1_RT3_1A

Q_CAP_0201-1UF,4V,20%,X6S,CH-10KMEE00  I4  C441
   1 P1V8_CPU1_RT3_1A_1D      A @T6G_MB_LIB.T6G(SCH_1):P1V8_CPU1_RT3_1A_1D
   2    GND      B @T6G_MB_LIB.T6G(SCH_1):GND

Q_CAP_C0201-0.1UF,10V,10%,X7S,CH4102K6E00  I6  C444
   1 P1V8_CPU1_RT3_1A_1D      A @T6G_MB_LIB.T6G(SCH_1):P1V8_CPU1_RT3_1A_1D
   2    GND      B @T6G_MB_LIB.T6G(SCH_1):GND

Q_RES_0603LF-0,5%,1/4W,EMPTY,CS00006J900  I8  R898
   1 P0V9_CPU1_RT_2D      A @T6G_MB_LIB.T6G(SCH_1):P0V9_CPU1_RT_2D
   2 P0V9_CPU1_RT3_2A_2D      B @T6G_MB_LIB.T6G(SCH_1):P0V9_CPU1_RT3_2A_2D

Q_INDUCTOR_SMLF-BLM21SN300SN1D/5A,IND,CX300SN1000  I11  L9
   2 P1V8_CPU1_RT3_1A      2 @T6G_MB_LIB.T6G(SCH_1):P1V8_CPU1_RT3_1A
   1 P1V8_CPU1_RT_1D      1 @T6G_MB_LIB.T6G(SCH_1):P1V8_CPU1_RT_1D

Q_CAP_C0805-100UF,4V,20%,X6S,CH710KMEA01  I14  C433
   1 P1V8_CPU1_RT3_1A      A @T6G_MB_LIB.T6G(SCH_1):P1V8_CPU1_RT3_1A
   2    GND      B @T6G_MB_LIB.T6G(SCH_1):GND

Q_CAP_C0402-22UF,4V,20%,X6S,CH622KMEB02  I15  C435
   1 P1V8_CPU1_RT3_1A      A @T6G_MB_LIB.T6G(SCH_1):P1V8_CPU1_RT3_1A
   2    GND      B @T6G_MB_LIB.T6G(SCH_1):GND

Q_CAP_C0402-10UF,6.3V,20%,X6S,CH6101MEB01  I16  C437
   1 P1V8_CPU1_RT3_1A      A @T6G_MB_LIB.T6G(SCH_1):P1V8_CPU1_RT3_1A
   2    GND      B @T6G_MB_LIB.T6G(SCH_1):GND

Q_CAP_C0805-100UF,4V,20%,X6S,CH710KMEA01  I17  C432
   1 P1V8_CPU1_RT_1D      A @T6G_MB_LIB.T6G(SCH_1):P1V8_CPU1_RT_1D
   2    GND      B @T6G_MB_LIB.T6G(SCH_1):GND

Q_CAP_C0402-22UF,4V,20%,X6S,CH622KMEB02  I18  C434
   1 P1V8_CPU1_RT_1D      A @T6G_MB_LIB.T6G(SCH_1):P1V8_CPU1_RT_1D
   2    GND      B @T6G_MB_LIB.T6G(SCH_1):GND

Q_CAP_0402-4.7UF,6.3V,20%,X6S,CH5471MEB01  I19  C438
   1 P1V8_CPU1_RT3_1A      A @T6G_MB_LIB.T6G(SCH_1):P1V8_CPU1_RT3_1A
   2    GND      B @T6G_MB_LIB.T6G(SCH_1):GND

Q_CAP_0201-1UF,4V,20%,X6S,CH-10KMEE00  I20  C440
   1 P1V8_CPU1_RT3_1A      A @T6G_MB_LIB.T6G(SCH_1):P1V8_CPU1_RT3_1A
   2    GND      B @T6G_MB_LIB.T6G(SCH_1):GND

Q_CAP_C0402-10UF,6.3V,20%,X6S,CH6101MEB01  I21  C436
   1 P1V8_CPU1_RT_1D      A @T6G_MB_LIB.T6G(SCH_1):P1V8_CPU1_RT_1D
   2    GND      B @T6G_MB_LIB.T6G(SCH_1):GND

Q_CAP_0402-4.7UF,6.3V,20%,X6S,CH5471MEB01  I23  C439
   1 P1V8_CPU1_RT_1D      A @T6G_MB_LIB.T6G(SCH_1):P1V8_CPU1_RT_1D
   2    GND      B @T6G_MB_LIB.T6G(SCH_1):GND

Q_CAP_0201-1UF,4V,20%,X6S,CH-10KMEE00  I24  C442
   1 P1V8_CPU1_RT3_1A      A @T6G_MB_LIB.T6G(SCH_1):P1V8_CPU1_RT3_1A
   2    GND      B @T6G_MB_LIB.T6G(SCH_1):GND

Q_CAP_C0201-0.1UF,10V,10%,X7S,CH4102K6E00  I25  C443
   1 P1V8_CPU1_RT3_1A      A @T6G_MB_LIB.T6G(SCH_1):P1V8_CPU1_RT3_1A
   2    GND      B @T6G_MB_LIB.T6G(SCH_1):GND

Q_CAP_C0201-0.1UF,10V,10%,X7S,CH4102K6E00  I26  C445
   1 P1V8_CPU1_RT3_1A      A @T6G_MB_LIB.T6G(SCH_1):P1V8_CPU1_RT3_1A
   2    GND      B @T6G_MB_LIB.T6G(SCH_1):GND

Q_CAP_C0201-0.1UF,10V,10%,X7S,CH4102K6E00  I27  C446
   1 P1V8_CPU1_RT3_1A      A @T6G_MB_LIB.T6G(SCH_1):P1V8_CPU1_RT3_1A
   2    GND      B @T6G_MB_LIB.T6G(SCH_1):GND

Q_CAP_C0201-0.1UF,10V,10%,X7S,CH4102K6E00  I28  C447
   1 P1V8_CPU1_RT3_1A      A @T6G_MB_LIB.T6G(SCH_1):P1V8_CPU1_RT3_1A
   2    GND      B @T6G_MB_LIB.T6G(SCH_1):GND

Q_CAP_C0201-0.1UF,10V,10%,X7S,CH4102K6E00  I34  C463
   1 P0V9_CPU1_RT3_2A_2D      A @T6G_MB_LIB.T6G(SCH_1):P0V9_CPU1_RT3_2A_2D
   2    GND      B @T6G_MB_LIB.T6G(SCH_1):GND

Q_CAP_C0201-0.1UF,10V,10%,X7S,CH4102K6E00  I35  C464
   1 P0V9_CPU1_RT3_2A_2D      A @T6G_MB_LIB.T6G(SCH_1):P0V9_CPU1_RT3_2A_2D
   2    GND      B @T6G_MB_LIB.T6G(SCH_1):GND

Q_RES_0603LF-0,5%,1/4W,CHIP,CS00006J900  I36  R900
   1 P0V9_CPU1_RT3_2A_2D      A @T6G_MB_LIB.T6G(SCH_1):P0V9_CPU1_RT3_2A_2D
   2 P0V9_CPU1_RT3_2A      B @T6G_MB_LIB.T6G(SCH_1):P0V9_CPU1_RT3_2A

Q_CAP_C0201-0.1UF,10V,10%,X7S,CH4102K6E00  I37  C495
   1 P0V9_CPU1_RT3_2A      A @T6G_MB_LIB.T6G(SCH_1):P0V9_CPU1_RT3_2A
   2    GND      B @T6G_MB_LIB.T6G(SCH_1):GND

Q_CAP_0201-1UF,4V,20%,X6S,CH-10KMEE00  I38  C470
   1 P0V9_CPU1_RT3_2A      A @T6G_MB_LIB.T6G(SCH_1):P0V9_CPU1_RT3_2A
   2    GND      B @T6G_MB_LIB.T6G(SCH_1):GND

Q_CAP_0201-1UF,4V,20%,X6S,CH-10KMEE00  I39  C459
   1 P0V9_CPU1_RT3_2A      A @T6G_MB_LIB.T6G(SCH_1):P0V9_CPU1_RT3_2A
   2    GND      B @T6G_MB_LIB.T6G(SCH_1):GND

Q_CAP_C0402-10UF,6.3V,20%,X6S,CH6101MEB01  I40  C480
   1 P0V9_CPU1_RT3_2A      A @T6G_MB_LIB.T6G(SCH_1):P0V9_CPU1_RT3_2A
   2    GND      B @T6G_MB_LIB.T6G(SCH_1):GND

Q_CAP_C0402-10UF,6.3V,20%,X6S,CH6101MEB01  I41  C490
   1 P0V9_CPU1_RT3_2A      A @T6G_MB_LIB.T6G(SCH_1):P0V9_CPU1_RT3_2A
   2    GND      B @T6G_MB_LIB.T6G(SCH_1):GND

Q_CAP_C0201-0.1UF,10V,10%,X7S,CH4102K6E00  I42  C500
   1 P0V9_CPU1_RT3_2A      A @T6G_MB_LIB.T6G(SCH_1):P0V9_CPU1_RT3_2A
   2    GND      B @T6G_MB_LIB.T6G(SCH_1):GND

Q_CAP_C0201-0.1UF,10V,10%,X7S,CH4102K6E00  I43  C473
   1 P0V9_CPU1_RT3_2A      A @T6G_MB_LIB.T6G(SCH_1):P0V9_CPU1_RT3_2A
   2    GND      B @T6G_MB_LIB.T6G(SCH_1):GND

Q_CAP_0201-1UF,4V,20%,X6S,CH-10KMEE00  I44  C448
   1 P0V9_CPU1_RT3_2A      A @T6G_MB_LIB.T6G(SCH_1):P0V9_CPU1_RT3_2A
   2    GND      B @T6G_MB_LIB.T6G(SCH_1):GND

Q_CAP_0201-1UF,4V,20%,X6S,CH-10KMEE00  I45  C453
   1 P0V9_CPU1_RT3_2A      A @T6G_MB_LIB.T6G(SCH_1):P0V9_CPU1_RT3_2A
   2    GND      B @T6G_MB_LIB.T6G(SCH_1):GND

Q_CAP_C0201-0.1UF,10V,10%,X7S,CH4102K6E00  I46  C477
   1 P0V9_CPU1_RT3_2A      A @T6G_MB_LIB.T6G(SCH_1):P0V9_CPU1_RT3_2A
   2    GND      B @T6G_MB_LIB.T6G(SCH_1):GND

Q_CAP_C0201-0.1UF,10V,10%,X7S,CH4102K6E00  I47  C450
   1 P0V9_CPU1_RT3_2A      A @T6G_MB_LIB.T6G(SCH_1):P0V9_CPU1_RT3_2A
   2    GND      B @T6G_MB_LIB.T6G(SCH_1):GND

Q_CAP_0201-1UF,4V,20%,X6S,CH-10KMEE00  I48  C485
   1 P0V9_CPU1_RT3_2A      A @T6G_MB_LIB.T6G(SCH_1):P0V9_CPU1_RT3_2A
   2    GND      B @T6G_MB_LIB.T6G(SCH_1):GND

Q_CAP_0201-1UF,4V,20%,X6S,CH-10KMEE00  I49  C488
   1 P0V9_CPU1_RT3_2A      A @T6G_MB_LIB.T6G(SCH_1):P0V9_CPU1_RT3_2A
   2    GND      B @T6G_MB_LIB.T6G(SCH_1):GND

Q_CAP_0402-4.7UF,6.3V,20%,X6S,CH5471MEB01  I50  C472
   1 P0V9_CPU1_RT3_2A      A @T6G_MB_LIB.T6G(SCH_1):P0V9_CPU1_RT3_2A
   2    GND      B @T6G_MB_LIB.T6G(SCH_1):GND

Q_CAP_0402-4.7UF,6.3V,20%,X6S,CH5471MEB01  I51  C469
   1 P0V9_CPU1_RT3_2A      A @T6G_MB_LIB.T6G(SCH_1):P0V9_CPU1_RT3_2A
   2    GND      B @T6G_MB_LIB.T6G(SCH_1):GND

Q_CAP_0402-4.7UF,6.3V,20%,X6S,CH5471MEB01  I52  C494
   1 P0V9_CPU1_RT3_2A      A @T6G_MB_LIB.T6G(SCH_1):P0V9_CPU1_RT3_2A
   2    GND      B @T6G_MB_LIB.T6G(SCH_1):GND

Q_CAP_0201-1UF,4V,20%,X6S,CH-10KMEE00  I53  C491
   1 P0V9_CPU1_RT3_2A      A @T6G_MB_LIB.T6G(SCH_1):P0V9_CPU1_RT3_2A
   2    GND      B @T6G_MB_LIB.T6G(SCH_1):GND

Q_CAP_0201-1UF,4V,20%,X6S,CH-10KMEE00  I54  C492
   1 P0V9_CPU1_RT3_2A      A @T6G_MB_LIB.T6G(SCH_1):P0V9_CPU1_RT3_2A
   2    GND      B @T6G_MB_LIB.T6G(SCH_1):GND

Q_CAP_C0201-0.1UF,10V,10%,X7S,CH4102K6E00  I56  C481
   1 P0V9_CPU1_RT3_2A      A @T6G_MB_LIB.T6G(SCH_1):P0V9_CPU1_RT3_2A
   2    GND      B @T6G_MB_LIB.T6G(SCH_1):GND

Q_CAP_C0201-0.1UF,10V,10%,X7S,CH4102K6E00  I57  C457
   1 P0V9_CPU1_RT3_2A      A @T6G_MB_LIB.T6G(SCH_1):P0V9_CPU1_RT3_2A
   2    GND      B @T6G_MB_LIB.T6G(SCH_1):GND

Q_CAP_0201-1UF,4V,20%,X6S,CH-10KMEE00  I60  C497
   1 P0V9_CPU1_RT3_2A      A @T6G_MB_LIB.T6G(SCH_1):P0V9_CPU1_RT3_2A
   2    GND      B @T6G_MB_LIB.T6G(SCH_1):GND

Q_CAP_0201-1UF,4V,20%,X6S,CH-10KMEE00  I61  C455
   1 P0V9_CPU1_RT3_2A      A @T6G_MB_LIB.T6G(SCH_1):P0V9_CPU1_RT3_2A
   2    GND      B @T6G_MB_LIB.T6G(SCH_1):GND

Q_INDUCTOR_SMLF-100NH/16A,IND,CV+10G0MZ04  I63  L10
   2 P0V9_CPU1_RT3_2A      2 @T6G_MB_LIB.T6G(SCH_1):P0V9_CPU1_RT3_2A
   1 P0V9_CPU1_RT_2D      1 @T6G_MB_LIB.T6G(SCH_1):P0V9_CPU1_RT_2D

Q_CAP_C0805-100UF,4V,20%,X6S,CH710KMEA01  I64  C466
   1 P0V9_CPU1_RT3_2A      A @T6G_MB_LIB.T6G(SCH_1):P0V9_CPU1_RT3_2A
   2    GND      B @T6G_MB_LIB.T6G(SCH_1):GND

Q_CAP_C0805-100UF,4V,20%,X6S,CH710KMEA01  I65  C471
   1 P0V9_CPU1_RT3_2A      A @T6G_MB_LIB.T6G(SCH_1):P0V9_CPU1_RT3_2A
   2    GND      B @T6G_MB_LIB.T6G(SCH_1):GND

Q_CAP_C0805-100UF,4V,20%,X6S,CH710KMEA01  I67  C474
   1 P0V9_CPU1_RT_2D      A @T6G_MB_LIB.T6G(SCH_1):P0V9_CPU1_RT_2D
   2    GND      B @T6G_MB_LIB.T6G(SCH_1):GND

Q_CAP_C0402-22UF,4V,20%,X6S,CH622KMEB02  I68  C478
   1 P0V9_CPU1_RT_2D      A @T6G_MB_LIB.T6G(SCH_1):P0V9_CPU1_RT_2D
   2    GND      B @T6G_MB_LIB.T6G(SCH_1):GND

Q_CAP_C0805-100UF,4V,20%,X6S,CH710KMEA01  I69  C475
   1 P0V9_CPU1_RT3_2A      A @T6G_MB_LIB.T6G(SCH_1):P0V9_CPU1_RT3_2A
   2    GND      B @T6G_MB_LIB.T6G(SCH_1):GND

Q_CAP_C0402-22UF,4V,20%,X6S,CH622KMEB02  I70  C501
   1 P0V9_CPU1_RT3_2A      A @T6G_MB_LIB.T6G(SCH_1):P0V9_CPU1_RT3_2A
   2    GND      B @T6G_MB_LIB.T6G(SCH_1):GND

Q_CAP_C0402-22UF,4V,20%,X6S,CH622KMEB02  I71  C476
   1 P0V9_CPU1_RT3_2A      A @T6G_MB_LIB.T6G(SCH_1):P0V9_CPU1_RT3_2A
   2    GND      B @T6G_MB_LIB.T6G(SCH_1):GND

Q_CAP_C0402-10UF,6.3V,20%,X6S,CH6101MEB01  I72  C489
   1 P0V9_CPU1_RT_2D      A @T6G_MB_LIB.T6G(SCH_1):P0V9_CPU1_RT_2D
   2    GND      B @T6G_MB_LIB.T6G(SCH_1):GND

Q_CAP_0402-4.7UF,6.3V,20%,X6S,CH5471MEB01  I73  C484
   1 P0V9_CPU1_RT_2D      A @T6G_MB_LIB.T6G(SCH_1):P0V9_CPU1_RT_2D
   2    GND      B @T6G_MB_LIB.T6G(SCH_1):GND

Q_CAP_0201-1UF,4V,20%,X6S,CH-10KMEE00  I74  C454
   1 P0V9_CPU1_RT_2D      A @T6G_MB_LIB.T6G(SCH_1):P0V9_CPU1_RT_2D
   2    GND      B @T6G_MB_LIB.T6G(SCH_1):GND

Q_CAP_C0402-22UF,4V,20%,X6S,CH622KMEB02  I75  C487
   1 P0V9_CPU1_RT3_2A      A @T6G_MB_LIB.T6G(SCH_1):P0V9_CPU1_RT3_2A
   2    GND      B @T6G_MB_LIB.T6G(SCH_1):GND

Q_CAP_C0402-10UF,6.3V,20%,X6S,CH6101MEB01  I76  C499
   1 P0V9_CPU1_RT3_2A      A @T6G_MB_LIB.T6G(SCH_1):P0V9_CPU1_RT3_2A
   2    GND      B @T6G_MB_LIB.T6G(SCH_1):GND

Q_CAP_C0402-10UF,6.3V,20%,X6S,CH6101MEB01  I77  C482
   1 P0V9_CPU1_RT3_2A      A @T6G_MB_LIB.T6G(SCH_1):P0V9_CPU1_RT3_2A
   2    GND      B @T6G_MB_LIB.T6G(SCH_1):GND

Q_CAP_C0201-0.1UF,10V,10%,X7S,CH4102K6E00  I78  C449
   1 P0V9_CPU1_RT_2D      A @T6G_MB_LIB.T6G(SCH_1):P0V9_CPU1_RT_2D
   2    GND      B @T6G_MB_LIB.T6G(SCH_1):GND

Q_CAP_C0201-0.1UF,10V,10%,X7S,CH4102K6E00  I79  C451
   1 P0V9_CPU1_RT_2D      A @T6G_MB_LIB.T6G(SCH_1):P0V9_CPU1_RT_2D
   2    GND      B @T6G_MB_LIB.T6G(SCH_1):GND

Q_CAP_C0201-0.1UF,10V,10%,X7S,CH4102K6E00  I80  C493
   1 P0V9_CPU1_RT_2D      A @T6G_MB_LIB.T6G(SCH_1):P0V9_CPU1_RT_2D
   2    GND      B @T6G_MB_LIB.T6G(SCH_1):GND

Q_CAP_C0201-0.1UF,10V,10%,X7S,CH4102K6E00  I82  C458
   1 P0V9_CPU1_RT_2D      A @T6G_MB_LIB.T6G(SCH_1):P0V9_CPU1_RT_2D
   2    GND      B @T6G_MB_LIB.T6G(SCH_1):GND

Q_CAP_C0201-0.1UF,10V,10%,X7S,CH4102K6E00  I83  C462
   1 P0V9_CPU1_RT3_2A      A @T6G_MB_LIB.T6G(SCH_1):P0V9_CPU1_RT3_2A
   2    GND      B @T6G_MB_LIB.T6G(SCH_1):GND

Q_CAP_0201-1UF,4V,20%,X6S,CH-10KMEE00  I84  C452
   1 P0V9_CPU1_RT3_2A      A @T6G_MB_LIB.T6G(SCH_1):P0V9_CPU1_RT3_2A
   2    GND      B @T6G_MB_LIB.T6G(SCH_1):GND

Q_CAP_C0402-22UF,4V,20%,X6S,CH622KMEB02  I85  C486
   1 P0V9_CPU1_RT3_2A      A @T6G_MB_LIB.T6G(SCH_1):P0V9_CPU1_RT3_2A
   2    GND      B @T6G_MB_LIB.T6G(SCH_1):GND

Q_CAP_0402-4.7UF,6.3V,20%,X6S,CH5471MEB01  I86  C483
   1 P0V9_CPU1_RT3_2A      A @T6G_MB_LIB.T6G(SCH_1):P0V9_CPU1_RT3_2A
   2    GND      B @T6G_MB_LIB.T6G(SCH_1):GND

Q_CAP_C0805-100UF,4V,20%,X6S,CH710KMEA01  I87  C479
   1 P0V9_CPU1_RT3_2A      A @T6G_MB_LIB.T6G(SCH_1):P0V9_CPU1_RT3_2A
   2    GND      B @T6G_MB_LIB.T6G(SCH_1):GND

Q_INDUCTOR_SMLF-BLM15PD121SN1D/1300MA,IND,CX5PD121A  I88  L33
   2 P1V8_CPU1_RT3_1A_1D      2 @T6G_MB_LIB.T6G(SCH_1):P1V8_CPU1_RT3_1A_1D
   1 P1V8_CPU1_RT_1D      1 @T6G_MB_LIB.T6G(SCH_1):P1V8_CPU1_RT_1D

Q_RES_0402LF-0,5%,1/16W,EMPTY,CS00002JB13  I89  R897
   1 P1V8_CPU1_RT_1D      A @T6G_MB_LIB.T6G(SCH_1):P1V8_CPU1_RT_1D
   2 P1V8_CPU1_RT3_1A_1D      B @T6G_MB_LIB.T6G(SCH_1):P1V8_CPU1_RT3_1A_1D

Q_CAP_0201-1UF,4V,20%,X6S,CH-10KMEE00  I90  C456
   1 P0V9_CPU1_RT3_2A_2D      A @T6G_MB_LIB.T6G(SCH_1):P0V9_CPU1_RT3_2A_2D
   2    GND      B @T6G_MB_LIB.T6G(SCH_1):GND

Q_CAP_0201-1UF,4V,20%,X6S,CH-10KMEE00  I91  C460
   1 P0V9_CPU1_RT3_2A_2D      A @T6G_MB_LIB.T6G(SCH_1):P0V9_CPU1_RT3_2A_2D
   2    GND      B @T6G_MB_LIB.T6G(SCH_1):GND

Q_CAP_C0201-0.1UF,10V,10%,X7S,CH4102K6E00  I92  C496
   1 P0V9_CPU1_RT3_2A      A @T6G_MB_LIB.T6G(SCH_1):P0V9_CPU1_RT3_2A
   2    GND      B @T6G_MB_LIB.T6G(SCH_1):GND

Q_CAP_C0201-0.1UF,10V,10%,X7S,CH4102K6E00  I93  C498
   1 P0V9_CPU1_RT3_2A      A @T6G_MB_LIB.T6G(SCH_1):P0V9_CPU1_RT3_2A
   2    GND      B @T6G_MB_LIB.T6G(SCH_1):GND

Q_CAPP_SMLF-470UF,2.5V,20%,SPCAP,CH747LM8818  I94  C7029
   1 P0V9_CPU1_RT3_2A      A @T6G_MB_LIB.T6G(SCH_1):P0V9_CPU1_RT3_2A
   2    GND      B @T6G_MB_LIB.T6G(SCH_1):GND

Q_CAPP_SMLF-470UF,2.5V,20%,SPCAP,CH747LM8818  I95  C7030
   1 P0V9_CPU1_RT3_2A      A @T6G_MB_LIB.T6G(SCH_1):P0V9_CPU1_RT3_2A
   2    GND      B @T6G_MB_LIB.T6G(SCH_1):GND

Q_CAP_C0805-100UF,4V,20%,X6S,CH710KMEA01  I96  C7031
   1 P0V9_CPU1_RT3_2A      A @T6G_MB_LIB.T6G(SCH_1):P0V9_CPU1_RT3_2A
   2    GND      B @T6G_MB_LIB.T6G(SCH_1):GND


DRAWING: @T6G_MB_LIB.T6G(SCH_1):PAGE332 

Q_RES_0402LF-100K,1%,1/16W,EMPTY,CS41002FB09  I2  R4154
   1 PRSNT_CABLE_GPU_A1_N      A @T6G_MB_LIB.T6G(SCH_1):PRSNT_CABLE_GPU_A1_N
   2    GND      B @T6G_MB_LIB.T6G(SCH_1):GND

Q_RES_0402LF-10K,1%,1/16W,CHIP,CS31002FB08  I4  R4153
   1 P3V3_AUX      A @T6G_MB_LIB.T6G(SCH_1):P3V3_AUX
   2 PRSNT_CABLE_GPU_A1_N      B @T6G_MB_LIB.T6G(SCH_1):PRSNT_CABLE_GPU_A1_N

MOSFET_NCH_DUAL-PJT138K,SMLF,IC,BAM138K0003  I6  Q134
   1    GND     S1 @T6G_MB_LIB.T6G(SCH_1):GND
   2 PRSNT_CABLE_GPU_A1_N     G1 @T6G_MB_LIB.T6G(SCH_1):PRSNT_CABLE_GPU_A1_N
   6 PRSNT_CABLE_GPU_A1     D1 @T6G_MB_LIB.T6G(SCH_1):PRSNT_CABLE_GPU_A1

Q_RES_0402LF-4.7K,5%,1/16W,CHIP,CS24702JB10  I8  R4155
   1 P3V3_AUX      A @T6G_MB_LIB.T6G(SCH_1):P3V3_AUX
   2 PRSNT_CABLE_GPU_A1      B @T6G_MB_LIB.T6G(SCH_1):PRSNT_CABLE_GPU_A1

MOSFET_NCH_DUAL-PJT138K,SMLF,IC,BAM138K0003  I10  Q134
   3 PRSNT_CABLE_GPU_A1_ISO_N     D2 @T6G_MB_LIB.T6G(SCH_1):PRSNT_CABLE_GPU_A1_ISO_N
   5 PRSNT_CABLE_GPU_A1     G2 @T6G_MB_LIB.T6G(SCH_1):PRSNT_CABLE_GPU_A1
   4    GND     S2 @T6G_MB_LIB.T6G(SCH_1):GND

Q_RES_0402LF-100K,1%,1/16W,EMPTY,CS41002FB09  I13  R4122
   1 PRSNT_CABLE_GPU_B3_N      A @T6G_MB_LIB.T6G(SCH_1):PRSNT_CABLE_GPU_B3_N
   2    GND      B @T6G_MB_LIB.T6G(SCH_1):GND

Q_RES_0402LF-10K,1%,1/16W,CHIP,CS31002FB08  I14  R4121
   1 P3V3_AUX      A @T6G_MB_LIB.T6G(SCH_1):P3V3_AUX
   2 PRSNT_CABLE_GPU_B3_N      B @T6G_MB_LIB.T6G(SCH_1):PRSNT_CABLE_GPU_B3_N

Q_RES_0402LF-54.9K,1%,1/16W,EMPTY,CS35492FB03  I18  R4123
   1 P3V3_AUX      A @T6G_MB_LIB.T6G(SCH_1):P3V3_AUX
   2 GPU_3V3IO_RSVD1_FFU      B @T6G_MB_LIB.T6G(SCH_1):GPU_3V3IO_RSVD1_FFU

Q_RES_0402LF-100K,1%,1/16W,EMPTY,CS41002FB09  I22  R4120
   1 GPU_3V3IO_RSVD0_FFU      A @T6G_MB_LIB.T6G(SCH_1):GPU_3V3IO_RSVD0_FFU
   2    GND      B @T6G_MB_LIB.T6G(SCH_1):GND

Q_RES_0402LF-54.9K,1%,1/16W,EMPTY,CS35492FB03  I23  R4119
   1 P3V3_AUX      A @T6G_MB_LIB.T6G(SCH_1):P3V3_AUX
   2 GPU_3V3IO_RSVD0_FFU      B @T6G_MB_LIB.T6G(SCH_1):GPU_3V3IO_RSVD0_FFU

MOSFET_NCH_DUAL-PJT138K,SMLF,IC,BAM138K0003  I25  Q132
   1    GND     S1 @T6G_MB_LIB.T6G(SCH_1):GND
   2 PRSNT_CABLE_GPU_B3_N     G1 @T6G_MB_LIB.T6G(SCH_1):PRSNT_CABLE_GPU_B3_N
   6 PRSNT_CABLE_GPU_B3     D1 @T6G_MB_LIB.T6G(SCH_1):PRSNT_CABLE_GPU_B3

Q_RES_0402LF-4.7K,5%,1/16W,CHIP,CS24702JB10  I27  R4126
   1 P3V3_AUX      A @T6G_MB_LIB.T6G(SCH_1):P3V3_AUX
   2 PRSNT_CABLE_GPU_B3      B @T6G_MB_LIB.T6G(SCH_1):PRSNT_CABLE_GPU_B3

MOSFET_NCH_DUAL-PJT138K,SMLF,IC,BAM138K0003  I30  Q131
   1    GND     S1 @T6G_MB_LIB.T6G(SCH_1):GND
   2 GPU_3V3IO_RSVD1_FFU     G1 @T6G_MB_LIB.T6G(SCH_1):GPU_3V3IO_RSVD1_FFU
   6 GPU_3V3IO_RSVD1_FFU_N     D1 @T6G_MB_LIB.T6G(SCH_1):GPU_3V3IO_RSVD1_FFU_N

Q_RES_0402LF-0,5%,1/16W,EMPTY,CS00002JB13  I31  R4574
   1 PRSNT_CABLE_GPU_A1_N      A @T6G_MB_LIB.T6G(SCH_1):PRSNT_CABLE_GPU_A1_N
   2 PRSNT_CABLE_GPU_A1_ISO_N      B @T6G_MB_LIB.T6G(SCH_1):PRSNT_CABLE_GPU_A1_ISO_N

MOSFET_NCH_DUAL-PJT138K,SMLF,IC,BAM138K0003  I32  Q132
   3 PRSNT_CABLE_GPU_B3_ISO_N     D2 @T6G_MB_LIB.T6G(SCH_1):PRSNT_CABLE_GPU_B3_ISO_N
   5 PRSNT_CABLE_GPU_B3     G2 @T6G_MB_LIB.T6G(SCH_1):PRSNT_CABLE_GPU_B3
   4    GND     S2 @T6G_MB_LIB.T6G(SCH_1):GND

Q_RES_0402LF-0,5%,1/16W,EMPTY,CS00002JB13  I33  R4573
   1 PRSNT_CABLE_GPU_B3_N      A @T6G_MB_LIB.T6G(SCH_1):PRSNT_CABLE_GPU_B3_N
   2 PRSNT_CABLE_GPU_B3_ISO_N      B @T6G_MB_LIB.T6G(SCH_1):PRSNT_CABLE_GPU_B3_ISO_N

Q_RES_0402LF-4.7K,5%,1/16W,CHIP,CS24702JB10  I35  R4127
   1 P3V3_AUX      A @T6G_MB_LIB.T6G(SCH_1):P3V3_AUX
   2 GPU_3V3IO_RSVD1_FFU_N      B @T6G_MB_LIB.T6G(SCH_1):GPU_3V3IO_RSVD1_FFU_N

MOSFET_NCH_DUAL-PJT138K,SMLF,IC,BAM138K0003  I37  Q128
   1    GND     S1 @T6G_MB_LIB.T6G(SCH_1):GND
   2 GPU_3V3IO_RSVD0_FFU     G1 @T6G_MB_LIB.T6G(SCH_1):GPU_3V3IO_RSVD0_FFU
   6 GPU_3V3IO_RSVD0_FFU_N     D1 @T6G_MB_LIB.T6G(SCH_1):GPU_3V3IO_RSVD0_FFU_N

Q_RES_0402LF-4.7K,5%,1/16W,CHIP,CS24702JB10  I39  R4125
   1 P3V3_AUX      A @T6G_MB_LIB.T6G(SCH_1):P3V3_AUX
   2 GPU_3V3IO_RSVD0_FFU_N      B @T6G_MB_LIB.T6G(SCH_1):GPU_3V3IO_RSVD0_FFU_N

MOSFET_NCH_DUAL-PJT138K,SMLF,IC,BAM138K0003  I40  Q131
   3 GPU_3V3IO_RSVD1_FFU_ISO     D2 @T6G_MB_LIB.T6G(SCH_1):GPU_3V3IO_RSVD1_FFU_ISO
   5 GPU_3V3IO_RSVD1_FFU_N     G2 @T6G_MB_LIB.T6G(SCH_1):GPU_3V3IO_RSVD1_FFU_N
   4    GND     S2 @T6G_MB_LIB.T6G(SCH_1):GND

Q_RES_0402LF-0,5%,1/16W,EMPTY,CS00002JB13  I41  R4572
   1 GPU_3V3IO_RSVD1_FFU      A @T6G_MB_LIB.T6G(SCH_1):GPU_3V3IO_RSVD1_FFU
   2 GPU_3V3IO_RSVD1_FFU_ISO      B @T6G_MB_LIB.T6G(SCH_1):GPU_3V3IO_RSVD1_FFU_ISO

MOSFET_NCH_DUAL-PJT138K,SMLF,IC,BAM138K0003  I42  Q128
   3 GPU_3V3IO_RSVD0_FFU_ISO     D2 @T6G_MB_LIB.T6G(SCH_1):GPU_3V3IO_RSVD0_FFU_ISO
   5 GPU_3V3IO_RSVD0_FFU_N     G2 @T6G_MB_LIB.T6G(SCH_1):GPU_3V3IO_RSVD0_FFU_N
   4    GND     S2 @T6G_MB_LIB.T6G(SCH_1):GND

Q_RES_0402LF-0,5%,1/16W,EMPTY,CS00002JB13  I44  R4575
   1 GPU_3V3IO_RSVD0_FFU      A @T6G_MB_LIB.T6G(SCH_1):GPU_3V3IO_RSVD0_FFU
   2 GPU_3V3IO_RSVD0_FFU_ISO      B @T6G_MB_LIB.T6G(SCH_1):GPU_3V3IO_RSVD0_FFU_ISO

Q_RES_0402LF-100K,1%,1/16W,CHIP,CS41002FB09  I48  R4156
   1 P3V3_AUX      A @T6G_MB_LIB.T6G(SCH_1):P3V3_AUX
   2 PRSNT_CABLE_GPU_A1_ISO_N      B @T6G_MB_LIB.T6G(SCH_1):PRSNT_CABLE_GPU_A1_ISO_N

Q_CAP_0402-0.1UF,25V,10%,X7R,CH4104K1B00  I50  C15
   1 PRSNT_CABLE_GPU_A1_ISO_N      A @T6G_MB_LIB.T6G(SCH_1):PRSNT_CABLE_GPU_A1_ISO_N
   2    GND      B @T6G_MB_LIB.T6G(SCH_1):GND

Q_RES_0402LF-100K,1%,1/16W,CHIP,CS41002FB09  I54  R4559
   1 SWB_HSC_PWRGD      A @T6G_MB_LIB.T6G(SCH_1):SWB_HSC_PWRGD
   2    GND      B @T6G_MB_LIB.T6G(SCH_1):GND

Q_RES_0402LF-100K,1%,1/16W,EMPTY,CS41002FB09  I55  R4562
   1 P3V3_AUX      A @T6G_MB_LIB.T6G(SCH_1):P3V3_AUX
   2 SWB_HSC_PWRGD      B @T6G_MB_LIB.T6G(SCH_1):SWB_HSC_PWRGD

MOSFET_NCH_DUAL-PJT138K,SMLF,IC,BAM138K0003  I57  Q146
   1    GND     S1 @T6G_MB_LIB.T6G(SCH_1):GND
   2 SWB_HSC_PWRGD     G1 @T6G_MB_LIB.T6G(SCH_1):SWB_HSC_PWRGD
   6 SWB_HSC_PWRGD_N     D1 @T6G_MB_LIB.T6G(SCH_1):SWB_HSC_PWRGD_N

Q_CAP_0402-0.1UF,25V,10%,X7R,CH4104K1B00  I61  C18
   1 SWB_HSC_PWRGD_ISO      A @T6G_MB_LIB.T6G(SCH_1):SWB_HSC_PWRGD_ISO
   2    GND      B @T6G_MB_LIB.T6G(SCH_1):GND

Q_RES_0402LF-4.7K,5%,1/16W,CHIP,CS24702JB10  I62  R4560
   1 P3V3_AUX      A @T6G_MB_LIB.T6G(SCH_1):P3V3_AUX
   2 SWB_HSC_PWRGD_N      B @T6G_MB_LIB.T6G(SCH_1):SWB_HSC_PWRGD_N

Q_CAP_0402-0.1UF,25V,10%,X7R,CH4104K1B00  I64  C13
   1 PRSNT_CABLE_GPU_B3_ISO_N      A @T6G_MB_LIB.T6G(SCH_1):PRSNT_CABLE_GPU_B3_ISO_N
   2    GND      B @T6G_MB_LIB.T6G(SCH_1):GND

Q_RES_0402LF-100K,1%,1/16W,CHIP,CS41002FB09  I66  R4129
   1 P3V3_AUX      A @T6G_MB_LIB.T6G(SCH_1):P3V3_AUX
   2 PRSNT_CABLE_GPU_B3_ISO_N      B @T6G_MB_LIB.T6G(SCH_1):PRSNT_CABLE_GPU_B3_ISO_N

Q_RES_0402LF-100K,1%,1/16W,CHIP,CS41002FB09  I70  R4130
   1 P3V3_AUX      A @T6G_MB_LIB.T6G(SCH_1):P3V3_AUX
   2 GPU_3V3IO_RSVD1_FFU_ISO      B @T6G_MB_LIB.T6G(SCH_1):GPU_3V3IO_RSVD1_FFU_ISO

Q_CAP_0402-0.1UF,25V,10%,X7R,CH4104K1B00  I73  C14
   1 GPU_3V3IO_RSVD1_FFU_ISO      A @T6G_MB_LIB.T6G(SCH_1):GPU_3V3IO_RSVD1_FFU_ISO
   2    GND      B @T6G_MB_LIB.T6G(SCH_1):GND

Q_CAP_0402-0.1UF,25V,10%,X7R,CH4104K1B00  I75  C12
   1 GPU_3V3IO_RSVD0_FFU_ISO      A @T6G_MB_LIB.T6G(SCH_1):GPU_3V3IO_RSVD0_FFU_ISO
   2    GND      B @T6G_MB_LIB.T6G(SCH_1):GND

Q_RES_0402LF-100K,1%,1/16W,EMPTY,CS41002FB09  I81  R4134
   1 GPU_3V3IO_RSVD5_FFU      A @T6G_MB_LIB.T6G(SCH_1):GPU_3V3IO_RSVD5_FFU
   2    GND      B @T6G_MB_LIB.T6G(SCH_1):GND

Q_RES_0402LF-54.9K,1%,1/16W,EMPTY,CS35492FB03  I82  R4133
   1 P3V3_AUX      A @T6G_MB_LIB.T6G(SCH_1):P3V3_AUX
   2 GPU_3V3IO_RSVD5_FFU      B @T6G_MB_LIB.T6G(SCH_1):GPU_3V3IO_RSVD5_FFU

MOSFET_NCH_DUAL-PJT138K,SMLF,IC,BAM138K0003  I86  Q129
   1    GND     S1 @T6G_MB_LIB.T6G(SCH_1):GND
   2 GPU_3V3IO_RSVD5_FFU     G1 @T6G_MB_LIB.T6G(SCH_1):GPU_3V3IO_RSVD5_FFU
   6 GPU_3V3IO_RSVD5_FFU_N     D1 @T6G_MB_LIB.T6G(SCH_1):GPU_3V3IO_RSVD5_FFU_N

Q_RES_0402LF-4.7K,5%,1/16W,CHIP,CS24702JB10  I88  R4138
   1 P3V3_AUX      A @T6G_MB_LIB.T6G(SCH_1):P3V3_AUX
   2 GPU_3V3IO_RSVD5_FFU_N      B @T6G_MB_LIB.T6G(SCH_1):GPU_3V3IO_RSVD5_FFU_N

Q_RES_0402LF-0,5%,1/16W,EMPTY,CS00002JB13  I91  R4576
   1 GPU_3V3IO_RSVD5_FFU      A @T6G_MB_LIB.T6G(SCH_1):GPU_3V3IO_RSVD5_FFU
   2 GPU_3V3IO_RSVD5_FFU_ISO      B @T6G_MB_LIB.T6G(SCH_1):GPU_3V3IO_RSVD5_FFU_ISO

Q_RES_0402LF-100K,1%,1/16W,EMPTY,CS41002FB09  I92  R4136
   1 PRSNT_CABLE_GPU_A2_N      A @T6G_MB_LIB.T6G(SCH_1):PRSNT_CABLE_GPU_A2_N
   2    GND      B @T6G_MB_LIB.T6G(SCH_1):GND

Q_RES_0402LF-10K,1%,1/16W,CHIP,CS31002FB08  I93  R4135
   1 P3V3_AUX      A @T6G_MB_LIB.T6G(SCH_1):P3V3_AUX
   2 PRSNT_CABLE_GPU_A2_N      B @T6G_MB_LIB.T6G(SCH_1):PRSNT_CABLE_GPU_A2_N

Q_RES_0402LF-100K,1%,1/16W,EMPTY,CS41002FB09  I96  R4132
   1 GPU_3V3IO_RSVD3_FFU      A @T6G_MB_LIB.T6G(SCH_1):GPU_3V3IO_RSVD3_FFU
   2    GND      B @T6G_MB_LIB.T6G(SCH_1):GND

Q_RES_0402LF-54.9K,1%,1/16W,EMPTY,CS35492FB03  I97  R4131
   1 P3V3_AUX      A @T6G_MB_LIB.T6G(SCH_1):P3V3_AUX
   2 GPU_3V3IO_RSVD3_FFU      B @T6G_MB_LIB.T6G(SCH_1):GPU_3V3IO_RSVD3_FFU

MOSFET_NCH_DUAL-PJT138K,SMLF,IC,BAM138K0003  I98  Q133
   1    GND     S1 @T6G_MB_LIB.T6G(SCH_1):GND
   2 PRSNT_CABLE_GPU_A2_N     G1 @T6G_MB_LIB.T6G(SCH_1):PRSNT_CABLE_GPU_A2_N
   6 PRSNT_CABLE_GPU_A2     D1 @T6G_MB_LIB.T6G(SCH_1):PRSNT_CABLE_GPU_A2

Q_RES_0402LF-4.7K,5%,1/16W,CHIP,CS24702JB10  I99  R4139
   1 P3V3_AUX      A @T6G_MB_LIB.T6G(SCH_1):P3V3_AUX
   2 PRSNT_CABLE_GPU_A2      B @T6G_MB_LIB.T6G(SCH_1):PRSNT_CABLE_GPU_A2

MOSFET_NCH_DUAL-PJT138K,SMLF,IC,BAM138K0003  I102  Q130
   1    GND     S1 @T6G_MB_LIB.T6G(SCH_1):GND
   2 GPU_3V3IO_RSVD3_FFU     G1 @T6G_MB_LIB.T6G(SCH_1):GPU_3V3IO_RSVD3_FFU
   6 GPU_3V3IO_RSVD3_FFU_N     D1 @T6G_MB_LIB.T6G(SCH_1):GPU_3V3IO_RSVD3_FFU_N

Q_RES_0402LF-0,5%,1/16W,EMPTY,CS00002JB13  I103  R4578
   1 PRSNT_CABLE_GPU_A2_N      A @T6G_MB_LIB.T6G(SCH_1):PRSNT_CABLE_GPU_A2_N
   2 PRSNT_CABLE_GPU_A2_ISO_N      B @T6G_MB_LIB.T6G(SCH_1):PRSNT_CABLE_GPU_A2_ISO_N

Q_RES_0402LF-100K,1%,1/16W,CHIP,CS41002FB09  I104  R4128
   1 P3V3_AUX      A @T6G_MB_LIB.T6G(SCH_1):P3V3_AUX
   2 GPU_3V3IO_RSVD0_FFU_ISO      B @T6G_MB_LIB.T6G(SCH_1):GPU_3V3IO_RSVD0_FFU_ISO

Q_RES_0402LF-4.7K,5%,1/16W,CHIP,CS24702JB10  I107  R4137
   1 P3V3_AUX      A @T6G_MB_LIB.T6G(SCH_1):P3V3_AUX
   2 GPU_3V3IO_RSVD3_FFU_N      B @T6G_MB_LIB.T6G(SCH_1):GPU_3V3IO_RSVD3_FFU_N

Q_RES_0402LF-0,5%,1/16W,EMPTY,CS00002JB13  I109  R4577
   1 GPU_3V3IO_RSVD3_FFU      A @T6G_MB_LIB.T6G(SCH_1):GPU_3V3IO_RSVD3_FFU
   2 GPU_3V3IO_RSVD3_FFU_ISO      B @T6G_MB_LIB.T6G(SCH_1):GPU_3V3IO_RSVD3_FFU_ISO

Q_RES_0402LF-100K,1%,1/16W,CHIP,CS41002FB09  I110  R4561
   1 P3V3_AUX      A @T6G_MB_LIB.T6G(SCH_1):P3V3_AUX
   2 SWB_HSC_PWRGD_ISO      B @T6G_MB_LIB.T6G(SCH_1):SWB_HSC_PWRGD_ISO

MOSFET_NCH_DUAL-PJT138K,SMLF,IC,BAM138K0003  I113  Q129
   3 GPU_3V3IO_RSVD5_FFU_ISO     D2 @T6G_MB_LIB.T6G(SCH_1):GPU_3V3IO_RSVD5_FFU_ISO
   5 GPU_3V3IO_RSVD5_FFU_N     G2 @T6G_MB_LIB.T6G(SCH_1):GPU_3V3IO_RSVD5_FFU_N
   4    GND     S2 @T6G_MB_LIB.T6G(SCH_1):GND

Q_RES_0402LF-100K,1%,1/16W,CHIP,CS41002FB09  I114  R4141
   1 P3V3_AUX      A @T6G_MB_LIB.T6G(SCH_1):P3V3_AUX
   2 GPU_3V3IO_RSVD5_FFU_ISO      B @T6G_MB_LIB.T6G(SCH_1):GPU_3V3IO_RSVD5_FFU_ISO

Q_CAP_0402-0.1UF,25V,10%,X7R,CH4104K1B00  I118  C17
   1 GPU_3V3IO_RSVD5_FFU_ISO      A @T6G_MB_LIB.T6G(SCH_1):GPU_3V3IO_RSVD5_FFU_ISO
   2    GND      B @T6G_MB_LIB.T6G(SCH_1):GND

MOSFET_NCH_DUAL-PJT138K,SMLF,IC,BAM138K0003  I120  Q133
   3 PRSNT_CABLE_GPU_A2_ISO_N     D2 @T6G_MB_LIB.T6G(SCH_1):PRSNT_CABLE_GPU_A2_ISO_N
   5 PRSNT_CABLE_GPU_A2     G2 @T6G_MB_LIB.T6G(SCH_1):PRSNT_CABLE_GPU_A2
   4    GND     S2 @T6G_MB_LIB.T6G(SCH_1):GND

Q_RES_0402LF-100K,1%,1/16W,CHIP,CS41002FB09  I122  R4142
   1 P3V3_AUX      A @T6G_MB_LIB.T6G(SCH_1):P3V3_AUX
   2 PRSNT_CABLE_GPU_A2_ISO_N      B @T6G_MB_LIB.T6G(SCH_1):PRSNT_CABLE_GPU_A2_ISO_N

MOSFET_NCH_DUAL-PJT138K,SMLF,IC,BAM138K0003  I123  Q130
   3 GPU_3V3IO_RSVD3_FFU_ISO     D2 @T6G_MB_LIB.T6G(SCH_1):GPU_3V3IO_RSVD3_FFU_ISO
   5 GPU_3V3IO_RSVD3_FFU_N     G2 @T6G_MB_LIB.T6G(SCH_1):GPU_3V3IO_RSVD3_FFU_N
   4    GND     S2 @T6G_MB_LIB.T6G(SCH_1):GND

Q_CAP_0402-0.1UF,25V,10%,X7R,CH4104K1B00  I127  C19
   1 PRSNT_CABLE_GPU_A2_ISO_N      A @T6G_MB_LIB.T6G(SCH_1):PRSNT_CABLE_GPU_A2_ISO_N
   2    GND      B @T6G_MB_LIB.T6G(SCH_1):GND

Q_CAP_0402-0.1UF,25V,10%,X7R,CH4104K1B00  I130  C16
   1 GPU_3V3IO_RSVD3_FFU_ISO      A @T6G_MB_LIB.T6G(SCH_1):GPU_3V3IO_RSVD3_FFU_ISO
   2    GND      B @T6G_MB_LIB.T6G(SCH_1):GND

Q_RES_0402LF-100K,1%,1/16W,CHIP,CS41002FB09  I131  R4140
   1 P3V3_AUX      A @T6G_MB_LIB.T6G(SCH_1):P3V3_AUX
   2 GPU_3V3IO_RSVD3_FFU_ISO      B @T6G_MB_LIB.T6G(SCH_1):GPU_3V3IO_RSVD3_FFU_ISO

MOSFET_NCH_DUAL-PJT138K,SMLF,IC,BAM138K0003  I134  Q146
   3 SWB_HSC_PWRGD_ISO     D2 @T6G_MB_LIB.T6G(SCH_1):SWB_HSC_PWRGD_ISO
   5 SWB_HSC_PWRGD_N     G2 @T6G_MB_LIB.T6G(SCH_1):SWB_HSC_PWRGD_N
   4    GND     S2 @T6G_MB_LIB.T6G(SCH_1):GND

Q_RES_0402LF-100K,1%,1/16W,EMPTY,CS41002FB09  I135  R4124
   1 GPU_3V3IO_RSVD1_FFU      A @T6G_MB_LIB.T6G(SCH_1):GPU_3V3IO_RSVD1_FFU
   2    GND      B @T6G_MB_LIB.T6G(SCH_1):GND


DRAWING: @T6G_MB_LIB.T6G(SCH_1):PAGE385 

Q_RES_0201LF-4.7K,5%,1/20W,EMPTY,CS24701JE04  I25  R972
   1 P1V8_CPU0_RT_1D      A @T6G_MB_LIB.T6G(SCH_1):P1V8_CPU0_RT_1D
   2 RT_CPU0_P0_SCAN_MODE      B @T6G_MB_LIB.T6G(SCH_1):RT_CPU0_P0_SCAN_MODE

Q_RES_0201LF-10K,1%,1/20W,CHIP,CS31001FE17  I27  R979
   1 GPIO2_RT_CPU0_P0      A @T6G_MB_LIB.T6G(SCH_1):GPIO2_RT_CPU0_P0
   2    GND      B @T6G_MB_LIB.T6G(SCH_1):GND

Q_RES_0201LF-10K,1%,1/20W,CHIP,CS31001FE17  I28  R980
   1 GPIO3_RT_CPU0_P0      A @T6G_MB_LIB.T6G(SCH_1):GPIO3_RT_CPU0_P0
   2    GND      B @T6G_MB_LIB.T6G(SCH_1):GND

Q_RES_0201LF-4.7K,5%,1/20W,CHIP,CS24701JE04  I29  R982
   1 TEST0_RT_CPU0_P0      A @T6G_MB_LIB.T6G(SCH_1):TEST0_RT_CPU0_P0
   2    GND      B @T6G_MB_LIB.T6G(SCH_1):GND

Q_RES_0201LF-4.7K,5%,1/20W,EMPTY,CS24701JE04  I30  R978
   1 P1V8_CPU0_RT_1D      A @T6G_MB_LIB.T6G(SCH_1):P1V8_CPU0_RT_1D
   2 GPIO2_RT_CPU0_P0      B @T6G_MB_LIB.T6G(SCH_1):GPIO2_RT_CPU0_P0

Q_RES_0201LF-4.7K,5%,1/20W,EMPTY,CS24701JE04  I31  R981
   1 P1V8_CPU0_RT_1D      A @T6G_MB_LIB.T6G(SCH_1):P1V8_CPU0_RT_1D
   2 TEST0_RT_CPU0_P0      B @T6G_MB_LIB.T6G(SCH_1):TEST0_RT_CPU0_P0

Q_RES_0201LF-51.1,1%,1/20W,EMPTY,CS05111FE00  I37  R623
   1 CLK_100M_RETIMER_CPU0_P0_DN      A @T6G_MB_LIB.T6G(SCH_1):CLK_100M_RETIMER_CPU0_P0_DN
   2    GND      B @T6G_MB_LIB.T6G(SCH_1):GND

Q_RES_0201LF-51.1,1%,1/20W,EMPTY,CS05111FE00  I38  R624
   1 CLK_100M_RETIMER_CPU0_P0_DP      A @T6G_MB_LIB.T6G(SCH_1):CLK_100M_RETIMER_CPU0_P0_DP
   2    GND      B @T6G_MB_LIB.T6G(SCH_1):GND

Q_RES_0201LF-0,5%,1/20W,CHIP,CS00001JE10  I39  R595
   1 CLK_100M_RETIMER_CPU0_P0_R_DP      A @T6G_MB_LIB.T6G(SCH_1):CLK_100M_RETIMER_CPU0_P0_R_DP
   2 CLK_100M_RETIMER_CPU0_P0_DP      B @T6G_MB_LIB.T6G(SCH_1):CLK_100M_RETIMER_CPU0_P0_DP

Q_RES_0201LF-0,5%,1/20W,CHIP,CS00001JE10  I40  R596
   1 CLK_100M_RETIMER_CPU0_P0_R_DN      A @T6G_MB_LIB.T6G(SCH_1):CLK_100M_RETIMER_CPU0_P0_R_DN
   2 CLK_100M_RETIMER_CPU0_P0_DN      B @T6G_MB_LIB.T6G(SCH_1):CLK_100M_RETIMER_CPU0_P0_DN

Q_RES_0201LF-49.9,1%,1/20W,CHIP,CS04991FE06  I41  R667
   1 SMB_RT_CPU0_P0_ROM_MUX_1D_SDA      A @T6G_MB_LIB.T6G(SCH_1):SMB_RT_CPU0_P0_ROM_MUX_1D_SDA
   2 SMB_RT_CPU0_P0_ROM_MUX_1D_R_SDA      B @T6G_MB_LIB.T6G(SCH_1):SMB_RT_CPU0_P0_ROM_MUX_1D_R_SDA

Q_RES_0201LF-49.9,1%,1/20W,CHIP,CS04991FE06  I42  R666
   1 SMB_RT_CPU0_P0_ROM_MUX_1D_SCL      A @T6G_MB_LIB.T6G(SCH_1):SMB_RT_CPU0_P0_ROM_MUX_1D_SCL
   2 SMB_RT_CPU0_P0_ROM_MUX_1D_R_SCL      B @T6G_MB_LIB.T6G(SCH_1):SMB_RT_CPU0_P0_ROM_MUX_1D_R_SCL

Q_RES_0201LF-0,5%,1/20W,CHIP,CS00001JE10  I49  R977
   1 SMB_RT_CPU0_P0_R_SDA      A @T6G_MB_LIB.T6G(SCH_1):SMB_RT_CPU0_P0_R_SDA
   2 SMB_RT_CPU0_P0_R2_SDA      B @T6G_MB_LIB.T6G(SCH_1):SMB_RT_CPU0_P0_R2_SDA

Q_RES_0201LF-0,5%,1/20W,CHIP,CS00001JE10  I50  R976
   1 SMB_RT_CPU0_P0_R_SCL      A @T6G_MB_LIB.T6G(SCH_1):SMB_RT_CPU0_P0_R_SCL
   2 SMB_RT_CPU0_P0_R2_SCL      B @T6G_MB_LIB.T6G(SCH_1):SMB_RT_CPU0_P0_R2_SCL

PT5161LRS-PT5161LRS,SMLF,IC,AJ051610U03  I53  U6010
 FJ6     NC  GPIO0     NC
FJ23     NC  GPIO1     NC
FJ25 GPIO2_RT_CPU0_P0  GPIO2 @T6G_MB_LIB.T6G(SCH_1):GPIO2_RT_CPU0_P0
FJ28 GPIO3_RT_CPU0_P0  GPIO3 @T6G_MB_LIB.T6G(SCH_1):GPIO3_RT_CPU0_P0
FJ31     NC  INT_N     NC
  B3 JTAG_TCK_RT_CPU0_P0 JTAG_TCK @T6G_MB_LIB.T6G(SCH_1):JTAG_TCK_RT_CPU0_P0
  B6 JTAG_TDI_RT_CPU0_P0 JTAG_TDI @T6G_MB_LIB.T6G(SCH_1):JTAG_TDI_RT_CPU0_P0
  B9 JTAG_TDO_RT_CPU0_P0 JTAG_TDO @T6G_MB_LIB.T6G(SCH_1):JTAG_TDO_RT_CPU0_P0
 FF8 JTAG_TEST_MODE_RT_CPU0_P0 JTAG_TEST_MODE @T6G_MB_LIB.T6G(SCH_1):JTAG_TEST_MODE_RT_CPU0_P0
 B12 JTAG_TMS_RT_CPU0_P0 JTAG_TMS @T6G_MB_LIB.T6G(SCH_1):JTAG_TMS_RT_CPU0_P0
  E8 JTAG_TRST_RT_CPU0_P0_N JTAG_TRST_N @T6G_MB_LIB.T6G(SCH_1):JTAG_TRST_RT_CPU0_P0_N
 FJ9 MODE_RT_CPU0_P0   MODE @T6G_MB_LIB.T6G(SCH_1):MODE_RT_CPU0_P0
  F2 RST_RT_CPU0_P0_PERST_N PERST_N @T6G_MB_LIB.T6G(SCH_1):RST_RT_CPU0_P0_PERST_N
 E18     NC REFCLK_OUTN     NC
 B16     NC REFCLK_OUTP     NC
FF18 CLK_100M_RETIMER_CPU0_P0_DN REFCLKN @T6G_MB_LIB.T6G(SCH_1):CLK_100M_RETIMER_CPU0_P0_DN
FJ16 CLK_100M_RETIMER_CPU0_P0_DP REFCLKP @T6G_MB_LIB.T6G(SCH_1):CLK_100M_RETIMER_CPU0_P0_DP
FF11 RST_RT_CPU0_P0_RESET_N RESET_N @T6G_MB_LIB.T6G(SCH_1):RST_RT_CPU0_P0_RESET_N
 E11 RXDET_BYP_RT_CPU0_P0 RXDET_BYP @T6G_MB_LIB.T6G(SCH_1):RXDET_BYP_RT_CPU0_P0
FF33 RT_CPU0_P0_SCAN_MODE SCAN_MODE @T6G_MB_LIB.T6G(SCH_1):RT_CPU0_P0_SCAN_MODE
 F34 RT_CPU0_P0_ADDR1 SMB_ADDR1 @T6G_MB_LIB.T6G(SCH_1):RT_CPU0_P0_ADDR1
 B23 RT_CPU0_P0_ADDR2 SMB_ADDR2 @T6G_MB_LIB.T6G(SCH_1):RT_CPU0_P0_ADDR2
 B25 RT_CPU0_P0_ADDR3 SMB_ADDR3 @T6G_MB_LIB.T6G(SCH_1):RT_CPU0_P0_ADDR3
 B31 SMB_RT_CPU0_P0_R2_SCL SMBCLK @T6G_MB_LIB.T6G(SCH_1):SMB_RT_CPU0_P0_R2_SCL
 B28 SMB_RT_CPU0_P0_R2_SDA SMBDAT @T6G_MB_LIB.T6G(SCH_1):SMB_RT_CPU0_P0_R2_SDA
 E30    GND T_SENSE @T6G_MB_LIB.T6G(SCH_1):GND
FF24 TEST0_RT_CPU0_P0  TEST0 @T6G_MB_LIB.T6G(SCH_1):TEST0_RT_CPU0_P0
FF27 TEST1_RT_CPU0_P0  TEST1 @T6G_MB_LIB.T6G(SCH_1):TEST1_RT_CPU0_P0
FF30 TEST2_RT_CPU0_P0  TEST2 @T6G_MB_LIB.T6G(SCH_1):TEST2_RT_CPU0_P0
 G35 CLKREQ_RT_CPU0_P0_N CLKREQ_N @T6G_MB_LIB.T6G(SCH_1):CLKREQ_RT_CPU0_P0_N
 FF5 SMB_RT_CPU0_P0_ROM_MUX_1D_R_SCL EE_CLK @T6G_MB_LIB.T6G(SCH_1):SMB_RT_CPU0_P0_ROM_MUX_1D_R_SCL
 FJ3 SMB_RT_CPU0_P0_ROM_MUX_1D_R_SDA EE_DAT @T6G_MB_LIB.T6G(SCH_1):SMB_RT_CPU0_P0_ROM_MUX_1D_R_SDA

Q_RES_0201LF-4.7K,5%,1/20W,CHIP,CS24701JE04  I57  R984
   1 TEST1_RT_CPU0_P0      A @T6G_MB_LIB.T6G(SCH_1):TEST1_RT_CPU0_P0
   2    GND      B @T6G_MB_LIB.T6G(SCH_1):GND

Q_RES_0201LF-4.7K,5%,1/20W,CHIP,CS24701JE04  I58  R995
   1 TEST2_RT_CPU0_P0      A @T6G_MB_LIB.T6G(SCH_1):TEST2_RT_CPU0_P0
   2    GND      B @T6G_MB_LIB.T6G(SCH_1):GND

Q_RES_0201LF-4.7K,5%,1/20W,CHIP,CS24701JE04  I60  R997
   1 JTAG_TEST_MODE_RT_CPU0_P0      A @T6G_MB_LIB.T6G(SCH_1):JTAG_TEST_MODE_RT_CPU0_P0
   2    GND      B @T6G_MB_LIB.T6G(SCH_1):GND

Q_RES_0201LF-4.7K,5%,1/20W,EMPTY,CS24701JE04  I61  R983
   1 P1V8_CPU0_RT_1D      A @T6G_MB_LIB.T6G(SCH_1):P1V8_CPU0_RT_1D
   2 TEST1_RT_CPU0_P0      B @T6G_MB_LIB.T6G(SCH_1):TEST1_RT_CPU0_P0

Q_RES_0201LF-4.7K,5%,1/20W,EMPTY,CS24701JE04  I62  R985
   1 P1V8_CPU0_RT_1D      A @T6G_MB_LIB.T6G(SCH_1):P1V8_CPU0_RT_1D
   2 TEST2_RT_CPU0_P0      B @T6G_MB_LIB.T6G(SCH_1):TEST2_RT_CPU0_P0

Q_RES_0201LF-4.7K,5%,1/20W,EMPTY,CS24701JE04  I63  R975
   1 P1V8_CPU0_RT_1D      A @T6G_MB_LIB.T6G(SCH_1):P1V8_CPU0_RT_1D
   2 JTAG_TEST_MODE_RT_CPU0_P0      B @T6G_MB_LIB.T6G(SCH_1):JTAG_TEST_MODE_RT_CPU0_P0

Q_RES_0201LF-4.7K,5%,1/20W,EMPTY,CS24701JE04  I71  R1001
   1 MODE_RT_CPU0_P0      A @T6G_MB_LIB.T6G(SCH_1):MODE_RT_CPU0_P0
   2    GND      B @T6G_MB_LIB.T6G(SCH_1):GND

Q_RES_0201LF-4.7K,5%,1/20W,CHIP,CS24701JE04  I72  R998
   1 P1V8_CPU0_RT_1D      A @T6G_MB_LIB.T6G(SCH_1):P1V8_CPU0_RT_1D
   2 MODE_RT_CPU0_P0      B @T6G_MB_LIB.T6G(SCH_1):MODE_RT_CPU0_P0

Q_RES_0201LF-0,5%,1/20W,CHIP,CS00001JE10  I76  R953
   1 RST_RT_CPU0_P0_PERST_N      A @T6G_MB_LIB.T6G(SCH_1):RST_RT_CPU0_P0_PERST_N
   2 RST_RT_CPU0_P0_PERST_R_N      B @T6G_MB_LIB.T6G(SCH_1):RST_RT_CPU0_P0_PERST_R_N

Q_RES_0201LF-0,5%,1/20W,CHIP,CS00001JE10  I77  R963
   1 RST_RT_CPU0_P0_RESET_N      A @T6G_MB_LIB.T6G(SCH_1):RST_RT_CPU0_P0_RESET_N
   2 RST_RT_CPU0_P0_RESET_R_N      B @T6G_MB_LIB.T6G(SCH_1):RST_RT_CPU0_P0_RESET_R_N

Q_RES_0201LF-1K,1%,1/20W,EMPTY,CS21001FE07  I86  R965
   1 RT_CPU0_P0_ADDR3      A @T6G_MB_LIB.T6G(SCH_1):RT_CPU0_P0_ADDR3
   2    GND      B @T6G_MB_LIB.T6G(SCH_1):GND

Q_RES_0201LF-20K,1%,1/20W,CHIP,CS32001FE00  I87  R967
   1 RT_CPU0_P0_ADDR2      A @T6G_MB_LIB.T6G(SCH_1):RT_CPU0_P0_ADDR2
   2    GND      B @T6G_MB_LIB.T6G(SCH_1):GND

Q_RES_0201LF-1K,1%,1/20W,CHIP,CS21001FE07  I88  R964
   1 P1V8_CPU0_RT_1D      A @T6G_MB_LIB.T6G(SCH_1):P1V8_CPU0_RT_1D
   2 RT_CPU0_P0_ADDR3      B @T6G_MB_LIB.T6G(SCH_1):RT_CPU0_P0_ADDR3

Q_RES_0201LF-1K,1%,1/20W,EMPTY,CS21001FE07  I89  R966
   1 P1V8_CPU0_RT_1D      A @T6G_MB_LIB.T6G(SCH_1):P1V8_CPU0_RT_1D
   2 RT_CPU0_P0_ADDR2      B @T6G_MB_LIB.T6G(SCH_1):RT_CPU0_P0_ADDR2

Q_RES_0201LF-1K,1%,1/20W,CHIP,CS21001FE07  I90  R969
   1 RT_CPU0_P0_ADDR1      A @T6G_MB_LIB.T6G(SCH_1):RT_CPU0_P0_ADDR1
   2    GND      B @T6G_MB_LIB.T6G(SCH_1):GND

Q_RES_0201LF-1K,1%,1/20W,EMPTY,CS21001FE07  I91  R968
   1 P1V8_CPU0_RT_1D      A @T6G_MB_LIB.T6G(SCH_1):P1V8_CPU0_RT_1D
   2 RT_CPU0_P0_ADDR1      B @T6G_MB_LIB.T6G(SCH_1):RT_CPU0_P0_ADDR1

Q_RES_0201LF-10K,1%,1/20W,CHIP,CS31001FE17  I96  R971
   1 RST_RT_CPU0_P0_RESET_R_N      A @T6G_MB_LIB.T6G(SCH_1):RST_RT_CPU0_P0_RESET_R_N
   2    GND      B @T6G_MB_LIB.T6G(SCH_1):GND

Q_RES_0201LF-10K,1%,1/20W,CHIP,CS31001FE17  I97  R970
   1 RST_RT_CPU0_P0_PERST_R_N      A @T6G_MB_LIB.T6G(SCH_1):RST_RT_CPU0_P0_PERST_R_N
   2    GND      B @T6G_MB_LIB.T6G(SCH_1):GND

Q_RES_0201LF-4.7K,5%,1/20W,EMPTY,CS24701JE04  I98  R974
   1 P1V8_CPU0_RT_1D      A @T6G_MB_LIB.T6G(SCH_1):P1V8_CPU0_RT_1D
   2 RST_RT_CPU0_P0_RESET_R_N      B @T6G_MB_LIB.T6G(SCH_1):RST_RT_CPU0_P0_RESET_R_N

Q_RES_0201LF-1K,1%,1/20W,CHIP,CS21001FE07  I111  R1364
   1 JTAG_TRST_RT_CPU0_P0_N      A @T6G_MB_LIB.T6G(SCH_1):JTAG_TRST_RT_CPU0_P0_N
   2    GND      B @T6G_MB_LIB.T6G(SCH_1):GND

Q_RES_0201LF-10K,1%,1/20W,CHIP,CS31001FE17  I114  R1370
   1 RXDET_BYP_RT_CPU0_P0      A @T6G_MB_LIB.T6G(SCH_1):RXDET_BYP_RT_CPU0_P0
   2    GND      B @T6G_MB_LIB.T6G(SCH_1):GND

Q_RES_0201LF-1K,1%,1/20W,EMPTY,CS21001FE07  I116  R1369
   1 P1V8_CPU0_RT_1D      A @T6G_MB_LIB.T6G(SCH_1):P1V8_CPU0_RT_1D
   2 RXDET_BYP_RT_CPU0_P0      B @T6G_MB_LIB.T6G(SCH_1):RXDET_BYP_RT_CPU0_P0

Q_RES_0201LF-4.7K,5%,1/20W,CHIP,CS24701JE04  I119  R1368
   1 CLKREQ_RT_CPU0_P0_N      A @T6G_MB_LIB.T6G(SCH_1):CLKREQ_RT_CPU0_P0_N
   2    GND      B @T6G_MB_LIB.T6G(SCH_1):GND

Q_RES_0201LF-200,1%,1/20W,CHIP,CS12001FE12  I121  R973
   1 RT_CPU0_P0_SCAN_MODE      A @T6G_MB_LIB.T6G(SCH_1):RT_CPU0_P0_SCAN_MODE
   2    GND      B @T6G_MB_LIB.T6G(SCH_1):GND

Q_RES_0201LF-4.7K,5%,1/20W,CHIP,CS24701JE04  I123  R1365
   1 JTAG_TCK_RT_CPU0_P0      A @T6G_MB_LIB.T6G(SCH_1):JTAG_TCK_RT_CPU0_P0
   2    GND      B @T6G_MB_LIB.T6G(SCH_1):GND

Q_RES_0201LF-4.7K,5%,1/20W,EMPTY,CS24701JE04  I143  R1446
   1 P1V8_CPU0_RT_1D      A @T6G_MB_LIB.T6G(SCH_1):P1V8_CPU0_RT_1D
   2 JTAG_TCK_RT_CPU0_P0      B @T6G_MB_LIB.T6G(SCH_1):JTAG_TCK_RT_CPU0_P0

Q_RES_0201LF-1K,1%,1/20W,EMPTY,CS21001FE07  I145  R1445
   1 P1V8_CPU0_RT_1D      A @T6G_MB_LIB.T6G(SCH_1):P1V8_CPU0_RT_1D
   2 JTAG_TDO_RT_CPU0_P0      B @T6G_MB_LIB.T6G(SCH_1):JTAG_TDO_RT_CPU0_P0

Q_RES_0201LF-4.7K,5%,1/20W,EMPTY,CS24701JE04  I146  R1439
   1 P1V8_CPU0_RT_1D      A @T6G_MB_LIB.T6G(SCH_1):P1V8_CPU0_RT_1D
   2 JTAG_TMS_RT_CPU0_P0      B @T6G_MB_LIB.T6G(SCH_1):JTAG_TMS_RT_CPU0_P0

Q_RES_0201LF-4.7K,5%,1/20W,EMPTY,CS24701JE04  I147  R1438
   1 P1V8_CPU0_RT_1D      A @T6G_MB_LIB.T6G(SCH_1):P1V8_CPU0_RT_1D
   2 JTAG_TDI_RT_CPU0_P0      B @T6G_MB_LIB.T6G(SCH_1):JTAG_TDI_RT_CPU0_P0


DRAWING: @T6G_MB_LIB.T6G(SCH_1):PAGE386 

PT5161LRS-PT5161LRS,SMLF,IC,AJ051610U03  I3  U6010
  G1 RT_CPU0_P0_VQPS   VQPS @T6G_MB_LIB.T6G(SCH_1):RT_CPU0_P0_VQPS
BV20 P1V8_CPU0_RT0_1A PWR_1A_1 @T6G_MB_LIB.T6G(SCH_1):P1V8_CPU0_RT0_1A
CE17 P1V8_CPU0_RT0_1A PWR_1A_2 @T6G_MB_LIB.T6G(SCH_1):P1V8_CPU0_RT0_1A
CE20 P1V8_CPU0_RT0_1A PWR_1A_3 @T6G_MB_LIB.T6G(SCH_1):P1V8_CPU0_RT0_1A
CM17 P1V8_CPU0_RT0_1A PWR_1A_4 @T6G_MB_LIB.T6G(SCH_1):P1V8_CPU0_RT0_1A
CM20 P1V8_CPU0_RT0_1A PWR_1A_5 @T6G_MB_LIB.T6G(SCH_1):P1V8_CPU0_RT0_1A
BL17 P0V9_CPU0_RT_2D PWR_2D_1 @T6G_MB_LIB.T6G(SCH_1):P0V9_CPU0_RT_2D
BL20 P0V9_CPU0_RT_2D PWR_2D_2 @T6G_MB_LIB.T6G(SCH_1):P0V9_CPU0_RT_2D
CW17 P0V9_CPU0_RT_2D PWR_2D_3 @T6G_MB_LIB.T6G(SCH_1):P0V9_CPU0_RT_2D
CW20 P0V9_CPU0_RT_2D PWR_2D_4 @T6G_MB_LIB.T6G(SCH_1):P0V9_CPU0_RT_2D
BV17 P1V8_CPU0_RT0_1A_1D PWR_1D @T6G_MB_LIB.T6G(SCH_1):P1V8_CPU0_RT0_1A_1D
AC17 P0V9_CPU0_RT0_2A PWR_2A_1 @T6G_MB_LIB.T6G(SCH_1):P0V9_CPU0_RT0_2A
AC20 P0V9_CPU0_RT0_2A PWR_2A_2 @T6G_MB_LIB.T6G(SCH_1):P0V9_CPU0_RT0_2A
AK17 P0V9_CPU0_RT0_2A PWR_2A_3 @T6G_MB_LIB.T6G(SCH_1):P0V9_CPU0_RT0_2A
AK20 P0V9_CPU0_RT0_2A PWR_2A_4 @T6G_MB_LIB.T6G(SCH_1):P0V9_CPU0_RT0_2A
AU17 P0V9_CPU0_RT0_2A PWR_2A_5 @T6G_MB_LIB.T6G(SCH_1):P0V9_CPU0_RT0_2A
AU20 P0V9_CPU0_RT0_2A PWR_2A_6 @T6G_MB_LIB.T6G(SCH_1):P0V9_CPU0_RT0_2A
BD17 P0V9_CPU0_RT0_2A_2D PWR_2A_7 @T6G_MB_LIB.T6G(SCH_1):P0V9_CPU0_RT0_2A_2D
BD20 P0V9_CPU0_RT0_2A_2D PWR_2A_8 @T6G_MB_LIB.T6G(SCH_1):P0V9_CPU0_RT0_2A_2D
DF17 P0V9_CPU0_RT0_2A_2D PWR_2A_9 @T6G_MB_LIB.T6G(SCH_1):P0V9_CPU0_RT0_2A_2D
DF20 P0V9_CPU0_RT0_2A_2D PWR_2A_10 @T6G_MB_LIB.T6G(SCH_1):P0V9_CPU0_RT0_2A_2D
DN17 P0V9_CPU0_RT0_2A PWR_2A_11 @T6G_MB_LIB.T6G(SCH_1):P0V9_CPU0_RT0_2A
DN20 P0V9_CPU0_RT0_2A PWR_2A_12 @T6G_MB_LIB.T6G(SCH_1):P0V9_CPU0_RT0_2A
DY17 P0V9_CPU0_RT0_2A PWR_2A_13 @T6G_MB_LIB.T6G(SCH_1):P0V9_CPU0_RT0_2A
DY20 P0V9_CPU0_RT0_2A PWR_2A_14 @T6G_MB_LIB.T6G(SCH_1):P0V9_CPU0_RT0_2A
EG17 P0V9_CPU0_RT0_2A PWR_2A_15 @T6G_MB_LIB.T6G(SCH_1):P0V9_CPU0_RT0_2A
EG20 P0V9_CPU0_RT0_2A PWR_2A_16 @T6G_MB_LIB.T6G(SCH_1):P0V9_CPU0_RT0_2A
EP17 P0V9_CPU0_RT0_2A PWR_2A_17 @T6G_MB_LIB.T6G(SCH_1):P0V9_CPU0_RT0_2A
EP20 P0V9_CPU0_RT0_2A PWR_2A_18 @T6G_MB_LIB.T6G(SCH_1):P0V9_CPU0_RT0_2A
 T17 P0V9_CPU0_RT0_2A PWR_2A_19 @T6G_MB_LIB.T6G(SCH_1):P0V9_CPU0_RT0_2A
 T20 P0V9_CPU0_RT0_2A PWR_2A_20 @T6G_MB_LIB.T6G(SCH_1):P0V9_CPU0_RT0_2A

Q_RES_0201LF-0,5%,1/20W,CHIP,CS00001JE10  I13  R6821
   1 NCF_CPU0_P0_GND      A @T6G_MB_LIB.T6G(SCH_1):NCF_CPU0_P0_GND
   2    GND      B @T6G_MB_LIB.T6G(SCH_1):GND

Q_RES_0201LF-0,5%,1/20W,CHIP,CS00001JE10  I15  R6820
   1 NCF_A1_CPU0_P0_GND      A @T6G_MB_LIB.T6G(SCH_1):NCF_A1_CPU0_P0_GND
   2    GND      B @T6G_MB_LIB.T6G(SCH_1):GND

PT5161LRS-PT5161LRS,SMLF,IC,AJ051610U03  I17  U6010
AC13    GND   GND1 @T6G_MB_LIB.T6G(SCH_1):GND
AC22    GND   GND2 @T6G_MB_LIB.T6G(SCH_1):GND
AC32    GND   GND3 @T6G_MB_LIB.T6G(SCH_1):GND
 AC4    GND   GND4 @T6G_MB_LIB.T6G(SCH_1):GND
 AD2    GND   GND5 @T6G_MB_LIB.T6G(SCH_1):GND
AD34    GND   GND6 @T6G_MB_LIB.T6G(SCH_1):GND
 AE1    GND   GND7 @T6G_MB_LIB.T6G(SCH_1):GND
AE35    GND   GND8 @T6G_MB_LIB.T6G(SCH_1):GND
AK13    GND   GND9 @T6G_MB_LIB.T6G(SCH_1):GND
AK22    GND  GND10 @T6G_MB_LIB.T6G(SCH_1):GND
AK32    GND  GND11 @T6G_MB_LIB.T6G(SCH_1):GND
 AK4    GND  GND12 @T6G_MB_LIB.T6G(SCH_1):GND
 AL2    GND  GND13 @T6G_MB_LIB.T6G(SCH_1):GND
AL34    GND  GND14 @T6G_MB_LIB.T6G(SCH_1):GND
 AM1    GND  GND15 @T6G_MB_LIB.T6G(SCH_1):GND
AM35    GND  GND16 @T6G_MB_LIB.T6G(SCH_1):GND
AU13    GND  GND17 @T6G_MB_LIB.T6G(SCH_1):GND
AU22    GND  GND18 @T6G_MB_LIB.T6G(SCH_1):GND
AU32    GND  GND19 @T6G_MB_LIB.T6G(SCH_1):GND
 AU4    GND  GND20 @T6G_MB_LIB.T6G(SCH_1):GND
 AV2    GND  GND21 @T6G_MB_LIB.T6G(SCH_1):GND
AV34    GND  GND22 @T6G_MB_LIB.T6G(SCH_1):GND
 AW1    GND  GND23 @T6G_MB_LIB.T6G(SCH_1):GND
AW35    GND  GND24 @T6G_MB_LIB.T6G(SCH_1):GND
 B19    GND  GND25 @T6G_MB_LIB.T6G(SCH_1):GND
BD13    GND  GND26 @T6G_MB_LIB.T6G(SCH_1):GND
BD22    GND  GND27 @T6G_MB_LIB.T6G(SCH_1):GND
BD32    GND  GND28 @T6G_MB_LIB.T6G(SCH_1):GND
 BD4    GND  GND29 @T6G_MB_LIB.T6G(SCH_1):GND
 BE2    GND  GND30 @T6G_MB_LIB.T6G(SCH_1):GND
BE34    GND  GND31 @T6G_MB_LIB.T6G(SCH_1):GND
 BF1    GND  GND32 @T6G_MB_LIB.T6G(SCH_1):GND
BF35    GND  GND33 @T6G_MB_LIB.T6G(SCH_1):GND
BL13    GND  GND34 @T6G_MB_LIB.T6G(SCH_1):GND
BL22    GND  GND35 @T6G_MB_LIB.T6G(SCH_1):GND
BL32    GND  GND36 @T6G_MB_LIB.T6G(SCH_1):GND
 BL4    GND  GND37 @T6G_MB_LIB.T6G(SCH_1):GND
 BM2    GND  GND38 @T6G_MB_LIB.T6G(SCH_1):GND
BM34    GND  GND39 @T6G_MB_LIB.T6G(SCH_1):GND
 BN1    GND  GND40 @T6G_MB_LIB.T6G(SCH_1):GND
BN35    GND  GND41 @T6G_MB_LIB.T6G(SCH_1):GND
BV13    GND  GND42 @T6G_MB_LIB.T6G(SCH_1):GND
BV22    GND  GND43 @T6G_MB_LIB.T6G(SCH_1):GND
BV32    GND  GND44 @T6G_MB_LIB.T6G(SCH_1):GND
 BV4    GND  GND45 @T6G_MB_LIB.T6G(SCH_1):GND
 BW2    GND  GND46 @T6G_MB_LIB.T6G(SCH_1):GND
BW34    GND  GND47 @T6G_MB_LIB.T6G(SCH_1):GND
 BY1    GND  GND48 @T6G_MB_LIB.T6G(SCH_1):GND
BY35    GND  GND49 @T6G_MB_LIB.T6G(SCH_1):GND
CE13    GND  GND50 @T6G_MB_LIB.T6G(SCH_1):GND
CE22    GND  GND51 @T6G_MB_LIB.T6G(SCH_1):GND
CE32    GND  GND52 @T6G_MB_LIB.T6G(SCH_1):GND
 CE4    GND  GND53 @T6G_MB_LIB.T6G(SCH_1):GND
 CF2    GND  GND54 @T6G_MB_LIB.T6G(SCH_1):GND
CF34    GND  GND55 @T6G_MB_LIB.T6G(SCH_1):GND
 CG1    GND  GND56 @T6G_MB_LIB.T6G(SCH_1):GND
CG35    GND  GND57 @T6G_MB_LIB.T6G(SCH_1):GND
CM13    GND  GND58 @T6G_MB_LIB.T6G(SCH_1):GND
CM22    GND  GND59 @T6G_MB_LIB.T6G(SCH_1):GND
CM32    GND  GND60 @T6G_MB_LIB.T6G(SCH_1):GND
 CM4    GND  GND61 @T6G_MB_LIB.T6G(SCH_1):GND
 CN2    GND  GND62 @T6G_MB_LIB.T6G(SCH_1):GND
CN34    GND  GND63 @T6G_MB_LIB.T6G(SCH_1):GND
 CP1    GND  GND64 @T6G_MB_LIB.T6G(SCH_1):GND
CP35    GND  GND65 @T6G_MB_LIB.T6G(SCH_1):GND
CW13    GND  GND66 @T6G_MB_LIB.T6G(SCH_1):GND
CW22    GND  GND67 @T6G_MB_LIB.T6G(SCH_1):GND
CW32    GND  GND68 @T6G_MB_LIB.T6G(SCH_1):GND
 CW4    GND  GND69 @T6G_MB_LIB.T6G(SCH_1):GND
 CY2    GND  GND70 @T6G_MB_LIB.T6G(SCH_1):GND
CY34    GND  GND71 @T6G_MB_LIB.T6G(SCH_1):GND
 DA1    GND  GND72 @T6G_MB_LIB.T6G(SCH_1):GND
DA35    GND  GND73 @T6G_MB_LIB.T6G(SCH_1):GND
DF13    GND  GND74 @T6G_MB_LIB.T6G(SCH_1):GND
DF22    GND  GND75 @T6G_MB_LIB.T6G(SCH_1):GND
DF32    GND  GND76 @T6G_MB_LIB.T6G(SCH_1):GND
 DF4    GND  GND77 @T6G_MB_LIB.T6G(SCH_1):GND
 DG2    GND  GND78 @T6G_MB_LIB.T6G(SCH_1):GND
DG34    GND  GND79 @T6G_MB_LIB.T6G(SCH_1):GND
 DH1    GND  GND80 @T6G_MB_LIB.T6G(SCH_1):GND
DH35    GND  GND81 @T6G_MB_LIB.T6G(SCH_1):GND
DN13    GND  GND82 @T6G_MB_LIB.T6G(SCH_1):GND
  A1 NCF_A1_CPU0_P0_GND NCF_GND1 @T6G_MB_LIB.T6G(SCH_1):NCF_A1_CPU0_P0_GND
 A35 NCF_CPU0_P0_GND NCF_GND2 @T6G_MB_LIB.T6G(SCH_1):NCF_CPU0_P0_GND
  C2 NCF_CPU0_P0_GND NCF_GND3 @T6G_MB_LIB.T6G(SCH_1):NCF_CPU0_P0_GND
 C34 NCF_CPU0_P0_GND NCF_GND4 @T6G_MB_LIB.T6G(SCH_1):NCF_CPU0_P0_GND
  D1 NCF_CPU0_P0_GND NCF_GND5 @T6G_MB_LIB.T6G(SCH_1):NCF_CPU0_P0_GND
 D35 NCF_CPU0_P0_GND NCF_GND6 @T6G_MB_LIB.T6G(SCH_1):NCF_CPU0_P0_GND
 FE2 NCF_CPU0_P0_GND NCF_GND7 @T6G_MB_LIB.T6G(SCH_1):NCF_CPU0_P0_GND
FE34 NCF_CPU0_P0_GND NCF_GND8 @T6G_MB_LIB.T6G(SCH_1):NCF_CPU0_P0_GND
 FG1 NCF_CPU0_P0_GND NCF_GND9 @T6G_MB_LIB.T6G(SCH_1):NCF_CPU0_P0_GND
FG35 NCF_CPU0_P0_GND NCF_GND10 @T6G_MB_LIB.T6G(SCH_1):NCF_CPU0_P0_GND
 FH2 NCF_CPU0_P0_GND NCF_GND11 @T6G_MB_LIB.T6G(SCH_1):NCF_CPU0_P0_GND
FH34 NCF_CPU0_P0_GND NCF_GND12 @T6G_MB_LIB.T6G(SCH_1):NCF_CPU0_P0_GND
DN22    GND  GND83 @T6G_MB_LIB.T6G(SCH_1):GND
DN32    GND  GND84 @T6G_MB_LIB.T6G(SCH_1):GND
 DN4    GND  GND85 @T6G_MB_LIB.T6G(SCH_1):GND
 DP2    GND  GND86 @T6G_MB_LIB.T6G(SCH_1):GND
DP34    GND  GND87 @T6G_MB_LIB.T6G(SCH_1):GND
 DR1    GND  GND88 @T6G_MB_LIB.T6G(SCH_1):GND
DR35    GND  GND89 @T6G_MB_LIB.T6G(SCH_1):GND
DY13    GND  GND90 @T6G_MB_LIB.T6G(SCH_1):GND
DY22    GND  GND91 @T6G_MB_LIB.T6G(SCH_1):GND
DY32    GND  GND92 @T6G_MB_LIB.T6G(SCH_1):GND
 DY4    GND  GND93 @T6G_MB_LIB.T6G(SCH_1):GND
 E14    GND  GND94 @T6G_MB_LIB.T6G(SCH_1):GND
 E27    GND  GND95 @T6G_MB_LIB.T6G(SCH_1):GND
 E33    GND  GND96 @T6G_MB_LIB.T6G(SCH_1):GND
 EA2    GND  GND97 @T6G_MB_LIB.T6G(SCH_1):GND
EA34    GND  GND98 @T6G_MB_LIB.T6G(SCH_1):GND
 EB1    GND  GND99 @T6G_MB_LIB.T6G(SCH_1):GND
EB35    GND GND100 @T6G_MB_LIB.T6G(SCH_1):GND
EG13    GND GND101 @T6G_MB_LIB.T6G(SCH_1):GND
EG22    GND GND102 @T6G_MB_LIB.T6G(SCH_1):GND
EG32    GND GND103 @T6G_MB_LIB.T6G(SCH_1):GND
 EG4    GND GND104 @T6G_MB_LIB.T6G(SCH_1):GND
 EH2    GND GND105 @T6G_MB_LIB.T6G(SCH_1):GND
EH34    GND GND106 @T6G_MB_LIB.T6G(SCH_1):GND
 EJ1    GND GND107 @T6G_MB_LIB.T6G(SCH_1):GND
EJ35    GND GND108 @T6G_MB_LIB.T6G(SCH_1):GND
EP13    GND GND109 @T6G_MB_LIB.T6G(SCH_1):GND
EP22    GND GND110 @T6G_MB_LIB.T6G(SCH_1):GND
EP32    GND GND111 @T6G_MB_LIB.T6G(SCH_1):GND
 EP4    GND GND112 @T6G_MB_LIB.T6G(SCH_1):GND
 ER2    GND GND113 @T6G_MB_LIB.T6G(SCH_1):GND
ER34    GND GND114 @T6G_MB_LIB.T6G(SCH_1):GND
 ET1    GND GND115 @T6G_MB_LIB.T6G(SCH_1):GND
ET35    GND GND116 @T6G_MB_LIB.T6G(SCH_1):GND
FA15    GND GND117 @T6G_MB_LIB.T6G(SCH_1):GND
FA32    GND GND118 @T6G_MB_LIB.T6G(SCH_1):GND
 FB2    GND GND119 @T6G_MB_LIB.T6G(SCH_1):GND
FB34    GND GND120 @T6G_MB_LIB.T6G(SCH_1):GND
FC19    GND GND121 @T6G_MB_LIB.T6G(SCH_1):GND
FC23    GND GND122 @T6G_MB_LIB.T6G(SCH_1):GND
FC25    GND GND123 @T6G_MB_LIB.T6G(SCH_1):GND
FC28    GND GND124 @T6G_MB_LIB.T6G(SCH_1):GND
 FC3    GND GND125 @T6G_MB_LIB.T6G(SCH_1):GND
 FC6    GND GND126 @T6G_MB_LIB.T6G(SCH_1):GND
 FC9    GND GND127 @T6G_MB_LIB.T6G(SCH_1):GND
 FD1    GND GND128 @T6G_MB_LIB.T6G(SCH_1):GND
FD35    GND GND129 @T6G_MB_LIB.T6G(SCH_1):GND
FF14    GND GND130 @T6G_MB_LIB.T6G(SCH_1):GND
FF21    GND GND131 @T6G_MB_LIB.T6G(SCH_1):GND
FJ12    GND GND132 @T6G_MB_LIB.T6G(SCH_1):GND
FJ19    GND GND133 @T6G_MB_LIB.T6G(SCH_1):GND
 H12    GND GND134 @T6G_MB_LIB.T6G(SCH_1):GND
 H16    GND GND135 @T6G_MB_LIB.T6G(SCH_1):GND
 H19    GND GND136 @T6G_MB_LIB.T6G(SCH_1):GND
 H31    GND GND137 @T6G_MB_LIB.T6G(SCH_1):GND
 J22    GND GND138 @T6G_MB_LIB.T6G(SCH_1):GND
  J4    GND GND139 @T6G_MB_LIB.T6G(SCH_1):GND
  K2    GND GND140 @T6G_MB_LIB.T6G(SCH_1):GND
 K34    GND GND141 @T6G_MB_LIB.T6G(SCH_1):GND
  L1    GND GND142 @T6G_MB_LIB.T6G(SCH_1):GND
 L35    GND GND143 @T6G_MB_LIB.T6G(SCH_1):GND
 T13    GND GND144 @T6G_MB_LIB.T6G(SCH_1):GND
 T22    GND GND145 @T6G_MB_LIB.T6G(SCH_1):GND
 T32    GND GND146 @T6G_MB_LIB.T6G(SCH_1):GND
  T4    GND GND147 @T6G_MB_LIB.T6G(SCH_1):GND
  U2    GND GND148 @T6G_MB_LIB.T6G(SCH_1):GND
 U34    GND GND149 @T6G_MB_LIB.T6G(SCH_1):GND
  V1    GND GND150 @T6G_MB_LIB.T6G(SCH_1):GND
 V35    GND GND151 @T6G_MB_LIB.T6G(SCH_1):GND

Q_RES_0201LF-200,1%,1/20W,CHIP,CS12001FE12  I18  R6809
   1 RT_CPU0_P0_VQPS      A @T6G_MB_LIB.T6G(SCH_1):RT_CPU0_P0_VQPS
   2    GND      B @T6G_MB_LIB.T6G(SCH_1):GND

Q_RES_0201LF-1K,1%,1/20W,EMPTY,CS21001FE07  I19  R6808
   1 P1V8_CPU0_RT_1D      A @T6G_MB_LIB.T6G(SCH_1):P1V8_CPU0_RT_1D
   2 RT_CPU0_P0_VQPS      B @T6G_MB_LIB.T6G(SCH_1):RT_CPU0_P0_VQPS


DRAWING: @T6G_MB_LIB.T6G(SCH_1):PAGE388 

Q_RES_0402LF-0,5%,1/16W,EMPTY,CS00002JB13  I4  R952
   1 P1V8_CPU0_RT0_1A_1D      A @T6G_MB_LIB.T6G(SCH_1):P1V8_CPU0_RT0_1A_1D
   2 P1V8_CPU0_RT0_1A      B @T6G_MB_LIB.T6G(SCH_1):P1V8_CPU0_RT0_1A

Q_RES_0402LF-0,5%,1/16W,EMPTY,CS00002JB13  I5  R951
   1 P1V8_CPU0_RT0_1A_1D      A @T6G_MB_LIB.T6G(SCH_1):P1V8_CPU0_RT0_1A_1D
   2 P1V8_CPU0_RT0_1A      B @T6G_MB_LIB.T6G(SCH_1):P1V8_CPU0_RT0_1A

Q_CAP_0201-1UF,4V,20%,X6S,CH-10KMEE00  I8  C513
   1 P1V8_CPU0_RT0_1A_1D      A @T6G_MB_LIB.T6G(SCH_1):P1V8_CPU0_RT0_1A_1D
   2    GND      B @T6G_MB_LIB.T6G(SCH_1):GND

Q_CAP_C0201-0.1UF,10V,10%,X7S,CH4102K6E00  I9  C516
   1 P1V8_CPU0_RT0_1A_1D      A @T6G_MB_LIB.T6G(SCH_1):P1V8_CPU0_RT0_1A_1D
   2    GND      B @T6G_MB_LIB.T6G(SCH_1):GND

Q_RES_0603LF-0,5%,1/4W,EMPTY,CS00006J900  I10  R961
   1 P0V9_CPU0_RT_2D      A @T6G_MB_LIB.T6G(SCH_1):P0V9_CPU0_RT_2D
   2 P0V9_CPU0_RT0_2A_2D      B @T6G_MB_LIB.T6G(SCH_1):P0V9_CPU0_RT0_2A_2D

Q_RES_0603LF-0,5%,1/4W,CHIP,CS00006J900  I11  R962
   1 P0V9_CPU0_RT0_2A_2D      A @T6G_MB_LIB.T6G(SCH_1):P0V9_CPU0_RT0_2A_2D
   2 P0V9_CPU0_RT0_2A      B @T6G_MB_LIB.T6G(SCH_1):P0V9_CPU0_RT0_2A

Q_INDUCTOR_SMLF-BLM21SN300SN1D/5A,IND,CX300SN1000  I12  L11
   2 P1V8_CPU0_RT0_1A      2 @T6G_MB_LIB.T6G(SCH_1):P1V8_CPU0_RT0_1A
   1 P1V8_CPU0_RT_1D      1 @T6G_MB_LIB.T6G(SCH_1):P1V8_CPU0_RT_1D

Q_CAP_C0805-100UF,4V,20%,X6S,CH710KMEA01  I13  C503
   1 P1V8_CPU0_RT0_1A      A @T6G_MB_LIB.T6G(SCH_1):P1V8_CPU0_RT0_1A
   2    GND      B @T6G_MB_LIB.T6G(SCH_1):GND

Q_CAP_C0402-22UF,4V,20%,X6S,CH622KMEB02  I14  C505
   1 P1V8_CPU0_RT0_1A      A @T6G_MB_LIB.T6G(SCH_1):P1V8_CPU0_RT0_1A
   2    GND      B @T6G_MB_LIB.T6G(SCH_1):GND

Q_CAP_C0805-100UF,4V,20%,X6S,CH710KMEA01  I16  C502
   1 P1V8_CPU0_RT_1D      A @T6G_MB_LIB.T6G(SCH_1):P1V8_CPU0_RT_1D
   2    GND      B @T6G_MB_LIB.T6G(SCH_1):GND

Q_CAP_C0402-10UF,6.3V,20%,X6S,CH6101MEB01  I17  C507
   1 P1V8_CPU0_RT0_1A      A @T6G_MB_LIB.T6G(SCH_1):P1V8_CPU0_RT0_1A
   2    GND      B @T6G_MB_LIB.T6G(SCH_1):GND

Q_CAP_0402-4.7UF,6.3V,20%,X6S,CH5471MEB01  I18  C510
   1 P1V8_CPU0_RT0_1A      A @T6G_MB_LIB.T6G(SCH_1):P1V8_CPU0_RT0_1A
   2    GND      B @T6G_MB_LIB.T6G(SCH_1):GND

Q_CAP_0201-1UF,4V,20%,X6S,CH-10KMEE00  I19  C512
   1 P1V8_CPU0_RT0_1A      A @T6G_MB_LIB.T6G(SCH_1):P1V8_CPU0_RT0_1A
   2    GND      B @T6G_MB_LIB.T6G(SCH_1):GND

Q_CAP_0201-1UF,4V,20%,X6S,CH-10KMEE00  I22  C514
   1 P1V8_CPU0_RT0_1A      A @T6G_MB_LIB.T6G(SCH_1):P1V8_CPU0_RT0_1A
   2    GND      B @T6G_MB_LIB.T6G(SCH_1):GND

Q_CAP_C0201-0.1UF,10V,10%,X7S,CH4102K6E00  I23  C515
   1 P1V8_CPU0_RT0_1A      A @T6G_MB_LIB.T6G(SCH_1):P1V8_CPU0_RT0_1A
   2    GND      B @T6G_MB_LIB.T6G(SCH_1):GND

Q_CAP_C0402-22UF,4V,20%,X6S,CH622KMEB02  I24  C504
   1 P1V8_CPU0_RT_1D      A @T6G_MB_LIB.T6G(SCH_1):P1V8_CPU0_RT_1D
   2    GND      B @T6G_MB_LIB.T6G(SCH_1):GND

Q_CAP_C0402-10UF,6.3V,20%,X6S,CH6101MEB01  I25  C506
   1 P1V8_CPU0_RT_1D      A @T6G_MB_LIB.T6G(SCH_1):P1V8_CPU0_RT_1D
   2    GND      B @T6G_MB_LIB.T6G(SCH_1):GND

Q_CAP_0402-4.7UF,6.3V,20%,X6S,CH5471MEB01  I26  C511
   1 P1V8_CPU0_RT_1D      A @T6G_MB_LIB.T6G(SCH_1):P1V8_CPU0_RT_1D
   2    GND      B @T6G_MB_LIB.T6G(SCH_1):GND

Q_CAP_C0201-0.1UF,10V,10%,X7S,CH4102K6E00  I27  C517
   1 P1V8_CPU0_RT0_1A      A @T6G_MB_LIB.T6G(SCH_1):P1V8_CPU0_RT0_1A
   2    GND      B @T6G_MB_LIB.T6G(SCH_1):GND

Q_CAP_C0201-0.1UF,10V,10%,X7S,CH4102K6E00  I28  C519
   1 P1V8_CPU0_RT0_1A      A @T6G_MB_LIB.T6G(SCH_1):P1V8_CPU0_RT0_1A
   2    GND      B @T6G_MB_LIB.T6G(SCH_1):GND

Q_CAP_C0201-0.1UF,10V,10%,X7S,CH4102K6E00  I29  C520
   1 P1V8_CPU0_RT0_1A      A @T6G_MB_LIB.T6G(SCH_1):P1V8_CPU0_RT0_1A
   2    GND      B @T6G_MB_LIB.T6G(SCH_1):GND

Q_INDUCTOR_SMLF-100NH/16A,IND,CV+10G0MZ04  I30  L12
   2 P0V9_CPU0_RT0_2A      2 @T6G_MB_LIB.T6G(SCH_1):P0V9_CPU0_RT0_2A
   1 P0V9_CPU0_RT_2D      1 @T6G_MB_LIB.T6G(SCH_1):P0V9_CPU0_RT_2D

Q_CAP_C0201-0.1UF,10V,10%,X7S,CH4102K6E00  I32  C538
   1 P0V9_CPU0_RT0_2A_2D      A @T6G_MB_LIB.T6G(SCH_1):P0V9_CPU0_RT0_2A_2D
   2    GND      B @T6G_MB_LIB.T6G(SCH_1):GND

Q_CAP_C0201-0.1UF,10V,10%,X7S,CH4102K6E00  I36  C544
   1 P0V9_CPU0_RT0_2A_2D      A @T6G_MB_LIB.T6G(SCH_1):P0V9_CPU0_RT0_2A_2D
   2    GND      B @T6G_MB_LIB.T6G(SCH_1):GND

Q_CAP_C0201-0.1UF,10V,10%,X7S,CH4102K6E00  I38  C576
   1 P0V9_CPU0_RT0_2A      A @T6G_MB_LIB.T6G(SCH_1):P0V9_CPU0_RT0_2A
   2    GND      B @T6G_MB_LIB.T6G(SCH_1):GND

Q_CAP_C0201-0.1UF,10V,10%,X7S,CH4102K6E00  I39  C580
   1 P0V9_CPU0_RT0_2A      A @T6G_MB_LIB.T6G(SCH_1):P0V9_CPU0_RT0_2A
   2    GND      B @T6G_MB_LIB.T6G(SCH_1):GND

Q_CAP_0201-1UF,4V,20%,X6S,CH-10KMEE00  I40  C555
   1 P0V9_CPU0_RT0_2A      A @T6G_MB_LIB.T6G(SCH_1):P0V9_CPU0_RT0_2A
   2    GND      B @T6G_MB_LIB.T6G(SCH_1):GND

Q_CAP_C0402-10UF,6.3V,20%,X6S,CH6101MEB01  I41  C561
   1 P0V9_CPU0_RT0_2A      A @T6G_MB_LIB.T6G(SCH_1):P0V9_CPU0_RT0_2A
   2    GND      B @T6G_MB_LIB.T6G(SCH_1):GND

Q_CAP_0201-1UF,4V,20%,X6S,CH-10KMEE00  I42  C539
   1 P0V9_CPU0_RT0_2A      A @T6G_MB_LIB.T6G(SCH_1):P0V9_CPU0_RT0_2A
   2    GND      B @T6G_MB_LIB.T6G(SCH_1):GND

Q_CAP_0201-1UF,4V,20%,X6S,CH-10KMEE00  I43  C562
   1 P0V9_CPU0_RT0_2A      A @T6G_MB_LIB.T6G(SCH_1):P0V9_CPU0_RT0_2A
   2    GND      B @T6G_MB_LIB.T6G(SCH_1):GND

Q_CAP_C0402-10UF,6.3V,20%,X6S,CH6101MEB01  I44  C579
   1 P0V9_CPU0_RT0_2A      A @T6G_MB_LIB.T6G(SCH_1):P0V9_CPU0_RT0_2A
   2    GND      B @T6G_MB_LIB.T6G(SCH_1):GND

Q_CAP_0402-4.7UF,6.3V,20%,X6S,CH5471MEB01  I45  C554
   1 P0V9_CPU0_RT0_2A      A @T6G_MB_LIB.T6G(SCH_1):P0V9_CPU0_RT0_2A
   2    GND      B @T6G_MB_LIB.T6G(SCH_1):GND

Q_CAP_0402-4.7UF,6.3V,20%,X6S,CH5471MEB01  I46  C571
   1 P0V9_CPU0_RT0_2A      A @T6G_MB_LIB.T6G(SCH_1):P0V9_CPU0_RT0_2A
   2    GND      B @T6G_MB_LIB.T6G(SCH_1):GND

Q_CAP_C0201-0.1UF,10V,10%,X7S,CH4102K6E00  I48  C541
   1 P0V9_CPU0_RT0_2A      A @T6G_MB_LIB.T6G(SCH_1):P0V9_CPU0_RT0_2A
   2    GND      B @T6G_MB_LIB.T6G(SCH_1):GND

Q_CAP_C0201-0.1UF,10V,10%,X7S,CH4102K6E00  I49  C582
   1 P0V9_CPU0_RT0_2A      A @T6G_MB_LIB.T6G(SCH_1):P0V9_CPU0_RT0_2A
   2    GND      B @T6G_MB_LIB.T6G(SCH_1):GND

Q_CAP_C0201-0.1UF,10V,10%,X7S,CH4102K6E00  I50  C523
   1 P0V9_CPU0_RT0_2A      A @T6G_MB_LIB.T6G(SCH_1):P0V9_CPU0_RT0_2A
   2    GND      B @T6G_MB_LIB.T6G(SCH_1):GND

Q_CAP_C0201-0.1UF,10V,10%,X7S,CH4102K6E00  I51  C585
   1 P0V9_CPU0_RT0_2A      A @T6G_MB_LIB.T6G(SCH_1):P0V9_CPU0_RT0_2A
   2    GND      B @T6G_MB_LIB.T6G(SCH_1):GND

Q_CAP_0201-1UF,4V,20%,X6S,CH-10KMEE00  I52  C570
   1 P0V9_CPU0_RT0_2A      A @T6G_MB_LIB.T6G(SCH_1):P0V9_CPU0_RT0_2A
   2    GND      B @T6G_MB_LIB.T6G(SCH_1):GND

Q_CAP_0201-1UF,4V,20%,X6S,CH-10KMEE00  I53  C573
   1 P0V9_CPU0_RT0_2A      A @T6G_MB_LIB.T6G(SCH_1):P0V9_CPU0_RT0_2A
   2    GND      B @T6G_MB_LIB.T6G(SCH_1):GND

Q_CAP_0402-4.7UF,6.3V,20%,X6S,CH5471MEB01  I54  C557
   1 P0V9_CPU0_RT0_2A      A @T6G_MB_LIB.T6G(SCH_1):P0V9_CPU0_RT0_2A
   2    GND      B @T6G_MB_LIB.T6G(SCH_1):GND

Q_CAP_0402-4.7UF,6.3V,20%,X6S,CH5471MEB01  I55  C572
   1 P0V9_CPU0_RT0_2A      A @T6G_MB_LIB.T6G(SCH_1):P0V9_CPU0_RT0_2A
   2    GND      B @T6G_MB_LIB.T6G(SCH_1):GND

Q_CAP_0201-1UF,4V,20%,X6S,CH-10KMEE00  I56  C577
   1 P0V9_CPU0_RT0_2A      A @T6G_MB_LIB.T6G(SCH_1):P0V9_CPU0_RT0_2A
   2    GND      B @T6G_MB_LIB.T6G(SCH_1):GND

Q_CAP_0201-1UF,4V,20%,X6S,CH-10KMEE00  I57  C581
   1 P0V9_CPU0_RT0_2A      A @T6G_MB_LIB.T6G(SCH_1):P0V9_CPU0_RT0_2A
   2    GND      B @T6G_MB_LIB.T6G(SCH_1):GND

Q_CAP_0201-1UF,4V,20%,X6S,CH-10KMEE00  I58  C525
   1 P0V9_CPU0_RT0_2A      A @T6G_MB_LIB.T6G(SCH_1):P0V9_CPU0_RT0_2A
   2    GND      B @T6G_MB_LIB.T6G(SCH_1):GND

Q_CAP_0201-1UF,4V,20%,X6S,CH-10KMEE00  I59  C529
   1 P0V9_CPU0_RT0_2A      A @T6G_MB_LIB.T6G(SCH_1):P0V9_CPU0_RT0_2A
   2    GND      B @T6G_MB_LIB.T6G(SCH_1):GND

Q_CAP_C0201-0.1UF,10V,10%,X7S,CH4102K6E00  I60  C558
   1 P0V9_CPU0_RT0_2A      A @T6G_MB_LIB.T6G(SCH_1):P0V9_CPU0_RT0_2A
   2    GND      B @T6G_MB_LIB.T6G(SCH_1):GND

Q_CAP_C0201-0.1UF,10V,10%,X7S,CH4102K6E00  I62  C543
   1 P0V9_CPU0_RT0_2A      A @T6G_MB_LIB.T6G(SCH_1):P0V9_CPU0_RT0_2A
   2    GND      B @T6G_MB_LIB.T6G(SCH_1):GND

Q_CAP_0201-1UF,4V,20%,X6S,CH-10KMEE00  I65  C521
   1 P0V9_CPU0_RT0_2A      A @T6G_MB_LIB.T6G(SCH_1):P0V9_CPU0_RT0_2A
   2    GND      B @T6G_MB_LIB.T6G(SCH_1):GND

Q_CAP_0201-1UF,4V,20%,X6S,CH-10KMEE00  I66  C526
   1 P0V9_CPU0_RT0_2A      A @T6G_MB_LIB.T6G(SCH_1):P0V9_CPU0_RT0_2A
   2    GND      B @T6G_MB_LIB.T6G(SCH_1):GND

Q_CAP_C0805-100UF,4V,20%,X6S,CH710KMEA01  I67  C550
   1 P0V9_CPU0_RT0_2A      A @T6G_MB_LIB.T6G(SCH_1):P0V9_CPU0_RT0_2A
   2    GND      B @T6G_MB_LIB.T6G(SCH_1):GND

Q_CAP_C0805-100UF,4V,20%,X6S,CH710KMEA01  I69  C556
   1 P0V9_CPU0_RT0_2A      A @T6G_MB_LIB.T6G(SCH_1):P0V9_CPU0_RT0_2A
   2    GND      B @T6G_MB_LIB.T6G(SCH_1):GND

Q_CAP_C0805-100UF,4V,20%,X6S,CH710KMEA01  I70  C560
   1 P0V9_CPU0_RT0_2A      A @T6G_MB_LIB.T6G(SCH_1):P0V9_CPU0_RT0_2A
   2    GND      B @T6G_MB_LIB.T6G(SCH_1):GND

Q_CAP_C0805-100UF,4V,20%,X6S,CH710KMEA01  I71  C564
   1 P0V9_CPU0_RT0_2A      A @T6G_MB_LIB.T6G(SCH_1):P0V9_CPU0_RT0_2A
   2    GND      B @T6G_MB_LIB.T6G(SCH_1):GND

Q_CAP_C0805-100UF,4V,20%,X6S,CH710KMEA01  I72  C559
   1 P0V9_CPU0_RT_2D      A @T6G_MB_LIB.T6G(SCH_1):P0V9_CPU0_RT_2D
   2    GND      B @T6G_MB_LIB.T6G(SCH_1):GND

Q_CAP_C0402-10UF,6.3V,20%,X6S,CH6101MEB01  I73  C574
   1 P0V9_CPU0_RT_2D      A @T6G_MB_LIB.T6G(SCH_1):P0V9_CPU0_RT_2D
   2    GND      B @T6G_MB_LIB.T6G(SCH_1):GND

Q_CAP_C0402-22UF,4V,20%,X6S,CH622KMEB02  I74  C563
   1 P0V9_CPU0_RT_2D      A @T6G_MB_LIB.T6G(SCH_1):P0V9_CPU0_RT_2D
   2    GND      B @T6G_MB_LIB.T6G(SCH_1):GND

Q_CAP_C0402-22UF,4V,20%,X6S,CH622KMEB02  I75  C586
   1 P0V9_CPU0_RT0_2A      A @T6G_MB_LIB.T6G(SCH_1):P0V9_CPU0_RT0_2A
   2    GND      B @T6G_MB_LIB.T6G(SCH_1):GND

Q_CAP_C0402-22UF,4V,20%,X6S,CH622KMEB02  I76  C565
   1 P0V9_CPU0_RT0_2A      A @T6G_MB_LIB.T6G(SCH_1):P0V9_CPU0_RT0_2A
   2    GND      B @T6G_MB_LIB.T6G(SCH_1):GND

Q_CAP_C0402-22UF,4V,20%,X6S,CH622KMEB02  I77  C575
   1 P0V9_CPU0_RT0_2A      A @T6G_MB_LIB.T6G(SCH_1):P0V9_CPU0_RT0_2A
   2    GND      B @T6G_MB_LIB.T6G(SCH_1):GND

Q_CAP_C0402-22UF,4V,20%,X6S,CH622KMEB02  I78  C568
   1 P0V9_CPU0_RT0_2A      A @T6G_MB_LIB.T6G(SCH_1):P0V9_CPU0_RT0_2A
   2    GND      B @T6G_MB_LIB.T6G(SCH_1):GND

Q_CAP_0402-4.7UF,6.3V,20%,X6S,CH5471MEB01  I79  C569
   1 P0V9_CPU0_RT_2D      A @T6G_MB_LIB.T6G(SCH_1):P0V9_CPU0_RT_2D
   2    GND      B @T6G_MB_LIB.T6G(SCH_1):GND

Q_CAP_0201-1UF,4V,20%,X6S,CH-10KMEE00  I80  C528
   1 P0V9_CPU0_RT_2D      A @T6G_MB_LIB.T6G(SCH_1):P0V9_CPU0_RT_2D
   2    GND      B @T6G_MB_LIB.T6G(SCH_1):GND

Q_CAP_C0201-0.1UF,10V,10%,X7S,CH4102K6E00  I81  C522
   1 P0V9_CPU0_RT_2D      A @T6G_MB_LIB.T6G(SCH_1):P0V9_CPU0_RT_2D
   2    GND      B @T6G_MB_LIB.T6G(SCH_1):GND

Q_CAP_C0402-10UF,6.3V,20%,X6S,CH6101MEB01  I82  C584
   1 P0V9_CPU0_RT0_2A      A @T6G_MB_LIB.T6G(SCH_1):P0V9_CPU0_RT0_2A
   2    GND      B @T6G_MB_LIB.T6G(SCH_1):GND

Q_CAP_C0402-10UF,6.3V,20%,X6S,CH6101MEB01  I83  C567
   1 P0V9_CPU0_RT0_2A      A @T6G_MB_LIB.T6G(SCH_1):P0V9_CPU0_RT0_2A
   2    GND      B @T6G_MB_LIB.T6G(SCH_1):GND

Q_CAP_C0201-0.1UF,10V,10%,X7S,CH4102K6E00  I84  C524
   1 P0V9_CPU0_RT_2D      A @T6G_MB_LIB.T6G(SCH_1):P0V9_CPU0_RT_2D
   2    GND      B @T6G_MB_LIB.T6G(SCH_1):GND

Q_CAP_C0201-0.1UF,10V,10%,X7S,CH4102K6E00  I85  C578
   1 P0V9_CPU0_RT_2D      A @T6G_MB_LIB.T6G(SCH_1):P0V9_CPU0_RT_2D
   2    GND      B @T6G_MB_LIB.T6G(SCH_1):GND

Q_CAP_C0201-0.1UF,10V,10%,X7S,CH4102K6E00  I87  C540
   1 P0V9_CPU0_RT_2D      A @T6G_MB_LIB.T6G(SCH_1):P0V9_CPU0_RT_2D
   2    GND      B @T6G_MB_LIB.T6G(SCH_1):GND

Q_INDUCTOR_SMLF-BLM15PD121SN1D/1300MA,IND,CX5PD121A  I88  L26
   2 P1V8_CPU0_RT0_1A_1D      2 @T6G_MB_LIB.T6G(SCH_1):P1V8_CPU0_RT0_1A_1D
   1 P1V8_CPU0_RT_1D      1 @T6G_MB_LIB.T6G(SCH_1):P1V8_CPU0_RT_1D

Q_RES_0402LF-0,5%,1/16W,EMPTY,CS00002JB13  I89  R960
   1 P1V8_CPU0_RT_1D      A @T6G_MB_LIB.T6G(SCH_1):P1V8_CPU0_RT_1D
   2 P1V8_CPU0_RT0_1A_1D      B @T6G_MB_LIB.T6G(SCH_1):P1V8_CPU0_RT0_1A_1D

Q_CAP_0201-1UF,4V,20%,X6S,CH-10KMEE00  I90  C542
   1 P0V9_CPU0_RT0_2A_2D      A @T6G_MB_LIB.T6G(SCH_1):P0V9_CPU0_RT0_2A_2D
   2    GND      B @T6G_MB_LIB.T6G(SCH_1):GND

Q_CAP_0201-1UF,4V,20%,X6S,CH-10KMEE00  I91  C545
   1 P0V9_CPU0_RT0_2A_2D      A @T6G_MB_LIB.T6G(SCH_1):P0V9_CPU0_RT0_2A_2D
   2    GND      B @T6G_MB_LIB.T6G(SCH_1):GND

Q_CAP_C0201-0.1UF,10V,10%,X7S,CH4102K6E00  I93  C583
   1 P0V9_CPU0_RT0_2A      A @T6G_MB_LIB.T6G(SCH_1):P0V9_CPU0_RT0_2A
   2    GND      B @T6G_MB_LIB.T6G(SCH_1):GND

Q_CAP_C0201-0.1UF,10V,10%,X7S,CH4102K6E00  I94  C566
   1 P0V9_CPU0_RT0_2A      A @T6G_MB_LIB.T6G(SCH_1):P0V9_CPU0_RT0_2A
   2    GND      B @T6G_MB_LIB.T6G(SCH_1):GND

Q_CAP_C0805-47UF,4V,20%,X6S,CH647KMEA04  I95  C7003
   1 P0V9_CPU0_RT_2D      A @T6G_MB_LIB.T6G(SCH_1):P0V9_CPU0_RT_2D
   2    GND      B @T6G_MB_LIB.T6G(SCH_1):GND

Q_CAP_C0805-47UF,4V,20%,X6S,CH647KMEA04  I96  C7002
   1 P0V9_CPU0_RT_2D      A @T6G_MB_LIB.T6G(SCH_1):P0V9_CPU0_RT_2D
   2    GND      B @T6G_MB_LIB.T6G(SCH_1):GND

Q_CAPP_SMLF-470UF,2.5V,20%,SPCAP,CH747LM8818  I97  C7001
   1 P0V9_CPU0_RT_2D      A @T6G_MB_LIB.T6G(SCH_1):P0V9_CPU0_RT_2D
   2    GND      B @T6G_MB_LIB.T6G(SCH_1):GND

Q_CAPP_SMLF-470UF,2.5V,20%,SPCAP,CH747LM8818  I98  C7000
   1 P0V9_CPU0_RT_2D      A @T6G_MB_LIB.T6G(SCH_1):P0V9_CPU0_RT_2D
   2    GND      B @T6G_MB_LIB.T6G(SCH_1):GND

Q_CAPP_SMLF-470UF,2.5V,20%,SPCAP,CH747LM8818  I99  C7008
   1 P0V9_CPU0_RT0_2A      A @T6G_MB_LIB.T6G(SCH_1):P0V9_CPU0_RT0_2A
   2    GND      B @T6G_MB_LIB.T6G(SCH_1):GND

Q_CAPP_SMLF-470UF,2.5V,20%,SPCAP,CH747LM8818  I100  C7009
   1 P0V9_CPU0_RT0_2A      A @T6G_MB_LIB.T6G(SCH_1):P0V9_CPU0_RT0_2A
   2    GND      B @T6G_MB_LIB.T6G(SCH_1):GND

Q_CAP_C0805-100UF,4V,20%,X6S,CH710KMEA01  I101  C7010
   1 P0V9_CPU0_RT0_2A      A @T6G_MB_LIB.T6G(SCH_1):P0V9_CPU0_RT0_2A
   2    GND      B @T6G_MB_LIB.T6G(SCH_1):GND

Q_CAPP_SMLF-470UF,2.5V,20%,SPCAP,CH747LM8818  I102  C7032
   1 P0V9_CPU0_RT_2D      A @T6G_MB_LIB.T6G(SCH_1):P0V9_CPU0_RT_2D
   2    GND      B @T6G_MB_LIB.T6G(SCH_1):GND

Q_CAP_C0805-47UF,4V,20%,X6S,CH647KMEA04  I103  C7033
   1 P0V9_CPU0_RT_2D      A @T6G_MB_LIB.T6G(SCH_1):P0V9_CPU0_RT_2D
   2    GND      B @T6G_MB_LIB.T6G(SCH_1):GND

Q_CAP_C0805-47UF,4V,20%,X6S,CH647KMEA04  I104  C7034
   1 P0V9_CPU0_RT_2D      A @T6G_MB_LIB.T6G(SCH_1):P0V9_CPU0_RT_2D
   2    GND      B @T6G_MB_LIB.T6G(SCH_1):GND

Q_CAP_C0805-47UF,4V,20%,X6S,CH647KMEA04  I105  C7035
   1 P0V9_CPU0_RT_2D      A @T6G_MB_LIB.T6G(SCH_1):P0V9_CPU0_RT_2D
   2    GND      B @T6G_MB_LIB.T6G(SCH_1):GND

Q_CAP_C0805-47UF,4V,20%,X6S,CH647KMEA04  I106  C7036
   1 P0V9_CPU0_RT_2D      A @T6G_MB_LIB.T6G(SCH_1):P0V9_CPU0_RT_2D
   2    GND      B @T6G_MB_LIB.T6G(SCH_1):GND


DRAWING: @T6G_MB_LIB.T6G(SCH_1):PAGE409 

PT5161LRS-PT5161LRS,SMLF,IC,AJ051610U03  I5  U6011
  G1 RT_CPU0_P1_VQPS   VQPS @T6G_MB_LIB.T6G(SCH_1):RT_CPU0_P1_VQPS
BV20 P1V8_CPU0_RT1_1A PWR_1A_1 @T6G_MB_LIB.T6G(SCH_1):P1V8_CPU0_RT1_1A
CE17 P1V8_CPU0_RT1_1A PWR_1A_2 @T6G_MB_LIB.T6G(SCH_1):P1V8_CPU0_RT1_1A
CE20 P1V8_CPU0_RT1_1A PWR_1A_3 @T6G_MB_LIB.T6G(SCH_1):P1V8_CPU0_RT1_1A
CM17 P1V8_CPU0_RT1_1A PWR_1A_4 @T6G_MB_LIB.T6G(SCH_1):P1V8_CPU0_RT1_1A
CM20 P1V8_CPU0_RT1_1A PWR_1A_5 @T6G_MB_LIB.T6G(SCH_1):P1V8_CPU0_RT1_1A
BL17 P0V9_CPU0_RT_2D PWR_2D_1 @T6G_MB_LIB.T6G(SCH_1):P0V9_CPU0_RT_2D
BL20 P0V9_CPU0_RT_2D PWR_2D_2 @T6G_MB_LIB.T6G(SCH_1):P0V9_CPU0_RT_2D
CW17 P0V9_CPU0_RT_2D PWR_2D_3 @T6G_MB_LIB.T6G(SCH_1):P0V9_CPU0_RT_2D
CW20 P0V9_CPU0_RT_2D PWR_2D_4 @T6G_MB_LIB.T6G(SCH_1):P0V9_CPU0_RT_2D
BV17 P1V8_CPU0_RT1_1A_1D PWR_1D @T6G_MB_LIB.T6G(SCH_1):P1V8_CPU0_RT1_1A_1D
AC17 P0V9_CPU0_RT1_2A PWR_2A_1 @T6G_MB_LIB.T6G(SCH_1):P0V9_CPU0_RT1_2A
AC20 P0V9_CPU0_RT1_2A PWR_2A_2 @T6G_MB_LIB.T6G(SCH_1):P0V9_CPU0_RT1_2A
AK17 P0V9_CPU0_RT1_2A PWR_2A_3 @T6G_MB_LIB.T6G(SCH_1):P0V9_CPU0_RT1_2A
AK20 P0V9_CPU0_RT1_2A PWR_2A_4 @T6G_MB_LIB.T6G(SCH_1):P0V9_CPU0_RT1_2A
AU17 P0V9_CPU0_RT1_2A PWR_2A_5 @T6G_MB_LIB.T6G(SCH_1):P0V9_CPU0_RT1_2A
AU20 P0V9_CPU0_RT1_2A PWR_2A_6 @T6G_MB_LIB.T6G(SCH_1):P0V9_CPU0_RT1_2A
BD17 P0V9_CPU0_RT1_2A_2D PWR_2A_7 @T6G_MB_LIB.T6G(SCH_1):P0V9_CPU0_RT1_2A_2D
BD20 P0V9_CPU0_RT1_2A_2D PWR_2A_8 @T6G_MB_LIB.T6G(SCH_1):P0V9_CPU0_RT1_2A_2D
DF17 P0V9_CPU0_RT1_2A_2D PWR_2A_9 @T6G_MB_LIB.T6G(SCH_1):P0V9_CPU0_RT1_2A_2D
DF20 P0V9_CPU0_RT1_2A_2D PWR_2A_10 @T6G_MB_LIB.T6G(SCH_1):P0V9_CPU0_RT1_2A_2D
DN17 P0V9_CPU0_RT1_2A PWR_2A_11 @T6G_MB_LIB.T6G(SCH_1):P0V9_CPU0_RT1_2A
DN20 P0V9_CPU0_RT1_2A PWR_2A_12 @T6G_MB_LIB.T6G(SCH_1):P0V9_CPU0_RT1_2A
DY17 P0V9_CPU0_RT1_2A PWR_2A_13 @T6G_MB_LIB.T6G(SCH_1):P0V9_CPU0_RT1_2A
DY20 P0V9_CPU0_RT1_2A PWR_2A_14 @T6G_MB_LIB.T6G(SCH_1):P0V9_CPU0_RT1_2A
EG17 P0V9_CPU0_RT1_2A PWR_2A_15 @T6G_MB_LIB.T6G(SCH_1):P0V9_CPU0_RT1_2A
EG20 P0V9_CPU0_RT1_2A PWR_2A_16 @T6G_MB_LIB.T6G(SCH_1):P0V9_CPU0_RT1_2A
EP17 P0V9_CPU0_RT1_2A PWR_2A_17 @T6G_MB_LIB.T6G(SCH_1):P0V9_CPU0_RT1_2A
EP20 P0V9_CPU0_RT1_2A PWR_2A_18 @T6G_MB_LIB.T6G(SCH_1):P0V9_CPU0_RT1_2A
 T17 P0V9_CPU0_RT1_2A PWR_2A_19 @T6G_MB_LIB.T6G(SCH_1):P0V9_CPU0_RT1_2A
 T20 P0V9_CPU0_RT1_2A PWR_2A_20 @T6G_MB_LIB.T6G(SCH_1):P0V9_CPU0_RT1_2A

Q_RES_0201LF-0,5%,1/20W,CHIP,CS00001JE10  I13  R1042
   1 NCF_CPU0_P1_GND      A @T6G_MB_LIB.T6G(SCH_1):NCF_CPU0_P1_GND
   2    GND      B @T6G_MB_LIB.T6G(SCH_1):GND

Q_RES_0201LF-0,5%,1/20W,CHIP,CS00001JE10  I15  R1043
   1 NCF_A1_CPU0_P1_GND      A @T6G_MB_LIB.T6G(SCH_1):NCF_A1_CPU0_P1_GND
   2    GND      B @T6G_MB_LIB.T6G(SCH_1):GND

PT5161LRS-PT5161LRS,SMLF,IC,AJ051610U03  I17  U6011
AC13    GND   GND1 @T6G_MB_LIB.T6G(SCH_1):GND
AC22    GND   GND2 @T6G_MB_LIB.T6G(SCH_1):GND
AC32    GND   GND3 @T6G_MB_LIB.T6G(SCH_1):GND
 AC4    GND   GND4 @T6G_MB_LIB.T6G(SCH_1):GND
 AD2    GND   GND5 @T6G_MB_LIB.T6G(SCH_1):GND
AD34    GND   GND6 @T6G_MB_LIB.T6G(SCH_1):GND
 AE1    GND   GND7 @T6G_MB_LIB.T6G(SCH_1):GND
AE35    GND   GND8 @T6G_MB_LIB.T6G(SCH_1):GND
AK13    GND   GND9 @T6G_MB_LIB.T6G(SCH_1):GND
AK22    GND  GND10 @T6G_MB_LIB.T6G(SCH_1):GND
AK32    GND  GND11 @T6G_MB_LIB.T6G(SCH_1):GND
 AK4    GND  GND12 @T6G_MB_LIB.T6G(SCH_1):GND
 AL2    GND  GND13 @T6G_MB_LIB.T6G(SCH_1):GND
AL34    GND  GND14 @T6G_MB_LIB.T6G(SCH_1):GND
 AM1    GND  GND15 @T6G_MB_LIB.T6G(SCH_1):GND
AM35    GND  GND16 @T6G_MB_LIB.T6G(SCH_1):GND
AU13    GND  GND17 @T6G_MB_LIB.T6G(SCH_1):GND
AU22    GND  GND18 @T6G_MB_LIB.T6G(SCH_1):GND
AU32    GND  GND19 @T6G_MB_LIB.T6G(SCH_1):GND
 AU4    GND  GND20 @T6G_MB_LIB.T6G(SCH_1):GND
 AV2    GND  GND21 @T6G_MB_LIB.T6G(SCH_1):GND
AV34    GND  GND22 @T6G_MB_LIB.T6G(SCH_1):GND
 AW1    GND  GND23 @T6G_MB_LIB.T6G(SCH_1):GND
AW35    GND  GND24 @T6G_MB_LIB.T6G(SCH_1):GND
 B19    GND  GND25 @T6G_MB_LIB.T6G(SCH_1):GND
BD13    GND  GND26 @T6G_MB_LIB.T6G(SCH_1):GND
BD22    GND  GND27 @T6G_MB_LIB.T6G(SCH_1):GND
BD32    GND  GND28 @T6G_MB_LIB.T6G(SCH_1):GND
 BD4    GND  GND29 @T6G_MB_LIB.T6G(SCH_1):GND
 BE2    GND  GND30 @T6G_MB_LIB.T6G(SCH_1):GND
BE34    GND  GND31 @T6G_MB_LIB.T6G(SCH_1):GND
 BF1    GND  GND32 @T6G_MB_LIB.T6G(SCH_1):GND
BF35    GND  GND33 @T6G_MB_LIB.T6G(SCH_1):GND
BL13    GND  GND34 @T6G_MB_LIB.T6G(SCH_1):GND
BL22    GND  GND35 @T6G_MB_LIB.T6G(SCH_1):GND
BL32    GND  GND36 @T6G_MB_LIB.T6G(SCH_1):GND
 BL4    GND  GND37 @T6G_MB_LIB.T6G(SCH_1):GND
 BM2    GND  GND38 @T6G_MB_LIB.T6G(SCH_1):GND
BM34    GND  GND39 @T6G_MB_LIB.T6G(SCH_1):GND
 BN1    GND  GND40 @T6G_MB_LIB.T6G(SCH_1):GND
BN35    GND  GND41 @T6G_MB_LIB.T6G(SCH_1):GND
BV13    GND  GND42 @T6G_MB_LIB.T6G(SCH_1):GND
BV22    GND  GND43 @T6G_MB_LIB.T6G(SCH_1):GND
BV32    GND  GND44 @T6G_MB_LIB.T6G(SCH_1):GND
 BV4    GND  GND45 @T6G_MB_LIB.T6G(SCH_1):GND
 BW2    GND  GND46 @T6G_MB_LIB.T6G(SCH_1):GND
BW34    GND  GND47 @T6G_MB_LIB.T6G(SCH_1):GND
 BY1    GND  GND48 @T6G_MB_LIB.T6G(SCH_1):GND
BY35    GND  GND49 @T6G_MB_LIB.T6G(SCH_1):GND
CE13    GND  GND50 @T6G_MB_LIB.T6G(SCH_1):GND
CE22    GND  GND51 @T6G_MB_LIB.T6G(SCH_1):GND
CE32    GND  GND52 @T6G_MB_LIB.T6G(SCH_1):GND
 CE4    GND  GND53 @T6G_MB_LIB.T6G(SCH_1):GND
 CF2    GND  GND54 @T6G_MB_LIB.T6G(SCH_1):GND
CF34    GND  GND55 @T6G_MB_LIB.T6G(SCH_1):GND
 CG1    GND  GND56 @T6G_MB_LIB.T6G(SCH_1):GND
CG35    GND  GND57 @T6G_MB_LIB.T6G(SCH_1):GND
CM13    GND  GND58 @T6G_MB_LIB.T6G(SCH_1):GND
CM22    GND  GND59 @T6G_MB_LIB.T6G(SCH_1):GND
CM32    GND  GND60 @T6G_MB_LIB.T6G(SCH_1):GND
 CM4    GND  GND61 @T6G_MB_LIB.T6G(SCH_1):GND
 CN2    GND  GND62 @T6G_MB_LIB.T6G(SCH_1):GND
CN34    GND  GND63 @T6G_MB_LIB.T6G(SCH_1):GND
 CP1    GND  GND64 @T6G_MB_LIB.T6G(SCH_1):GND
CP35    GND  GND65 @T6G_MB_LIB.T6G(SCH_1):GND
CW13    GND  GND66 @T6G_MB_LIB.T6G(SCH_1):GND
CW22    GND  GND67 @T6G_MB_LIB.T6G(SCH_1):GND
CW32    GND  GND68 @T6G_MB_LIB.T6G(SCH_1):GND
 CW4    GND  GND69 @T6G_MB_LIB.T6G(SCH_1):GND
 CY2    GND  GND70 @T6G_MB_LIB.T6G(SCH_1):GND
CY34    GND  GND71 @T6G_MB_LIB.T6G(SCH_1):GND
 DA1    GND  GND72 @T6G_MB_LIB.T6G(SCH_1):GND
DA35    GND  GND73 @T6G_MB_LIB.T6G(SCH_1):GND
DF13    GND  GND74 @T6G_MB_LIB.T6G(SCH_1):GND
DF22    GND  GND75 @T6G_MB_LIB.T6G(SCH_1):GND
DF32    GND  GND76 @T6G_MB_LIB.T6G(SCH_1):GND
 DF4    GND  GND77 @T6G_MB_LIB.T6G(SCH_1):GND
 DG2    GND  GND78 @T6G_MB_LIB.T6G(SCH_1):GND
DG34    GND  GND79 @T6G_MB_LIB.T6G(SCH_1):GND
 DH1    GND  GND80 @T6G_MB_LIB.T6G(SCH_1):GND
DH35    GND  GND81 @T6G_MB_LIB.T6G(SCH_1):GND
DN13    GND  GND82 @T6G_MB_LIB.T6G(SCH_1):GND
  A1 NCF_A1_CPU0_P1_GND NCF_GND1 @T6G_MB_LIB.T6G(SCH_1):NCF_A1_CPU0_P1_GND
 A35 NCF_CPU0_P1_GND NCF_GND2 @T6G_MB_LIB.T6G(SCH_1):NCF_CPU0_P1_GND
  C2 NCF_CPU0_P1_GND NCF_GND3 @T6G_MB_LIB.T6G(SCH_1):NCF_CPU0_P1_GND
 C34 NCF_CPU0_P1_GND NCF_GND4 @T6G_MB_LIB.T6G(SCH_1):NCF_CPU0_P1_GND
  D1 NCF_CPU0_P1_GND NCF_GND5 @T6G_MB_LIB.T6G(SCH_1):NCF_CPU0_P1_GND
 D35 NCF_CPU0_P1_GND NCF_GND6 @T6G_MB_LIB.T6G(SCH_1):NCF_CPU0_P1_GND
 FE2 NCF_CPU0_P1_GND NCF_GND7 @T6G_MB_LIB.T6G(SCH_1):NCF_CPU0_P1_GND
FE34 NCF_CPU0_P1_GND NCF_GND8 @T6G_MB_LIB.T6G(SCH_1):NCF_CPU0_P1_GND
 FG1 NCF_CPU0_P1_GND NCF_GND9 @T6G_MB_LIB.T6G(SCH_1):NCF_CPU0_P1_GND
FG35 NCF_CPU0_P1_GND NCF_GND10 @T6G_MB_LIB.T6G(SCH_1):NCF_CPU0_P1_GND
 FH2 NCF_CPU0_P1_GND NCF_GND11 @T6G_MB_LIB.T6G(SCH_1):NCF_CPU0_P1_GND
FH34 NCF_CPU0_P1_GND NCF_GND12 @T6G_MB_LIB.T6G(SCH_1):NCF_CPU0_P1_GND
DN22    GND  GND83 @T6G_MB_LIB.T6G(SCH_1):GND
DN32    GND  GND84 @T6G_MB_LIB.T6G(SCH_1):GND
 DN4    GND  GND85 @T6G_MB_LIB.T6G(SCH_1):GND
 DP2    GND  GND86 @T6G_MB_LIB.T6G(SCH_1):GND
DP34    GND  GND87 @T6G_MB_LIB.T6G(SCH_1):GND
 DR1    GND  GND88 @T6G_MB_LIB.T6G(SCH_1):GND
DR35    GND  GND89 @T6G_MB_LIB.T6G(SCH_1):GND
DY13    GND  GND90 @T6G_MB_LIB.T6G(SCH_1):GND
DY22    GND  GND91 @T6G_MB_LIB.T6G(SCH_1):GND
DY32    GND  GND92 @T6G_MB_LIB.T6G(SCH_1):GND
 DY4    GND  GND93 @T6G_MB_LIB.T6G(SCH_1):GND
 E14    GND  GND94 @T6G_MB_LIB.T6G(SCH_1):GND
 E27    GND  GND95 @T6G_MB_LIB.T6G(SCH_1):GND
 E33    GND  GND96 @T6G_MB_LIB.T6G(SCH_1):GND
 EA2    GND  GND97 @T6G_MB_LIB.T6G(SCH_1):GND
EA34    GND  GND98 @T6G_MB_LIB.T6G(SCH_1):GND
 EB1    GND  GND99 @T6G_MB_LIB.T6G(SCH_1):GND
EB35    GND GND100 @T6G_MB_LIB.T6G(SCH_1):GND
EG13    GND GND101 @T6G_MB_LIB.T6G(SCH_1):GND
EG22    GND GND102 @T6G_MB_LIB.T6G(SCH_1):GND
EG32    GND GND103 @T6G_MB_LIB.T6G(SCH_1):GND
 EG4    GND GND104 @T6G_MB_LIB.T6G(SCH_1):GND
 EH2    GND GND105 @T6G_MB_LIB.T6G(SCH_1):GND
EH34    GND GND106 @T6G_MB_LIB.T6G(SCH_1):GND
 EJ1    GND GND107 @T6G_MB_LIB.T6G(SCH_1):GND
EJ35    GND GND108 @T6G_MB_LIB.T6G(SCH_1):GND
EP13    GND GND109 @T6G_MB_LIB.T6G(SCH_1):GND
EP22    GND GND110 @T6G_MB_LIB.T6G(SCH_1):GND
EP32    GND GND111 @T6G_MB_LIB.T6G(SCH_1):GND
 EP4    GND GND112 @T6G_MB_LIB.T6G(SCH_1):GND
 ER2    GND GND113 @T6G_MB_LIB.T6G(SCH_1):GND
ER34    GND GND114 @T6G_MB_LIB.T6G(SCH_1):GND
 ET1    GND GND115 @T6G_MB_LIB.T6G(SCH_1):GND
ET35    GND GND116 @T6G_MB_LIB.T6G(SCH_1):GND
FA15    GND GND117 @T6G_MB_LIB.T6G(SCH_1):GND
FA32    GND GND118 @T6G_MB_LIB.T6G(SCH_1):GND
 FB2    GND GND119 @T6G_MB_LIB.T6G(SCH_1):GND
FB34    GND GND120 @T6G_MB_LIB.T6G(SCH_1):GND
FC19    GND GND121 @T6G_MB_LIB.T6G(SCH_1):GND
FC23    GND GND122 @T6G_MB_LIB.T6G(SCH_1):GND
FC25    GND GND123 @T6G_MB_LIB.T6G(SCH_1):GND
FC28    GND GND124 @T6G_MB_LIB.T6G(SCH_1):GND
 FC3    GND GND125 @T6G_MB_LIB.T6G(SCH_1):GND
 FC6    GND GND126 @T6G_MB_LIB.T6G(SCH_1):GND
 FC9    GND GND127 @T6G_MB_LIB.T6G(SCH_1):GND
 FD1    GND GND128 @T6G_MB_LIB.T6G(SCH_1):GND
FD35    GND GND129 @T6G_MB_LIB.T6G(SCH_1):GND
FF14    GND GND130 @T6G_MB_LIB.T6G(SCH_1):GND
FF21    GND GND131 @T6G_MB_LIB.T6G(SCH_1):GND
FJ12    GND GND132 @T6G_MB_LIB.T6G(SCH_1):GND
FJ19    GND GND133 @T6G_MB_LIB.T6G(SCH_1):GND
 H12    GND GND134 @T6G_MB_LIB.T6G(SCH_1):GND
 H16    GND GND135 @T6G_MB_LIB.T6G(SCH_1):GND
 H19    GND GND136 @T6G_MB_LIB.T6G(SCH_1):GND
 H31    GND GND137 @T6G_MB_LIB.T6G(SCH_1):GND
 J22    GND GND138 @T6G_MB_LIB.T6G(SCH_1):GND
  J4    GND GND139 @T6G_MB_LIB.T6G(SCH_1):GND
  K2    GND GND140 @T6G_MB_LIB.T6G(SCH_1):GND
 K34    GND GND141 @T6G_MB_LIB.T6G(SCH_1):GND
  L1    GND GND142 @T6G_MB_LIB.T6G(SCH_1):GND
 L35    GND GND143 @T6G_MB_LIB.T6G(SCH_1):GND
 T13    GND GND144 @T6G_MB_LIB.T6G(SCH_1):GND
 T22    GND GND145 @T6G_MB_LIB.T6G(SCH_1):GND
 T32    GND GND146 @T6G_MB_LIB.T6G(SCH_1):GND
  T4    GND GND147 @T6G_MB_LIB.T6G(SCH_1):GND
  U2    GND GND148 @T6G_MB_LIB.T6G(SCH_1):GND
 U34    GND GND149 @T6G_MB_LIB.T6G(SCH_1):GND
  V1    GND GND150 @T6G_MB_LIB.T6G(SCH_1):GND
 V35    GND GND151 @T6G_MB_LIB.T6G(SCH_1):GND

Q_RES_0201LF-200,1%,1/20W,CHIP,CS12001FE12  I18  R1041
   1 RT_CPU0_P1_VQPS      A @T6G_MB_LIB.T6G(SCH_1):RT_CPU0_P1_VQPS
   2    GND      B @T6G_MB_LIB.T6G(SCH_1):GND

Q_RES_0201LF-1K,1%,1/20W,EMPTY,CS21001FE07  I19  R1040
   1 P1V8_CPU0_RT_1D      A @T6G_MB_LIB.T6G(SCH_1):P1V8_CPU0_RT_1D
   2 RT_CPU0_P1_VQPS      B @T6G_MB_LIB.T6G(SCH_1):RT_CPU0_P1_VQPS


DRAWING: @T6G_MB_LIB.T6G(SCH_1):PAGE411 

Q_RES_0402LF-0,5%,1/16W,EMPTY,CS00002JB13  I2  R1003
   1 P1V8_CPU0_RT1_1A_1D      A @T6G_MB_LIB.T6G(SCH_1):P1V8_CPU0_RT1_1A_1D
   2 P1V8_CPU0_RT1_1A      B @T6G_MB_LIB.T6G(SCH_1):P1V8_CPU0_RT1_1A

Q_RES_0402LF-0,5%,1/16W,EMPTY,CS00002JB13  I4  R1002
   1 P1V8_CPU0_RT1_1A_1D      A @T6G_MB_LIB.T6G(SCH_1):P1V8_CPU0_RT1_1A_1D
   2 P1V8_CPU0_RT1_1A      B @T6G_MB_LIB.T6G(SCH_1):P1V8_CPU0_RT1_1A

Q_CAP_0201-1UF,4V,20%,X6S,CH-10KMEE00  I5  C598
   1 P1V8_CPU0_RT1_1A_1D      A @T6G_MB_LIB.T6G(SCH_1):P1V8_CPU0_RT1_1A_1D
   2    GND      B @T6G_MB_LIB.T6G(SCH_1):GND

Q_CAP_C0201-0.1UF,10V,10%,X7S,CH4102K6E00  I7  C601
   1 P1V8_CPU0_RT1_1A_1D      A @T6G_MB_LIB.T6G(SCH_1):P1V8_CPU0_RT1_1A_1D
   2    GND      B @T6G_MB_LIB.T6G(SCH_1):GND

Q_RES_0603LF-0,5%,1/4W,EMPTY,CS00006J900  I10  R1010
   1 P0V9_CPU0_RT_2D      A @T6G_MB_LIB.T6G(SCH_1):P0V9_CPU0_RT_2D
   2 P0V9_CPU0_RT1_2A_2D      B @T6G_MB_LIB.T6G(SCH_1):P0V9_CPU0_RT1_2A_2D

Q_INDUCTOR_SMLF-BLM21SN300SN1D/5A,IND,CX300SN1000  I11  L13
   2 P1V8_CPU0_RT1_1A      2 @T6G_MB_LIB.T6G(SCH_1):P1V8_CPU0_RT1_1A
   1 P1V8_CPU0_RT_1D      1 @T6G_MB_LIB.T6G(SCH_1):P1V8_CPU0_RT_1D

Q_CAP_C0805-100UF,4V,20%,X6S,CH710KMEA01  I12  C588
   1 P1V8_CPU0_RT1_1A      A @T6G_MB_LIB.T6G(SCH_1):P1V8_CPU0_RT1_1A
   2    GND      B @T6G_MB_LIB.T6G(SCH_1):GND

Q_CAP_C0402-22UF,4V,20%,X6S,CH622KMEB02  I15  C590
   1 P1V8_CPU0_RT1_1A      A @T6G_MB_LIB.T6G(SCH_1):P1V8_CPU0_RT1_1A
   2    GND      B @T6G_MB_LIB.T6G(SCH_1):GND

Q_CAP_C0402-10UF,6.3V,20%,X6S,CH6101MEB01  I16  C595
   1 P1V8_CPU0_RT1_1A      A @T6G_MB_LIB.T6G(SCH_1):P1V8_CPU0_RT1_1A
   2    GND      B @T6G_MB_LIB.T6G(SCH_1):GND

Q_CAP_C0805-100UF,4V,20%,X6S,CH710KMEA01  I17  C587
   1 P1V8_CPU0_RT_1D      A @T6G_MB_LIB.T6G(SCH_1):P1V8_CPU0_RT_1D
   2    GND      B @T6G_MB_LIB.T6G(SCH_1):GND

Q_CAP_C0402-22UF,4V,20%,X6S,CH622KMEB02  I18  C589
   1 P1V8_CPU0_RT_1D      A @T6G_MB_LIB.T6G(SCH_1):P1V8_CPU0_RT_1D
   2    GND      B @T6G_MB_LIB.T6G(SCH_1):GND

Q_CAP_0402-4.7UF,6.3V,20%,X6S,CH5471MEB01  I19  C594
   1 P1V8_CPU0_RT1_1A      A @T6G_MB_LIB.T6G(SCH_1):P1V8_CPU0_RT1_1A
   2    GND      B @T6G_MB_LIB.T6G(SCH_1):GND

Q_CAP_0201-1UF,4V,20%,X6S,CH-10KMEE00  I20  C597
   1 P1V8_CPU0_RT1_1A      A @T6G_MB_LIB.T6G(SCH_1):P1V8_CPU0_RT1_1A
   2    GND      B @T6G_MB_LIB.T6G(SCH_1):GND

Q_CAP_0201-1UF,4V,20%,X6S,CH-10KMEE00  I21  C599
   1 P1V8_CPU0_RT1_1A      A @T6G_MB_LIB.T6G(SCH_1):P1V8_CPU0_RT1_1A
   2    GND      B @T6G_MB_LIB.T6G(SCH_1):GND

Q_CAP_C0402-10UF,6.3V,20%,X6S,CH6101MEB01  I22  C591
   1 P1V8_CPU0_RT_1D      A @T6G_MB_LIB.T6G(SCH_1):P1V8_CPU0_RT_1D
   2    GND      B @T6G_MB_LIB.T6G(SCH_1):GND

Q_CAP_0402-4.7UF,6.3V,20%,X6S,CH5471MEB01  I24  C596
   1 P1V8_CPU0_RT_1D      A @T6G_MB_LIB.T6G(SCH_1):P1V8_CPU0_RT_1D
   2    GND      B @T6G_MB_LIB.T6G(SCH_1):GND

Q_CAP_C0201-0.1UF,10V,10%,X7S,CH4102K6E00  I25  C600
   1 P1V8_CPU0_RT1_1A      A @T6G_MB_LIB.T6G(SCH_1):P1V8_CPU0_RT1_1A
   2    GND      B @T6G_MB_LIB.T6G(SCH_1):GND

Q_CAP_C0201-0.1UF,10V,10%,X7S,CH4102K6E00  I26  C602
   1 P1V8_CPU0_RT1_1A      A @T6G_MB_LIB.T6G(SCH_1):P1V8_CPU0_RT1_1A
   2    GND      B @T6G_MB_LIB.T6G(SCH_1):GND

Q_CAP_C0201-0.1UF,10V,10%,X7S,CH4102K6E00  I27  C603
   1 P1V8_CPU0_RT1_1A      A @T6G_MB_LIB.T6G(SCH_1):P1V8_CPU0_RT1_1A
   2    GND      B @T6G_MB_LIB.T6G(SCH_1):GND

Q_CAP_C0201-0.1UF,10V,10%,X7S,CH4102K6E00  I28  C606
   1 P1V8_CPU0_RT1_1A      A @T6G_MB_LIB.T6G(SCH_1):P1V8_CPU0_RT1_1A
   2    GND      B @T6G_MB_LIB.T6G(SCH_1):GND

Q_CAP_C0201-0.1UF,10V,10%,X7S,CH4102K6E00  I32  C617
   1 P0V9_CPU0_RT1_2A_2D      A @T6G_MB_LIB.T6G(SCH_1):P0V9_CPU0_RT1_2A_2D
   2    GND      B @T6G_MB_LIB.T6G(SCH_1):GND

Q_CAP_C0201-0.1UF,10V,10%,X7S,CH4102K6E00  I34  C623
   1 P0V9_CPU0_RT1_2A_2D      A @T6G_MB_LIB.T6G(SCH_1):P0V9_CPU0_RT1_2A_2D
   2    GND      B @T6G_MB_LIB.T6G(SCH_1):GND

Q_RES_0603LF-0,5%,1/4W,CHIP,CS00006J900  I36  R1011
   1 P0V9_CPU0_RT1_2A_2D      A @T6G_MB_LIB.T6G(SCH_1):P0V9_CPU0_RT1_2A_2D
   2 P0V9_CPU0_RT1_2A      B @T6G_MB_LIB.T6G(SCH_1):P0V9_CPU0_RT1_2A

Q_CAP_C0201-0.1UF,10V,10%,X7S,CH4102K6E00  I37  C662
   1 P0V9_CPU0_RT1_2A      A @T6G_MB_LIB.T6G(SCH_1):P0V9_CPU0_RT1_2A
   2    GND      B @T6G_MB_LIB.T6G(SCH_1):GND

Q_CAP_0201-1UF,4V,20%,X6S,CH-10KMEE00  I38  C609
   1 P0V9_CPU0_RT1_2A      A @T6G_MB_LIB.T6G(SCH_1):P0V9_CPU0_RT1_2A
   2    GND      B @T6G_MB_LIB.T6G(SCH_1):GND

Q_CAP_0201-1UF,4V,20%,X6S,CH-10KMEE00  I39  C618
   1 P0V9_CPU0_RT1_2A      A @T6G_MB_LIB.T6G(SCH_1):P0V9_CPU0_RT1_2A
   2    GND      B @T6G_MB_LIB.T6G(SCH_1):GND

Q_CAP_C0402-10UF,6.3V,20%,X6S,CH6101MEB01  I40  C626
   1 P0V9_CPU0_RT1_2A      A @T6G_MB_LIB.T6G(SCH_1):P0V9_CPU0_RT1_2A
   2    GND      B @T6G_MB_LIB.T6G(SCH_1):GND

Q_CAP_C0402-10UF,6.3V,20%,X6S,CH6101MEB01  I41  C645
   1 P0V9_CPU0_RT1_2A      A @T6G_MB_LIB.T6G(SCH_1):P0V9_CPU0_RT1_2A
   2    GND      B @T6G_MB_LIB.T6G(SCH_1):GND

Q_CAP_C0201-0.1UF,10V,10%,X7S,CH4102K6E00  I42  C616
   1 P0V9_CPU0_RT1_2A      A @T6G_MB_LIB.T6G(SCH_1):P0V9_CPU0_RT1_2A
   2    GND      B @T6G_MB_LIB.T6G(SCH_1):GND

Q_CAP_C0201-0.1UF,10V,10%,X7S,CH4102K6E00  I43  C657
   1 P0V9_CPU0_RT1_2A      A @T6G_MB_LIB.T6G(SCH_1):P0V9_CPU0_RT1_2A
   2    GND      B @T6G_MB_LIB.T6G(SCH_1):GND

Q_CAP_0201-1UF,4V,20%,X6S,CH-10KMEE00  I44  C607
   1 P0V9_CPU0_RT1_2A      A @T6G_MB_LIB.T6G(SCH_1):P0V9_CPU0_RT1_2A
   2    GND      B @T6G_MB_LIB.T6G(SCH_1):GND

Q_CAP_0201-1UF,4V,20%,X6S,CH-10KMEE00  I45  C643
   1 P0V9_CPU0_RT1_2A      A @T6G_MB_LIB.T6G(SCH_1):P0V9_CPU0_RT1_2A
   2    GND      B @T6G_MB_LIB.T6G(SCH_1):GND

Q_CAP_C0201-0.1UF,10V,10%,X7S,CH4102K6E00  I46  C635
   1 P0V9_CPU0_RT1_2A      A @T6G_MB_LIB.T6G(SCH_1):P0V9_CPU0_RT1_2A
   2    GND      B @T6G_MB_LIB.T6G(SCH_1):GND

Q_CAP_C0201-0.1UF,10V,10%,X7S,CH4102K6E00  I47  C627
   1 P0V9_CPU0_RT1_2A      A @T6G_MB_LIB.T6G(SCH_1):P0V9_CPU0_RT1_2A
   2    GND      B @T6G_MB_LIB.T6G(SCH_1):GND

Q_CAP_0201-1UF,4V,20%,X6S,CH-10KMEE00  I48  C647
   1 P0V9_CPU0_RT1_2A      A @T6G_MB_LIB.T6G(SCH_1):P0V9_CPU0_RT1_2A
   2    GND      B @T6G_MB_LIB.T6G(SCH_1):GND

Q_CAP_0201-1UF,4V,20%,X6S,CH-10KMEE00  I49  C654
   1 P0V9_CPU0_RT1_2A      A @T6G_MB_LIB.T6G(SCH_1):P0V9_CPU0_RT1_2A
   2    GND      B @T6G_MB_LIB.T6G(SCH_1):GND

Q_CAP_0402-4.7UF,6.3V,20%,X6S,CH5471MEB01  I50  C644
   1 P0V9_CPU0_RT1_2A      A @T6G_MB_LIB.T6G(SCH_1):P0V9_CPU0_RT1_2A
   2    GND      B @T6G_MB_LIB.T6G(SCH_1):GND

Q_CAP_0402-4.7UF,6.3V,20%,X6S,CH5471MEB01  I51  C638
   1 P0V9_CPU0_RT1_2A      A @T6G_MB_LIB.T6G(SCH_1):P0V9_CPU0_RT1_2A
   2    GND      B @T6G_MB_LIB.T6G(SCH_1):GND

Q_CAP_0402-4.7UF,6.3V,20%,X6S,CH5471MEB01  I52  C649
   1 P0V9_CPU0_RT1_2A      A @T6G_MB_LIB.T6G(SCH_1):P0V9_CPU0_RT1_2A
   2    GND      B @T6G_MB_LIB.T6G(SCH_1):GND

Q_CAP_0201-1UF,4V,20%,X6S,CH-10KMEE00  I53  C653
   1 P0V9_CPU0_RT1_2A      A @T6G_MB_LIB.T6G(SCH_1):P0V9_CPU0_RT1_2A
   2    GND      B @T6G_MB_LIB.T6G(SCH_1):GND

Q_CAP_C0201-0.1UF,10V,10%,X7S,CH4102K6E00  I55  C631
   1 P0V9_CPU0_RT1_2A      A @T6G_MB_LIB.T6G(SCH_1):P0V9_CPU0_RT1_2A
   2    GND      B @T6G_MB_LIB.T6G(SCH_1):GND

Q_CAP_C0201-0.1UF,10V,10%,X7S,CH4102K6E00  I58  C650
   1 P0V9_CPU0_RT1_2A      A @T6G_MB_LIB.T6G(SCH_1):P0V9_CPU0_RT1_2A
   2    GND      B @T6G_MB_LIB.T6G(SCH_1):GND

Q_CAP_0201-1UF,4V,20%,X6S,CH-10KMEE00  I59  C620
   1 P0V9_CPU0_RT1_2A      A @T6G_MB_LIB.T6G(SCH_1):P0V9_CPU0_RT1_2A
   2    GND      B @T6G_MB_LIB.T6G(SCH_1):GND

Q_CAP_0201-1UF,4V,20%,X6S,CH-10KMEE00  I61  C613
   1 P0V9_CPU0_RT1_2A      A @T6G_MB_LIB.T6G(SCH_1):P0V9_CPU0_RT1_2A
   2    GND      B @T6G_MB_LIB.T6G(SCH_1):GND

Q_INDUCTOR_SMLF-100NH/16A,IND,CV+10G0MZ04  I63  L14
   2 P0V9_CPU0_RT1_2A      2 @T6G_MB_LIB.T6G(SCH_1):P0V9_CPU0_RT1_2A
   1 P0V9_CPU0_RT_2D      1 @T6G_MB_LIB.T6G(SCH_1):P0V9_CPU0_RT_2D

Q_CAP_C0805-100UF,4V,20%,X6S,CH710KMEA01  I64  C625
   1 P0V9_CPU0_RT1_2A      A @T6G_MB_LIB.T6G(SCH_1):P0V9_CPU0_RT1_2A
   2    GND      B @T6G_MB_LIB.T6G(SCH_1):GND

Q_CAP_C0805-100UF,4V,20%,X6S,CH710KMEA01  I65  C628
   1 P0V9_CPU0_RT1_2A      A @T6G_MB_LIB.T6G(SCH_1):P0V9_CPU0_RT1_2A
   2    GND      B @T6G_MB_LIB.T6G(SCH_1):GND

Q_CAP_C0805-100UF,4V,20%,X6S,CH710KMEA01  I67  C632
   1 P0V9_CPU0_RT_2D      A @T6G_MB_LIB.T6G(SCH_1):P0V9_CPU0_RT_2D
   2    GND      B @T6G_MB_LIB.T6G(SCH_1):GND

Q_CAP_C0402-22UF,4V,20%,X6S,CH622KMEB02  I68  C636
   1 P0V9_CPU0_RT_2D      A @T6G_MB_LIB.T6G(SCH_1):P0V9_CPU0_RT_2D
   2    GND      B @T6G_MB_LIB.T6G(SCH_1):GND

Q_CAP_C0805-100UF,4V,20%,X6S,CH710KMEA01  I69  C633
   1 P0V9_CPU0_RT1_2A      A @T6G_MB_LIB.T6G(SCH_1):P0V9_CPU0_RT1_2A
   2    GND      B @T6G_MB_LIB.T6G(SCH_1):GND

Q_CAP_C0805-100UF,4V,20%,X6S,CH710KMEA01  I70  C637
   1 P0V9_CPU0_RT1_2A      A @T6G_MB_LIB.T6G(SCH_1):P0V9_CPU0_RT1_2A
   2    GND      B @T6G_MB_LIB.T6G(SCH_1):GND

Q_CAP_C0402-22UF,4V,20%,X6S,CH622KMEB02  I71  C634
   1 P0V9_CPU0_RT1_2A      A @T6G_MB_LIB.T6G(SCH_1):P0V9_CPU0_RT1_2A
   2    GND      B @T6G_MB_LIB.T6G(SCH_1):GND

Q_CAP_C0402-22UF,4V,20%,X6S,CH622KMEB02  I72  C663
   1 P0V9_CPU0_RT1_2A      A @T6G_MB_LIB.T6G(SCH_1):P0V9_CPU0_RT1_2A
   2    GND      B @T6G_MB_LIB.T6G(SCH_1):GND

Q_CAP_C0402-22UF,4V,20%,X6S,CH622KMEB02  I73  C630
   1 P0V9_CPU0_RT1_2A      A @T6G_MB_LIB.T6G(SCH_1):P0V9_CPU0_RT1_2A
   2    GND      B @T6G_MB_LIB.T6G(SCH_1):GND

Q_CAP_C0402-10UF,6.3V,20%,X6S,CH6101MEB01  I74  C646
   1 P0V9_CPU0_RT_2D      A @T6G_MB_LIB.T6G(SCH_1):P0V9_CPU0_RT_2D
   2    GND      B @T6G_MB_LIB.T6G(SCH_1):GND

Q_CAP_0402-4.7UF,6.3V,20%,X6S,CH5471MEB01  I75  C651
   1 P0V9_CPU0_RT_2D      A @T6G_MB_LIB.T6G(SCH_1):P0V9_CPU0_RT_2D
   2    GND      B @T6G_MB_LIB.T6G(SCH_1):GND

Q_CAP_0201-1UF,4V,20%,X6S,CH-10KMEE00  I76  C655
   1 P0V9_CPU0_RT_2D      A @T6G_MB_LIB.T6G(SCH_1):P0V9_CPU0_RT_2D
   2    GND      B @T6G_MB_LIB.T6G(SCH_1):GND

Q_CAP_C0402-22UF,4V,20%,X6S,CH622KMEB02  I77  C656
   1 P0V9_CPU0_RT1_2A      A @T6G_MB_LIB.T6G(SCH_1):P0V9_CPU0_RT1_2A
   2    GND      B @T6G_MB_LIB.T6G(SCH_1):GND

Q_CAP_C0402-10UF,6.3V,20%,X6S,CH6101MEB01  I78  C661
   1 P0V9_CPU0_RT1_2A      A @T6G_MB_LIB.T6G(SCH_1):P0V9_CPU0_RT1_2A
   2    GND      B @T6G_MB_LIB.T6G(SCH_1):GND

Q_CAP_C0402-10UF,6.3V,20%,X6S,CH6101MEB01  I79  C648
   1 P0V9_CPU0_RT1_2A      A @T6G_MB_LIB.T6G(SCH_1):P0V9_CPU0_RT1_2A
   2    GND      B @T6G_MB_LIB.T6G(SCH_1):GND

Q_CAP_C0201-0.1UF,10V,10%,X7S,CH4102K6E00  I81  C608
   1 P0V9_CPU0_RT_2D      A @T6G_MB_LIB.T6G(SCH_1):P0V9_CPU0_RT_2D
   2    GND      B @T6G_MB_LIB.T6G(SCH_1):GND

Q_CAP_C0201-0.1UF,10V,10%,X7S,CH4102K6E00  I82  C610
   1 P0V9_CPU0_RT_2D      A @T6G_MB_LIB.T6G(SCH_1):P0V9_CPU0_RT_2D
   2    GND      B @T6G_MB_LIB.T6G(SCH_1):GND

Q_CAP_C0201-0.1UF,10V,10%,X7S,CH4102K6E00  I83  C615
   1 P0V9_CPU0_RT_2D      A @T6G_MB_LIB.T6G(SCH_1):P0V9_CPU0_RT_2D
   2    GND      B @T6G_MB_LIB.T6G(SCH_1):GND

Q_CAP_C0201-0.1UF,10V,10%,X7S,CH4102K6E00  I84  C619
   1 P0V9_CPU0_RT_2D      A @T6G_MB_LIB.T6G(SCH_1):P0V9_CPU0_RT_2D
   2    GND      B @T6G_MB_LIB.T6G(SCH_1):GND

Q_CAP_C0201-0.1UF,10V,10%,X7S,CH4102K6E00  I85  C614
   1 P0V9_CPU0_RT1_2A      A @T6G_MB_LIB.T6G(SCH_1):P0V9_CPU0_RT1_2A
   2    GND      B @T6G_MB_LIB.T6G(SCH_1):GND

Q_CAP_0201-1UF,4V,20%,X6S,CH-10KMEE00  I86  C622
   1 P0V9_CPU0_RT1_2A      A @T6G_MB_LIB.T6G(SCH_1):P0V9_CPU0_RT1_2A
   2    GND      B @T6G_MB_LIB.T6G(SCH_1):GND

Q_CAP_0402-4.7UF,6.3V,20%,X6S,CH5471MEB01  I87  C652
   1 P0V9_CPU0_RT1_2A      A @T6G_MB_LIB.T6G(SCH_1):P0V9_CPU0_RT1_2A
   2    GND      B @T6G_MB_LIB.T6G(SCH_1):GND

Q_INDUCTOR_SMLF-BLM15PD121SN1D/1300MA,IND,CX5PD121A  I88  L28
   2 P1V8_CPU0_RT1_1A_1D      2 @T6G_MB_LIB.T6G(SCH_1):P1V8_CPU0_RT1_1A_1D
   1 P1V8_CPU0_RT_1D      1 @T6G_MB_LIB.T6G(SCH_1):P1V8_CPU0_RT_1D

Q_RES_0402LF-0,5%,1/16W,EMPTY,CS00002JB13  I89  R1008
   1 P1V8_CPU0_RT_1D      A @T6G_MB_LIB.T6G(SCH_1):P1V8_CPU0_RT_1D
   2 P1V8_CPU0_RT1_1A_1D      B @T6G_MB_LIB.T6G(SCH_1):P1V8_CPU0_RT1_1A_1D

Q_CAP_0201-1UF,4V,20%,X6S,CH-10KMEE00  I90  C621
   1 P0V9_CPU0_RT1_2A_2D      A @T6G_MB_LIB.T6G(SCH_1):P0V9_CPU0_RT1_2A_2D
   2    GND      B @T6G_MB_LIB.T6G(SCH_1):GND

Q_CAP_0201-1UF,4V,20%,X6S,CH-10KMEE00  I91  C624
   1 P0V9_CPU0_RT1_2A_2D      A @T6G_MB_LIB.T6G(SCH_1):P0V9_CPU0_RT1_2A_2D
   2    GND      B @T6G_MB_LIB.T6G(SCH_1):GND

Q_CAP_C0201-0.1UF,10V,10%,X7S,CH4102K6E00  I92  C658
   1 P0V9_CPU0_RT1_2A      A @T6G_MB_LIB.T6G(SCH_1):P0V9_CPU0_RT1_2A
   2    GND      B @T6G_MB_LIB.T6G(SCH_1):GND

Q_CAP_C0201-0.1UF,10V,10%,X7S,CH4102K6E00  I93  C659
   1 P0V9_CPU0_RT1_2A      A @T6G_MB_LIB.T6G(SCH_1):P0V9_CPU0_RT1_2A
   2    GND      B @T6G_MB_LIB.T6G(SCH_1):GND

Q_CAP_0201-1UF,4V,20%,X6S,CH-10KMEE00  I94  C660
   1 P0V9_CPU0_RT1_2A      A @T6G_MB_LIB.T6G(SCH_1):P0V9_CPU0_RT1_2A
   2    GND      B @T6G_MB_LIB.T6G(SCH_1):GND

Q_CAPP_SMLF-470UF,2.5V,20%,SPCAP,CH747LM8818  I95  C7011
   1 P0V9_CPU0_RT1_2A      A @T6G_MB_LIB.T6G(SCH_1):P0V9_CPU0_RT1_2A
   2    GND      B @T6G_MB_LIB.T6G(SCH_1):GND

Q_CAPP_SMLF-470UF,2.5V,20%,SPCAP,CH747LM8818  I96  C7012
   1 P0V9_CPU0_RT1_2A      A @T6G_MB_LIB.T6G(SCH_1):P0V9_CPU0_RT1_2A
   2    GND      B @T6G_MB_LIB.T6G(SCH_1):GND

Q_CAP_C0805-100UF,4V,20%,X6S,CH710KMEA01  I97  C7013
   1 P0V9_CPU0_RT1_2A      A @T6G_MB_LIB.T6G(SCH_1):P0V9_CPU0_RT1_2A
   2    GND      B @T6G_MB_LIB.T6G(SCH_1):GND


DRAWING: @T6G_MB_LIB.T6G(SCH_1):PAGE420 

PT5161LRS-PT5161LRS,SMLF,IC,AJ051610U03  I6  U6012
  G1 RT_CPU0_P2_VQPS   VQPS @T6G_MB_LIB.T6G(SCH_1):RT_CPU0_P2_VQPS
BV20 P1V8_CPU0_RT2_1A PWR_1A_1 @T6G_MB_LIB.T6G(SCH_1):P1V8_CPU0_RT2_1A
CE17 P1V8_CPU0_RT2_1A PWR_1A_2 @T6G_MB_LIB.T6G(SCH_1):P1V8_CPU0_RT2_1A
CE20 P1V8_CPU0_RT2_1A PWR_1A_3 @T6G_MB_LIB.T6G(SCH_1):P1V8_CPU0_RT2_1A
CM17 P1V8_CPU0_RT2_1A PWR_1A_4 @T6G_MB_LIB.T6G(SCH_1):P1V8_CPU0_RT2_1A
CM20 P1V8_CPU0_RT2_1A PWR_1A_5 @T6G_MB_LIB.T6G(SCH_1):P1V8_CPU0_RT2_1A
BL17 P0V9_CPU0_RT_2D PWR_2D_1 @T6G_MB_LIB.T6G(SCH_1):P0V9_CPU0_RT_2D
BL20 P0V9_CPU0_RT_2D PWR_2D_2 @T6G_MB_LIB.T6G(SCH_1):P0V9_CPU0_RT_2D
CW17 P0V9_CPU0_RT_2D PWR_2D_3 @T6G_MB_LIB.T6G(SCH_1):P0V9_CPU0_RT_2D
CW20 P0V9_CPU0_RT_2D PWR_2D_4 @T6G_MB_LIB.T6G(SCH_1):P0V9_CPU0_RT_2D
BV17 P1V8_CPU0_RT2_1A_1D PWR_1D @T6G_MB_LIB.T6G(SCH_1):P1V8_CPU0_RT2_1A_1D
AC17 P0V9_CPU0_RT2_2A PWR_2A_1 @T6G_MB_LIB.T6G(SCH_1):P0V9_CPU0_RT2_2A
AC20 P0V9_CPU0_RT2_2A PWR_2A_2 @T6G_MB_LIB.T6G(SCH_1):P0V9_CPU0_RT2_2A
AK17 P0V9_CPU0_RT2_2A PWR_2A_3 @T6G_MB_LIB.T6G(SCH_1):P0V9_CPU0_RT2_2A
AK20 P0V9_CPU0_RT2_2A PWR_2A_4 @T6G_MB_LIB.T6G(SCH_1):P0V9_CPU0_RT2_2A
AU17 P0V9_CPU0_RT2_2A PWR_2A_5 @T6G_MB_LIB.T6G(SCH_1):P0V9_CPU0_RT2_2A
AU20 P0V9_CPU0_RT2_2A PWR_2A_6 @T6G_MB_LIB.T6G(SCH_1):P0V9_CPU0_RT2_2A
BD17 P0V9_CPU0_RT2_2A_2D PWR_2A_7 @T6G_MB_LIB.T6G(SCH_1):P0V9_CPU0_RT2_2A_2D
BD20 P0V9_CPU0_RT2_2A_2D PWR_2A_8 @T6G_MB_LIB.T6G(SCH_1):P0V9_CPU0_RT2_2A_2D
DF17 P0V9_CPU0_RT2_2A_2D PWR_2A_9 @T6G_MB_LIB.T6G(SCH_1):P0V9_CPU0_RT2_2A_2D
DF20 P0V9_CPU0_RT2_2A_2D PWR_2A_10 @T6G_MB_LIB.T6G(SCH_1):P0V9_CPU0_RT2_2A_2D
DN17 P0V9_CPU0_RT2_2A PWR_2A_11 @T6G_MB_LIB.T6G(SCH_1):P0V9_CPU0_RT2_2A
DN20 P0V9_CPU0_RT2_2A PWR_2A_12 @T6G_MB_LIB.T6G(SCH_1):P0V9_CPU0_RT2_2A
DY17 P0V9_CPU0_RT2_2A PWR_2A_13 @T6G_MB_LIB.T6G(SCH_1):P0V9_CPU0_RT2_2A
DY20 P0V9_CPU0_RT2_2A PWR_2A_14 @T6G_MB_LIB.T6G(SCH_1):P0V9_CPU0_RT2_2A
EG17 P0V9_CPU0_RT2_2A PWR_2A_15 @T6G_MB_LIB.T6G(SCH_1):P0V9_CPU0_RT2_2A
EG20 P0V9_CPU0_RT2_2A PWR_2A_16 @T6G_MB_LIB.T6G(SCH_1):P0V9_CPU0_RT2_2A
EP17 P0V9_CPU0_RT2_2A PWR_2A_17 @T6G_MB_LIB.T6G(SCH_1):P0V9_CPU0_RT2_2A
EP20 P0V9_CPU0_RT2_2A PWR_2A_18 @T6G_MB_LIB.T6G(SCH_1):P0V9_CPU0_RT2_2A
 T17 P0V9_CPU0_RT2_2A PWR_2A_19 @T6G_MB_LIB.T6G(SCH_1):P0V9_CPU0_RT2_2A
 T20 P0V9_CPU0_RT2_2A PWR_2A_20 @T6G_MB_LIB.T6G(SCH_1):P0V9_CPU0_RT2_2A

Q_RES_0201LF-0,5%,1/20W,CHIP,CS00001JE10  I13  R1083
   1 NCF_CPU0_P2_GND      A @T6G_MB_LIB.T6G(SCH_1):NCF_CPU0_P2_GND
   2    GND      B @T6G_MB_LIB.T6G(SCH_1):GND

Q_RES_0201LF-0,5%,1/20W,CHIP,CS00001JE10  I14  R1084
   1 NCF_A1_CPU0_P2_GND      A @T6G_MB_LIB.T6G(SCH_1):NCF_A1_CPU0_P2_GND
   2    GND      B @T6G_MB_LIB.T6G(SCH_1):GND

PT5161LRS-PT5161LRS,SMLF,IC,AJ051610U03  I17  U6012
AC13    GND   GND1 @T6G_MB_LIB.T6G(SCH_1):GND
AC22    GND   GND2 @T6G_MB_LIB.T6G(SCH_1):GND
AC32    GND   GND3 @T6G_MB_LIB.T6G(SCH_1):GND
 AC4    GND   GND4 @T6G_MB_LIB.T6G(SCH_1):GND
 AD2    GND   GND5 @T6G_MB_LIB.T6G(SCH_1):GND
AD34    GND   GND6 @T6G_MB_LIB.T6G(SCH_1):GND
 AE1    GND   GND7 @T6G_MB_LIB.T6G(SCH_1):GND
AE35    GND   GND8 @T6G_MB_LIB.T6G(SCH_1):GND
AK13    GND   GND9 @T6G_MB_LIB.T6G(SCH_1):GND
AK22    GND  GND10 @T6G_MB_LIB.T6G(SCH_1):GND
AK32    GND  GND11 @T6G_MB_LIB.T6G(SCH_1):GND
 AK4    GND  GND12 @T6G_MB_LIB.T6G(SCH_1):GND
 AL2    GND  GND13 @T6G_MB_LIB.T6G(SCH_1):GND
AL34    GND  GND14 @T6G_MB_LIB.T6G(SCH_1):GND
 AM1    GND  GND15 @T6G_MB_LIB.T6G(SCH_1):GND
AM35    GND  GND16 @T6G_MB_LIB.T6G(SCH_1):GND
AU13    GND  GND17 @T6G_MB_LIB.T6G(SCH_1):GND
AU22    GND  GND18 @T6G_MB_LIB.T6G(SCH_1):GND
AU32    GND  GND19 @T6G_MB_LIB.T6G(SCH_1):GND
 AU4    GND  GND20 @T6G_MB_LIB.T6G(SCH_1):GND
 AV2    GND  GND21 @T6G_MB_LIB.T6G(SCH_1):GND
AV34    GND  GND22 @T6G_MB_LIB.T6G(SCH_1):GND
 AW1    GND  GND23 @T6G_MB_LIB.T6G(SCH_1):GND
AW35    GND  GND24 @T6G_MB_LIB.T6G(SCH_1):GND
 B19    GND  GND25 @T6G_MB_LIB.T6G(SCH_1):GND
BD13    GND  GND26 @T6G_MB_LIB.T6G(SCH_1):GND
BD22    GND  GND27 @T6G_MB_LIB.T6G(SCH_1):GND
BD32    GND  GND28 @T6G_MB_LIB.T6G(SCH_1):GND
 BD4    GND  GND29 @T6G_MB_LIB.T6G(SCH_1):GND
 BE2    GND  GND30 @T6G_MB_LIB.T6G(SCH_1):GND
BE34    GND  GND31 @T6G_MB_LIB.T6G(SCH_1):GND
 BF1    GND  GND32 @T6G_MB_LIB.T6G(SCH_1):GND
BF35    GND  GND33 @T6G_MB_LIB.T6G(SCH_1):GND
BL13    GND  GND34 @T6G_MB_LIB.T6G(SCH_1):GND
BL22    GND  GND35 @T6G_MB_LIB.T6G(SCH_1):GND
BL32    GND  GND36 @T6G_MB_LIB.T6G(SCH_1):GND
 BL4    GND  GND37 @T6G_MB_LIB.T6G(SCH_1):GND
 BM2    GND  GND38 @T6G_MB_LIB.T6G(SCH_1):GND
BM34    GND  GND39 @T6G_MB_LIB.T6G(SCH_1):GND
 BN1    GND  GND40 @T6G_MB_LIB.T6G(SCH_1):GND
BN35    GND  GND41 @T6G_MB_LIB.T6G(SCH_1):GND
BV13    GND  GND42 @T6G_MB_LIB.T6G(SCH_1):GND
BV22    GND  GND43 @T6G_MB_LIB.T6G(SCH_1):GND
BV32    GND  GND44 @T6G_MB_LIB.T6G(SCH_1):GND
 BV4    GND  GND45 @T6G_MB_LIB.T6G(SCH_1):GND
 BW2    GND  GND46 @T6G_MB_LIB.T6G(SCH_1):GND
BW34    GND  GND47 @T6G_MB_LIB.T6G(SCH_1):GND
 BY1    GND  GND48 @T6G_MB_LIB.T6G(SCH_1):GND
BY35    GND  GND49 @T6G_MB_LIB.T6G(SCH_1):GND
CE13    GND  GND50 @T6G_MB_LIB.T6G(SCH_1):GND
CE22    GND  GND51 @T6G_MB_LIB.T6G(SCH_1):GND
CE32    GND  GND52 @T6G_MB_LIB.T6G(SCH_1):GND
 CE4    GND  GND53 @T6G_MB_LIB.T6G(SCH_1):GND
 CF2    GND  GND54 @T6G_MB_LIB.T6G(SCH_1):GND
CF34    GND  GND55 @T6G_MB_LIB.T6G(SCH_1):GND
 CG1    GND  GND56 @T6G_MB_LIB.T6G(SCH_1):GND
CG35    GND  GND57 @T6G_MB_LIB.T6G(SCH_1):GND
CM13    GND  GND58 @T6G_MB_LIB.T6G(SCH_1):GND
CM22    GND  GND59 @T6G_MB_LIB.T6G(SCH_1):GND
CM32    GND  GND60 @T6G_MB_LIB.T6G(SCH_1):GND
 CM4    GND  GND61 @T6G_MB_LIB.T6G(SCH_1):GND
 CN2    GND  GND62 @T6G_MB_LIB.T6G(SCH_1):GND
CN34    GND  GND63 @T6G_MB_LIB.T6G(SCH_1):GND
 CP1    GND  GND64 @T6G_MB_LIB.T6G(SCH_1):GND
CP35    GND  GND65 @T6G_MB_LIB.T6G(SCH_1):GND
CW13    GND  GND66 @T6G_MB_LIB.T6G(SCH_1):GND
CW22    GND  GND67 @T6G_MB_LIB.T6G(SCH_1):GND
CW32    GND  GND68 @T6G_MB_LIB.T6G(SCH_1):GND
 CW4    GND  GND69 @T6G_MB_LIB.T6G(SCH_1):GND
 CY2    GND  GND70 @T6G_MB_LIB.T6G(SCH_1):GND
CY34    GND  GND71 @T6G_MB_LIB.T6G(SCH_1):GND
 DA1    GND  GND72 @T6G_MB_LIB.T6G(SCH_1):GND
DA35    GND  GND73 @T6G_MB_LIB.T6G(SCH_1):GND
DF13    GND  GND74 @T6G_MB_LIB.T6G(SCH_1):GND
DF22    GND  GND75 @T6G_MB_LIB.T6G(SCH_1):GND
DF32    GND  GND76 @T6G_MB_LIB.T6G(SCH_1):GND
 DF4    GND  GND77 @T6G_MB_LIB.T6G(SCH_1):GND
 DG2    GND  GND78 @T6G_MB_LIB.T6G(SCH_1):GND
DG34    GND  GND79 @T6G_MB_LIB.T6G(SCH_1):GND
 DH1    GND  GND80 @T6G_MB_LIB.T6G(SCH_1):GND
DH35    GND  GND81 @T6G_MB_LIB.T6G(SCH_1):GND
DN13    GND  GND82 @T6G_MB_LIB.T6G(SCH_1):GND
  A1 NCF_A1_CPU0_P2_GND NCF_GND1 @T6G_MB_LIB.T6G(SCH_1):NCF_A1_CPU0_P2_GND
 A35 NCF_CPU0_P2_GND NCF_GND2 @T6G_MB_LIB.T6G(SCH_1):NCF_CPU0_P2_GND
  C2 NCF_CPU0_P2_GND NCF_GND3 @T6G_MB_LIB.T6G(SCH_1):NCF_CPU0_P2_GND
 C34 NCF_CPU0_P2_GND NCF_GND4 @T6G_MB_LIB.T6G(SCH_1):NCF_CPU0_P2_GND
  D1 NCF_CPU0_P2_GND NCF_GND5 @T6G_MB_LIB.T6G(SCH_1):NCF_CPU0_P2_GND
 D35 NCF_CPU0_P2_GND NCF_GND6 @T6G_MB_LIB.T6G(SCH_1):NCF_CPU0_P2_GND
 FE2 NCF_CPU0_P2_GND NCF_GND7 @T6G_MB_LIB.T6G(SCH_1):NCF_CPU0_P2_GND
FE34 NCF_CPU0_P2_GND NCF_GND8 @T6G_MB_LIB.T6G(SCH_1):NCF_CPU0_P2_GND
 FG1 NCF_CPU0_P2_GND NCF_GND9 @T6G_MB_LIB.T6G(SCH_1):NCF_CPU0_P2_GND
FG35 NCF_CPU0_P2_GND NCF_GND10 @T6G_MB_LIB.T6G(SCH_1):NCF_CPU0_P2_GND
 FH2 NCF_CPU0_P2_GND NCF_GND11 @T6G_MB_LIB.T6G(SCH_1):NCF_CPU0_P2_GND
FH34 NCF_CPU0_P2_GND NCF_GND12 @T6G_MB_LIB.T6G(SCH_1):NCF_CPU0_P2_GND
DN22    GND  GND83 @T6G_MB_LIB.T6G(SCH_1):GND
DN32    GND  GND84 @T6G_MB_LIB.T6G(SCH_1):GND
 DN4    GND  GND85 @T6G_MB_LIB.T6G(SCH_1):GND
 DP2    GND  GND86 @T6G_MB_LIB.T6G(SCH_1):GND
DP34    GND  GND87 @T6G_MB_LIB.T6G(SCH_1):GND
 DR1    GND  GND88 @T6G_MB_LIB.T6G(SCH_1):GND
DR35    GND  GND89 @T6G_MB_LIB.T6G(SCH_1):GND
DY13    GND  GND90 @T6G_MB_LIB.T6G(SCH_1):GND
DY22    GND  GND91 @T6G_MB_LIB.T6G(SCH_1):GND
DY32    GND  GND92 @T6G_MB_LIB.T6G(SCH_1):GND
 DY4    GND  GND93 @T6G_MB_LIB.T6G(SCH_1):GND
 E14    GND  GND94 @T6G_MB_LIB.T6G(SCH_1):GND
 E27    GND  GND95 @T6G_MB_LIB.T6G(SCH_1):GND
 E33    GND  GND96 @T6G_MB_LIB.T6G(SCH_1):GND
 EA2    GND  GND97 @T6G_MB_LIB.T6G(SCH_1):GND
EA34    GND  GND98 @T6G_MB_LIB.T6G(SCH_1):GND
 EB1    GND  GND99 @T6G_MB_LIB.T6G(SCH_1):GND
EB35    GND GND100 @T6G_MB_LIB.T6G(SCH_1):GND
EG13    GND GND101 @T6G_MB_LIB.T6G(SCH_1):GND
EG22    GND GND102 @T6G_MB_LIB.T6G(SCH_1):GND
EG32    GND GND103 @T6G_MB_LIB.T6G(SCH_1):GND
 EG4    GND GND104 @T6G_MB_LIB.T6G(SCH_1):GND
 EH2    GND GND105 @T6G_MB_LIB.T6G(SCH_1):GND
EH34    GND GND106 @T6G_MB_LIB.T6G(SCH_1):GND
 EJ1    GND GND107 @T6G_MB_LIB.T6G(SCH_1):GND
EJ35    GND GND108 @T6G_MB_LIB.T6G(SCH_1):GND
EP13    GND GND109 @T6G_MB_LIB.T6G(SCH_1):GND
EP22    GND GND110 @T6G_MB_LIB.T6G(SCH_1):GND
EP32    GND GND111 @T6G_MB_LIB.T6G(SCH_1):GND
 EP4    GND GND112 @T6G_MB_LIB.T6G(SCH_1):GND
 ER2    GND GND113 @T6G_MB_LIB.T6G(SCH_1):GND
ER34    GND GND114 @T6G_MB_LIB.T6G(SCH_1):GND
 ET1    GND GND115 @T6G_MB_LIB.T6G(SCH_1):GND
ET35    GND GND116 @T6G_MB_LIB.T6G(SCH_1):GND
FA15    GND GND117 @T6G_MB_LIB.T6G(SCH_1):GND
FA32    GND GND118 @T6G_MB_LIB.T6G(SCH_1):GND
 FB2    GND GND119 @T6G_MB_LIB.T6G(SCH_1):GND
FB34    GND GND120 @T6G_MB_LIB.T6G(SCH_1):GND
FC19    GND GND121 @T6G_MB_LIB.T6G(SCH_1):GND
FC23    GND GND122 @T6G_MB_LIB.T6G(SCH_1):GND
FC25    GND GND123 @T6G_MB_LIB.T6G(SCH_1):GND
FC28    GND GND124 @T6G_MB_LIB.T6G(SCH_1):GND
 FC3    GND GND125 @T6G_MB_LIB.T6G(SCH_1):GND
 FC6    GND GND126 @T6G_MB_LIB.T6G(SCH_1):GND
 FC9    GND GND127 @T6G_MB_LIB.T6G(SCH_1):GND
 FD1    GND GND128 @T6G_MB_LIB.T6G(SCH_1):GND
FD35    GND GND129 @T6G_MB_LIB.T6G(SCH_1):GND
FF14    GND GND130 @T6G_MB_LIB.T6G(SCH_1):GND
FF21    GND GND131 @T6G_MB_LIB.T6G(SCH_1):GND
FJ12    GND GND132 @T6G_MB_LIB.T6G(SCH_1):GND
FJ19    GND GND133 @T6G_MB_LIB.T6G(SCH_1):GND
 H12    GND GND134 @T6G_MB_LIB.T6G(SCH_1):GND
 H16    GND GND135 @T6G_MB_LIB.T6G(SCH_1):GND
 H19    GND GND136 @T6G_MB_LIB.T6G(SCH_1):GND
 H31    GND GND137 @T6G_MB_LIB.T6G(SCH_1):GND
 J22    GND GND138 @T6G_MB_LIB.T6G(SCH_1):GND
  J4    GND GND139 @T6G_MB_LIB.T6G(SCH_1):GND
  K2    GND GND140 @T6G_MB_LIB.T6G(SCH_1):GND
 K34    GND GND141 @T6G_MB_LIB.T6G(SCH_1):GND
  L1    GND GND142 @T6G_MB_LIB.T6G(SCH_1):GND
 L35    GND GND143 @T6G_MB_LIB.T6G(SCH_1):GND
 T13    GND GND144 @T6G_MB_LIB.T6G(SCH_1):GND
 T22    GND GND145 @T6G_MB_LIB.T6G(SCH_1):GND
 T32    GND GND146 @T6G_MB_LIB.T6G(SCH_1):GND
  T4    GND GND147 @T6G_MB_LIB.T6G(SCH_1):GND
  U2    GND GND148 @T6G_MB_LIB.T6G(SCH_1):GND
 U34    GND GND149 @T6G_MB_LIB.T6G(SCH_1):GND
  V1    GND GND150 @T6G_MB_LIB.T6G(SCH_1):GND
 V35    GND GND151 @T6G_MB_LIB.T6G(SCH_1):GND

Q_RES_0201LF-200,1%,1/20W,CHIP,CS12001FE12  I18  R1082
   1 RT_CPU0_P2_VQPS      A @T6G_MB_LIB.T6G(SCH_1):RT_CPU0_P2_VQPS
   2    GND      B @T6G_MB_LIB.T6G(SCH_1):GND

Q_RES_0201LF-1K,1%,1/20W,EMPTY,CS21001FE07  I19  R1081
   1 P1V8_CPU0_RT_1D      A @T6G_MB_LIB.T6G(SCH_1):P1V8_CPU0_RT_1D
   2 RT_CPU0_P2_VQPS      B @T6G_MB_LIB.T6G(SCH_1):RT_CPU0_P2_VQPS


DRAWING: @T6G_MB_LIB.T6G(SCH_1):PAGE422 

Q_RES_0402LF-0,5%,1/16W,EMPTY,CS00002JB13  I4  R1046
   1 P1V8_CPU0_RT2_1A_1D      A @T6G_MB_LIB.T6G(SCH_1):P1V8_CPU0_RT2_1A_1D
   2 P1V8_CPU0_RT2_1A      B @T6G_MB_LIB.T6G(SCH_1):P1V8_CPU0_RT2_1A

Q_RES_0402LF-0,5%,1/16W,EMPTY,CS00002JB13  I5  R1045
   1 P1V8_CPU0_RT2_1A_1D      A @T6G_MB_LIB.T6G(SCH_1):P1V8_CPU0_RT2_1A_1D
   2 P1V8_CPU0_RT2_1A      B @T6G_MB_LIB.T6G(SCH_1):P1V8_CPU0_RT2_1A

Q_CAP_C0805-100UF,4V,20%,X6S,CH710KMEA01  I6  C666
   1 P1V8_CPU0_RT2_1A      A @T6G_MB_LIB.T6G(SCH_1):P1V8_CPU0_RT2_1A
   2    GND      B @T6G_MB_LIB.T6G(SCH_1):GND

Q_CAP_C0402-22UF,4V,20%,X6S,CH622KMEB02  I7  C668
   1 P1V8_CPU0_RT2_1A      A @T6G_MB_LIB.T6G(SCH_1):P1V8_CPU0_RT2_1A
   2    GND      B @T6G_MB_LIB.T6G(SCH_1):GND

Q_CAP_0201-1UF,4V,20%,X6S,CH-10KMEE00  I9  C676
   1 P1V8_CPU0_RT2_1A_1D      A @T6G_MB_LIB.T6G(SCH_1):P1V8_CPU0_RT2_1A_1D
   2    GND      B @T6G_MB_LIB.T6G(SCH_1):GND

Q_CAP_C0201-0.1UF,10V,10%,X7S,CH4102K6E00  I10  C775
   1 P1V8_CPU0_RT2_1A_1D      A @T6G_MB_LIB.T6G(SCH_1):P1V8_CPU0_RT2_1A_1D
   2    GND      B @T6G_MB_LIB.T6G(SCH_1):GND

Q_CAP_C0402-10UF,6.3V,20%,X6S,CH6101MEB01  I12  C671
   1 P1V8_CPU0_RT2_1A      A @T6G_MB_LIB.T6G(SCH_1):P1V8_CPU0_RT2_1A
   2    GND      B @T6G_MB_LIB.T6G(SCH_1):GND

Q_CAP_0402-4.7UF,6.3V,20%,X6S,CH5471MEB01  I13  C670
   1 P1V8_CPU0_RT2_1A      A @T6G_MB_LIB.T6G(SCH_1):P1V8_CPU0_RT2_1A
   2    GND      B @T6G_MB_LIB.T6G(SCH_1):GND

Q_CAP_0201-1UF,4V,20%,X6S,CH-10KMEE00  I15  C673
   1 P1V8_CPU0_RT2_1A      A @T6G_MB_LIB.T6G(SCH_1):P1V8_CPU0_RT2_1A
   2    GND      B @T6G_MB_LIB.T6G(SCH_1):GND

Q_CAP_0201-1UF,4V,20%,X6S,CH-10KMEE00  I16  C677
   1 P1V8_CPU0_RT2_1A      A @T6G_MB_LIB.T6G(SCH_1):P1V8_CPU0_RT2_1A
   2    GND      B @T6G_MB_LIB.T6G(SCH_1):GND

Q_CAP_C0201-0.1UF,10V,10%,X7S,CH4102K6E00  I17  C774
   1 P1V8_CPU0_RT2_1A      A @T6G_MB_LIB.T6G(SCH_1):P1V8_CPU0_RT2_1A
   2    GND      B @T6G_MB_LIB.T6G(SCH_1):GND

Q_CAP_C0201-0.1UF,10V,10%,X7S,CH4102K6E00  I18  C776
   1 P1V8_CPU0_RT2_1A      A @T6G_MB_LIB.T6G(SCH_1):P1V8_CPU0_RT2_1A
   2    GND      B @T6G_MB_LIB.T6G(SCH_1):GND

Q_CAP_C0201-0.1UF,10V,10%,X7S,CH4102K6E00  I19  C777
   1 P1V8_CPU0_RT2_1A      A @T6G_MB_LIB.T6G(SCH_1):P1V8_CPU0_RT2_1A
   2    GND      B @T6G_MB_LIB.T6G(SCH_1):GND

Q_CAP_C0201-0.1UF,10V,10%,X7S,CH4102K6E00  I20  C778
   1 P1V8_CPU0_RT2_1A      A @T6G_MB_LIB.T6G(SCH_1):P1V8_CPU0_RT2_1A
   2    GND      B @T6G_MB_LIB.T6G(SCH_1):GND

Q_RES_0603LF-0,5%,1/4W,EMPTY,CS00006J900  I21  R1051
   1 P0V9_CPU0_RT_2D      A @T6G_MB_LIB.T6G(SCH_1):P0V9_CPU0_RT_2D
   2 P0V9_CPU0_RT2_2A_2D      B @T6G_MB_LIB.T6G(SCH_1):P0V9_CPU0_RT2_2A_2D

Q_RES_0603LF-0,5%,1/4W,CHIP,CS00006J900  I22  R1053
   1 P0V9_CPU0_RT2_2A_2D      A @T6G_MB_LIB.T6G(SCH_1):P0V9_CPU0_RT2_2A_2D
   2 P0V9_CPU0_RT2_2A      B @T6G_MB_LIB.T6G(SCH_1):P0V9_CPU0_RT2_2A

Q_INDUCTOR_SMLF-BLM21SN300SN1D/5A,IND,CX300SN1000  I23  L18
   2 P1V8_CPU0_RT2_1A      2 @T6G_MB_LIB.T6G(SCH_1):P1V8_CPU0_RT2_1A
   1 P1V8_CPU0_RT_1D      1 @T6G_MB_LIB.T6G(SCH_1):P1V8_CPU0_RT_1D

Q_CAP_C0805-100UF,4V,20%,X6S,CH710KMEA01  I25  C665
   1 P1V8_CPU0_RT_1D      A @T6G_MB_LIB.T6G(SCH_1):P1V8_CPU0_RT_1D
   2    GND      B @T6G_MB_LIB.T6G(SCH_1):GND

Q_CAP_C0402-10UF,6.3V,20%,X6S,CH6101MEB01  I26  C669
   1 P1V8_CPU0_RT_1D      A @T6G_MB_LIB.T6G(SCH_1):P1V8_CPU0_RT_1D
   2    GND      B @T6G_MB_LIB.T6G(SCH_1):GND

Q_CAP_C0402-22UF,4V,20%,X6S,CH622KMEB02  I27  C667
   1 P1V8_CPU0_RT_1D      A @T6G_MB_LIB.T6G(SCH_1):P1V8_CPU0_RT_1D
   2    GND      B @T6G_MB_LIB.T6G(SCH_1):GND

Q_CAP_0402-4.7UF,6.3V,20%,X6S,CH5471MEB01  I29  C672
   1 P1V8_CPU0_RT_1D      A @T6G_MB_LIB.T6G(SCH_1):P1V8_CPU0_RT_1D
   2    GND      B @T6G_MB_LIB.T6G(SCH_1):GND

Q_INDUCTOR_SMLF-100NH/16A,IND,CV+10G0MZ04  I30  L21
   2 P0V9_CPU0_RT2_2A      2 @T6G_MB_LIB.T6G(SCH_1):P0V9_CPU0_RT2_2A
   1 P0V9_CPU0_RT_2D      1 @T6G_MB_LIB.T6G(SCH_1):P0V9_CPU0_RT_2D

Q_CAP_C0201-0.1UF,10V,10%,X7S,CH4102K6E00  I34  C982
   1 P0V9_CPU0_RT2_2A      A @T6G_MB_LIB.T6G(SCH_1):P0V9_CPU0_RT2_2A
   2    GND      B @T6G_MB_LIB.T6G(SCH_1):GND

Q_CAP_C0201-0.1UF,10V,10%,X7S,CH4102K6E00  I35  C984
   1 P0V9_CPU0_RT2_2A      A @T6G_MB_LIB.T6G(SCH_1):P0V9_CPU0_RT2_2A
   2    GND      B @T6G_MB_LIB.T6G(SCH_1):GND

Q_CAP_C0201-0.1UF,10V,10%,X7S,CH4102K6E00  I36  C791
   1 P0V9_CPU0_RT2_2A_2D      A @T6G_MB_LIB.T6G(SCH_1):P0V9_CPU0_RT2_2A_2D
   2    GND      B @T6G_MB_LIB.T6G(SCH_1):GND

Q_CAP_C0201-0.1UF,10V,10%,X7S,CH4102K6E00  I39  C794
   1 P0V9_CPU0_RT2_2A_2D      A @T6G_MB_LIB.T6G(SCH_1):P0V9_CPU0_RT2_2A_2D
   2    GND      B @T6G_MB_LIB.T6G(SCH_1):GND

Q_CAP_C0201-0.1UF,10V,10%,X7S,CH4102K6E00  I40  C790
   1 P0V9_CPU0_RT2_2A      A @T6G_MB_LIB.T6G(SCH_1):P0V9_CPU0_RT2_2A
   2    GND      B @T6G_MB_LIB.T6G(SCH_1):GND

Q_CAP_C0201-0.1UF,10V,10%,X7S,CH4102K6E00  I41  C987
   1 P0V9_CPU0_RT2_2A      A @T6G_MB_LIB.T6G(SCH_1):P0V9_CPU0_RT2_2A
   2    GND      B @T6G_MB_LIB.T6G(SCH_1):GND

Q_CAP_C0201-0.1UF,10V,10%,X7S,CH4102K6E00  I42  C800
   1 P0V9_CPU0_RT2_2A      A @T6G_MB_LIB.T6G(SCH_1):P0V9_CPU0_RT2_2A
   2    GND      B @T6G_MB_LIB.T6G(SCH_1):GND

Q_CAP_C0201-0.1UF,10V,10%,X7S,CH4102K6E00  I43  C784
   1 P0V9_CPU0_RT2_2A      A @T6G_MB_LIB.T6G(SCH_1):P0V9_CPU0_RT2_2A
   2    GND      B @T6G_MB_LIB.T6G(SCH_1):GND

Q_CAP_0201-1UF,4V,20%,X6S,CH-10KMEE00  I44  C797
   1 P0V9_CPU0_RT2_2A      A @T6G_MB_LIB.T6G(SCH_1):P0V9_CPU0_RT2_2A
   2    GND      B @T6G_MB_LIB.T6G(SCH_1):GND

Q_CAP_0201-1UF,4V,20%,X6S,CH-10KMEE00  I45  C781
   1 P0V9_CPU0_RT2_2A      A @T6G_MB_LIB.T6G(SCH_1):P0V9_CPU0_RT2_2A
   2    GND      B @T6G_MB_LIB.T6G(SCH_1):GND

Q_CAP_0201-1UF,4V,20%,X6S,CH-10KMEE00  I46  C788
   1 P0V9_CPU0_RT2_2A      A @T6G_MB_LIB.T6G(SCH_1):P0V9_CPU0_RT2_2A
   2    GND      B @T6G_MB_LIB.T6G(SCH_1):GND

Q_CAP_C0402-10UF,6.3V,20%,X6S,CH6101MEB01  I47  C796
   1 P0V9_CPU0_RT2_2A      A @T6G_MB_LIB.T6G(SCH_1):P0V9_CPU0_RT2_2A
   2    GND      B @T6G_MB_LIB.T6G(SCH_1):GND

Q_CAP_C0805-100UF,4V,20%,X6S,CH710KMEA01  I48  C795
   1 P0V9_CPU0_RT2_2A      A @T6G_MB_LIB.T6G(SCH_1):P0V9_CPU0_RT2_2A
   2    GND      B @T6G_MB_LIB.T6G(SCH_1):GND

Q_CAP_0402-4.7UF,6.3V,20%,X6S,CH5471MEB01  I49  C981
   1 P0V9_CPU0_RT2_2A      A @T6G_MB_LIB.T6G(SCH_1):P0V9_CPU0_RT2_2A
   2    GND      B @T6G_MB_LIB.T6G(SCH_1):GND

Q_CAP_C0805-100UF,4V,20%,X6S,CH710KMEA01  I50  C798
   1 P0V9_CPU0_RT2_2A      A @T6G_MB_LIB.T6G(SCH_1):P0V9_CPU0_RT2_2A
   2    GND      B @T6G_MB_LIB.T6G(SCH_1):GND

Q_CAP_C0805-100UF,4V,20%,X6S,CH710KMEA01  I51  C802
   1 P0V9_CPU0_RT2_2A      A @T6G_MB_LIB.T6G(SCH_1):P0V9_CPU0_RT2_2A
   2    GND      B @T6G_MB_LIB.T6G(SCH_1):GND

Q_CAP_0201-1UF,4V,20%,X6S,CH-10KMEE00  I52  C792
   1 P0V9_CPU0_RT2_2A      A @T6G_MB_LIB.T6G(SCH_1):P0V9_CPU0_RT2_2A
   2    GND      B @T6G_MB_LIB.T6G(SCH_1):GND

Q_CAP_0201-1UF,4V,20%,X6S,CH-10KMEE00  I54  C975
   1 P0V9_CPU0_RT2_2A      A @T6G_MB_LIB.T6G(SCH_1):P0V9_CPU0_RT2_2A
   2    GND      B @T6G_MB_LIB.T6G(SCH_1):GND

Q_CAP_0201-1UF,4V,20%,X6S,CH-10KMEE00  I55  C979
   1 P0V9_CPU0_RT2_2A      A @T6G_MB_LIB.T6G(SCH_1):P0V9_CPU0_RT2_2A
   2    GND      B @T6G_MB_LIB.T6G(SCH_1):GND

Q_CAP_0402-4.7UF,6.3V,20%,X6S,CH5471MEB01  I56  C967
   1 P0V9_CPU0_RT2_2A      A @T6G_MB_LIB.T6G(SCH_1):P0V9_CPU0_RT2_2A
   2    GND      B @T6G_MB_LIB.T6G(SCH_1):GND

Q_CAP_0402-4.7UF,6.3V,20%,X6S,CH5471MEB01  I57  C970
   1 P0V9_CPU0_RT2_2A      A @T6G_MB_LIB.T6G(SCH_1):P0V9_CPU0_RT2_2A
   2    GND      B @T6G_MB_LIB.T6G(SCH_1):GND

Q_CAP_C0805-100UF,4V,20%,X6S,CH710KMEA01  I58  C966
   1 P0V9_CPU0_RT2_2A      A @T6G_MB_LIB.T6G(SCH_1):P0V9_CPU0_RT2_2A
   2    GND      B @T6G_MB_LIB.T6G(SCH_1):GND

Q_CAP_C0402-22UF,4V,20%,X6S,CH622KMEB02  I59  C969
   1 P0V9_CPU0_RT2_2A      A @T6G_MB_LIB.T6G(SCH_1):P0V9_CPU0_RT2_2A
   2    GND      B @T6G_MB_LIB.T6G(SCH_1):GND

Q_CAP_0402-4.7UF,6.3V,20%,X6S,CH5471MEB01  I60  C977
   1 P0V9_CPU0_RT2_2A      A @T6G_MB_LIB.T6G(SCH_1):P0V9_CPU0_RT2_2A
   2    GND      B @T6G_MB_LIB.T6G(SCH_1):GND

Q_CAP_0201-1UF,4V,20%,X6S,CH-10KMEE00  I61  C978
   1 P0V9_CPU0_RT2_2A      A @T6G_MB_LIB.T6G(SCH_1):P0V9_CPU0_RT2_2A
   2    GND      B @T6G_MB_LIB.T6G(SCH_1):GND

Q_CAP_0201-1UF,4V,20%,X6S,CH-10KMEE00  I62  C783
   1 P0V9_CPU0_RT2_2A      A @T6G_MB_LIB.T6G(SCH_1):P0V9_CPU0_RT2_2A
   2    GND      B @T6G_MB_LIB.T6G(SCH_1):GND

Q_CAP_C0402-22UF,4V,20%,X6S,CH622KMEB02  I63  C988
   1 P0V9_CPU0_RT2_2A      A @T6G_MB_LIB.T6G(SCH_1):P0V9_CPU0_RT2_2A
   2    GND      B @T6G_MB_LIB.T6G(SCH_1):GND

Q_CAP_C0402-22UF,4V,20%,X6S,CH622KMEB02  I64  C974
   1 P0V9_CPU0_RT2_2A      A @T6G_MB_LIB.T6G(SCH_1):P0V9_CPU0_RT2_2A
   2    GND      B @T6G_MB_LIB.T6G(SCH_1):GND

Q_CAP_C0402-22UF,4V,20%,X6S,CH622KMEB02  I65  C799
   1 P0V9_CPU0_RT2_2A      A @T6G_MB_LIB.T6G(SCH_1):P0V9_CPU0_RT2_2A
   2    GND      B @T6G_MB_LIB.T6G(SCH_1):GND

Q_CAP_0201-1UF,4V,20%,X6S,CH-10KMEE00  I66  C983
   1 P0V9_CPU0_RT2_2A      A @T6G_MB_LIB.T6G(SCH_1):P0V9_CPU0_RT2_2A
   2    GND      B @T6G_MB_LIB.T6G(SCH_1):GND

Q_CAP_C0201-0.1UF,10V,10%,X7S,CH4102K6E00  I68  C804
   1 P0V9_CPU0_RT2_2A      A @T6G_MB_LIB.T6G(SCH_1):P0V9_CPU0_RT2_2A
   2    GND      B @T6G_MB_LIB.T6G(SCH_1):GND

Q_CAP_C0201-0.1UF,10V,10%,X7S,CH4102K6E00  I69  C968
   1 P0V9_CPU0_RT2_2A      A @T6G_MB_LIB.T6G(SCH_1):P0V9_CPU0_RT2_2A
   2    GND      B @T6G_MB_LIB.T6G(SCH_1):GND

Q_CAP_0201-1UF,4V,20%,X6S,CH-10KMEE00  I72  C786
   1 P0V9_CPU0_RT2_2A      A @T6G_MB_LIB.T6G(SCH_1):P0V9_CPU0_RT2_2A
   2    GND      B @T6G_MB_LIB.T6G(SCH_1):GND

Q_CAP_0201-1UF,4V,20%,X6S,CH-10KMEE00  I73  C779
   1 P0V9_CPU0_RT2_2A      A @T6G_MB_LIB.T6G(SCH_1):P0V9_CPU0_RT2_2A
   2    GND      B @T6G_MB_LIB.T6G(SCH_1):GND

Q_CAP_C0402-10UF,6.3V,20%,X6S,CH6101MEB01  I74  C986
   1 P0V9_CPU0_RT2_2A      A @T6G_MB_LIB.T6G(SCH_1):P0V9_CPU0_RT2_2A
   2    GND      B @T6G_MB_LIB.T6G(SCH_1):GND

Q_CAP_C0402-10UF,6.3V,20%,X6S,CH6101MEB01  I75  C973
   1 P0V9_CPU0_RT2_2A      A @T6G_MB_LIB.T6G(SCH_1):P0V9_CPU0_RT2_2A
   2    GND      B @T6G_MB_LIB.T6G(SCH_1):GND

Q_CAP_C0805-100UF,4V,20%,X6S,CH710KMEA01  I77  C801
   1 P0V9_CPU0_RT_2D      A @T6G_MB_LIB.T6G(SCH_1):P0V9_CPU0_RT_2D
   2    GND      B @T6G_MB_LIB.T6G(SCH_1):GND

Q_CAP_C0402-22UF,4V,20%,X6S,CH622KMEB02  I78  C805
   1 P0V9_CPU0_RT_2D      A @T6G_MB_LIB.T6G(SCH_1):P0V9_CPU0_RT_2D
   2    GND      B @T6G_MB_LIB.T6G(SCH_1):GND

Q_CAP_C0402-10UF,6.3V,20%,X6S,CH6101MEB01  I79  C971
   1 P0V9_CPU0_RT_2D      A @T6G_MB_LIB.T6G(SCH_1):P0V9_CPU0_RT_2D
   2    GND      B @T6G_MB_LIB.T6G(SCH_1):GND

Q_CAP_0402-4.7UF,6.3V,20%,X6S,CH5471MEB01  I80  C976
   1 P0V9_CPU0_RT_2D      A @T6G_MB_LIB.T6G(SCH_1):P0V9_CPU0_RT_2D
   2    GND      B @T6G_MB_LIB.T6G(SCH_1):GND

Q_CAP_0201-1UF,4V,20%,X6S,CH-10KMEE00  I81  C980
   1 P0V9_CPU0_RT_2D      A @T6G_MB_LIB.T6G(SCH_1):P0V9_CPU0_RT_2D
   2    GND      B @T6G_MB_LIB.T6G(SCH_1):GND

Q_CAP_C0201-0.1UF,10V,10%,X7S,CH4102K6E00  I82  C780
   1 P0V9_CPU0_RT_2D      A @T6G_MB_LIB.T6G(SCH_1):P0V9_CPU0_RT_2D
   2    GND      B @T6G_MB_LIB.T6G(SCH_1):GND

Q_CAP_C0201-0.1UF,10V,10%,X7S,CH4102K6E00  I83  C782
   1 P0V9_CPU0_RT_2D      A @T6G_MB_LIB.T6G(SCH_1):P0V9_CPU0_RT_2D
   2    GND      B @T6G_MB_LIB.T6G(SCH_1):GND

Q_CAP_C0201-0.1UF,10V,10%,X7S,CH4102K6E00  I84  C785
   1 P0V9_CPU0_RT_2D      A @T6G_MB_LIB.T6G(SCH_1):P0V9_CPU0_RT_2D
   2    GND      B @T6G_MB_LIB.T6G(SCH_1):GND

Q_CAP_C0201-0.1UF,10V,10%,X7S,CH4102K6E00  I86  C789
   1 P0V9_CPU0_RT_2D      A @T6G_MB_LIB.T6G(SCH_1):P0V9_CPU0_RT_2D
   2    GND      B @T6G_MB_LIB.T6G(SCH_1):GND

Q_CAP_C0402-10UF,6.3V,20%,X6S,CH6101MEB01  I87  C803
   1 P0V9_CPU0_RT2_2A      A @T6G_MB_LIB.T6G(SCH_1):P0V9_CPU0_RT2_2A
   2    GND      B @T6G_MB_LIB.T6G(SCH_1):GND

Q_INDUCTOR_SMLF-BLM15PD121SN1D/1300MA,IND,CX5PD121A  I88  L29
   2 P1V8_CPU0_RT2_1A_1D      2 @T6G_MB_LIB.T6G(SCH_1):P1V8_CPU0_RT2_1A_1D
   1 P1V8_CPU0_RT_1D      1 @T6G_MB_LIB.T6G(SCH_1):P1V8_CPU0_RT_1D

Q_RES_0402LF-0,5%,1/16W,EMPTY,CS00002JB13  I89  R1050
   1 P1V8_CPU0_RT_1D      A @T6G_MB_LIB.T6G(SCH_1):P1V8_CPU0_RT_1D
   2 P1V8_CPU0_RT2_1A_1D      B @T6G_MB_LIB.T6G(SCH_1):P1V8_CPU0_RT2_1A_1D

Q_CAP_0201-1UF,4V,20%,X6S,CH-10KMEE00  I90  C787
   1 P0V9_CPU0_RT2_2A_2D      A @T6G_MB_LIB.T6G(SCH_1):P0V9_CPU0_RT2_2A_2D
   2    GND      B @T6G_MB_LIB.T6G(SCH_1):GND

Q_CAP_0201-1UF,4V,20%,X6S,CH-10KMEE00  I91  C793
   1 P0V9_CPU0_RT2_2A_2D      A @T6G_MB_LIB.T6G(SCH_1):P0V9_CPU0_RT2_2A_2D
   2    GND      B @T6G_MB_LIB.T6G(SCH_1):GND

Q_CAP_C0201-0.1UF,10V,10%,X7S,CH4102K6E00  I92  C972
   1 P0V9_CPU0_RT2_2A      A @T6G_MB_LIB.T6G(SCH_1):P0V9_CPU0_RT2_2A
   2    GND      B @T6G_MB_LIB.T6G(SCH_1):GND

Q_CAP_C0201-0.1UF,10V,10%,X7S,CH4102K6E00  I93  C985
   1 P0V9_CPU0_RT2_2A      A @T6G_MB_LIB.T6G(SCH_1):P0V9_CPU0_RT2_2A
   2    GND      B @T6G_MB_LIB.T6G(SCH_1):GND

Q_CAPP_SMLF-470UF,2.5V,20%,SPCAP,CH747LM8818  I94  C7014
   1 P0V9_CPU0_RT2_2A      A @T6G_MB_LIB.T6G(SCH_1):P0V9_CPU0_RT2_2A
   2    GND      B @T6G_MB_LIB.T6G(SCH_1):GND

Q_CAPP_SMLF-470UF,2.5V,20%,SPCAP,CH747LM8818  I95  C7015
   1 P0V9_CPU0_RT2_2A      A @T6G_MB_LIB.T6G(SCH_1):P0V9_CPU0_RT2_2A
   2    GND      B @T6G_MB_LIB.T6G(SCH_1):GND

Q_CAP_C0805-100UF,4V,20%,X6S,CH710KMEA01  I96  C7016
   1 P0V9_CPU0_RT2_2A      A @T6G_MB_LIB.T6G(SCH_1):P0V9_CPU0_RT2_2A
   2    GND      B @T6G_MB_LIB.T6G(SCH_1):GND


DRAWING: @T6G_MB_LIB.T6G(SCH_1):PAGE431 

PT5161LRS-PT5161LRS,SMLF,IC,AJ051610U03  I6  U6013
  G1 RT_CPU0_P3_VQPS   VQPS @T6G_MB_LIB.T6G(SCH_1):RT_CPU0_P3_VQPS
BV20 P1V8_CPU0_RT3_1A PWR_1A_1 @T6G_MB_LIB.T6G(SCH_1):P1V8_CPU0_RT3_1A
CE17 P1V8_CPU0_RT3_1A PWR_1A_2 @T6G_MB_LIB.T6G(SCH_1):P1V8_CPU0_RT3_1A
CE20 P1V8_CPU0_RT3_1A PWR_1A_3 @T6G_MB_LIB.T6G(SCH_1):P1V8_CPU0_RT3_1A
CM17 P1V8_CPU0_RT3_1A PWR_1A_4 @T6G_MB_LIB.T6G(SCH_1):P1V8_CPU0_RT3_1A
CM20 P1V8_CPU0_RT3_1A PWR_1A_5 @T6G_MB_LIB.T6G(SCH_1):P1V8_CPU0_RT3_1A
BL17 P0V9_CPU0_RT_2D PWR_2D_1 @T6G_MB_LIB.T6G(SCH_1):P0V9_CPU0_RT_2D
BL20 P0V9_CPU0_RT_2D PWR_2D_2 @T6G_MB_LIB.T6G(SCH_1):P0V9_CPU0_RT_2D
CW17 P0V9_CPU0_RT_2D PWR_2D_3 @T6G_MB_LIB.T6G(SCH_1):P0V9_CPU0_RT_2D
CW20 P0V9_CPU0_RT_2D PWR_2D_4 @T6G_MB_LIB.T6G(SCH_1):P0V9_CPU0_RT_2D
BV17 P1V8_CPU0_RT3_1A_1D PWR_1D @T6G_MB_LIB.T6G(SCH_1):P1V8_CPU0_RT3_1A_1D
AC17 P0V9_CPU0_RT3_2A PWR_2A_1 @T6G_MB_LIB.T6G(SCH_1):P0V9_CPU0_RT3_2A
AC20 P0V9_CPU0_RT3_2A PWR_2A_2 @T6G_MB_LIB.T6G(SCH_1):P0V9_CPU0_RT3_2A
AK17 P0V9_CPU0_RT3_2A PWR_2A_3 @T6G_MB_LIB.T6G(SCH_1):P0V9_CPU0_RT3_2A
AK20 P0V9_CPU0_RT3_2A PWR_2A_4 @T6G_MB_LIB.T6G(SCH_1):P0V9_CPU0_RT3_2A
AU17 P0V9_CPU0_RT3_2A PWR_2A_5 @T6G_MB_LIB.T6G(SCH_1):P0V9_CPU0_RT3_2A
AU20 P0V9_CPU0_RT3_2A PWR_2A_6 @T6G_MB_LIB.T6G(SCH_1):P0V9_CPU0_RT3_2A
BD17 P0V9_CPU0_RT3_2A_2D PWR_2A_7 @T6G_MB_LIB.T6G(SCH_1):P0V9_CPU0_RT3_2A_2D
BD20 P0V9_CPU0_RT3_2A_2D PWR_2A_8 @T6G_MB_LIB.T6G(SCH_1):P0V9_CPU0_RT3_2A_2D
DF17 P0V9_CPU0_RT3_2A_2D PWR_2A_9 @T6G_MB_LIB.T6G(SCH_1):P0V9_CPU0_RT3_2A_2D
DF20 P0V9_CPU0_RT3_2A_2D PWR_2A_10 @T6G_MB_LIB.T6G(SCH_1):P0V9_CPU0_RT3_2A_2D
DN17 P0V9_CPU0_RT3_2A PWR_2A_11 @T6G_MB_LIB.T6G(SCH_1):P0V9_CPU0_RT3_2A
DN20 P0V9_CPU0_RT3_2A PWR_2A_12 @T6G_MB_LIB.T6G(SCH_1):P0V9_CPU0_RT3_2A
DY17 P0V9_CPU0_RT3_2A PWR_2A_13 @T6G_MB_LIB.T6G(SCH_1):P0V9_CPU0_RT3_2A
DY20 P0V9_CPU0_RT3_2A PWR_2A_14 @T6G_MB_LIB.T6G(SCH_1):P0V9_CPU0_RT3_2A
EG17 P0V9_CPU0_RT3_2A PWR_2A_15 @T6G_MB_LIB.T6G(SCH_1):P0V9_CPU0_RT3_2A
EG20 P0V9_CPU0_RT3_2A PWR_2A_16 @T6G_MB_LIB.T6G(SCH_1):P0V9_CPU0_RT3_2A
EP17 P0V9_CPU0_RT3_2A PWR_2A_17 @T6G_MB_LIB.T6G(SCH_1):P0V9_CPU0_RT3_2A
EP20 P0V9_CPU0_RT3_2A PWR_2A_18 @T6G_MB_LIB.T6G(SCH_1):P0V9_CPU0_RT3_2A
 T17 P0V9_CPU0_RT3_2A PWR_2A_19 @T6G_MB_LIB.T6G(SCH_1):P0V9_CPU0_RT3_2A
 T20 P0V9_CPU0_RT3_2A PWR_2A_20 @T6G_MB_LIB.T6G(SCH_1):P0V9_CPU0_RT3_2A

Q_RES_0201LF-0,5%,1/20W,CHIP,CS00001JE10  I13  R1125
   1 NCF_CPU0_P3_GND      A @T6G_MB_LIB.T6G(SCH_1):NCF_CPU0_P3_GND
   2    GND      B @T6G_MB_LIB.T6G(SCH_1):GND

Q_RES_0201LF-0,5%,1/20W,CHIP,CS00001JE10  I14  R1126
   1 NCF_A1_CPU0_P3_GND      A @T6G_MB_LIB.T6G(SCH_1):NCF_A1_CPU0_P3_GND
   2    GND      B @T6G_MB_LIB.T6G(SCH_1):GND

PT5161LRS-PT5161LRS,SMLF,IC,AJ051610U03  I17  U6013
AC13    GND   GND1 @T6G_MB_LIB.T6G(SCH_1):GND
AC22    GND   GND2 @T6G_MB_LIB.T6G(SCH_1):GND
AC32    GND   GND3 @T6G_MB_LIB.T6G(SCH_1):GND
 AC4    GND   GND4 @T6G_MB_LIB.T6G(SCH_1):GND
 AD2    GND   GND5 @T6G_MB_LIB.T6G(SCH_1):GND
AD34    GND   GND6 @T6G_MB_LIB.T6G(SCH_1):GND
 AE1    GND   GND7 @T6G_MB_LIB.T6G(SCH_1):GND
AE35    GND   GND8 @T6G_MB_LIB.T6G(SCH_1):GND
AK13    GND   GND9 @T6G_MB_LIB.T6G(SCH_1):GND
AK22    GND  GND10 @T6G_MB_LIB.T6G(SCH_1):GND
AK32    GND  GND11 @T6G_MB_LIB.T6G(SCH_1):GND
 AK4    GND  GND12 @T6G_MB_LIB.T6G(SCH_1):GND
 AL2    GND  GND13 @T6G_MB_LIB.T6G(SCH_1):GND
AL34    GND  GND14 @T6G_MB_LIB.T6G(SCH_1):GND
 AM1    GND  GND15 @T6G_MB_LIB.T6G(SCH_1):GND
AM35    GND  GND16 @T6G_MB_LIB.T6G(SCH_1):GND
AU13    GND  GND17 @T6G_MB_LIB.T6G(SCH_1):GND
AU22    GND  GND18 @T6G_MB_LIB.T6G(SCH_1):GND
AU32    GND  GND19 @T6G_MB_LIB.T6G(SCH_1):GND
 AU4    GND  GND20 @T6G_MB_LIB.T6G(SCH_1):GND
 AV2    GND  GND21 @T6G_MB_LIB.T6G(SCH_1):GND
AV34    GND  GND22 @T6G_MB_LIB.T6G(SCH_1):GND
 AW1    GND  GND23 @T6G_MB_LIB.T6G(SCH_1):GND
AW35    GND  GND24 @T6G_MB_LIB.T6G(SCH_1):GND
 B19    GND  GND25 @T6G_MB_LIB.T6G(SCH_1):GND
BD13    GND  GND26 @T6G_MB_LIB.T6G(SCH_1):GND
BD22    GND  GND27 @T6G_MB_LIB.T6G(SCH_1):GND
BD32    GND  GND28 @T6G_MB_LIB.T6G(SCH_1):GND
 BD4    GND  GND29 @T6G_MB_LIB.T6G(SCH_1):GND
 BE2    GND  GND30 @T6G_MB_LIB.T6G(SCH_1):GND
BE34    GND  GND31 @T6G_MB_LIB.T6G(SCH_1):GND
 BF1    GND  GND32 @T6G_MB_LIB.T6G(SCH_1):GND
BF35    GND  GND33 @T6G_MB_LIB.T6G(SCH_1):GND
BL13    GND  GND34 @T6G_MB_LIB.T6G(SCH_1):GND
BL22    GND  GND35 @T6G_MB_LIB.T6G(SCH_1):GND
BL32    GND  GND36 @T6G_MB_LIB.T6G(SCH_1):GND
 BL4    GND  GND37 @T6G_MB_LIB.T6G(SCH_1):GND
 BM2    GND  GND38 @T6G_MB_LIB.T6G(SCH_1):GND
BM34    GND  GND39 @T6G_MB_LIB.T6G(SCH_1):GND
 BN1    GND  GND40 @T6G_MB_LIB.T6G(SCH_1):GND
BN35    GND  GND41 @T6G_MB_LIB.T6G(SCH_1):GND
BV13    GND  GND42 @T6G_MB_LIB.T6G(SCH_1):GND
BV22    GND  GND43 @T6G_MB_LIB.T6G(SCH_1):GND
BV32    GND  GND44 @T6G_MB_LIB.T6G(SCH_1):GND
 BV4    GND  GND45 @T6G_MB_LIB.T6G(SCH_1):GND
 BW2    GND  GND46 @T6G_MB_LIB.T6G(SCH_1):GND
BW34    GND  GND47 @T6G_MB_LIB.T6G(SCH_1):GND
 BY1    GND  GND48 @T6G_MB_LIB.T6G(SCH_1):GND
BY35    GND  GND49 @T6G_MB_LIB.T6G(SCH_1):GND
CE13    GND  GND50 @T6G_MB_LIB.T6G(SCH_1):GND
CE22    GND  GND51 @T6G_MB_LIB.T6G(SCH_1):GND
CE32    GND  GND52 @T6G_MB_LIB.T6G(SCH_1):GND
 CE4    GND  GND53 @T6G_MB_LIB.T6G(SCH_1):GND
 CF2    GND  GND54 @T6G_MB_LIB.T6G(SCH_1):GND
CF34    GND  GND55 @T6G_MB_LIB.T6G(SCH_1):GND
 CG1    GND  GND56 @T6G_MB_LIB.T6G(SCH_1):GND
CG35    GND  GND57 @T6G_MB_LIB.T6G(SCH_1):GND
CM13    GND  GND58 @T6G_MB_LIB.T6G(SCH_1):GND
CM22    GND  GND59 @T6G_MB_LIB.T6G(SCH_1):GND
CM32    GND  GND60 @T6G_MB_LIB.T6G(SCH_1):GND
 CM4    GND  GND61 @T6G_MB_LIB.T6G(SCH_1):GND
 CN2    GND  GND62 @T6G_MB_LIB.T6G(SCH_1):GND
CN34    GND  GND63 @T6G_MB_LIB.T6G(SCH_1):GND
 CP1    GND  GND64 @T6G_MB_LIB.T6G(SCH_1):GND
CP35    GND  GND65 @T6G_MB_LIB.T6G(SCH_1):GND
CW13    GND  GND66 @T6G_MB_LIB.T6G(SCH_1):GND
CW22    GND  GND67 @T6G_MB_LIB.T6G(SCH_1):GND
CW32    GND  GND68 @T6G_MB_LIB.T6G(SCH_1):GND
 CW4    GND  GND69 @T6G_MB_LIB.T6G(SCH_1):GND
 CY2    GND  GND70 @T6G_MB_LIB.T6G(SCH_1):GND
CY34    GND  GND71 @T6G_MB_LIB.T6G(SCH_1):GND
 DA1    GND  GND72 @T6G_MB_LIB.T6G(SCH_1):GND
DA35    GND  GND73 @T6G_MB_LIB.T6G(SCH_1):GND
DF13    GND  GND74 @T6G_MB_LIB.T6G(SCH_1):GND
DF22    GND  GND75 @T6G_MB_LIB.T6G(SCH_1):GND
DF32    GND  GND76 @T6G_MB_LIB.T6G(SCH_1):GND
 DF4    GND  GND77 @T6G_MB_LIB.T6G(SCH_1):GND
 DG2    GND  GND78 @T6G_MB_LIB.T6G(SCH_1):GND
DG34    GND  GND79 @T6G_MB_LIB.T6G(SCH_1):GND
 DH1    GND  GND80 @T6G_MB_LIB.T6G(SCH_1):GND
DH35    GND  GND81 @T6G_MB_LIB.T6G(SCH_1):GND
DN13    GND  GND82 @T6G_MB_LIB.T6G(SCH_1):GND
  A1 NCF_A1_CPU0_P3_GND NCF_GND1 @T6G_MB_LIB.T6G(SCH_1):NCF_A1_CPU0_P3_GND
 A35 NCF_CPU0_P3_GND NCF_GND2 @T6G_MB_LIB.T6G(SCH_1):NCF_CPU0_P3_GND
  C2 NCF_CPU0_P3_GND NCF_GND3 @T6G_MB_LIB.T6G(SCH_1):NCF_CPU0_P3_GND
 C34 NCF_CPU0_P3_GND NCF_GND4 @T6G_MB_LIB.T6G(SCH_1):NCF_CPU0_P3_GND
  D1 NCF_CPU0_P3_GND NCF_GND5 @T6G_MB_LIB.T6G(SCH_1):NCF_CPU0_P3_GND
 D35 NCF_CPU0_P3_GND NCF_GND6 @T6G_MB_LIB.T6G(SCH_1):NCF_CPU0_P3_GND
 FE2 NCF_CPU0_P3_GND NCF_GND7 @T6G_MB_LIB.T6G(SCH_1):NCF_CPU0_P3_GND
FE34 NCF_CPU0_P3_GND NCF_GND8 @T6G_MB_LIB.T6G(SCH_1):NCF_CPU0_P3_GND
 FG1 NCF_CPU0_P3_GND NCF_GND9 @T6G_MB_LIB.T6G(SCH_1):NCF_CPU0_P3_GND
FG35 NCF_CPU0_P3_GND NCF_GND10 @T6G_MB_LIB.T6G(SCH_1):NCF_CPU0_P3_GND
 FH2 NCF_CPU0_P3_GND NCF_GND11 @T6G_MB_LIB.T6G(SCH_1):NCF_CPU0_P3_GND
FH34 NCF_CPU0_P3_GND NCF_GND12 @T6G_MB_LIB.T6G(SCH_1):NCF_CPU0_P3_GND
DN22    GND  GND83 @T6G_MB_LIB.T6G(SCH_1):GND
DN32    GND  GND84 @T6G_MB_LIB.T6G(SCH_1):GND
 DN4    GND  GND85 @T6G_MB_LIB.T6G(SCH_1):GND
 DP2    GND  GND86 @T6G_MB_LIB.T6G(SCH_1):GND
DP34    GND  GND87 @T6G_MB_LIB.T6G(SCH_1):GND
 DR1    GND  GND88 @T6G_MB_LIB.T6G(SCH_1):GND
DR35    GND  GND89 @T6G_MB_LIB.T6G(SCH_1):GND
DY13    GND  GND90 @T6G_MB_LIB.T6G(SCH_1):GND
DY22    GND  GND91 @T6G_MB_LIB.T6G(SCH_1):GND
DY32    GND  GND92 @T6G_MB_LIB.T6G(SCH_1):GND
 DY4    GND  GND93 @T6G_MB_LIB.T6G(SCH_1):GND
 E14    GND  GND94 @T6G_MB_LIB.T6G(SCH_1):GND
 E27    GND  GND95 @T6G_MB_LIB.T6G(SCH_1):GND
 E33    GND  GND96 @T6G_MB_LIB.T6G(SCH_1):GND
 EA2    GND  GND97 @T6G_MB_LIB.T6G(SCH_1):GND
EA34    GND  GND98 @T6G_MB_LIB.T6G(SCH_1):GND
 EB1    GND  GND99 @T6G_MB_LIB.T6G(SCH_1):GND
EB35    GND GND100 @T6G_MB_LIB.T6G(SCH_1):GND
EG13    GND GND101 @T6G_MB_LIB.T6G(SCH_1):GND
EG22    GND GND102 @T6G_MB_LIB.T6G(SCH_1):GND
EG32    GND GND103 @T6G_MB_LIB.T6G(SCH_1):GND
 EG4    GND GND104 @T6G_MB_LIB.T6G(SCH_1):GND
 EH2    GND GND105 @T6G_MB_LIB.T6G(SCH_1):GND
EH34    GND GND106 @T6G_MB_LIB.T6G(SCH_1):GND
 EJ1    GND GND107 @T6G_MB_LIB.T6G(SCH_1):GND
EJ35    GND GND108 @T6G_MB_LIB.T6G(SCH_1):GND
EP13    GND GND109 @T6G_MB_LIB.T6G(SCH_1):GND
EP22    GND GND110 @T6G_MB_LIB.T6G(SCH_1):GND
EP32    GND GND111 @T6G_MB_LIB.T6G(SCH_1):GND
 EP4    GND GND112 @T6G_MB_LIB.T6G(SCH_1):GND
 ER2    GND GND113 @T6G_MB_LIB.T6G(SCH_1):GND
ER34    GND GND114 @T6G_MB_LIB.T6G(SCH_1):GND
 ET1    GND GND115 @T6G_MB_LIB.T6G(SCH_1):GND
ET35    GND GND116 @T6G_MB_LIB.T6G(SCH_1):GND
FA15    GND GND117 @T6G_MB_LIB.T6G(SCH_1):GND
FA32    GND GND118 @T6G_MB_LIB.T6G(SCH_1):GND
 FB2    GND GND119 @T6G_MB_LIB.T6G(SCH_1):GND
FB34    GND GND120 @T6G_MB_LIB.T6G(SCH_1):GND
FC19    GND GND121 @T6G_MB_LIB.T6G(SCH_1):GND
FC23    GND GND122 @T6G_MB_LIB.T6G(SCH_1):GND
FC25    GND GND123 @T6G_MB_LIB.T6G(SCH_1):GND
FC28    GND GND124 @T6G_MB_LIB.T6G(SCH_1):GND
 FC3    GND GND125 @T6G_MB_LIB.T6G(SCH_1):GND
 FC6    GND GND126 @T6G_MB_LIB.T6G(SCH_1):GND
 FC9    GND GND127 @T6G_MB_LIB.T6G(SCH_1):GND
 FD1    GND GND128 @T6G_MB_LIB.T6G(SCH_1):GND
FD35    GND GND129 @T6G_MB_LIB.T6G(SCH_1):GND
FF14    GND GND130 @T6G_MB_LIB.T6G(SCH_1):GND
FF21    GND GND131 @T6G_MB_LIB.T6G(SCH_1):GND
FJ12    GND GND132 @T6G_MB_LIB.T6G(SCH_1):GND
FJ19    GND GND133 @T6G_MB_LIB.T6G(SCH_1):GND
 H12    GND GND134 @T6G_MB_LIB.T6G(SCH_1):GND
 H16    GND GND135 @T6G_MB_LIB.T6G(SCH_1):GND
 H19    GND GND136 @T6G_MB_LIB.T6G(SCH_1):GND
 H31    GND GND137 @T6G_MB_LIB.T6G(SCH_1):GND
 J22    GND GND138 @T6G_MB_LIB.T6G(SCH_1):GND
  J4    GND GND139 @T6G_MB_LIB.T6G(SCH_1):GND
  K2    GND GND140 @T6G_MB_LIB.T6G(SCH_1):GND
 K34    GND GND141 @T6G_MB_LIB.T6G(SCH_1):GND
  L1    GND GND142 @T6G_MB_LIB.T6G(SCH_1):GND
 L35    GND GND143 @T6G_MB_LIB.T6G(SCH_1):GND
 T13    GND GND144 @T6G_MB_LIB.T6G(SCH_1):GND
 T22    GND GND145 @T6G_MB_LIB.T6G(SCH_1):GND
 T32    GND GND146 @T6G_MB_LIB.T6G(SCH_1):GND
  T4    GND GND147 @T6G_MB_LIB.T6G(SCH_1):GND
  U2    GND GND148 @T6G_MB_LIB.T6G(SCH_1):GND
 U34    GND GND149 @T6G_MB_LIB.T6G(SCH_1):GND
  V1    GND GND150 @T6G_MB_LIB.T6G(SCH_1):GND
 V35    GND GND151 @T6G_MB_LIB.T6G(SCH_1):GND

Q_RES_0201LF-200,1%,1/20W,CHIP,CS12001FE12  I18  R1124
   1 RT_CPU0_P3_VQPS      A @T6G_MB_LIB.T6G(SCH_1):RT_CPU0_P3_VQPS
   2    GND      B @T6G_MB_LIB.T6G(SCH_1):GND

Q_RES_0201LF-1K,1%,1/20W,EMPTY,CS21001FE07  I19  R1123
   1 P1V8_CPU0_RT_1D      A @T6G_MB_LIB.T6G(SCH_1):P1V8_CPU0_RT_1D
   2 RT_CPU0_P3_VQPS      B @T6G_MB_LIB.T6G(SCH_1):RT_CPU0_P3_VQPS


DRAWING: @T6G_MB_LIB.T6G(SCH_1):PAGE433 

Q_RES_0402LF-0,5%,1/16W,EMPTY,CS00002JB13  I1  R1087
   1 P1V8_CPU0_RT3_1A_1D      A @T6G_MB_LIB.T6G(SCH_1):P1V8_CPU0_RT3_1A_1D
   2 P1V8_CPU0_RT3_1A      B @T6G_MB_LIB.T6G(SCH_1):P1V8_CPU0_RT3_1A

Q_RES_0402LF-0,5%,1/16W,EMPTY,CS00002JB13  I2  R1086
   1 P1V8_CPU0_RT3_1A_1D      A @T6G_MB_LIB.T6G(SCH_1):P1V8_CPU0_RT3_1A_1D
   2 P1V8_CPU0_RT3_1A      B @T6G_MB_LIB.T6G(SCH_1):P1V8_CPU0_RT3_1A

Q_CAP_0201-1UF,4V,20%,X6S,CH-10KMEE00  I5  C999
   1 P1V8_CPU0_RT3_1A_1D      A @T6G_MB_LIB.T6G(SCH_1):P1V8_CPU0_RT3_1A_1D
   2    GND      B @T6G_MB_LIB.T6G(SCH_1):GND

Q_CAP_C0201-0.1UF,10V,10%,X7S,CH4102K6E00  I6  C1002
   1 P1V8_CPU0_RT3_1A_1D      A @T6G_MB_LIB.T6G(SCH_1):P1V8_CPU0_RT3_1A_1D
   2    GND      B @T6G_MB_LIB.T6G(SCH_1):GND

Q_RES_0603LF-0,5%,1/4W,EMPTY,CS00006J900  I7  R1094
   1 P0V9_CPU0_RT_2D      A @T6G_MB_LIB.T6G(SCH_1):P0V9_CPU0_RT_2D
   2 P0V9_CPU0_RT3_2A_2D      B @T6G_MB_LIB.T6G(SCH_1):P0V9_CPU0_RT3_2A_2D

Q_INDUCTOR_SMLF-BLM21SN300SN1D/5A,IND,CX300SN1000  I10  L22
   2 P1V8_CPU0_RT3_1A      2 @T6G_MB_LIB.T6G(SCH_1):P1V8_CPU0_RT3_1A
   1 P1V8_CPU0_RT_1D      1 @T6G_MB_LIB.T6G(SCH_1):P1V8_CPU0_RT_1D

Q_CAP_C0805-100UF,4V,20%,X6S,CH710KMEA01  I12  C991
   1 P1V8_CPU0_RT3_1A      A @T6G_MB_LIB.T6G(SCH_1):P1V8_CPU0_RT3_1A
   2    GND      B @T6G_MB_LIB.T6G(SCH_1):GND

Q_CAP_C0402-22UF,4V,20%,X6S,CH622KMEB02  I13  C993
   1 P1V8_CPU0_RT3_1A      A @T6G_MB_LIB.T6G(SCH_1):P1V8_CPU0_RT3_1A
   2    GND      B @T6G_MB_LIB.T6G(SCH_1):GND

Q_CAP_C0402-10UF,6.3V,20%,X6S,CH6101MEB01  I15  C995
   1 P1V8_CPU0_RT3_1A      A @T6G_MB_LIB.T6G(SCH_1):P1V8_CPU0_RT3_1A
   2    GND      B @T6G_MB_LIB.T6G(SCH_1):GND

Q_CAP_0402-4.7UF,6.3V,20%,X6S,CH5471MEB01  I16  C996
   1 P1V8_CPU0_RT3_1A      A @T6G_MB_LIB.T6G(SCH_1):P1V8_CPU0_RT3_1A
   2    GND      B @T6G_MB_LIB.T6G(SCH_1):GND

Q_CAP_0201-1UF,4V,20%,X6S,CH-10KMEE00  I17  C998
   1 P1V8_CPU0_RT3_1A      A @T6G_MB_LIB.T6G(SCH_1):P1V8_CPU0_RT3_1A
   2    GND      B @T6G_MB_LIB.T6G(SCH_1):GND

Q_CAP_C0805-100UF,4V,20%,X6S,CH710KMEA01  I19  C990
   1 P1V8_CPU0_RT_1D      A @T6G_MB_LIB.T6G(SCH_1):P1V8_CPU0_RT_1D
   2    GND      B @T6G_MB_LIB.T6G(SCH_1):GND

Q_CAP_C0402-22UF,4V,20%,X6S,CH622KMEB02  I20  C992
   1 P1V8_CPU0_RT_1D      A @T6G_MB_LIB.T6G(SCH_1):P1V8_CPU0_RT_1D
   2    GND      B @T6G_MB_LIB.T6G(SCH_1):GND

Q_CAP_C0402-10UF,6.3V,20%,X6S,CH6101MEB01  I21  C994
   1 P1V8_CPU0_RT_1D      A @T6G_MB_LIB.T6G(SCH_1):P1V8_CPU0_RT_1D
   2    GND      B @T6G_MB_LIB.T6G(SCH_1):GND

Q_CAP_0402-4.7UF,6.3V,20%,X6S,CH5471MEB01  I22  C997
   1 P1V8_CPU0_RT_1D      A @T6G_MB_LIB.T6G(SCH_1):P1V8_CPU0_RT_1D
   2    GND      B @T6G_MB_LIB.T6G(SCH_1):GND

Q_CAP_0201-1UF,4V,20%,X6S,CH-10KMEE00  I24  C1000
   1 P1V8_CPU0_RT3_1A      A @T6G_MB_LIB.T6G(SCH_1):P1V8_CPU0_RT3_1A
   2    GND      B @T6G_MB_LIB.T6G(SCH_1):GND

Q_CAP_C0201-0.1UF,10V,10%,X7S,CH4102K6E00  I25  C1001
   1 P1V8_CPU0_RT3_1A      A @T6G_MB_LIB.T6G(SCH_1):P1V8_CPU0_RT3_1A
   2    GND      B @T6G_MB_LIB.T6G(SCH_1):GND

Q_CAP_C0201-0.1UF,10V,10%,X7S,CH4102K6E00  I26  C1003
   1 P1V8_CPU0_RT3_1A      A @T6G_MB_LIB.T6G(SCH_1):P1V8_CPU0_RT3_1A
   2    GND      B @T6G_MB_LIB.T6G(SCH_1):GND

Q_CAP_C0201-0.1UF,10V,10%,X7S,CH4102K6E00  I27  C1004
   1 P1V8_CPU0_RT3_1A      A @T6G_MB_LIB.T6G(SCH_1):P1V8_CPU0_RT3_1A
   2    GND      B @T6G_MB_LIB.T6G(SCH_1):GND

Q_CAP_C0201-0.1UF,10V,10%,X7S,CH4102K6E00  I28  C1005
   1 P1V8_CPU0_RT3_1A      A @T6G_MB_LIB.T6G(SCH_1):P1V8_CPU0_RT3_1A
   2    GND      B @T6G_MB_LIB.T6G(SCH_1):GND

Q_CAP_C0201-0.1UF,10V,10%,X7S,CH4102K6E00  I30  C1014
   1 P0V9_CPU0_RT3_2A_2D      A @T6G_MB_LIB.T6G(SCH_1):P0V9_CPU0_RT3_2A_2D
   2    GND      B @T6G_MB_LIB.T6G(SCH_1):GND

Q_CAP_C0201-0.1UF,10V,10%,X7S,CH4102K6E00  I35  C1021
   1 P0V9_CPU0_RT3_2A_2D      A @T6G_MB_LIB.T6G(SCH_1):P0V9_CPU0_RT3_2A_2D
   2    GND      B @T6G_MB_LIB.T6G(SCH_1):GND

Q_RES_0603LF-0,5%,1/4W,CHIP,CS00006J900  I36  R1095
   1 P0V9_CPU0_RT3_2A_2D      A @T6G_MB_LIB.T6G(SCH_1):P0V9_CPU0_RT3_2A_2D
   2 P0V9_CPU0_RT3_2A      B @T6G_MB_LIB.T6G(SCH_1):P0V9_CPU0_RT3_2A

Q_CAP_0201-1UF,4V,20%,X6S,CH-10KMEE00  I37  C1024
   1 P0V9_CPU0_RT3_2A      A @T6G_MB_LIB.T6G(SCH_1):P0V9_CPU0_RT3_2A
   2    GND      B @T6G_MB_LIB.T6G(SCH_1):GND

Q_CAP_0201-1UF,4V,20%,X6S,CH-10KMEE00  I38  C1027
   1 P0V9_CPU0_RT3_2A      A @T6G_MB_LIB.T6G(SCH_1):P0V9_CPU0_RT3_2A
   2    GND      B @T6G_MB_LIB.T6G(SCH_1):GND

Q_CAP_C0402-10UF,6.3V,20%,X6S,CH6101MEB01  I39  C1023
   1 P0V9_CPU0_RT3_2A      A @T6G_MB_LIB.T6G(SCH_1):P0V9_CPU0_RT3_2A
   2    GND      B @T6G_MB_LIB.T6G(SCH_1):GND

Q_CAP_C0402-10UF,6.3V,20%,X6S,CH6101MEB01  I40  C1036
   1 P0V9_CPU0_RT3_2A      A @T6G_MB_LIB.T6G(SCH_1):P0V9_CPU0_RT3_2A
   2    GND      B @T6G_MB_LIB.T6G(SCH_1):GND

Q_CAP_C0201-0.1UF,10V,10%,X7S,CH4102K6E00  I41  C1010
   1 P0V9_CPU0_RT3_2A      A @T6G_MB_LIB.T6G(SCH_1):P0V9_CPU0_RT3_2A
   2    GND      B @T6G_MB_LIB.T6G(SCH_1):GND

Q_CAP_C0201-0.1UF,10V,10%,X7S,CH4102K6E00  I42  C1052
   1 P0V9_CPU0_RT3_2A      A @T6G_MB_LIB.T6G(SCH_1):P0V9_CPU0_RT3_2A
   2    GND      B @T6G_MB_LIB.T6G(SCH_1):GND

Q_CAP_C0201-0.1UF,10V,10%,X7S,CH4102K6E00  I43  C1055
   1 P0V9_CPU0_RT3_2A      A @T6G_MB_LIB.T6G(SCH_1):P0V9_CPU0_RT3_2A
   2    GND      B @T6G_MB_LIB.T6G(SCH_1):GND

Q_CAP_C0201-0.1UF,10V,10%,X7S,CH4102K6E00  I44  C1035
   1 P0V9_CPU0_RT3_2A      A @T6G_MB_LIB.T6G(SCH_1):P0V9_CPU0_RT3_2A
   2    GND      B @T6G_MB_LIB.T6G(SCH_1):GND

Q_CAP_0201-1UF,4V,20%,X6S,CH-10KMEE00  I45  C1031
   1 P0V9_CPU0_RT3_2A      A @T6G_MB_LIB.T6G(SCH_1):P0V9_CPU0_RT3_2A
   2    GND      B @T6G_MB_LIB.T6G(SCH_1):GND

Q_CAP_0201-1UF,4V,20%,X6S,CH-10KMEE00  I46  C1006
   1 P0V9_CPU0_RT3_2A      A @T6G_MB_LIB.T6G(SCH_1):P0V9_CPU0_RT3_2A
   2    GND      B @T6G_MB_LIB.T6G(SCH_1):GND

Q_CAP_0402-4.7UF,6.3V,20%,X6S,CH5471MEB01  I47  C1034
   1 P0V9_CPU0_RT3_2A      A @T6G_MB_LIB.T6G(SCH_1):P0V9_CPU0_RT3_2A
   2    GND      B @T6G_MB_LIB.T6G(SCH_1):GND

Q_CAP_0201-1UF,4V,20%,X6S,CH-10KMEE00  I48  C1039
   1 P0V9_CPU0_RT3_2A      A @T6G_MB_LIB.T6G(SCH_1):P0V9_CPU0_RT3_2A
   2    GND      B @T6G_MB_LIB.T6G(SCH_1):GND

Q_CAP_0201-1UF,4V,20%,X6S,CH-10KMEE00  I49  C1015
   1 P0V9_CPU0_RT3_2A      A @T6G_MB_LIB.T6G(SCH_1):P0V9_CPU0_RT3_2A
   2    GND      B @T6G_MB_LIB.T6G(SCH_1):GND

Q_CAP_0402-4.7UF,6.3V,20%,X6S,CH5471MEB01  I50  C1054
   1 P0V9_CPU0_RT3_2A      A @T6G_MB_LIB.T6G(SCH_1):P0V9_CPU0_RT3_2A
   2    GND      B @T6G_MB_LIB.T6G(SCH_1):GND

Q_CAP_0402-4.7UF,6.3V,20%,X6S,CH5471MEB01  I51  C1056
   1 P0V9_CPU0_RT3_2A      A @T6G_MB_LIB.T6G(SCH_1):P0V9_CPU0_RT3_2A
   2    GND      B @T6G_MB_LIB.T6G(SCH_1):GND

Q_CAP_C0201-0.1UF,10V,10%,X7S,CH4102K6E00  I52  C1008
   1 P0V9_CPU0_RT3_2A      A @T6G_MB_LIB.T6G(SCH_1):P0V9_CPU0_RT3_2A
   2    GND      B @T6G_MB_LIB.T6G(SCH_1):GND

Q_CAP_C0201-0.1UF,10V,10%,X7S,CH4102K6E00  I53  C1011
   1 P0V9_CPU0_RT3_2A      A @T6G_MB_LIB.T6G(SCH_1):P0V9_CPU0_RT3_2A
   2    GND      B @T6G_MB_LIB.T6G(SCH_1):GND

Q_CAP_C0201-0.1UF,10V,10%,X7S,CH4102K6E00  I54  C1043
   1 P0V9_CPU0_RT3_2A      A @T6G_MB_LIB.T6G(SCH_1):P0V9_CPU0_RT3_2A
   2    GND      B @T6G_MB_LIB.T6G(SCH_1):GND

Q_CAP_C0201-0.1UF,10V,10%,X7S,CH4102K6E00  I56  C1047
   1 P0V9_CPU0_RT3_2A      A @T6G_MB_LIB.T6G(SCH_1):P0V9_CPU0_RT3_2A
   2    GND      B @T6G_MB_LIB.T6G(SCH_1):GND

Q_CAP_0201-1UF,4V,20%,X6S,CH-10KMEE00  I57  C1019
   1 P0V9_CPU0_RT3_2A      A @T6G_MB_LIB.T6G(SCH_1):P0V9_CPU0_RT3_2A
   2    GND      B @T6G_MB_LIB.T6G(SCH_1):GND

Q_CAP_0201-1UF,4V,20%,X6S,CH-10KMEE00  I59  C1046
   1 P0V9_CPU0_RT3_2A      A @T6G_MB_LIB.T6G(SCH_1):P0V9_CPU0_RT3_2A
   2    GND      B @T6G_MB_LIB.T6G(SCH_1):GND

Q_CAP_0201-1UF,4V,20%,X6S,CH-10KMEE00  I60  C1050
   1 P0V9_CPU0_RT3_2A      A @T6G_MB_LIB.T6G(SCH_1):P0V9_CPU0_RT3_2A
   2    GND      B @T6G_MB_LIB.T6G(SCH_1):GND

Q_CAP_0201-1UF,4V,20%,X6S,CH-10KMEE00  I62  C1013
   1 P0V9_CPU0_RT3_2A      A @T6G_MB_LIB.T6G(SCH_1):P0V9_CPU0_RT3_2A
   2    GND      B @T6G_MB_LIB.T6G(SCH_1):GND

Q_CAP_0201-1UF,4V,20%,X6S,CH-10KMEE00  I63  C1017
   1 P0V9_CPU0_RT3_2A      A @T6G_MB_LIB.T6G(SCH_1):P0V9_CPU0_RT3_2A
   2    GND      B @T6G_MB_LIB.T6G(SCH_1):GND

Q_INDUCTOR_SMLF-100NH/16A,IND,CV+10G0MZ04  I65  L23
   2 P0V9_CPU0_RT3_2A      2 @T6G_MB_LIB.T6G(SCH_1):P0V9_CPU0_RT3_2A
   1 P0V9_CPU0_RT_2D      1 @T6G_MB_LIB.T6G(SCH_1):P0V9_CPU0_RT_2D

Q_CAP_C0805-100UF,4V,20%,X6S,CH710KMEA01  I66  C1022
   1 P0V9_CPU0_RT3_2A      A @T6G_MB_LIB.T6G(SCH_1):P0V9_CPU0_RT3_2A
   2    GND      B @T6G_MB_LIB.T6G(SCH_1):GND

Q_CAP_C0805-100UF,4V,20%,X6S,CH710KMEA01  I67  C1025
   1 P0V9_CPU0_RT3_2A      A @T6G_MB_LIB.T6G(SCH_1):P0V9_CPU0_RT3_2A
   2    GND      B @T6G_MB_LIB.T6G(SCH_1):GND

Q_CAP_C0805-100UF,4V,20%,X6S,CH710KMEA01  I69  C1028
   1 P0V9_CPU0_RT_2D      A @T6G_MB_LIB.T6G(SCH_1):P0V9_CPU0_RT_2D
   2    GND      B @T6G_MB_LIB.T6G(SCH_1):GND

Q_CAP_C0805-100UF,4V,20%,X6S,CH710KMEA01  I70  C1029
   1 P0V9_CPU0_RT3_2A      A @T6G_MB_LIB.T6G(SCH_1):P0V9_CPU0_RT3_2A
   2    GND      B @T6G_MB_LIB.T6G(SCH_1):GND

Q_CAP_C0805-100UF,4V,20%,X6S,CH710KMEA01  I71  C1033
   1 P0V9_CPU0_RT3_2A      A @T6G_MB_LIB.T6G(SCH_1):P0V9_CPU0_RT3_2A
   2    GND      B @T6G_MB_LIB.T6G(SCH_1):GND

Q_CAP_C0402-22UF,4V,20%,X6S,CH622KMEB02  I72  C1026
   1 P0V9_CPU0_RT3_2A      A @T6G_MB_LIB.T6G(SCH_1):P0V9_CPU0_RT3_2A
   2    GND      B @T6G_MB_LIB.T6G(SCH_1):GND

Q_CAP_C0402-10UF,6.3V,20%,X6S,CH6101MEB01  I73  C1044
   1 P0V9_CPU0_RT_2D      A @T6G_MB_LIB.T6G(SCH_1):P0V9_CPU0_RT_2D
   2    GND      B @T6G_MB_LIB.T6G(SCH_1):GND

Q_CAP_C0402-22UF,4V,20%,X6S,CH622KMEB02  I74  C1032
   1 P0V9_CPU0_RT_2D      A @T6G_MB_LIB.T6G(SCH_1):P0V9_CPU0_RT_2D
   2    GND      B @T6G_MB_LIB.T6G(SCH_1):GND

Q_CAP_0402-4.7UF,6.3V,20%,X6S,CH5471MEB01  I75  C1038
   1 P0V9_CPU0_RT_2D      A @T6G_MB_LIB.T6G(SCH_1):P0V9_CPU0_RT_2D
   2    GND      B @T6G_MB_LIB.T6G(SCH_1):GND

Q_CAP_0201-1UF,4V,20%,X6S,CH-10KMEE00  I76  C1016
   1 P0V9_CPU0_RT_2D      A @T6G_MB_LIB.T6G(SCH_1):P0V9_CPU0_RT_2D
   2    GND      B @T6G_MB_LIB.T6G(SCH_1):GND

Q_CAP_C0402-22UF,4V,20%,X6S,CH622KMEB02  I77  C1030
   1 P0V9_CPU0_RT3_2A      A @T6G_MB_LIB.T6G(SCH_1):P0V9_CPU0_RT3_2A
   2    GND      B @T6G_MB_LIB.T6G(SCH_1):GND

Q_CAP_C0402-22UF,4V,20%,X6S,CH622KMEB02  I78  C1041
   1 P0V9_CPU0_RT3_2A      A @T6G_MB_LIB.T6G(SCH_1):P0V9_CPU0_RT3_2A
   2    GND      B @T6G_MB_LIB.T6G(SCH_1):GND

Q_CAP_C0402-10UF,6.3V,20%,X6S,CH6101MEB01  I79  C1037
   1 P0V9_CPU0_RT3_2A      A @T6G_MB_LIB.T6G(SCH_1):P0V9_CPU0_RT3_2A
   2    GND      B @T6G_MB_LIB.T6G(SCH_1):GND

Q_CAP_C0402-10UF,6.3V,20%,X6S,CH6101MEB01  I80  C1049
   1 P0V9_CPU0_RT3_2A      A @T6G_MB_LIB.T6G(SCH_1):P0V9_CPU0_RT3_2A
   2    GND      B @T6G_MB_LIB.T6G(SCH_1):GND

Q_CAP_C0201-0.1UF,10V,10%,X7S,CH4102K6E00  I81  C1007
   1 P0V9_CPU0_RT_2D      A @T6G_MB_LIB.T6G(SCH_1):P0V9_CPU0_RT_2D
   2    GND      B @T6G_MB_LIB.T6G(SCH_1):GND

Q_CAP_C0201-0.1UF,10V,10%,X7S,CH4102K6E00  I82  C1009
   1 P0V9_CPU0_RT_2D      A @T6G_MB_LIB.T6G(SCH_1):P0V9_CPU0_RT_2D
   2    GND      B @T6G_MB_LIB.T6G(SCH_1):GND

Q_CAP_C0201-0.1UF,10V,10%,X7S,CH4102K6E00  I84  C1012
   1 P0V9_CPU0_RT_2D      A @T6G_MB_LIB.T6G(SCH_1):P0V9_CPU0_RT_2D
   2    GND      B @T6G_MB_LIB.T6G(SCH_1):GND

Q_CAP_C0201-0.1UF,10V,10%,X7S,CH4102K6E00  I85  C1048
   1 P0V9_CPU0_RT_2D      A @T6G_MB_LIB.T6G(SCH_1):P0V9_CPU0_RT_2D
   2    GND      B @T6G_MB_LIB.T6G(SCH_1):GND

Q_CAP_C0402-22UF,4V,20%,X6S,CH622KMEB02  I86  C1040
   1 P0V9_CPU0_RT3_2A      A @T6G_MB_LIB.T6G(SCH_1):P0V9_CPU0_RT3_2A
   2    GND      B @T6G_MB_LIB.T6G(SCH_1):GND

Q_CAP_0402-4.7UF,6.3V,20%,X6S,CH5471MEB01  I87  C1045
   1 P0V9_CPU0_RT3_2A      A @T6G_MB_LIB.T6G(SCH_1):P0V9_CPU0_RT3_2A
   2    GND      B @T6G_MB_LIB.T6G(SCH_1):GND

Q_INDUCTOR_SMLF-BLM15PD121SN1D/1300MA,IND,CX5PD121A  I88  L30
   2 P1V8_CPU0_RT3_1A_1D      2 @T6G_MB_LIB.T6G(SCH_1):P1V8_CPU0_RT3_1A_1D
   1 P1V8_CPU0_RT_1D      1 @T6G_MB_LIB.T6G(SCH_1):P1V8_CPU0_RT_1D

Q_RES_0402LF-0,5%,1/16W,EMPTY,CS00002JB13  I89  R1093
   1 P1V8_CPU0_RT_1D      A @T6G_MB_LIB.T6G(SCH_1):P1V8_CPU0_RT_1D
   2 P1V8_CPU0_RT3_1A_1D      B @T6G_MB_LIB.T6G(SCH_1):P1V8_CPU0_RT3_1A_1D

Q_CAP_0201-1UF,4V,20%,X6S,CH-10KMEE00  I90  C1018
   1 P0V9_CPU0_RT3_2A_2D      A @T6G_MB_LIB.T6G(SCH_1):P0V9_CPU0_RT3_2A_2D
   2    GND      B @T6G_MB_LIB.T6G(SCH_1):GND

Q_CAP_0201-1UF,4V,20%,X6S,CH-10KMEE00  I91  C1020
   1 P0V9_CPU0_RT3_2A_2D      A @T6G_MB_LIB.T6G(SCH_1):P0V9_CPU0_RT3_2A_2D
   2    GND      B @T6G_MB_LIB.T6G(SCH_1):GND

Q_CAP_C0201-0.1UF,10V,10%,X7S,CH4102K6E00  I92  C1051
   1 P0V9_CPU0_RT3_2A      A @T6G_MB_LIB.T6G(SCH_1):P0V9_CPU0_RT3_2A
   2    GND      B @T6G_MB_LIB.T6G(SCH_1):GND

Q_CAP_C0201-0.1UF,10V,10%,X7S,CH4102K6E00  I93  C1053
   1 P0V9_CPU0_RT3_2A      A @T6G_MB_LIB.T6G(SCH_1):P0V9_CPU0_RT3_2A
   2    GND      B @T6G_MB_LIB.T6G(SCH_1):GND

Q_CAPP_SMLF-470UF,2.5V,20%,SPCAP,CH747LM8818  I94  C7017
   1 P0V9_CPU0_RT3_2A      A @T6G_MB_LIB.T6G(SCH_1):P0V9_CPU0_RT3_2A
   2    GND      B @T6G_MB_LIB.T6G(SCH_1):GND

Q_CAPP_SMLF-470UF,2.5V,20%,SPCAP,CH747LM8818  I95  C7018
   1 P0V9_CPU0_RT3_2A      A @T6G_MB_LIB.T6G(SCH_1):P0V9_CPU0_RT3_2A
   2    GND      B @T6G_MB_LIB.T6G(SCH_1):GND

Q_CAP_C0805-100UF,4V,20%,X6S,CH710KMEA01  I96  C7019
   1 P0V9_CPU0_RT3_2A      A @T6G_MB_LIB.T6G(SCH_1):P0V9_CPU0_RT3_2A
   2    GND      B @T6G_MB_LIB.T6G(SCH_1):GND


DRAWING: @T6G_MB_LIB.T6G(SCH_1):PAGE340 

Q_RES_0402LF-10K,1%,1/16W,CHIP,CS31002FB08  I2  R9032
   1 P3V3_AUX      A @T6G_MB_LIB.T6G(SCH_1):P3V3_AUX
   2 FM_PLD_OCP_SFF_AUX_PWR_EN      B @T6G_MB_LIB.T6G(SCH_1):FM_PLD_OCP_SFF_AUX_PWR_EN

Q_RES_0402LF-33.2,1%,1/16W,CHIP,CS03322FB03  I3  R9034
   1 OCP_V3_1_P3V3_R3_PWRGD      A @T6G_MB_LIB.T6G(SCH_1):OCP_V3_1_P3V3_R3_PWRGD
   2 HP_LVC3_OCP_V3_1_PWRGD_R1      B @T6G_MB_LIB.T6G(SCH_1):HP_LVC3_OCP_V3_1_PWRGD_R1

Q_RES_0402LF-33.2,1%,1/16W,CHIP,CS03322FB03  I13  R9022
   1 OCP_V3_1_P3V3_R3_PWRGD      A @T6G_MB_LIB.T6G(SCH_1):OCP_V3_1_P3V3_R3_PWRGD
   2 HP_LVC3_OCP_V3_1_PWRGD      B @T6G_MB_LIB.T6G(SCH_1):HP_LVC3_OCP_V3_1_PWRGD

Q_RES_0402LF-33.2,1%,1/16W,CHIP,CS03322FB03  I14  R9023
   1 RST_PERST_OCP_SFF_N      A @T6G_MB_LIB.T6G(SCH_1):RST_PERST_OCP_SFF_N
   2 RST_PERST_OCP_SFF_R_N      B @T6G_MB_LIB.T6G(SCH_1):RST_PERST_OCP_SFF_R_N

Q_RES_0402LF-0,5%,1/16W,EMPTY,CS00002JB13  I15  R9030
   1 OCP_SFF_AUX_PWR_EN_R3      A @T6G_MB_LIB.T6G(SCH_1):OCP_SFF_AUX_PWR_EN_R3
   2 FM_PLD_OCP_SFF_AUX_PWR_EN      B @T6G_MB_LIB.T6G(SCH_1):FM_PLD_OCP_SFF_AUX_PWR_EN

Q_RES_0402LF-0,5%,1/16W,EMPTY,CS00002JB13  I18  R9029
   1 OCP_SFF_AUX_PWR_EN_R3      A @T6G_MB_LIB.T6G(SCH_1):OCP_SFF_AUX_PWR_EN_R3
   2 HP_LVC3_OCP_V3_1_PWRGD_R1      B @T6G_MB_LIB.T6G(SCH_1):HP_LVC3_OCP_V3_1_PWRGD_R1

Q_RES_0402LF-33.2,1%,1/16W,CHIP,CS03322FB03  I22  R9031
   1 OCP_SFF_AUX_PWR_EN_R3      A @T6G_MB_LIB.T6G(SCH_1):OCP_SFF_AUX_PWR_EN_R3
   2 OCP_SFF_AUX_PWR_EN      B @T6G_MB_LIB.T6G(SCH_1):OCP_SFF_AUX_PWR_EN

74LVC1G08W57-74LVC1G08W5-7,SMLF,IC,AL1G0008020  I25  U9001
   1 RST_PERST_OCP_SFF_R_N      A @T6G_MB_LIB.T6G(SCH_1):RST_PERST_OCP_SFF_R_N
   2 HP_LVC3_OCP_V3_1_PWRGD      B @T6G_MB_LIB.T6G(SCH_1):HP_LVC3_OCP_V3_1_PWRGD
   3    GND    GND @T6G_MB_LIB.T6G(SCH_1):GND
   4 RST_PERST_OCP_SFF_BUF_R_N      Y @T6G_MB_LIB.T6G(SCH_1):RST_PERST_OCP_SFF_BUF_R_N
   5 P3V3_AUX    VCC @T6G_MB_LIB.T6G(SCH_1):P3V3_AUX

Q_CAP_0402-0.1UF,25V,10%,X7R,CH4104K1B00  I27  C9007
   1 P3V3_AUX      A @T6G_MB_LIB.T6G(SCH_1):P3V3_AUX
   2    GND      B @T6G_MB_LIB.T6G(SCH_1):GND

Q_RES_0402LF-33.2,1%,1/16W,CHIP,CS03322FB03  I29  R9033
   1 RST_PERST_OCP_SFF_BUF_R_N      A @T6G_MB_LIB.T6G(SCH_1):RST_PERST_OCP_SFF_BUF_R_N
   2 RST_PERST_OCP_SFF_BUF_N      B @T6G_MB_LIB.T6G(SCH_1):RST_PERST_OCP_SFF_BUF_N

MOSFET_N_SMLF-BSS138K,BSS138K,IC,BAM138K0000  I31  U24
   G HP_LVC3_OCP_SFF_PRSNT2_N   GATE @T6G_MB_LIB.T6G(SCH_1):HP_LVC3_OCP_SFF_PRSNT2_N
   D HP_LVC3_OCP_SFF_PRSNT2  DRAIN @T6G_MB_LIB.T6G(SCH_1):HP_LVC3_OCP_SFF_PRSNT2
   S    GND SOURCE @T6G_MB_LIB.T6G(SCH_1):GND

Q_RES_0402LF-1K,1%,1/16W,CHIP,CS21002FB06  I34  R1128
   1 P3V3_AUX      A @T6G_MB_LIB.T6G(SCH_1):P3V3_AUX
   2 HP_LVC3_OCP_SFF_PRSNT2      B @T6G_MB_LIB.T6G(SCH_1):HP_LVC3_OCP_SFF_PRSNT2

74LVC1G08W57-74LVC1G08W5-7,SMLF,IC,AL1G0008020  I36  U23
   1 P12V_OCP_SFF_EN_R3      A @T6G_MB_LIB.T6G(SCH_1):P12V_OCP_SFF_EN_R3
   2 HP_LVC3_OCP_SFF_PRSNT2      B @T6G_MB_LIB.T6G(SCH_1):HP_LVC3_OCP_SFF_PRSNT2
   3    GND    GND @T6G_MB_LIB.T6G(SCH_1):GND
   4 P12V_OCP_SFF_BUF_EN      Y @T6G_MB_LIB.T6G(SCH_1):P12V_OCP_SFF_BUF_EN
   5 P3V3_AUX    VCC @T6G_MB_LIB.T6G(SCH_1):P3V3_AUX

Q_CAP_0402-0.1UF,25V,10%,X7R,CH4104K1B00  I40  C1059
   1 P3V3_AUX      A @T6G_MB_LIB.T6G(SCH_1):P3V3_AUX
   2    GND      B @T6G_MB_LIB.T6G(SCH_1):GND

Q_RES_0402LF-1K,1%,1/16W,CHIP,CS21002FB06  I44  R1131
   1 P3V3_AUX      A @T6G_MB_LIB.T6G(SCH_1):P3V3_AUX
   2 P12V_OCP_SFF_EN_R3      B @T6G_MB_LIB.T6G(SCH_1):P12V_OCP_SFF_EN_R3

Q_RES_0402LF-0,5%,1/16W,CHIP,CS00002JB13  I47  R1134
   1 P12V_OCP_SFF_BUF_EN      A @T6G_MB_LIB.T6G(SCH_1):P12V_OCP_SFF_BUF_EN
   2 P12V_OCP_SFF_BUF_EN_R      B @T6G_MB_LIB.T6G(SCH_1):P12V_OCP_SFF_BUF_EN_R

Q_RES_0402LF-0,5%,1/16W,EMPTY,CS00002JB13  I49  R1130
   1 P12V_OCP_SFF_EN_R      A @T6G_MB_LIB.T6G(SCH_1):P12V_OCP_SFF_EN_R
   2 P12V_OCP_SFF_EN_R3      B @T6G_MB_LIB.T6G(SCH_1):P12V_OCP_SFF_EN_R3

SN74LVC1G07DBVR_SMLF-SN74LVC1G07DBVR,IC,AL1G0007024  I51  U28
   2 HP_LVC3_OCP_V3_1_P12V_R_PWRGD      A @T6G_MB_LIB.T6G(SCH_1):HP_LVC3_OCP_V3_1_P12V_R_PWRGD
   4 P12V_OCP_V3_1_PLD_R_PWRGD      Y @T6G_MB_LIB.T6G(SCH_1):P12V_OCP_V3_1_PLD_R_PWRGD
   1     NC     NC     NC
   5 P3V3_AUX    VCC @T6G_MB_LIB.T6G(SCH_1):P3V3_AUX
   3    GND    GND @T6G_MB_LIB.T6G(SCH_1):GND

Q_CAP_0402-0.1UF,25V,10%,X7R,CH4104K1B00  I53  C1058
   1 P3V3_AUX      A @T6G_MB_LIB.T6G(SCH_1):P3V3_AUX
   2    GND      B @T6G_MB_LIB.T6G(SCH_1):GND

Q_RES_0402LF-0,5%,1/16W,CHIP,CS00002JB13  I57  R1129
   1 HP_LVC3_OCP_V3_1_P12V_PWRGD      A @T6G_MB_LIB.T6G(SCH_1):HP_LVC3_OCP_V3_1_P12V_PWRGD
   2 HP_LVC3_OCP_V3_1_P12V_R_PWRGD      B @T6G_MB_LIB.T6G(SCH_1):HP_LVC3_OCP_V3_1_P12V_R_PWRGD

Q_RES_0402LF-0,5%,1/16W,CHIP,CS00002JB13  I58  R1132
   1 P12V_OCP_V3_1_PLD_R_PWRGD      A @T6G_MB_LIB.T6G(SCH_1):P12V_OCP_V3_1_PLD_R_PWRGD
   2 P12V_OCP_V3_1_PLD_PWRGD      B @T6G_MB_LIB.T6G(SCH_1):P12V_OCP_V3_1_PLD_PWRGD

Q_RES_0402LF-1K,1%,1/16W,CHIP,CS21002FB06  I61  R1133
   1 P3V3_AUX      A @T6G_MB_LIB.T6G(SCH_1):P3V3_AUX
   2 P12V_OCP_V3_1_PLD_PWRGD      B @T6G_MB_LIB.T6G(SCH_1):P12V_OCP_V3_1_PLD_PWRGD

Q_RES_0402LF-1K,1%,1/16W,CHIP,CS21002FB06  I64  R1144
   1 P3V3_AUX      A @T6G_MB_LIB.T6G(SCH_1):P3V3_AUX
   2 OCP_V3_1_P3V3_PLD_R_PWRGD      B @T6G_MB_LIB.T6G(SCH_1):OCP_V3_1_P3V3_PLD_R_PWRGD

Q_RES_0402LF-0,5%,1/16W,CHIP,CS00002JB13  I65  R1143
   1 OCP_V3_1_P3V3_PLD_PWRGD      A @T6G_MB_LIB.T6G(SCH_1):OCP_V3_1_P3V3_PLD_PWRGD
   2 OCP_V3_1_P3V3_PLD_R_PWRGD      B @T6G_MB_LIB.T6G(SCH_1):OCP_V3_1_P3V3_PLD_R_PWRGD

SN74LVC1G07DBVR_SMLF-SN74LVC1G07DBVR,IC,AL1G0007024  I66  U30
   2 OCP_V3_1_P3V3_R2_PWRGD      A @T6G_MB_LIB.T6G(SCH_1):OCP_V3_1_P3V3_R2_PWRGD
   4 OCP_V3_1_P3V3_PLD_PWRGD      Y @T6G_MB_LIB.T6G(SCH_1):OCP_V3_1_P3V3_PLD_PWRGD
   1     NC     NC     NC
   5 P3V3_AUX    VCC @T6G_MB_LIB.T6G(SCH_1):P3V3_AUX
   3    GND    GND @T6G_MB_LIB.T6G(SCH_1):GND

Q_CAP_0402-0.1UF,25V,10%,X7R,CH4104K1B00  I69  C1060
   1 P3V3_AUX      A @T6G_MB_LIB.T6G(SCH_1):P3V3_AUX
   2    GND      B @T6G_MB_LIB.T6G(SCH_1):GND

Q_RES_0402LF-0,5%,1/16W,CHIP,CS00002JB13  I71  R1142
   1 OCP_V3_1_P3V3_PWRGD      A @T6G_MB_LIB.T6G(SCH_1):OCP_V3_1_P3V3_PWRGD
   2 OCP_V3_1_P3V3_R2_PWRGD      B @T6G_MB_LIB.T6G(SCH_1):OCP_V3_1_P3V3_R2_PWRGD

74LVC1G32GW_SMLF-74LVC1G32GW,IC,ALVC1G32007  I74  U9002
   1 HP_LVC3_OCP_V3_1_PWRGD_R1     I0 @T6G_MB_LIB.T6G(SCH_1):HP_LVC3_OCP_V3_1_PWRGD_R1
   2 FM_PLD_OCP_SFF_AUX_PWR_EN     I1 @T6G_MB_LIB.T6G(SCH_1):FM_PLD_OCP_SFF_AUX_PWR_EN
   4 OCP_SFF_AUX_PWR_EN_R3      O @T6G_MB_LIB.T6G(SCH_1):OCP_SFF_AUX_PWR_EN_R3
   5 P3V3_AUX    VCC @T6G_MB_LIB.T6G(SCH_1):P3V3_AUX
   3    GND    GND @T6G_MB_LIB.T6G(SCH_1):GND

Q_CAP_0402-0.1UF,25V,10%,X7R,CH4104K1B00  I75  C9008
   1 P3V3_AUX      A @T6G_MB_LIB.T6G(SCH_1):P3V3_AUX
   2    GND      B @T6G_MB_LIB.T6G(SCH_1):GND

Q_RES_0402LF-10K,5%,1/16W,EMPTY,CS31002JB08  I76  R1145
   1 P3V3_AUX      A @T6G_MB_LIB.T6G(SCH_1):P3V3_AUX
   2 OCP_SFF_AUX_PWR_EN      B @T6G_MB_LIB.T6G(SCH_1):OCP_SFF_AUX_PWR_EN

Q_CAP_0402-0.1UF,25V,10%,X7R,CH4104K1B00  I79  C8008
   1 P3V3_OCP_SFF_R      A @T6G_MB_LIB.T6G(SCH_1):P3V3_OCP_SFF_R
   2    GND      B @T6G_MB_LIB.T6G(SCH_1):GND

APX80929SAG7-APX809-29SAG-7,SMLF,IC,AL080929000  I80  U8001
   3 P3V3_OCP_SFF_R    VCC @T6G_MB_LIB.T6G(SCH_1):P3V3_OCP_SFF_R
   2 OCP_V3_1_P3V3_R1_PWRGD RESET_L @T6G_MB_LIB.T6G(SCH_1):OCP_V3_1_P3V3_R1_PWRGD
   1    GND    GND @T6G_MB_LIB.T6G(SCH_1):GND

Q_RES_0402LF-100K,1%,1/16W,CHIP,CS41002FB09  I84  R8093
   1 OCP_V3_1_P3V3_R1_PWRGD      A @T6G_MB_LIB.T6G(SCH_1):OCP_V3_1_P3V3_R1_PWRGD
   2    GND      B @T6G_MB_LIB.T6G(SCH_1):GND

Q_RES_0402LF-0,5%,1/16W,CHIP,CS00002JB13  I85  R8094
   1 OCP_V3_1_P3V3_R1_PWRGD      A @T6G_MB_LIB.T6G(SCH_1):OCP_V3_1_P3V3_R1_PWRGD
   2 OCP_V3_1_P3V3_PWRGD      B @T6G_MB_LIB.T6G(SCH_1):OCP_V3_1_P3V3_PWRGD

Q_RES_0402LF-10K,5%,1/16W,EMPTY,CS31002JB08  I90  R8092
   1 P3V3_OCP_SFF_R      A @T6G_MB_LIB.T6G(SCH_1):P3V3_OCP_SFF_R
   2 OCP_V3_1_P3V3_R1_PWRGD      B @T6G_MB_LIB.T6G(SCH_1):OCP_V3_1_P3V3_R1_PWRGD

74LVC1G08W57-74LVC1G08W5-7,SMLF,IC,AL1G0008020  I91  U9050
   1 OCP_V3_1_P3V3_PWRGD      A @T6G_MB_LIB.T6G(SCH_1):OCP_V3_1_P3V3_PWRGD
   2 HP_LVC3_OCP_V3_1_P12V_R2_PWRGD      B @T6G_MB_LIB.T6G(SCH_1):HP_LVC3_OCP_V3_1_P12V_R2_PWRGD
   3    GND    GND @T6G_MB_LIB.T6G(SCH_1):GND
   4 HP_LVC3_OCP_V3_1_PWRGD_R2      Y @T6G_MB_LIB.T6G(SCH_1):HP_LVC3_OCP_V3_1_PWRGD_R2
   5 P3V3_AUX    VCC @T6G_MB_LIB.T6G(SCH_1):P3V3_AUX

Q_CAP_0402-0.1UF,25V,10%,X7R,CH4104K1B00  I94  C9050
   1 P3V3_AUX      A @T6G_MB_LIB.T6G(SCH_1):P3V3_AUX
   2    GND      B @T6G_MB_LIB.T6G(SCH_1):GND

Q_RES_0402LF-0,5%,1/16W,CHIP,CS00002JB13  I96  R1509
   1 HP_LVC3_OCP_V3_1_P12V_PWRGD      A @T6G_MB_LIB.T6G(SCH_1):HP_LVC3_OCP_V3_1_P12V_PWRGD
   2 HP_LVC3_OCP_V3_1_P12V_R2_PWRGD      B @T6G_MB_LIB.T6G(SCH_1):HP_LVC3_OCP_V3_1_P12V_R2_PWRGD

Q_RES_0402LF-0,5%,1/16W,EMPTY,CS00002JB13  I101  R1519
   1 OCP_V3_1_P3V3_R3_PWRGD      A @T6G_MB_LIB.T6G(SCH_1):OCP_V3_1_P3V3_R3_PWRGD
   2 OCP_V3_1_P3V3_PWRGD      B @T6G_MB_LIB.T6G(SCH_1):OCP_V3_1_P3V3_PWRGD

Q_RES_0402LF-0,5%,1/16W,CHIP,CS00002JB13  I102  R1518
   1 HP_LVC3_OCP_V3_1_PWRGD_R2      A @T6G_MB_LIB.T6G(SCH_1):HP_LVC3_OCP_V3_1_PWRGD_R2
   2 OCP_V3_1_P3V3_R3_PWRGD      B @T6G_MB_LIB.T6G(SCH_1):OCP_V3_1_P3V3_R3_PWRGD


DRAWING: @T6G_MB_LIB.T6G(SCH_1):PAGE257 

Q_RES_0402LF-0,5%,1/16W,CHIP,CS00002JB13  I3  R1163
   1 HP_LVC3_OCP_V3_2_P12V_PWRGD      A @T6G_MB_LIB.T6G(SCH_1):HP_LVC3_OCP_V3_2_P12V_PWRGD
   2 HP_LVC3_OCP_V3_2_P12V_R_PWRGD      B @T6G_MB_LIB.T6G(SCH_1):HP_LVC3_OCP_V3_2_P12V_R_PWRGD

Q_CAP_0402-0.1UF,25V,10%,X7R,CH4104K1B00  I5  C1061
   1 P3V3_AUX      A @T6G_MB_LIB.T6G(SCH_1):P3V3_AUX
   2    GND      B @T6G_MB_LIB.T6G(SCH_1):GND

Q_RES_0402LF-10K,1%,1/16W,CHIP,CS31002FB08  I10  R1176
   1 P3V3_AUX      A @T6G_MB_LIB.T6G(SCH_1):P3V3_AUX
   2 FM_OCP_V3_2_AUX_PWR_R_EN      B @T6G_MB_LIB.T6G(SCH_1):FM_OCP_V3_2_AUX_PWR_R_EN

Q_RES_0402LF-33.2,1%,1/16W,CHIP,CS03322FB03  I12  R1178
   1 OCP_V3_2_P3V3_R3_PWRGD      A @T6G_MB_LIB.T6G(SCH_1):OCP_V3_2_P3V3_R3_PWRGD
   2 HP_LVC3_OCP_V3_2_PWRGD_R1      B @T6G_MB_LIB.T6G(SCH_1):HP_LVC3_OCP_V3_2_PWRGD_R1

Q_CAP_0402-0.1UF,25V,10%,X7R,CH4104K1B00  I14  C1065
   1 P3V3_AUX      A @T6G_MB_LIB.T6G(SCH_1):P3V3_AUX
   2    GND      B @T6G_MB_LIB.T6G(SCH_1):GND

Q_RES_0402LF-33.2,1%,1/16W,CHIP,CS03322FB03  I16  R1173
   1 OCP_V3_2_P3V3_R3_PWRGD      A @T6G_MB_LIB.T6G(SCH_1):OCP_V3_2_P3V3_R3_PWRGD
   2 HP_LVC3_OCP_V3_2_PWRGD      B @T6G_MB_LIB.T6G(SCH_1):HP_LVC3_OCP_V3_2_PWRGD

Q_RES_0402LF-33.2,1%,1/16W,CHIP,CS03322FB03  I17  R1174
   1 RST_PERST_OCP_V3_2_N      A @T6G_MB_LIB.T6G(SCH_1):RST_PERST_OCP_V3_2_N
   2 RST_PERST_OCP_V3_2_R_N      B @T6G_MB_LIB.T6G(SCH_1):RST_PERST_OCP_V3_2_R_N

Q_RES_0402LF-0,5%,1/16W,CHIP,CS00002JB13  I18  R1166
   1 P12V_OCP_V3_2_PLD_R_PWRGD      A @T6G_MB_LIB.T6G(SCH_1):P12V_OCP_V3_2_PLD_R_PWRGD
   2 P12V_OCP_V3_2_PLD_PWRGD      B @T6G_MB_LIB.T6G(SCH_1):P12V_OCP_V3_2_PLD_PWRGD

Q_RES_0402LF-1K,1%,1/16W,CHIP,CS21002FB06  I19  R1167
   1 P3V3_AUX      A @T6G_MB_LIB.T6G(SCH_1):P3V3_AUX
   2 P12V_OCP_V3_2_PLD_PWRGD      B @T6G_MB_LIB.T6G(SCH_1):P12V_OCP_V3_2_PLD_PWRGD

MOSFET_N_SMLF-BSS138K,BSS138K,IC,BAM138K0000  I24  U32
   G HP_LVC3_OCP_V3_2_PRSNT2_N   GATE @T6G_MB_LIB.T6G(SCH_1):HP_LVC3_OCP_V3_2_PRSNT2_N
   D HP_LVC3_OCP_V3_2_PRSNT2  DRAIN @T6G_MB_LIB.T6G(SCH_1):HP_LVC3_OCP_V3_2_PRSNT2
   S    GND SOURCE @T6G_MB_LIB.T6G(SCH_1):GND

Q_RES_0402LF-1K,1%,1/16W,CHIP,CS21002FB06  I25  R1149
   1 P3V3_AUX      A @T6G_MB_LIB.T6G(SCH_1):P3V3_AUX
   2 HP_LVC3_OCP_V3_2_PRSNT2      B @T6G_MB_LIB.T6G(SCH_1):HP_LVC3_OCP_V3_2_PRSNT2

Q_RES_0402LF-0,5%,1/16W,EMPTY,CS00002JB13  I28  R1164
   1 P12V_OCP_V3_2_EN_R      A @T6G_MB_LIB.T6G(SCH_1):P12V_OCP_V3_2_EN_R
   2 P12V_OCP_V3_2_EN_R3      B @T6G_MB_LIB.T6G(SCH_1):P12V_OCP_V3_2_EN_R3

74LVC1G08W57-74LVC1G08W5-7,SMLF,IC,AL1G0008020  I31  U31
   1 P12V_OCP_V3_2_EN_R3      A @T6G_MB_LIB.T6G(SCH_1):P12V_OCP_V3_2_EN_R3
   2 HP_LVC3_OCP_V3_2_PRSNT2      B @T6G_MB_LIB.T6G(SCH_1):HP_LVC3_OCP_V3_2_PRSNT2
   3    GND    GND @T6G_MB_LIB.T6G(SCH_1):GND
   4 P12V_OCP_V3_2_BUF_EN      Y @T6G_MB_LIB.T6G(SCH_1):P12V_OCP_V3_2_BUF_EN
   5 P3V3_AUX    VCC @T6G_MB_LIB.T6G(SCH_1):P3V3_AUX

Q_RES_0402LF-1K,1%,1/16W,CHIP,CS21002FB06  I32  R1165
   1 P3V3_AUX      A @T6G_MB_LIB.T6G(SCH_1):P3V3_AUX
   2 P12V_OCP_V3_2_EN_R3      B @T6G_MB_LIB.T6G(SCH_1):P12V_OCP_V3_2_EN_R3

Q_RES_0402LF-0,5%,1/16W,CHIP,CS00002JB13  I34  R1169
   1 OCP_V3_2_P3V3_PWRGD      A @T6G_MB_LIB.T6G(SCH_1):OCP_V3_2_P3V3_PWRGD
   2 OCP_V3_2_P3V3_R2_PWRGD      B @T6G_MB_LIB.T6G(SCH_1):OCP_V3_2_P3V3_R2_PWRGD

Q_CAP_0402-0.1UF,25V,10%,X7R,CH4104K1B00  I36  C1062
   1 P3V3_AUX      A @T6G_MB_LIB.T6G(SCH_1):P3V3_AUX
   2    GND      B @T6G_MB_LIB.T6G(SCH_1):GND

Q_RES_0402LF-0,5%,1/16W,EMPTY,CS00002JB13  I39  R1147
   1 OCP_V3_2_AUX_PWR_EN_R2      A @T6G_MB_LIB.T6G(SCH_1):OCP_V3_2_AUX_PWR_EN_R2
   2 FM_OCP_V3_2_AUX_PWR_R_EN      B @T6G_MB_LIB.T6G(SCH_1):FM_OCP_V3_2_AUX_PWR_R_EN

74LVC1G32GW_SMLF-74LVC1G32GW,IC,ALVC1G32007  I40  U37
   1 HP_LVC3_OCP_V3_2_PWRGD_R1     I0 @T6G_MB_LIB.T6G(SCH_1):HP_LVC3_OCP_V3_2_PWRGD_R1
   2 FM_OCP_V3_2_AUX_PWR_R_EN     I1 @T6G_MB_LIB.T6G(SCH_1):FM_OCP_V3_2_AUX_PWR_R_EN
   4 OCP_V3_2_AUX_PWR_EN_R2      O @T6G_MB_LIB.T6G(SCH_1):OCP_V3_2_AUX_PWR_EN_R2
   5 P3V3_AUX    VCC @T6G_MB_LIB.T6G(SCH_1):P3V3_AUX
   3    GND    GND @T6G_MB_LIB.T6G(SCH_1):GND

Q_RES_0402LF-0,5%,1/16W,EMPTY,CS00002JB13  I41  R1146
   1 OCP_V3_2_AUX_PWR_EN_R2      A @T6G_MB_LIB.T6G(SCH_1):OCP_V3_2_AUX_PWR_EN_R2
   2 HP_LVC3_OCP_V3_2_PWRGD_R1      B @T6G_MB_LIB.T6G(SCH_1):HP_LVC3_OCP_V3_2_PWRGD_R1

Q_RES_0402LF-33.2,1%,1/16W,CHIP,CS03322FB03  I42  R1175
   1 OCP_V3_2_AUX_PWR_EN_R2      A @T6G_MB_LIB.T6G(SCH_1):OCP_V3_2_AUX_PWR_EN_R2
   2 OCP_V3_2_AUX_PWR_EN      B @T6G_MB_LIB.T6G(SCH_1):OCP_V3_2_AUX_PWR_EN

SN74LVC1G07DBVR_SMLF-SN74LVC1G07DBVR,IC,AL1G0007024  I45  U34
   2 OCP_V3_2_P3V3_R2_PWRGD      A @T6G_MB_LIB.T6G(SCH_1):OCP_V3_2_P3V3_R2_PWRGD
   4 OCP_V3_2_P3V3_PLD_PWRGD      Y @T6G_MB_LIB.T6G(SCH_1):OCP_V3_2_P3V3_PLD_PWRGD
   1     NC     NC     NC
   5 P3V3_AUX    VCC @T6G_MB_LIB.T6G(SCH_1):P3V3_AUX
   3    GND    GND @T6G_MB_LIB.T6G(SCH_1):GND

Q_CAP_0402-0.1UF,25V,10%,X7R,CH4104K1B00  I46  C1064
   1 P3V3_AUX      A @T6G_MB_LIB.T6G(SCH_1):P3V3_AUX
   2    GND      B @T6G_MB_LIB.T6G(SCH_1):GND

Q_RES_0402LF-33.2,1%,1/16W,CHIP,CS03322FB03  I49  R1177
   1 RST_PERST_OCP_V3_2_BUF_R_N      A @T6G_MB_LIB.T6G(SCH_1):RST_PERST_OCP_V3_2_BUF_R_N
   2 RST_PERST_OCP_V3_2_BUF_N      B @T6G_MB_LIB.T6G(SCH_1):RST_PERST_OCP_V3_2_BUF_N

Q_RES_0402LF-10K,5%,1/16W,EMPTY,CS31002JB08  I51  R1172
   1 P3V3_AUX      A @T6G_MB_LIB.T6G(SCH_1):P3V3_AUX
   2 OCP_V3_2_AUX_PWR_EN      B @T6G_MB_LIB.T6G(SCH_1):OCP_V3_2_AUX_PWR_EN

Q_CAP_0402-0.1UF,25V,10%,X7R,CH4104K1B00  I55  C1063
   1 P3V3_AUX      A @T6G_MB_LIB.T6G(SCH_1):P3V3_AUX
   2    GND      B @T6G_MB_LIB.T6G(SCH_1):GND

Q_RES_0402LF-0,5%,1/16W,CHIP,CS00002JB13  I57  R1168
   1 P12V_OCP_V3_2_BUF_EN      A @T6G_MB_LIB.T6G(SCH_1):P12V_OCP_V3_2_BUF_EN
   2 P12V_OCP_V3_2_BUF_EN_R      B @T6G_MB_LIB.T6G(SCH_1):P12V_OCP_V3_2_BUF_EN_R

Q_RES_0402LF-0,5%,1/16W,CHIP,CS00002JB13  I58  R1170
   1 OCP_V3_2_P3V3_PLD_PWRGD      A @T6G_MB_LIB.T6G(SCH_1):OCP_V3_2_P3V3_PLD_PWRGD
   2 OCP_V3_2_P3V3_PLD_R_PWRGD      B @T6G_MB_LIB.T6G(SCH_1):OCP_V3_2_P3V3_PLD_R_PWRGD

Q_RES_0402LF-1K,1%,1/16W,CHIP,CS21002FB06  I60  R1171
   1 P3V3_AUX      A @T6G_MB_LIB.T6G(SCH_1):P3V3_AUX
   2 OCP_V3_2_P3V3_PLD_R_PWRGD      B @T6G_MB_LIB.T6G(SCH_1):OCP_V3_2_P3V3_PLD_R_PWRGD

74LVC1G08W57-74LVC1G08W5-7,SMLF,IC,AL1G0008020  I63  U35
   1 RST_PERST_OCP_V3_2_R_N      A @T6G_MB_LIB.T6G(SCH_1):RST_PERST_OCP_V3_2_R_N
   2 HP_LVC3_OCP_V3_2_PWRGD      B @T6G_MB_LIB.T6G(SCH_1):HP_LVC3_OCP_V3_2_PWRGD
   3    GND    GND @T6G_MB_LIB.T6G(SCH_1):GND
   4 RST_PERST_OCP_V3_2_BUF_R_N      Y @T6G_MB_LIB.T6G(SCH_1):RST_PERST_OCP_V3_2_BUF_R_N
   5 P3V3_AUX    VCC @T6G_MB_LIB.T6G(SCH_1):P3V3_AUX

SN74LVC1G07DBVR_SMLF-SN74LVC1G07DBVR,IC,AL1G0007024  I64  U33
   2 HP_LVC3_OCP_V3_2_P12V_R_PWRGD      A @T6G_MB_LIB.T6G(SCH_1):HP_LVC3_OCP_V3_2_P12V_R_PWRGD
   4 P12V_OCP_V3_2_PLD_R_PWRGD      Y @T6G_MB_LIB.T6G(SCH_1):P12V_OCP_V3_2_PLD_R_PWRGD
   1     NC     NC     NC
   5 P3V3_AUX    VCC @T6G_MB_LIB.T6G(SCH_1):P3V3_AUX
   3    GND    GND @T6G_MB_LIB.T6G(SCH_1):GND

Q_CAP_0402-0.1UF,25V,10%,X7R,CH4104K1B00  I66  C8009
   1 P3V3_OCP_V3_2_R      A @T6G_MB_LIB.T6G(SCH_1):P3V3_OCP_V3_2_R
   2    GND      B @T6G_MB_LIB.T6G(SCH_1):GND

APX80929SAG7-APX809-29SAG-7,SMLF,IC,AL080929000  I67  U8002
   3 P3V3_OCP_V3_2_R    VCC @T6G_MB_LIB.T6G(SCH_1):P3V3_OCP_V3_2_R
   2 OCP_V3_2_P3V3_R1_PWRGD RESET_L @T6G_MB_LIB.T6G(SCH_1):OCP_V3_2_P3V3_R1_PWRGD
   1    GND    GND @T6G_MB_LIB.T6G(SCH_1):GND

Q_RES_0402LF-100K,1%,1/16W,CHIP,CS41002FB09  I70  R8096
   1 OCP_V3_2_P3V3_R1_PWRGD      A @T6G_MB_LIB.T6G(SCH_1):OCP_V3_2_P3V3_R1_PWRGD
   2    GND      B @T6G_MB_LIB.T6G(SCH_1):GND

Q_RES_0402LF-0,5%,1/16W,CHIP,CS00002JB13  I73  R8097
   1 OCP_V3_2_P3V3_R1_PWRGD      A @T6G_MB_LIB.T6G(SCH_1):OCP_V3_2_P3V3_R1_PWRGD
   2 OCP_V3_2_P3V3_PWRGD      B @T6G_MB_LIB.T6G(SCH_1):OCP_V3_2_P3V3_PWRGD

Q_RES_0402LF-10K,5%,1/16W,EMPTY,CS31002JB08  I77  R8095
   1 P3V3_OCP_V3_2_R      A @T6G_MB_LIB.T6G(SCH_1):P3V3_OCP_V3_2_R
   2 OCP_V3_2_P3V3_R1_PWRGD      B @T6G_MB_LIB.T6G(SCH_1):OCP_V3_2_P3V3_R1_PWRGD

74LVC1G08W57-74LVC1G08W5-7,SMLF,IC,AL1G0008020  I78  U9051
   1 OCP_V3_2_P3V3_PWRGD      A @T6G_MB_LIB.T6G(SCH_1):OCP_V3_2_P3V3_PWRGD
   2 HP_LVC3_OCP_V3_2_P12V_PWRGD_R2      B @T6G_MB_LIB.T6G(SCH_1):HP_LVC3_OCP_V3_2_P12V_PWRGD_R2
   3    GND    GND @T6G_MB_LIB.T6G(SCH_1):GND
   4 HP_LVC3_OCP_V3_2_PWRGD_R2      Y @T6G_MB_LIB.T6G(SCH_1):HP_LVC3_OCP_V3_2_PWRGD_R2
   5 P3V3_AUX    VCC @T6G_MB_LIB.T6G(SCH_1):P3V3_AUX

Q_CAP_0402-0.1UF,25V,10%,X7R,CH4104K1B00  I81  C9051
   1 P3V3_AUX      A @T6G_MB_LIB.T6G(SCH_1):P3V3_AUX
   2    GND      B @T6G_MB_LIB.T6G(SCH_1):GND

Q_RES_0402LF-0,5%,1/16W,CHIP,CS00002JB13  I84  R1523
   1 HP_LVC3_OCP_V3_2_P12V_PWRGD      A @T6G_MB_LIB.T6G(SCH_1):HP_LVC3_OCP_V3_2_P12V_PWRGD
   2 HP_LVC3_OCP_V3_2_P12V_PWRGD_R2      B @T6G_MB_LIB.T6G(SCH_1):HP_LVC3_OCP_V3_2_P12V_PWRGD_R2

Q_RES_0402LF-0,5%,1/16W,EMPTY,CS00002JB13  I88  R1525
   1 OCP_V3_2_P3V3_PWRGD      A @T6G_MB_LIB.T6G(SCH_1):OCP_V3_2_P3V3_PWRGD
   2 OCP_V3_2_P3V3_R3_PWRGD      B @T6G_MB_LIB.T6G(SCH_1):OCP_V3_2_P3V3_R3_PWRGD

Q_RES_0402LF-0,5%,1/16W,CHIP,CS00002JB13  I89  R1524
   1 HP_LVC3_OCP_V3_2_PWRGD_R2      A @T6G_MB_LIB.T6G(SCH_1):HP_LVC3_OCP_V3_2_PWRGD_R2
   2 OCP_V3_2_P3V3_R3_PWRGD      B @T6G_MB_LIB.T6G(SCH_1):OCP_V3_2_P3V3_R3_PWRGD


DRAWING: @T6G_MB_LIB.T6G(SCH_1):PAGE376 

PI3CSW12ZUAEX-PI3CSW12ZUAEX,SMLF,IC,AL3CSW12000  I22  U45
   1 SMB_RT_CPU1_P0_ROM_MUX_1D_SCL    1D+ @T6G_MB_LIB.T6G(SCH_1):SMB_RT_CPU1_P0_ROM_MUX_1D_SCL
   3 SMB_RT_CPU1_P0_ROM_MUX_2D_SCL    2D+ @T6G_MB_LIB.T6G(SCH_1):SMB_RT_CPU1_P0_ROM_MUX_2D_SCL
   4 SMB_RT_CPU1_P0_ROM_MUX_2D_SDA    2D- @T6G_MB_LIB.T6G(SCH_1):SMB_RT_CPU1_P0_ROM_MUX_2D_SDA
   7 SMB_RT_CPU1_P0_ROM_R_SDA     D- @T6G_MB_LIB.T6G(SCH_1):SMB_RT_CPU1_P0_ROM_R_SDA
   6 RT_ROM_MUX1_OE_N    OE# @T6G_MB_LIB.T6G(SCH_1):RT_ROM_MUX1_OE_N
   9 FM_SMB_RT_ROM_MUX1_SEL      S @T6G_MB_LIB.T6G(SCH_1):FM_SMB_RT_ROM_MUX1_SEL
  10 P3V3_AUX    VDD @T6G_MB_LIB.T6G(SCH_1):P3V3_AUX
   2 SMB_RT_CPU1_P0_ROM_MUX_1D_SDA    1D- @T6G_MB_LIB.T6G(SCH_1):SMB_RT_CPU1_P0_ROM_MUX_1D_SDA
   5    GND    GND @T6G_MB_LIB.T6G(SCH_1):GND
   8 SMB_RT_CPU1_P0_ROM_R_SCL     D+ @T6G_MB_LIB.T6G(SCH_1):SMB_RT_CPU1_P0_ROM_R_SCL

Q_CAP_C0201-0.1UF,10V,10%,X7S,CH4102K6E00  I24  C1069
   1 P3V3_AUX      A @T6G_MB_LIB.T6G(SCH_1):P3V3_AUX
   2    GND      B @T6G_MB_LIB.T6G(SCH_1):GND

Q_RES_0201LF-1K,1%,1/20W,CHIP,CS21001FE07  I28  R1215
   1    GND      A @T6G_MB_LIB.T6G(SCH_1):GND
   2 RT_ROM_MUX1_OE_N      B @T6G_MB_LIB.T6G(SCH_1):RT_ROM_MUX1_OE_N

Q_RES_0201LF-0,5%,1/20W,CHIP,CS00001JE10  I30  R1201
   1 RST_SMB_RT_ROM_R1_N      A @T6G_MB_LIB.T6G(SCH_1):RST_SMB_RT_ROM_R1_N
   2 FM_SMB_RT_ROM_MUX1_SEL      B @T6G_MB_LIB.T6G(SCH_1):FM_SMB_RT_ROM_MUX1_SEL

PI3CSW12ZUAEX-PI3CSW12ZUAEX,SMLF,IC,AL3CSW12000  I31  U42
   1 SMB_RT_CPU1_P1_ROM_MUX_1D_SCL    1D+ @T6G_MB_LIB.T6G(SCH_1):SMB_RT_CPU1_P1_ROM_MUX_1D_SCL
   3 SMB_RT_CPU1_P1_ROM_MUX_2D_SCL    2D+ @T6G_MB_LIB.T6G(SCH_1):SMB_RT_CPU1_P1_ROM_MUX_2D_SCL
   4 SMB_RT_CPU1_P1_ROM_MUX_2D_SDA    2D- @T6G_MB_LIB.T6G(SCH_1):SMB_RT_CPU1_P1_ROM_MUX_2D_SDA
   7 SMB_RT_CPU1_P1_ROM_R_SDA     D- @T6G_MB_LIB.T6G(SCH_1):SMB_RT_CPU1_P1_ROM_R_SDA
   6 RT_ROM_MUX2_OE_N    OE# @T6G_MB_LIB.T6G(SCH_1):RT_ROM_MUX2_OE_N
   9 FM_SMB_RT_ROM_MUX2_SEL      S @T6G_MB_LIB.T6G(SCH_1):FM_SMB_RT_ROM_MUX2_SEL
  10 P3V3_AUX    VDD @T6G_MB_LIB.T6G(SCH_1):P3V3_AUX
   2 SMB_RT_CPU1_P1_ROM_MUX_1D_SDA    1D- @T6G_MB_LIB.T6G(SCH_1):SMB_RT_CPU1_P1_ROM_MUX_1D_SDA
   5    GND    GND @T6G_MB_LIB.T6G(SCH_1):GND
   8 SMB_RT_CPU1_P1_ROM_R_SCL     D+ @T6G_MB_LIB.T6G(SCH_1):SMB_RT_CPU1_P1_ROM_R_SCL

Q_CAP_C0201-0.1UF,10V,10%,X7S,CH4102K6E00  I37  C1067
   1 P3V3_AUX      A @T6G_MB_LIB.T6G(SCH_1):P3V3_AUX
   2    GND      B @T6G_MB_LIB.T6G(SCH_1):GND

Q_RES_0201LF-0,5%,1/20W,CHIP,CS00001JE10  I40  R1199
   1 RST_SMB_RT_ROM_R1_N      A @T6G_MB_LIB.T6G(SCH_1):RST_SMB_RT_ROM_R1_N
   2 FM_SMB_RT_ROM_MUX2_SEL      B @T6G_MB_LIB.T6G(SCH_1):FM_SMB_RT_ROM_MUX2_SEL

Q_RES_0201LF-1K,1%,1/20W,CHIP,CS21001FE07  I41  R1213
   1    GND      A @T6G_MB_LIB.T6G(SCH_1):GND
   2 RT_ROM_MUX2_OE_N      B @T6G_MB_LIB.T6G(SCH_1):RT_ROM_MUX2_OE_N

PI3CSW12ZUAEX-PI3CSW12ZUAEX,SMLF,IC,AL3CSW12000  I46  U41
   1 SMB_RT_CPU1_P3_ROM_MUX_1D_SCL    1D+ @T6G_MB_LIB.T6G(SCH_1):SMB_RT_CPU1_P3_ROM_MUX_1D_SCL
   3 SMB_RT_CPU1_P3_ROM_MUX_2D_SCL    2D+ @T6G_MB_LIB.T6G(SCH_1):SMB_RT_CPU1_P3_ROM_MUX_2D_SCL
   4 SMB_RT_CPU1_P3_ROM_MUX_2D_SDA    2D- @T6G_MB_LIB.T6G(SCH_1):SMB_RT_CPU1_P3_ROM_MUX_2D_SDA
   7 SMB_RT_CPU1_P3_ROM_R_SDA     D- @T6G_MB_LIB.T6G(SCH_1):SMB_RT_CPU1_P3_ROM_R_SDA
   6 RT_ROM_MUX3_OE_N    OE# @T6G_MB_LIB.T6G(SCH_1):RT_ROM_MUX3_OE_N
   9 FM_SMB_RT_ROM_MUX3_SEL      S @T6G_MB_LIB.T6G(SCH_1):FM_SMB_RT_ROM_MUX3_SEL
  10 P3V3_AUX    VDD @T6G_MB_LIB.T6G(SCH_1):P3V3_AUX
   2 SMB_RT_CPU1_P3_ROM_MUX_1D_SDA    1D- @T6G_MB_LIB.T6G(SCH_1):SMB_RT_CPU1_P3_ROM_MUX_1D_SDA
   5    GND    GND @T6G_MB_LIB.T6G(SCH_1):GND
   8 SMB_RT_CPU1_P3_ROM_R_SCL     D+ @T6G_MB_LIB.T6G(SCH_1):SMB_RT_CPU1_P3_ROM_R_SCL

Q_CAP_C0201-0.1UF,10V,10%,X7S,CH4102K6E00  I48  C1066
   1 P3V3_AUX      A @T6G_MB_LIB.T6G(SCH_1):P3V3_AUX
   2    GND      B @T6G_MB_LIB.T6G(SCH_1):GND

Q_RES_0201LF-0,5%,1/20W,CHIP,CS00001JE10  I53  R1198
   1 RST_SMB_RT_ROM_R1_N      A @T6G_MB_LIB.T6G(SCH_1):RST_SMB_RT_ROM_R1_N
   2 FM_SMB_RT_ROM_MUX3_SEL      B @T6G_MB_LIB.T6G(SCH_1):FM_SMB_RT_ROM_MUX3_SEL

Q_RES_0201LF-1K,1%,1/20W,CHIP,CS21001FE07  I54  R1212
   1    GND      A @T6G_MB_LIB.T6G(SCH_1):GND
   2 RT_ROM_MUX3_OE_N      B @T6G_MB_LIB.T6G(SCH_1):RT_ROM_MUX3_OE_N

PI3CSW12ZUAEX-PI3CSW12ZUAEX,SMLF,IC,AL3CSW12000  I61  U43
   1 SMB_RT_CPU1_P2_ROM_MUX_1D_SCL    1D+ @T6G_MB_LIB.T6G(SCH_1):SMB_RT_CPU1_P2_ROM_MUX_1D_SCL
   3 SMB_RT_CPU1_P2_ROM_MUX_2D_SCL    2D+ @T6G_MB_LIB.T6G(SCH_1):SMB_RT_CPU1_P2_ROM_MUX_2D_SCL
   4 SMB_RT_CPU1_P2_ROM_MUX_2D_SDA    2D- @T6G_MB_LIB.T6G(SCH_1):SMB_RT_CPU1_P2_ROM_MUX_2D_SDA
   7 SMB_RT_CPU1_P2_ROM_R_SDA     D- @T6G_MB_LIB.T6G(SCH_1):SMB_RT_CPU1_P2_ROM_R_SDA
   6 RT_ROM_MUX4_OE_N    OE# @T6G_MB_LIB.T6G(SCH_1):RT_ROM_MUX4_OE_N
   9 FM_SMB_RT_ROM_MUX4_SEL      S @T6G_MB_LIB.T6G(SCH_1):FM_SMB_RT_ROM_MUX4_SEL
  10 P3V3_AUX    VDD @T6G_MB_LIB.T6G(SCH_1):P3V3_AUX
   2 SMB_RT_CPU1_P2_ROM_MUX_1D_SDA    1D- @T6G_MB_LIB.T6G(SCH_1):SMB_RT_CPU1_P2_ROM_MUX_1D_SDA
   5    GND    GND @T6G_MB_LIB.T6G(SCH_1):GND
   8 SMB_RT_CPU1_P2_ROM_R_SCL     D+ @T6G_MB_LIB.T6G(SCH_1):SMB_RT_CPU1_P2_ROM_R_SCL

Q_CAP_C0201-0.1UF,10V,10%,X7S,CH4102K6E00  I65  C1068
   1 P3V3_AUX      A @T6G_MB_LIB.T6G(SCH_1):P3V3_AUX
   2    GND      B @T6G_MB_LIB.T6G(SCH_1):GND

Q_RES_0201LF-0,5%,1/20W,CHIP,CS00001JE10  I68  R1200
   1 RST_SMB_RT_ROM_R1_N      A @T6G_MB_LIB.T6G(SCH_1):RST_SMB_RT_ROM_R1_N
   2 FM_SMB_RT_ROM_MUX4_SEL      B @T6G_MB_LIB.T6G(SCH_1):FM_SMB_RT_ROM_MUX4_SEL

Q_RES_0201LF-1K,1%,1/20W,CHIP,CS21001FE07  I69  R1214
   1    GND      A @T6G_MB_LIB.T6G(SCH_1):GND
   2 RT_ROM_MUX4_OE_N      B @T6G_MB_LIB.T6G(SCH_1):RT_ROM_MUX4_OE_N

PI3CSW12ZUAEX-PI3CSW12ZUAEX,SMLF,IC,AL3CSW12000  I76  U48
   1 SMB_RT_CPU0_P1_ROM_MUX_1D_SCL    1D+ @T6G_MB_LIB.T6G(SCH_1):SMB_RT_CPU0_P1_ROM_MUX_1D_SCL
   3 SMB_RT_CPU0_P1_ROM_MUX_2D_SCL    2D+ @T6G_MB_LIB.T6G(SCH_1):SMB_RT_CPU0_P1_ROM_MUX_2D_SCL
   4 SMB_RT_CPU0_P1_ROM_MUX_2D_SDA    2D- @T6G_MB_LIB.T6G(SCH_1):SMB_RT_CPU0_P1_ROM_MUX_2D_SDA
   7 SMB_RT_CPU0_P1_ROM_R_SDA     D- @T6G_MB_LIB.T6G(SCH_1):SMB_RT_CPU0_P1_ROM_R_SDA
   6 RT_ROM_MUX6_OE_N    OE# @T6G_MB_LIB.T6G(SCH_1):RT_ROM_MUX6_OE_N
   9 FM_SMB_RT_ROM_MUX6_SEL      S @T6G_MB_LIB.T6G(SCH_1):FM_SMB_RT_ROM_MUX6_SEL
  10 P3V3_AUX    VDD @T6G_MB_LIB.T6G(SCH_1):P3V3_AUX
   2 SMB_RT_CPU0_P1_ROM_MUX_1D_SDA    1D- @T6G_MB_LIB.T6G(SCH_1):SMB_RT_CPU0_P1_ROM_MUX_1D_SDA
   5    GND    GND @T6G_MB_LIB.T6G(SCH_1):GND
   8 SMB_RT_CPU0_P1_ROM_R_SCL     D+ @T6G_MB_LIB.T6G(SCH_1):SMB_RT_CPU0_P1_ROM_R_SCL

Q_CAP_C0201-0.1UF,10V,10%,X7S,CH4102K6E00  I80  C1073
   1 P3V3_AUX      A @T6G_MB_LIB.T6G(SCH_1):P3V3_AUX
   2    GND      B @T6G_MB_LIB.T6G(SCH_1):GND

Q_CAP_C0201-0.1UF,10V,10%,X7S,CH4102K6E00  I84  C1072
   1 P3V3_AUX      A @T6G_MB_LIB.T6G(SCH_1):P3V3_AUX
   2    GND      B @T6G_MB_LIB.T6G(SCH_1):GND

PI3CSW12ZUAEX-PI3CSW12ZUAEX,SMLF,IC,AL3CSW12000  I85  U49
   1 SMB_RT_CPU0_P0_ROM_MUX_1D_SCL    1D+ @T6G_MB_LIB.T6G(SCH_1):SMB_RT_CPU0_P0_ROM_MUX_1D_SCL
   3 SMB_RT_CPU0_P0_ROM_MUX_2D_SCL    2D+ @T6G_MB_LIB.T6G(SCH_1):SMB_RT_CPU0_P0_ROM_MUX_2D_SCL
   4 SMB_RT_CPU0_P0_ROM_MUX_2D_SDA    2D- @T6G_MB_LIB.T6G(SCH_1):SMB_RT_CPU0_P0_ROM_MUX_2D_SDA
   7 SMB_RT_CPU0_P0_ROM_R_SDA     D- @T6G_MB_LIB.T6G(SCH_1):SMB_RT_CPU0_P0_ROM_R_SDA
   6 RT_ROM_MUX5_OE_N    OE# @T6G_MB_LIB.T6G(SCH_1):RT_ROM_MUX5_OE_N
   9 FM_SMB_RT_ROM_MUX5_SEL      S @T6G_MB_LIB.T6G(SCH_1):FM_SMB_RT_ROM_MUX5_SEL
  10 P3V3_AUX    VDD @T6G_MB_LIB.T6G(SCH_1):P3V3_AUX
   2 SMB_RT_CPU0_P0_ROM_MUX_1D_SDA    1D- @T6G_MB_LIB.T6G(SCH_1):SMB_RT_CPU0_P0_ROM_MUX_1D_SDA
   5    GND    GND @T6G_MB_LIB.T6G(SCH_1):GND
   8 SMB_RT_CPU0_P0_ROM_R_SCL     D+ @T6G_MB_LIB.T6G(SCH_1):SMB_RT_CPU0_P0_ROM_R_SCL

Q_RES_0201LF-0,5%,1/20W,CHIP,CS00001JE10  I86  R1211
   1 RST_SMB_RT_ROM_R1_N      A @T6G_MB_LIB.T6G(SCH_1):RST_SMB_RT_ROM_R1_N
   2 FM_SMB_RT_ROM_MUX5_SEL      B @T6G_MB_LIB.T6G(SCH_1):FM_SMB_RT_ROM_MUX5_SEL

Q_RES_0201LF-1K,1%,1/20W,CHIP,CS21001FE07  I87  R1219
   1    GND      A @T6G_MB_LIB.T6G(SCH_1):GND
   2 RT_ROM_MUX5_OE_N      B @T6G_MB_LIB.T6G(SCH_1):RT_ROM_MUX5_OE_N

Q_CAP_C0201-0.1UF,10V,10%,X7S,CH4102K6E00  I99  C1070
   1 P3V3_AUX      A @T6G_MB_LIB.T6G(SCH_1):P3V3_AUX
   2    GND      B @T6G_MB_LIB.T6G(SCH_1):GND

Q_CAP_C0201-0.1UF,10V,10%,X7S,CH4102K6E00  I105  C1071
   1 P3V3_AUX      A @T6G_MB_LIB.T6G(SCH_1):P3V3_AUX
   2    GND      B @T6G_MB_LIB.T6G(SCH_1):GND

PI3CSW12ZUAEX-PI3CSW12ZUAEX,SMLF,IC,AL3CSW12000  I108  U46
   1 SMB_RT_CPU0_P3_ROM_MUX_1D_SCL    1D+ @T6G_MB_LIB.T6G(SCH_1):SMB_RT_CPU0_P3_ROM_MUX_1D_SCL
   3 SMB_RT_CPU0_P3_ROM_MUX_2D_SCL    2D+ @T6G_MB_LIB.T6G(SCH_1):SMB_RT_CPU0_P3_ROM_MUX_2D_SCL
   4 SMB_RT_CPU0_P3_ROM_MUX_2D_SDA    2D- @T6G_MB_LIB.T6G(SCH_1):SMB_RT_CPU0_P3_ROM_MUX_2D_SDA
   7 SMB_RT_CPU0_P3_ROM_R_SDA     D- @T6G_MB_LIB.T6G(SCH_1):SMB_RT_CPU0_P3_ROM_R_SDA
   6 RT_ROM_MUX7_OE_N    OE# @T6G_MB_LIB.T6G(SCH_1):RT_ROM_MUX7_OE_N
   9 FM_SMB_RT_ROM_MUX7_SEL      S @T6G_MB_LIB.T6G(SCH_1):FM_SMB_RT_ROM_MUX7_SEL
  10 P3V3_AUX    VDD @T6G_MB_LIB.T6G(SCH_1):P3V3_AUX
   2 SMB_RT_CPU0_P3_ROM_MUX_1D_SDA    1D- @T6G_MB_LIB.T6G(SCH_1):SMB_RT_CPU0_P3_ROM_MUX_1D_SDA
   5    GND    GND @T6G_MB_LIB.T6G(SCH_1):GND
   8 SMB_RT_CPU0_P3_ROM_R_SCL     D+ @T6G_MB_LIB.T6G(SCH_1):SMB_RT_CPU0_P3_ROM_R_SCL

Q_RES_0201LF-0,5%,1/20W,CHIP,CS00001JE10  I109  R1210
   1 RST_SMB_RT_ROM_R1_N      A @T6G_MB_LIB.T6G(SCH_1):RST_SMB_RT_ROM_R1_N
   2 FM_SMB_RT_ROM_MUX6_SEL      B @T6G_MB_LIB.T6G(SCH_1):FM_SMB_RT_ROM_MUX6_SEL

Q_RES_0201LF-1K,1%,1/20W,CHIP,CS21001FE07  I110  R1218
   1    GND      A @T6G_MB_LIB.T6G(SCH_1):GND
   2 RT_ROM_MUX6_OE_N      B @T6G_MB_LIB.T6G(SCH_1):RT_ROM_MUX6_OE_N

Q_RES_0201LF-0,5%,1/20W,CHIP,CS00001JE10  I115  R1206
   1 RST_SMB_RT_ROM_R1_N      A @T6G_MB_LIB.T6G(SCH_1):RST_SMB_RT_ROM_R1_N
   2 FM_SMB_RT_ROM_MUX7_SEL      B @T6G_MB_LIB.T6G(SCH_1):FM_SMB_RT_ROM_MUX7_SEL

Q_RES_0201LF-1K,1%,1/20W,CHIP,CS21001FE07  I116  R1216
   1    GND      A @T6G_MB_LIB.T6G(SCH_1):GND
   2 RT_ROM_MUX7_OE_N      B @T6G_MB_LIB.T6G(SCH_1):RT_ROM_MUX7_OE_N

PI3CSW12ZUAEX-PI3CSW12ZUAEX,SMLF,IC,AL3CSW12000  I121  U47
   1 SMB_RT_CPU0_P2_ROM_MUX_1D_SCL    1D+ @T6G_MB_LIB.T6G(SCH_1):SMB_RT_CPU0_P2_ROM_MUX_1D_SCL
   3 SMB_RT_CPU0_P2_ROM_MUX_2D_SCL    2D+ @T6G_MB_LIB.T6G(SCH_1):SMB_RT_CPU0_P2_ROM_MUX_2D_SCL
   4 SMB_RT_CPU0_P2_ROM_MUX_2D_SDA    2D- @T6G_MB_LIB.T6G(SCH_1):SMB_RT_CPU0_P2_ROM_MUX_2D_SDA
   7 SMB_RT_CPU0_P2_ROM_R_SDA     D- @T6G_MB_LIB.T6G(SCH_1):SMB_RT_CPU0_P2_ROM_R_SDA
   6 RT_ROM_MUX8_OE_N    OE# @T6G_MB_LIB.T6G(SCH_1):RT_ROM_MUX8_OE_N
   9 FM_SMB_RT_ROM_MUX8_SEL      S @T6G_MB_LIB.T6G(SCH_1):FM_SMB_RT_ROM_MUX8_SEL
  10 P3V3_AUX    VDD @T6G_MB_LIB.T6G(SCH_1):P3V3_AUX
   2 SMB_RT_CPU0_P2_ROM_MUX_1D_SDA    1D- @T6G_MB_LIB.T6G(SCH_1):SMB_RT_CPU0_P2_ROM_MUX_1D_SDA
   5    GND    GND @T6G_MB_LIB.T6G(SCH_1):GND
   8 SMB_RT_CPU0_P2_ROM_R_SCL     D+ @T6G_MB_LIB.T6G(SCH_1):SMB_RT_CPU0_P2_ROM_R_SCL

Q_RES_0201LF-1K,1%,1/20W,CHIP,CS21001FE07  I122  R1217
   1    GND      A @T6G_MB_LIB.T6G(SCH_1):GND
   2 RT_ROM_MUX8_OE_N      B @T6G_MB_LIB.T6G(SCH_1):RT_ROM_MUX8_OE_N

Q_RES_0201LF-0,5%,1/20W,CHIP,CS00001JE10  I123  R1209
   1 RST_SMB_RT_ROM_R1_N      A @T6G_MB_LIB.T6G(SCH_1):RST_SMB_RT_ROM_R1_N
   2 FM_SMB_RT_ROM_MUX8_SEL      B @T6G_MB_LIB.T6G(SCH_1):FM_SMB_RT_ROM_MUX8_SEL


DRAWING: @T6G_MB_LIB.T6G(SCH_1):PAGE263 

Q_RES_0402LF-9.09K,1%,1/16W,CHIP,CS29092FB05  I12  R1226
   1 P5V_AUX_ADC      A @T6G_MB_LIB.T6G(SCH_1):P5V_AUX_ADC
   2    GND      B @T6G_MB_LIB.T6G(SCH_1):GND

Q_RES_0402LF-18K,1%,1/16W,CHIP,CS31802FB04  I13  R1238
   1 P5V_AUX      A @T6G_MB_LIB.T6G(SCH_1):P5V_AUX
   2 P5V_AUX_ADC      B @T6G_MB_LIB.T6G(SCH_1):P5V_AUX_ADC

Q_RES_0402LF-0,5%,1/16W,CHIP,CS00002JB13  I15  R1263
   1 P5V_AUX_ADC      A @T6G_MB_LIB.T6G(SCH_1):P5V_AUX_ADC
   2 P5V_AUX_ADC_TIC      B @T6G_MB_LIB.T6G(SCH_1):P5V_AUX_ADC_TIC

Q_RES_0402LF-0,5%,1/16W,EMPTY,CS00002JB13  I16  R1260
   1 P5V_AUX_ADC      A @T6G_MB_LIB.T6G(SCH_1):P5V_AUX_ADC
   2 P5V_AUX_ADC_MAM      B @T6G_MB_LIB.T6G(SCH_1):P5V_AUX_ADC_MAM

Q_RES_0402LF-5.11K,1%,1/16W,CHIP,CS25112FB04  I19  R1237
   1 P1V8_AUX      A @T6G_MB_LIB.T6G(SCH_1):P1V8_AUX
   2 P1V8_AUX_ADC      B @T6G_MB_LIB.T6G(SCH_1):P1V8_AUX_ADC

Q_RES_0402LF-0,5%,1/16W,CHIP,CS00002JB13  I21  R1259
   1 P1V8_AUX_ADC      A @T6G_MB_LIB.T6G(SCH_1):P1V8_AUX_ADC
   2 P1V8_AUX_ADC_TIC      B @T6G_MB_LIB.T6G(SCH_1):P1V8_AUX_ADC_TIC

Q_RES_0402LF-0,5%,1/16W,EMPTY,CS00002JB13  I22  R1258
   1 P1V8_AUX_ADC      A @T6G_MB_LIB.T6G(SCH_1):P1V8_AUX_ADC
   2 P1V8_AUX_ADC_MAM      B @T6G_MB_LIB.T6G(SCH_1):P1V8_AUX_ADC_MAM

Q_CAP_0402-0.1UF,25V,10%,X7R,CH4104K1B00  I43  C1093
   1 P5V_AUX_ADC_TIC      A @T6G_MB_LIB.T6G(SCH_1):P5V_AUX_ADC_TIC
   2    GND      B @T6G_MB_LIB.T6G(SCH_1):GND

Q_CAP_0402-100PF,50V,5%,EMPTY,CH11006JB18  I45  C1085
   1 P5V_AUX_ADC_MAM      A @T6G_MB_LIB.T6G(SCH_1):P5V_AUX_ADC_MAM
   2    GND      B @T6G_MB_LIB.T6G(SCH_1):GND

Q_RES_0402LF-1K,1%,1/16W,CHIP,CS21002FB06  I57  R1240
   1 ADC128_2_A1      A @T6G_MB_LIB.T6G(SCH_1):ADC128_2_A1
   2    GND      B @T6G_MB_LIB.T6G(SCH_1):GND

Q_RES_0402LF-1K,1%,1/16W,CHIP,CS21002FB06  I58  R1242
   1 ADC128_2_A0      A @T6G_MB_LIB.T6G(SCH_1):ADC128_2_A0
   2    GND      B @T6G_MB_LIB.T6G(SCH_1):GND

Q_RES_0402LF-1K,1%,1/16W,EMPTY,CS21002FB06  I59  R1239
   1 P3V3_AUX      A @T6G_MB_LIB.T6G(SCH_1):P3V3_AUX
   2 ADC128_2_A1      B @T6G_MB_LIB.T6G(SCH_1):ADC128_2_A1

Q_RES_0402LF-1K,1%,1/16W,EMPTY,CS21002FB06  I60  R1241
   1 P3V3_AUX      A @T6G_MB_LIB.T6G(SCH_1):P3V3_AUX
   2 ADC128_2_A0      B @T6G_MB_LIB.T6G(SCH_1):ADC128_2_A0

Q_CAP_0402-0.1UF,25V,10%,X7R,CH4104K1B00  I68  C1094
   1 P3V3_ADC128_2_VCC      A @T6G_MB_LIB.T6G(SCH_1):P3V3_ADC128_2_VCC
   2    GND      B @T6G_MB_LIB.T6G(SCH_1):GND

Q_INDUCTOR_SMLF-BLM18PG300SN1D ,IND,TMP_QCX8PG3000A  I69  L25
   2 P3V3_ADC128_2_VCC      2 @T6G_MB_LIB.T6G(SCH_1):P3V3_ADC128_2_VCC
   1 P3V3_AUX      1 @T6G_MB_LIB.T6G(SCH_1):P3V3_AUX

Q_CAP_0402-0.1UF,25V,10%,X7R,CH4104K1B00  I76  C1092
   1 P1V8_AUX_ADC_TIC      A @T6G_MB_LIB.T6G(SCH_1):P1V8_AUX_ADC_TIC
   2    GND      B @T6G_MB_LIB.T6G(SCH_1):GND

Q_CAP_0402-100PF,50V,5%,EMPTY,CH11006JB18  I77  C1084
   1 P1V8_AUX_ADC_MAM      A @T6G_MB_LIB.T6G(SCH_1):P1V8_AUX_ADC_MAM
   2    GND      B @T6G_MB_LIB.T6G(SCH_1):GND

Q_CAP_0402-0.1UF,25V,10%,X7R,CH4104K1B00  I115  C1074
   1 MAX11617_2_VREF      A @T6G_MB_LIB.T6G(SCH_1):MAX11617_2_VREF
   2    GND      B @T6G_MB_LIB.T6G(SCH_1):GND

Q_RES_0402LF-4.7K,1%,1/16W,EMPTY,CS24702FB06  I119  R1268
   1 ADC128_2_VREF      A @T6G_MB_LIB.T6G(SCH_1):ADC128_2_VREF
   2    GND      B @T6G_MB_LIB.T6G(SCH_1):GND

Q_CAP_0402-0.1UF,25V,10%,X7R,CH4104K1B00  I130  C1095
   1 P3V3_ADC128_2_VCC      A @T6G_MB_LIB.T6G(SCH_1):P3V3_ADC128_2_VCC
   2    GND      B @T6G_MB_LIB.T6G(SCH_1):GND

Q_RES_0402LF-4.7K,1%,1/16W,EMPTY,CS24702FB06  I131  R1267
   1 P3V3_ADC128_2_VCC      A @T6G_MB_LIB.T6G(SCH_1):P3V3_ADC128_2_VCC
   2 ADC128_2_VREF      B @T6G_MB_LIB.T6G(SCH_1):ADC128_2_VREF

Q_RES_0402LF-0,5%,1/16W,EMPTY,CS00002JB13  I138  R1227
   1 SMB_ADC_SDA_R      A @T6G_MB_LIB.T6G(SCH_1):SMB_ADC_SDA_R
   2 SMB_SEN_MAM_2_3V3AUX_SDA      B @T6G_MB_LIB.T6G(SCH_1):SMB_SEN_MAM_2_3V3AUX_SDA

Q_RES_0402LF-0,5%,1/16W,EMPTY,CS00002JB13  I139  R1228
   1 SMB_ADC_SCL_R      A @T6G_MB_LIB.T6G(SCH_1):SMB_ADC_SCL_R
   2 SMB_SEN_MAM_2_3V3AUX_SCL      B @T6G_MB_LIB.T6G(SCH_1):SMB_SEN_MAM_2_3V3AUX_SCL

Q_RES_0402LF-0,5%,1/16W,CHIP,CS00002JB13  I140  R1244
   1 SMB_ADC_SCL_R      A @T6G_MB_LIB.T6G(SCH_1):SMB_ADC_SCL_R
   2 SMB_SEN_TIC_2_3V3AUX_SCL      B @T6G_MB_LIB.T6G(SCH_1):SMB_SEN_TIC_2_3V3AUX_SCL

Q_RES_0402LF-0,5%,1/16W,CHIP,CS00002JB13  I141  R1243
   1 SMB_ADC_SDA_R      A @T6G_MB_LIB.T6G(SCH_1):SMB_ADC_SDA_R
   2 SMB_SEN_TIC_2_3V3AUX_SDA      B @T6G_MB_LIB.T6G(SCH_1):SMB_SEN_TIC_2_3V3AUX_SDA

ADC128D818CIMTXNOPB-ADC128D818CIMTX/NOPB,SMLF,IC,AA  I142  U51
   1 ADC128_2_VREF   VREF @T6G_MB_LIB.T6G(SCH_1):ADC128_2_VREF
   5 P3V3_ADC128_2_VCC     V+ @T6G_MB_LIB.T6G(SCH_1):P3V3_ADC128_2_VCC
   7 ADC128_2_A0     A0 @T6G_MB_LIB.T6G(SCH_1):ADC128_2_A0
   8 ADC128_2_A1     A1 @T6G_MB_LIB.T6G(SCH_1):ADC128_2_A1
   9 PVDD18_S5_P1_ADC_TIC    IN7 @T6G_MB_LIB.T6G(SCH_1):PVDD18_S5_P1_ADC_TIC
  10 PVDD18_S5_P0_ADC_TIC    IN6 @T6G_MB_LIB.T6G(SCH_1):PVDD18_S5_P0_ADC_TIC
  11 PVDD_33_S5_ADC_TIC    IN5 @T6G_MB_LIB.T6G(SCH_1):PVDD_33_S5_ADC_TIC
  12 P1V8_CPU1_RT_1D_ADC_TIC    IN4 @T6G_MB_LIB.T6G(SCH_1):P1V8_CPU1_RT_1D_ADC_TIC
  13 P1V8_CPU0_RT_1D_ADC_TIC    IN3 @T6G_MB_LIB.T6G(SCH_1):P1V8_CPU0_RT_1D_ADC_TIC
  14 P1V2_AUX_ADC_TIC    IN2 @T6G_MB_LIB.T6G(SCH_1):P1V2_AUX_ADC_TIC
  15 P1V8_AUX_ADC_TIC    IN1 @T6G_MB_LIB.T6G(SCH_1):P1V8_AUX_ADC_TIC
  16 P5V_AUX_ADC_TIC    IN0 @T6G_MB_LIB.T6G(SCH_1):P5V_AUX_ADC_TIC
   2 SMB_SEN_TIC_2_3V3AUX_SDA    SDA @T6G_MB_LIB.T6G(SCH_1):SMB_SEN_TIC_2_3V3AUX_SDA
   3 SMB_SEN_TIC_2_3V3AUX_SCL    SCL @T6G_MB_LIB.T6G(SCH_1):SMB_SEN_TIC_2_3V3AUX_SCL
   4    GND    GND @T6G_MB_LIB.T6G(SCH_1):GND
   6 TP_ADC128_2_INT   INT# @T6G_MB_LIB.T6G(SCH_1):TP_ADC128_2_INT

Q_CAP_C0805-10UF,16V,10%,X6S,CH6103KEA00  I152  C1076
   1 MAX11617_2_VREF      A @T6G_MB_LIB.T6G(SCH_1):MAX11617_2_VREF
   2    GND      B @T6G_MB_LIB.T6G(SCH_1):GND

Q_RES_0402LF-2K,1%,1/16W,CHIP,CS22002FB07  I154  R1230
   1 MAX11617_2_VREF      A @T6G_MB_LIB.T6G(SCH_1):MAX11617_2_VREF
   2 MAX11617_2_VREF_R      B @T6G_MB_LIB.T6G(SCH_1):MAX11617_2_VREF_R

MAX11617EEET-MAX11617EEE+T,SMLF,EMPTY,AL011617W00  I156  U50
   1 MAX11617_2_VREF_R AIN11||REF @T6G_MB_LIB.T6G(SCH_1):MAX11617_2_VREF_R
   2    GND  AIN10 @T6G_MB_LIB.T6G(SCH_1):GND
   3    GND   AIN9 @T6G_MB_LIB.T6G(SCH_1):GND
   4    GND   AIN8 @T6G_MB_LIB.T6G(SCH_1):GND
   5 P5V_AUX_ADC_MAM   AIN0 @T6G_MB_LIB.T6G(SCH_1):P5V_AUX_ADC_MAM
   6 P1V8_AUX_ADC_MAM   AIN1 @T6G_MB_LIB.T6G(SCH_1):P1V8_AUX_ADC_MAM
   7 P1V2_AUX_ADC_MAM   AIN2 @T6G_MB_LIB.T6G(SCH_1):P1V2_AUX_ADC_MAM
   8 P1V8_CPU0_RT_1D_ADC_MAM   AIN3 @T6G_MB_LIB.T6G(SCH_1):P1V8_CPU0_RT_1D_ADC_MAM
   9 P1V8_CPU1_RT_1D_ADC_MAM   AIN4 @T6G_MB_LIB.T6G(SCH_1):P1V8_CPU1_RT_1D_ADC_MAM
  10 PVDD_33_S5_ADC_MAM   AIN5 @T6G_MB_LIB.T6G(SCH_1):PVDD_33_S5_ADC_MAM
  11 PVDD18_S5_P0_ADC_MAM   AIN6 @T6G_MB_LIB.T6G(SCH_1):PVDD18_S5_P0_ADC_MAM
  12 PVDD18_S5_P1_ADC_MAM   AIN7 @T6G_MB_LIB.T6G(SCH_1):PVDD18_S5_P1_ADC_MAM
  13 SMB_SEN_MAM_2_3V3AUX_SCL    SCL @T6G_MB_LIB.T6G(SCH_1):SMB_SEN_MAM_2_3V3AUX_SCL
  14 SMB_SEN_MAM_2_3V3AUX_SDA    SDA @T6G_MB_LIB.T6G(SCH_1):SMB_SEN_MAM_2_3V3AUX_SDA
  15    GND    GND @T6G_MB_LIB.T6G(SCH_1):GND
  16 P3V3_MAX11617_2_VDD    VDD @T6G_MB_LIB.T6G(SCH_1):P3V3_MAX11617_2_VDD

Q_CAP_0402-0.1UF,25V,10%,X7R,CH4104K1B00  I165  C1075
   1 P3V3_MAX11617_2_VDD      A @T6G_MB_LIB.T6G(SCH_1):P3V3_MAX11617_2_VDD
   2    GND      B @T6G_MB_LIB.T6G(SCH_1):GND

Q_CAP_C0805-10UF,16V,10%,X6S,CH6103KEA00  I166  C1077
   1 P3V3_MAX11617_2_VDD      A @T6G_MB_LIB.T6G(SCH_1):P3V3_MAX11617_2_VDD
   2    GND      B @T6G_MB_LIB.T6G(SCH_1):GND

Q_INDUCTOR_SMLF-BLM18PG300SN1D ,IND,TMP_QCX8PG3000A  I168  L24
   2 P3V3_AUX      2 @T6G_MB_LIB.T6G(SCH_1):P3V3_AUX
   1 P3V3_MAX11617_2_VDD      1 @T6G_MB_LIB.T6G(SCH_1):P3V3_MAX11617_2_VDD

Q_CAP_0402-100PF,50V,5%,EMPTY,CH11006JB18  I173  C1078
   1 P1V2_AUX_ADC_MAM      A @T6G_MB_LIB.T6G(SCH_1):P1V2_AUX_ADC_MAM
   2    GND      B @T6G_MB_LIB.T6G(SCH_1):GND

Q_CAP_0402-0.1UF,25V,10%,X7R,CH4104K1B00  I175  C1086
   1 P1V2_AUX_ADC_TIC      A @T6G_MB_LIB.T6G(SCH_1):P1V2_AUX_ADC_TIC
   2    GND      B @T6G_MB_LIB.T6G(SCH_1):GND

Q_RES_0402LF-0,5%,1/16W,EMPTY,CS00002JB13  I177  R1245
   1 P1V2_AUX_ADC      A @T6G_MB_LIB.T6G(SCH_1):P1V2_AUX_ADC
   2 P1V2_AUX_ADC_MAM      B @T6G_MB_LIB.T6G(SCH_1):P1V2_AUX_ADC_MAM

Q_RES_0402LF-0,5%,1/16W,CHIP,CS00002JB13  I178  R1251
   1 P1V2_AUX_ADC      A @T6G_MB_LIB.T6G(SCH_1):P1V2_AUX_ADC
   2 P1V2_AUX_ADC_TIC      B @T6G_MB_LIB.T6G(SCH_1):P1V2_AUX_ADC_TIC

Q_RES_0402LF-5.11K,1%,1/16W,CHIP,CS25112FB04  I179  R1232
   1 P1V2_AUX      A @T6G_MB_LIB.T6G(SCH_1):P1V2_AUX
   2 P1V2_AUX_ADC      B @T6G_MB_LIB.T6G(SCH_1):P1V2_AUX_ADC

Q_CAP_0402-100PF,50V,5%,EMPTY,CH11006JB18  I185  C1079
   1 P1V8_CPU0_RT_1D_ADC_MAM      A @T6G_MB_LIB.T6G(SCH_1):P1V8_CPU0_RT_1D_ADC_MAM
   2    GND      B @T6G_MB_LIB.T6G(SCH_1):GND

Q_CAP_0402-0.1UF,25V,10%,X7R,CH4104K1B00  I187  C1087
   1 P1V8_CPU0_RT_1D_ADC_TIC      A @T6G_MB_LIB.T6G(SCH_1):P1V8_CPU0_RT_1D_ADC_TIC
   2    GND      B @T6G_MB_LIB.T6G(SCH_1):GND

Q_RES_0402LF-0,5%,1/16W,EMPTY,CS00002JB13  I189  R1246
   1 P1V8_CPU0_RT_1D_ADC      A @T6G_MB_LIB.T6G(SCH_1):P1V8_CPU0_RT_1D_ADC
   2 P1V8_CPU0_RT_1D_ADC_MAM      B @T6G_MB_LIB.T6G(SCH_1):P1V8_CPU0_RT_1D_ADC_MAM

Q_RES_0402LF-0,5%,1/16W,CHIP,CS00002JB13  I190  R1252
   1 P1V8_CPU0_RT_1D_ADC      A @T6G_MB_LIB.T6G(SCH_1):P1V8_CPU0_RT_1D_ADC
   2 P1V8_CPU0_RT_1D_ADC_TIC      B @T6G_MB_LIB.T6G(SCH_1):P1V8_CPU0_RT_1D_ADC_TIC

Q_RES_0402LF-5.11K,1%,1/16W,CHIP,CS25112FB04  I191  R1231
   1 P1V8_CPU0_RT_1D      A @T6G_MB_LIB.T6G(SCH_1):P1V8_CPU0_RT_1D
   2 P1V8_CPU0_RT_1D_ADC      B @T6G_MB_LIB.T6G(SCH_1):P1V8_CPU0_RT_1D_ADC

Q_RES_0402LF-5.11K,1%,1/16W,CHIP,CS25112FB04  I194  R1234
   1 P1V8_CPU1_RT_1D      A @T6G_MB_LIB.T6G(SCH_1):P1V8_CPU1_RT_1D
   2 P1V8_CPU1_RT_1D_ADC      B @T6G_MB_LIB.T6G(SCH_1):P1V8_CPU1_RT_1D_ADC

Q_CAP_0402-100PF,50V,5%,EMPTY,CH11006JB18  I198  C1083
   1 P1V8_CPU1_RT_1D_ADC_MAM      A @T6G_MB_LIB.T6G(SCH_1):P1V8_CPU1_RT_1D_ADC_MAM
   2    GND      B @T6G_MB_LIB.T6G(SCH_1):GND

Q_CAP_0402-0.1UF,25V,10%,X7R,CH4104K1B00  I200  C1091
   1 P1V8_CPU1_RT_1D_ADC_TIC      A @T6G_MB_LIB.T6G(SCH_1):P1V8_CPU1_RT_1D_ADC_TIC
   2    GND      B @T6G_MB_LIB.T6G(SCH_1):GND

Q_RES_0402LF-0,5%,1/16W,EMPTY,CS00002JB13  I202  R1250
   1 P1V8_CPU1_RT_1D_ADC      A @T6G_MB_LIB.T6G(SCH_1):P1V8_CPU1_RT_1D_ADC
   2 P1V8_CPU1_RT_1D_ADC_MAM      B @T6G_MB_LIB.T6G(SCH_1):P1V8_CPU1_RT_1D_ADC_MAM

Q_RES_0402LF-0,5%,1/16W,CHIP,CS00002JB13  I203  R1257
   1 P1V8_CPU1_RT_1D_ADC      A @T6G_MB_LIB.T6G(SCH_1):P1V8_CPU1_RT_1D_ADC
   2 P1V8_CPU1_RT_1D_ADC_TIC      B @T6G_MB_LIB.T6G(SCH_1):P1V8_CPU1_RT_1D_ADC_TIC

Q_CAP_0402-100PF,50V,5%,EMPTY,CH11006JB18  I209  C1082
   1 PVDD_33_S5_ADC_MAM      A @T6G_MB_LIB.T6G(SCH_1):PVDD_33_S5_ADC_MAM
   2    GND      B @T6G_MB_LIB.T6G(SCH_1):GND

Q_CAP_0402-0.1UF,25V,10%,X7R,CH4104K1B00  I211  C1089
   1 PVDD_33_S5_ADC_TIC      A @T6G_MB_LIB.T6G(SCH_1):PVDD_33_S5_ADC_TIC
   2    GND      B @T6G_MB_LIB.T6G(SCH_1):GND

Q_RES_0402LF-0,5%,1/16W,EMPTY,CS00002JB13  I213  R1248
   1 PVDD_33_S5_ADC      A @T6G_MB_LIB.T6G(SCH_1):PVDD_33_S5_ADC
   2 PVDD_33_S5_ADC_MAM      B @T6G_MB_LIB.T6G(SCH_1):PVDD_33_S5_ADC_MAM

Q_RES_0402LF-0,5%,1/16W,CHIP,CS00002JB13  I214  R1255
   1 PVDD_33_S5_ADC      A @T6G_MB_LIB.T6G(SCH_1):PVDD_33_S5_ADC
   2 PVDD_33_S5_ADC_TIC      B @T6G_MB_LIB.T6G(SCH_1):PVDD_33_S5_ADC_TIC

Q_RES_0402LF-5.11K,1%,1/16W,CHIP,CS25112FB04  I215  R1235
   1 PVDD_33_S5      A @T6G_MB_LIB.T6G(SCH_1):PVDD_33_S5
   2 PVDD_33_S5_ADC      B @T6G_MB_LIB.T6G(SCH_1):PVDD_33_S5_ADC

Q_RES_0402LF-4.7K,1%,1/16W,CHIP,CS24702FB06  I216  R1224
   1 PVDD_33_S5_ADC      A @T6G_MB_LIB.T6G(SCH_1):PVDD_33_S5_ADC
   2    GND      B @T6G_MB_LIB.T6G(SCH_1):GND

Q_CAP_0402-100PF,50V,5%,EMPTY,CH11006JB18  I221  C1080
   1 PVDD18_S5_P0_ADC_MAM      A @T6G_MB_LIB.T6G(SCH_1):PVDD18_S5_P0_ADC_MAM
   2    GND      B @T6G_MB_LIB.T6G(SCH_1):GND

Q_CAP_0402-0.1UF,25V,10%,X7R,CH4104K1B00  I223  C1088
   1 PVDD18_S5_P0_ADC_TIC      A @T6G_MB_LIB.T6G(SCH_1):PVDD18_S5_P0_ADC_TIC
   2    GND      B @T6G_MB_LIB.T6G(SCH_1):GND

Q_RES_0402LF-0,5%,1/16W,EMPTY,CS00002JB13  I225  R1247
   1 PVDD18_S5_P0_ADC      A @T6G_MB_LIB.T6G(SCH_1):PVDD18_S5_P0_ADC
   2 PVDD18_S5_P0_ADC_MAM      B @T6G_MB_LIB.T6G(SCH_1):PVDD18_S5_P0_ADC_MAM

Q_RES_0402LF-0,5%,1/16W,CHIP,CS00002JB13  I226  R1254
   1 PVDD18_S5_P0_ADC      A @T6G_MB_LIB.T6G(SCH_1):PVDD18_S5_P0_ADC
   2 PVDD18_S5_P0_ADC_TIC      B @T6G_MB_LIB.T6G(SCH_1):PVDD18_S5_P0_ADC_TIC

Q_RES_0402LF-5.11K,1%,1/16W,CHIP,CS25112FB04  I227  R1233
   1 PVDD18_S5_P0      A @T6G_MB_LIB.T6G(SCH_1):PVDD18_S5_P0
   2 PVDD18_S5_P0_ADC      B @T6G_MB_LIB.T6G(SCH_1):PVDD18_S5_P0_ADC

Q_RES_0402LF-5.11K,1%,1/16W,CHIP,CS25112FB04  I230  R1236
   1 PVDD18_S5_P1      A @T6G_MB_LIB.T6G(SCH_1):PVDD18_S5_P1
   2 PVDD18_S5_P1_ADC      B @T6G_MB_LIB.T6G(SCH_1):PVDD18_S5_P1_ADC

Q_RES_0402LF-0,5%,1/16W,EMPTY,CS00002JB13  I231  R1249
   1 PVDD18_S5_P1_ADC      A @T6G_MB_LIB.T6G(SCH_1):PVDD18_S5_P1_ADC
   2 PVDD18_S5_P1_ADC_MAM      B @T6G_MB_LIB.T6G(SCH_1):PVDD18_S5_P1_ADC_MAM

Q_CAP_0402-100PF,50V,5%,EMPTY,CH11006JB18  I232  C1081
   1 PVDD18_S5_P1_ADC_MAM      A @T6G_MB_LIB.T6G(SCH_1):PVDD18_S5_P1_ADC_MAM
   2    GND      B @T6G_MB_LIB.T6G(SCH_1):GND

Q_CAP_0402-0.1UF,25V,10%,X7R,CH4104K1B00  I237  C1090
   1 PVDD18_S5_P1_ADC_TIC      A @T6G_MB_LIB.T6G(SCH_1):PVDD18_S5_P1_ADC_TIC
   2    GND      B @T6G_MB_LIB.T6G(SCH_1):GND

Q_RES_0402LF-0,5%,1/16W,CHIP,CS00002JB13  I239  R1256
   1 PVDD18_S5_P1_ADC      A @T6G_MB_LIB.T6G(SCH_1):PVDD18_S5_P1_ADC
   2 PVDD18_S5_P1_ADC_TIC      B @T6G_MB_LIB.T6G(SCH_1):PVDD18_S5_P1_ADC_TIC

Q_RES_0402LF-18K,1%,1/16W,CHIP,CS31802FB04  I242  R1229
   1 P1V8_AUX_ADC      A @T6G_MB_LIB.T6G(SCH_1):P1V8_AUX_ADC
   2    GND      B @T6G_MB_LIB.T6G(SCH_1):GND

Q_RES_0402LF-18K,1%,1/16W,CHIP,CS31802FB04  I243  R1221
   1 P1V2_AUX_ADC      A @T6G_MB_LIB.T6G(SCH_1):P1V2_AUX_ADC
   2    GND      B @T6G_MB_LIB.T6G(SCH_1):GND

Q_RES_0402LF-18K,1%,1/16W,CHIP,CS31802FB04  I244  R1220
   1 P1V8_CPU0_RT_1D_ADC      A @T6G_MB_LIB.T6G(SCH_1):P1V8_CPU0_RT_1D_ADC
   2    GND      B @T6G_MB_LIB.T6G(SCH_1):GND

Q_RES_0402LF-18K,1%,1/16W,CHIP,CS31802FB04  I245  R1223
   1 P1V8_CPU1_RT_1D_ADC      A @T6G_MB_LIB.T6G(SCH_1):P1V8_CPU1_RT_1D_ADC
   2    GND      B @T6G_MB_LIB.T6G(SCH_1):GND

Q_RES_0402LF-18K,1%,1/16W,CHIP,CS31802FB04  I246  R1222
   1 PVDD18_S5_P0_ADC      A @T6G_MB_LIB.T6G(SCH_1):PVDD18_S5_P0_ADC
   2    GND      B @T6G_MB_LIB.T6G(SCH_1):GND

Q_RES_0402LF-18K,1%,1/16W,CHIP,CS31802FB04  I247  R1225
   1 PVDD18_S5_P1_ADC      A @T6G_MB_LIB.T6G(SCH_1):PVDD18_S5_P1_ADC
   2    GND      B @T6G_MB_LIB.T6G(SCH_1):GND


DRAWING: @T6G_MB_LIB.T6G(SCH_1):PAGE466 

Q_RES_2512LF-0.002,1%,2W,CHIP,CS+002AFR06  I2  R1324
   1 P12V_OCP_SFF_R      A @T6G_MB_LIB.T6G(SCH_1):P12V_OCP_SFF_R
   2 P12V_OCP_SFF      B @T6G_MB_LIB.T6G(SCH_1):P12V_OCP_SFF

Q_CAP_0402-0.1UF,25V,10%,X7R,CH4104K1B00  I5  C1108
   1 P12V_OCP_SFF      A @T6G_MB_LIB.T6G(SCH_1):P12V_OCP_SFF
   2    GND      B @T6G_MB_LIB.T6G(SCH_1):GND

Q_RES_0402LF-10,1%,1/16W,CHIP,CS01002FB07  I10  R1284
   1 P12V_OCP_SFF      A @T6G_MB_LIB.T6G(SCH_1):P12V_OCP_SFF
   2 VSENSE_P12V_INA230_6_INP      B @T6G_MB_LIB.T6G(SCH_1):VSENSE_P12V_INA230_6_INP

Q_RES_0402LF-10,1%,1/16W,CHIP,CS01002FB07  I11  R1301
   1 P12V_OCP_SFF_R      A @T6G_MB_LIB.T6G(SCH_1):P12V_OCP_SFF_R
   2 VSENSE_P12V_INA230_6_INN      B @T6G_MB_LIB.T6G(SCH_1):VSENSE_P12V_INA230_6_INN

Q_RES_0402LF-4.7K,1%,1/16W,EMPTY,CS24702FB06  I12  R1306
   1    GND      A @T6G_MB_LIB.T6G(SCH_1):GND
   2 INA230_6_A1      B @T6G_MB_LIB.T6G(SCH_1):INA230_6_A1

Q_RES_0402LF-4.7K,1%,1/16W,EMPTY,CS24702FB06  I13  R1309
   1    GND      A @T6G_MB_LIB.T6G(SCH_1):GND
   2 INA230_6_A0      B @T6G_MB_LIB.T6G(SCH_1):INA230_6_A0

Q_RES_0402LF-0,5%,1/16W,CHIP,CS00002JB13  I14  R1276
   1 SMB_INA230_6_3V3AUX_SDA_R      A @T6G_MB_LIB.T6G(SCH_1):SMB_INA230_6_3V3AUX_SDA_R
   2 SMB_INA230_6_3V3AUX_SDA_R1      B @T6G_MB_LIB.T6G(SCH_1):SMB_INA230_6_3V3AUX_SDA_R1

Q_CAP_0402-0.1UF,25V,10%,X7R,CH4104K1B00  I15  C1111
   1 VSENSE_P12V_INA230_6_INP      A @T6G_MB_LIB.T6G(SCH_1):VSENSE_P12V_INA230_6_INP
   2 VSENSE_P12V_INA230_6_INN      B @T6G_MB_LIB.T6G(SCH_1):VSENSE_P12V_INA230_6_INN

Q_RES_0402LF-4.7K,1%,1/16W,CHIP,CS24702FB06  I17  R1320
   1 P3V3_AUX      A @T6G_MB_LIB.T6G(SCH_1):P3V3_AUX
   2 INA230_6_A1      B @T6G_MB_LIB.T6G(SCH_1):INA230_6_A1

Q_CAP_0402-0.1UF,25V,10%,X7R,CH4104K1B00  I19  C1097
   1 P3V3_AUX      A @T6G_MB_LIB.T6G(SCH_1):P3V3_AUX
   2    GND      B @T6G_MB_LIB.T6G(SCH_1):GND

Q_RES_0402LF-0,5%,1/16W,CHIP,CS00002JB13  I23  R1270
   1 P12V_OCP_SFF_ADC_ALERT_R      A @T6G_MB_LIB.T6G(SCH_1):P12V_OCP_SFF_ADC_ALERT_R
   2 OCP_SFF_P3V3_P12V_ADC_R_ALERT      B @T6G_MB_LIB.T6G(SCH_1):OCP_SFF_P3V3_P12V_ADC_R_ALERT

Q_RES_0402LF-0,5%,1/16W,CHIP,CS00002JB13  I27  R1273
   1 SMB_INA230_6_3V3AUX_SCL_R      A @T6G_MB_LIB.T6G(SCH_1):SMB_INA230_6_3V3AUX_SCL_R
   2 SMB_INA230_6_3V3AUX_SCL_R1      B @T6G_MB_LIB.T6G(SCH_1):SMB_INA230_6_3V3AUX_SCL_R1

ISL28022FRZT-ISL28022FRZ-T,SMLF,IC,AL028022003  I28  U55
   9 P3V3_AUX    VCC @T6G_MB_LIB.T6G(SCH_1):P3V3_AUX
   1 INA230_6_A1     A1 @T6G_MB_LIB.T6G(SCH_1):INA230_6_A1
   2 INA230_6_A0     A0 @T6G_MB_LIB.T6G(SCH_1):INA230_6_A0
   5 SMB_INA230_6_3V3AUX_SCL_R1 SCL|||SMBCLK @T6G_MB_LIB.T6G(SCH_1):SMB_INA230_6_3V3AUX_SCL_R1
   4 SMB_INA230_6_3V3AUX_SDA_R1 SDA||SMBDAT @T6G_MB_LIB.T6G(SCH_1):SMB_INA230_6_3V3AUX_SDA_R1
  11 P12V_OCP_SFF   VBUS @T6G_MB_LIB.T6G(SCH_1):P12V_OCP_SFF
  13 VSENSE_P12V_INA230_6_INP   VINP @T6G_MB_LIB.T6G(SCH_1):VSENSE_P12V_INA230_6_INP
  12 VSENSE_P12V_INA230_6_INN   VINM @T6G_MB_LIB.T6G(SCH_1):VSENSE_P12V_INA230_6_INN
   3 P12V_OCP_SFF_ADC_ALERT_R EXT_CLK||INT @T6G_MB_LIB.T6G(SCH_1):P12V_OCP_SFF_ADC_ALERT_R
   6 NC_INA230_6_NC0    NC0 @T6G_MB_LIB.T6G(SCH_1):NC_INA230_6_NC0
   7 NC_INA230_6_NC1    NC1 @T6G_MB_LIB.T6G(SCH_1):NC_INA230_6_NC1
   8 NC_INA230_6_NC2    NC2 @T6G_MB_LIB.T6G(SCH_1):NC_INA230_6_NC2
  14 NC_INA230_6_NC3    NC3 @T6G_MB_LIB.T6G(SCH_1):NC_INA230_6_NC3
  15 NC_INA230_6_NC4    NC4 @T6G_MB_LIB.T6G(SCH_1):NC_INA230_6_NC4
  16 NC_INA230_6_NC5    NC5 @T6G_MB_LIB.T6G(SCH_1):NC_INA230_6_NC5
  10    GND    GND @T6G_MB_LIB.T6G(SCH_1):GND
  TH    GND TH_GND @T6G_MB_LIB.T6G(SCH_1):GND

ISL28022FRZT-ISL28022FRZ-T,SMLF,IC,AL028022003  I29  U56
   9 P3V3_AUX    VCC @T6G_MB_LIB.T6G(SCH_1):P3V3_AUX
   1 INA230_7_A1     A1 @T6G_MB_LIB.T6G(SCH_1):INA230_7_A1
   2 INA230_7_A0     A0 @T6G_MB_LIB.T6G(SCH_1):INA230_7_A0
   5 SMB_INA230_7_3V3AUX_SCL_R1 SCL|||SMBCLK @T6G_MB_LIB.T6G(SCH_1):SMB_INA230_7_3V3AUX_SCL_R1
   4 SMB_INA230_7_3V3AUX_SDA_R1 SDA||SMBDAT @T6G_MB_LIB.T6G(SCH_1):SMB_INA230_7_3V3AUX_SDA_R1
  11 P12V_OCP_V3_2   VBUS @T6G_MB_LIB.T6G(SCH_1):P12V_OCP_V3_2
  13 VSENSE_P12V_INA230_7_INP   VINP @T6G_MB_LIB.T6G(SCH_1):VSENSE_P12V_INA230_7_INP
  12 VSENSE_P12V_INA230_7_INN   VINM @T6G_MB_LIB.T6G(SCH_1):VSENSE_P12V_INA230_7_INN
   3 P12V_OCP_V3_2_ADC_ALERT_R EXT_CLK||INT @T6G_MB_LIB.T6G(SCH_1):P12V_OCP_V3_2_ADC_ALERT_R
   6 NC_INA230_7_NC0    NC0 @T6G_MB_LIB.T6G(SCH_1):NC_INA230_7_NC0
   7 NC_INA230_7_NC1    NC1 @T6G_MB_LIB.T6G(SCH_1):NC_INA230_7_NC1
   8 NC_INA230_7_NC2    NC2 @T6G_MB_LIB.T6G(SCH_1):NC_INA230_7_NC2
  14 NC_INA230_7_NC3    NC3 @T6G_MB_LIB.T6G(SCH_1):NC_INA230_7_NC3
  15 NC_INA230_7_NC4    NC4 @T6G_MB_LIB.T6G(SCH_1):NC_INA230_7_NC4
  16 NC_INA230_7_NC5    NC5 @T6G_MB_LIB.T6G(SCH_1):NC_INA230_7_NC5
  10    GND    GND @T6G_MB_LIB.T6G(SCH_1):GND
  TH    GND TH_GND @T6G_MB_LIB.T6G(SCH_1):GND

Q_RES_0402LF-0,5%,1/16W,CHIP,CS00002JB13  I33  R1271
   1 P12V_OCP_V3_2_ADC_ALERT_R      A @T6G_MB_LIB.T6G(SCH_1):P12V_OCP_V3_2_ADC_ALERT_R
   2 OCP_V3_2_P3V3_P12V_ADC_R_ALERT      B @T6G_MB_LIB.T6G(SCH_1):OCP_V3_2_P3V3_P12V_ADC_R_ALERT

Q_CAP_0402-0.1UF,25V,10%,X7R,CH4104K1B00  I36  C1106
   1 P3V3_AUX      A @T6G_MB_LIB.T6G(SCH_1):P3V3_AUX
   2    GND      B @T6G_MB_LIB.T6G(SCH_1):GND

Q_RES_0402LF-4.7K,1%,1/16W,CHIP,CS24702FB06  I39  R1322
   1 P3V3_AUX      A @T6G_MB_LIB.T6G(SCH_1):P3V3_AUX
   2 INA230_7_A1      B @T6G_MB_LIB.T6G(SCH_1):INA230_7_A1

Q_RES_0402LF-0,5%,1/16W,CHIP,CS00002JB13  I41  R1277
   1 SMB_INA230_7_3V3AUX_SDA_R      A @T6G_MB_LIB.T6G(SCH_1):SMB_INA230_7_3V3AUX_SDA_R
   2 SMB_INA230_7_3V3AUX_SDA_R1      B @T6G_MB_LIB.T6G(SCH_1):SMB_INA230_7_3V3AUX_SDA_R1

Q_RES_0402LF-0,5%,1/16W,CHIP,CS00002JB13  I42  R1274
   1 SMB_INA230_7_3V3AUX_SCL_R      A @T6G_MB_LIB.T6G(SCH_1):SMB_INA230_7_3V3AUX_SCL_R
   2 SMB_INA230_7_3V3AUX_SCL_R1      B @T6G_MB_LIB.T6G(SCH_1):SMB_INA230_7_3V3AUX_SCL_R1

Q_RES_0402LF-10,1%,1/16W,CHIP,CS01002FB07  I43  R1291
   1 P12V_OCP_V3_2      A @T6G_MB_LIB.T6G(SCH_1):P12V_OCP_V3_2
   2 VSENSE_P12V_INA230_7_INP      B @T6G_MB_LIB.T6G(SCH_1):VSENSE_P12V_INA230_7_INP

Q_RES_0402LF-4.7K,1%,1/16W,EMPTY,CS24702FB06  I44  R1307
   1    GND      A @T6G_MB_LIB.T6G(SCH_1):GND
   2 INA230_7_A1      B @T6G_MB_LIB.T6G(SCH_1):INA230_7_A1

Q_RES_0402LF-4.7K,1%,1/16W,EMPTY,CS24702FB06  I45  R1310
   1    GND      A @T6G_MB_LIB.T6G(SCH_1):GND
   2 INA230_7_A0      B @T6G_MB_LIB.T6G(SCH_1):INA230_7_A0

Q_CAP_0402-0.1UF,25V,10%,X7R,CH4104K1B00  I51  C1109
   1 P12V_OCP_V3_2      A @T6G_MB_LIB.T6G(SCH_1):P12V_OCP_V3_2
   2    GND      B @T6G_MB_LIB.T6G(SCH_1):GND

Q_RES_2512LF-0.002,1%,2W,CHIP,CS+002AFR06  I53  R1325
   1 P12V_OCP_V3_2_R      A @T6G_MB_LIB.T6G(SCH_1):P12V_OCP_V3_2_R
   2 P12V_OCP_V3_2      B @T6G_MB_LIB.T6G(SCH_1):P12V_OCP_V3_2

Q_CAP_0402-0.1UF,25V,10%,X7R,CH4104K1B00  I54  C1112
   1 VSENSE_P12V_INA230_7_INP      A @T6G_MB_LIB.T6G(SCH_1):VSENSE_P12V_INA230_7_INP
   2 VSENSE_P12V_INA230_7_INN      B @T6G_MB_LIB.T6G(SCH_1):VSENSE_P12V_INA230_7_INN

Q_RES_0402LF-10,1%,1/16W,CHIP,CS01002FB07  I55  R1302
   1 P12V_OCP_V3_2_R      A @T6G_MB_LIB.T6G(SCH_1):P12V_OCP_V3_2_R
   2 VSENSE_P12V_INA230_7_INN      B @T6G_MB_LIB.T6G(SCH_1):VSENSE_P12V_INA230_7_INN

ISL28022FRZT-ISL28022FRZ-T,SMLF,IC,AL028022003  I57  U52
   9 P3V3_AUX    VCC @T6G_MB_LIB.T6G(SCH_1):P3V3_AUX
   1 INA230_8_A1     A1 @T6G_MB_LIB.T6G(SCH_1):INA230_8_A1
   2 INA230_8_A0     A0 @T6G_MB_LIB.T6G(SCH_1):INA230_8_A0
   5 SMB_INA230_8_3V3AUX_SCL_R1 SCL|||SMBCLK @T6G_MB_LIB.T6G(SCH_1):SMB_INA230_8_3V3AUX_SCL_R1
   4 SMB_INA230_8_3V3AUX_SDA_R1 SDA||SMBDAT @T6G_MB_LIB.T6G(SCH_1):SMB_INA230_8_3V3AUX_SDA_R1
  11 P12V_E1S_0   VBUS @T6G_MB_LIB.T6G(SCH_1):P12V_E1S_0
  13 VSENSE_P12V_INA230_8_INP   VINP @T6G_MB_LIB.T6G(SCH_1):VSENSE_P12V_INA230_8_INP
  12 VSENSE_P12V_INA230_8_INN   VINM @T6G_MB_LIB.T6G(SCH_1):VSENSE_P12V_INA230_8_INN
   3 P12V_E1S_0_ADC_ALERT_R EXT_CLK||INT @T6G_MB_LIB.T6G(SCH_1):P12V_E1S_0_ADC_ALERT_R
   6 NC_INA230_8_NC0    NC0 @T6G_MB_LIB.T6G(SCH_1):NC_INA230_8_NC0
   7 NC_INA230_8_NC1    NC1 @T6G_MB_LIB.T6G(SCH_1):NC_INA230_8_NC1
   8 NC_INA230_8_NC2    NC2 @T6G_MB_LIB.T6G(SCH_1):NC_INA230_8_NC2
  14 NC_INA230_8_NC3    NC3 @T6G_MB_LIB.T6G(SCH_1):NC_INA230_8_NC3
  15 NC_INA230_8_NC4    NC4 @T6G_MB_LIB.T6G(SCH_1):NC_INA230_8_NC4
  16 NC_INA230_8_NC5    NC5 @T6G_MB_LIB.T6G(SCH_1):NC_INA230_8_NC5
  10    GND    GND @T6G_MB_LIB.T6G(SCH_1):GND
  TH    GND TH_GND @T6G_MB_LIB.T6G(SCH_1):GND

Q_RES_0402LF-0,5%,1/16W,CHIP,CS00002JB13  I62  R1269
   1 P12V_E1S_0_ADC_ALERT_R      A @T6G_MB_LIB.T6G(SCH_1):P12V_E1S_0_ADC_ALERT_R
   2 E1S_0_P3V3_P12V_ADC_R_ALERT      B @T6G_MB_LIB.T6G(SCH_1):E1S_0_P3V3_P12V_ADC_R_ALERT

Q_CAP_0402-0.1UF,25V,10%,X7R,CH4104K1B00  I66  C1096
   1 P3V3_AUX      A @T6G_MB_LIB.T6G(SCH_1):P3V3_AUX
   2    GND      B @T6G_MB_LIB.T6G(SCH_1):GND

Q_CAP_0402-0.1UF,25V,10%,X7R,CH4104K1B00  I68  C1110
   1 VSENSE_P12V_INA230_8_INP      A @T6G_MB_LIB.T6G(SCH_1):VSENSE_P12V_INA230_8_INP
   2 VSENSE_P12V_INA230_8_INN      B @T6G_MB_LIB.T6G(SCH_1):VSENSE_P12V_INA230_8_INN

Q_RES_0402LF-0,5%,1/16W,CHIP,CS00002JB13  I70  R1275
   1 SMB_INA230_8_3V3AUX_SDA_R      A @T6G_MB_LIB.T6G(SCH_1):SMB_INA230_8_3V3AUX_SDA_R
   2 SMB_INA230_8_3V3AUX_SDA_R1      B @T6G_MB_LIB.T6G(SCH_1):SMB_INA230_8_3V3AUX_SDA_R1

Q_RES_0402LF-0,5%,1/16W,CHIP,CS00002JB13  I71  R1272
   1 SMB_INA230_8_3V3AUX_SCL_R      A @T6G_MB_LIB.T6G(SCH_1):SMB_INA230_8_3V3AUX_SCL_R
   2 SMB_INA230_8_3V3AUX_SCL_R1      B @T6G_MB_LIB.T6G(SCH_1):SMB_INA230_8_3V3AUX_SCL_R1

Q_RES_0402LF-4.7K,1%,1/16W,EMPTY,CS24702FB06  I72  R1305
   1    GND      A @T6G_MB_LIB.T6G(SCH_1):GND
   2 INA230_8_A1      B @T6G_MB_LIB.T6G(SCH_1):INA230_8_A1

Q_RES_0402LF-10,1%,1/16W,CHIP,CS01002FB07  I74  R1283
   1 P12V_E1S_0      A @T6G_MB_LIB.T6G(SCH_1):P12V_E1S_0
   2 VSENSE_P12V_INA230_8_INP      B @T6G_MB_LIB.T6G(SCH_1):VSENSE_P12V_INA230_8_INP

Q_RES_0402LF-10,1%,1/16W,CHIP,CS01002FB07  I75  R1292
   1 P12V_E1S_0_R      A @T6G_MB_LIB.T6G(SCH_1):P12V_E1S_0_R
   2 VSENSE_P12V_INA230_8_INN      B @T6G_MB_LIB.T6G(SCH_1):VSENSE_P12V_INA230_8_INN

Q_CAP_0402-0.1UF,25V,10%,X7R,CH4104K1B00  I81  C1107
   1 P12V_E1S_0      A @T6G_MB_LIB.T6G(SCH_1):P12V_E1S_0
   2    GND      B @T6G_MB_LIB.T6G(SCH_1):GND

Q_RES_2512LF-0.002,1%,2W,CHIP,CS+002AFR06  I84  R1323
   1 P12V_E1S_0_R      A @T6G_MB_LIB.T6G(SCH_1):P12V_E1S_0_R
   2 P12V_E1S_0      B @T6G_MB_LIB.T6G(SCH_1):P12V_E1S_0

Q_RES_0402LF-1K,1%,1/16W,EMPTY,CS21002FB06  I85  R1327
   1 P3V3_AUX      A @T6G_MB_LIB.T6G(SCH_1):P3V3_AUX
   2 OCP_SFF_P3V3_P12V_ADC_R_ALERT      B @T6G_MB_LIB.T6G(SCH_1):OCP_SFF_P3V3_P12V_ADC_R_ALERT

Q_RES_0402LF-1K,1%,1/16W,EMPTY,CS21002FB06  I87  R1328
   1 P3V3_AUX      A @T6G_MB_LIB.T6G(SCH_1):P3V3_AUX
   2 OCP_V3_2_P3V3_P12V_ADC_R_ALERT      B @T6G_MB_LIB.T6G(SCH_1):OCP_V3_2_P3V3_P12V_ADC_R_ALERT

Q_RES_0402LF-1K,1%,1/16W,EMPTY,CS21002FB06  I90  R1326
   1 P3V3_AUX      A @T6G_MB_LIB.T6G(SCH_1):P3V3_AUX
   2 E1S_0_P3V3_P12V_ADC_R_ALERT      B @T6G_MB_LIB.T6G(SCH_1):E1S_0_P3V3_P12V_ADC_R_ALERT

Q_RES_0402LF-0,5%,1/16W,CHIP,CS00002JB13  I92  R1355
   1 INA230_6_A0      A @T6G_MB_LIB.T6G(SCH_1):INA230_6_A0
   2 SMB_INA230_6_3V3AUX_SDA_R1      B @T6G_MB_LIB.T6G(SCH_1):SMB_INA230_6_3V3AUX_SDA_R1

Q_RES_0402LF-0,5%,1/16W,CHIP,CS00002JB13  I93  R1360
   1 INA230_7_A0      A @T6G_MB_LIB.T6G(SCH_1):INA230_7_A0
   2 SMB_INA230_7_3V3AUX_SCL_R1      B @T6G_MB_LIB.T6G(SCH_1):SMB_INA230_7_3V3AUX_SCL_R1

Q_RES_0402LF-0,5%,1/16W,CHIP,CS00002JB13  I94  R1350
   1 INA230_8_A1      A @T6G_MB_LIB.T6G(SCH_1):INA230_8_A1
   2 SMB_INA230_8_3V3AUX_SDA_R1      B @T6G_MB_LIB.T6G(SCH_1):SMB_INA230_8_3V3AUX_SDA_R1

Q_RES_0402LF-4.7K,1%,1/16W,EMPTY,CS24702FB06  I95  R1317
   1 P3V3_AUX      A @T6G_MB_LIB.T6G(SCH_1):P3V3_AUX
   2 INA230_8_A1      B @T6G_MB_LIB.T6G(SCH_1):INA230_8_A1

Q_RES_0402LF-4.7K,1%,1/16W,CHIP,CS24702FB06  I96  R1308
   1    GND      A @T6G_MB_LIB.T6G(SCH_1):GND
   2 INA230_8_A0      B @T6G_MB_LIB.T6G(SCH_1):INA230_8_A0


DRAWING: @T6G_MB_LIB.T6G(SCH_1):PAGE211 

PICOPROBE_BXA-DELTA-L 4.0,SMLF,EMPTY,TP33  I65  J63
   2 DELTA_L_85_5INCH_TOP_DN    2_N @T6G_MB_LIB.T6G(SCH_1):DELTA_L_85_5INCH_TOP_DN
   3 DELTA_L_GND_1    3_G @T6G_MB_LIB.T6G(SCH_1):DELTA_L_GND_1
   1 DELTA_L_85_5INCH_TOP_DP    1_P @T6G_MB_LIB.T6G(SCH_1):DELTA_L_85_5INCH_TOP_DP

PICOPROBE_BXA-DELTA-L 4.0,SMLF,EMPTY,TP33  I66  J8069
   2 DELTA_L_85_5INCH_TOP_DP    2_N @T6G_MB_LIB.T6G(SCH_1):DELTA_L_85_5INCH_TOP_DP
   3 DELTA_L_GND_1    3_G @T6G_MB_LIB.T6G(SCH_1):DELTA_L_GND_1
   1 DELTA_L_85_5INCH_TOP_DN    1_P @T6G_MB_LIB.T6G(SCH_1):DELTA_L_85_5INCH_TOP_DN

PICOPROBE_BXA-DELTA-L 4.0,SMLF,EMPTY,TP33  I67  J64
   2 DELTA_L_85_5INCH_BOT_DN    2_N @T6G_MB_LIB.T6G(SCH_1):DELTA_L_85_5INCH_BOT_DN
   3 DELTA_L_GND_1    3_G @T6G_MB_LIB.T6G(SCH_1):DELTA_L_GND_1
   1 DELTA_L_85_5INCH_BOT_DP    1_P @T6G_MB_LIB.T6G(SCH_1):DELTA_L_85_5INCH_BOT_DP

PICOPROBE_BXA-DELTA-L 4.0,SMLF,EMPTY,TP33  I68  J70
   2 DELTA_L_85_5INCH_BOT_DP    2_N @T6G_MB_LIB.T6G(SCH_1):DELTA_L_85_5INCH_BOT_DP
   3 DELTA_L_GND_1    3_G @T6G_MB_LIB.T6G(SCH_1):DELTA_L_GND_1
   1 DELTA_L_85_5INCH_BOT_DN    1_P @T6G_MB_LIB.T6G(SCH_1):DELTA_L_85_5INCH_BOT_DN

PICOPROBE_BXA-DELTA-L 4.0,SMLF,EMPTY,TP33  I69  J65
   2 DELTA_L_85_5INCH_IN1_DN    2_N @T6G_MB_LIB.T6G(SCH_1):DELTA_L_85_5INCH_IN1_DN
   3 DELTA_L_GND_1    3_G @T6G_MB_LIB.T6G(SCH_1):DELTA_L_GND_1
   1 DELTA_L_85_5INCH_IN1_DP    1_P @T6G_MB_LIB.T6G(SCH_1):DELTA_L_85_5INCH_IN1_DP

PICOPROBE_BXA-DELTA-L 4.0,SMLF,EMPTY,TP33  I70  J71
   2 DELTA_L_85_5INCH_IN1_DP    2_N @T6G_MB_LIB.T6G(SCH_1):DELTA_L_85_5INCH_IN1_DP
   3 DELTA_L_GND_1    3_G @T6G_MB_LIB.T6G(SCH_1):DELTA_L_GND_1
   1 DELTA_L_85_5INCH_IN1_DN    1_P @T6G_MB_LIB.T6G(SCH_1):DELTA_L_85_5INCH_IN1_DN

PICOPROBE_BXA-DELTA-L 4.0,SMLF,EMPTY,TP33  I71  J66
   2 DELTA_L_85_5INCH_IN2_DN    2_N @T6G_MB_LIB.T6G(SCH_1):DELTA_L_85_5INCH_IN2_DN
   3 DELTA_L_GND_1    3_G @T6G_MB_LIB.T6G(SCH_1):DELTA_L_GND_1
   1 DELTA_L_85_5INCH_IN2_DP    1_P @T6G_MB_LIB.T6G(SCH_1):DELTA_L_85_5INCH_IN2_DP

PICOPROBE_BXA-DELTA-L 4.0,SMLF,EMPTY,TP33  I72  J72
   2 DELTA_L_85_5INCH_IN2_DP    2_N @T6G_MB_LIB.T6G(SCH_1):DELTA_L_85_5INCH_IN2_DP
   3 DELTA_L_GND_1    3_G @T6G_MB_LIB.T6G(SCH_1):DELTA_L_GND_1
   1 DELTA_L_85_5INCH_IN2_DN    1_P @T6G_MB_LIB.T6G(SCH_1):DELTA_L_85_5INCH_IN2_DN

PICOPROBE_BXA-DELTA-L 4.0,SMLF,EMPTY,TP33  I73  J8067
   2 DELTA_L_85_5INCH_IN3_DN    2_N @T6G_MB_LIB.T6G(SCH_1):DELTA_L_85_5INCH_IN3_DN
   3 DELTA_L_GND_1    3_G @T6G_MB_LIB.T6G(SCH_1):DELTA_L_GND_1
   1 DELTA_L_85_5INCH_IN3_DP    1_P @T6G_MB_LIB.T6G(SCH_1):DELTA_L_85_5INCH_IN3_DP

PICOPROBE_BXA-DELTA-L 4.0,SMLF,EMPTY,TP33  I74  J73
   2 DELTA_L_85_5INCH_IN3_DP    2_N @T6G_MB_LIB.T6G(SCH_1):DELTA_L_85_5INCH_IN3_DP
   3 DELTA_L_GND_1    3_G @T6G_MB_LIB.T6G(SCH_1):DELTA_L_GND_1
   1 DELTA_L_85_5INCH_IN3_DN    1_P @T6G_MB_LIB.T6G(SCH_1):DELTA_L_85_5INCH_IN3_DN

PICOPROBE_BXA-DELTA-L 4.0,SMLF,EMPTY,TP33  I75  J8068
   2 DELTA_L_85_5INCH_IN4_DN    2_N @T6G_MB_LIB.T6G(SCH_1):DELTA_L_85_5INCH_IN4_DN
   3 DELTA_L_GND_1    3_G @T6G_MB_LIB.T6G(SCH_1):DELTA_L_GND_1
   1 DELTA_L_85_5INCH_IN4_DP    1_P @T6G_MB_LIB.T6G(SCH_1):DELTA_L_85_5INCH_IN4_DP

PICOPROBE_BXA-DELTA-L 4.0,SMLF,EMPTY,TP33  I76  J74
   2 DELTA_L_85_5INCH_IN4_DP    2_N @T6G_MB_LIB.T6G(SCH_1):DELTA_L_85_5INCH_IN4_DP
   3 DELTA_L_GND_1    3_G @T6G_MB_LIB.T6G(SCH_1):DELTA_L_GND_1
   1 DELTA_L_85_5INCH_IN4_DN    1_P @T6G_MB_LIB.T6G(SCH_1):DELTA_L_85_5INCH_IN4_DN

PICOPROBE_BXA-DELTA-L 4.0,SMLF,EMPTY,TP33  I77  J114
   2 DELTA_L_85_5INCH_IN5_DN    2_N @T6G_MB_LIB.T6G(SCH_1):DELTA_L_85_5INCH_IN5_DN
   3 DELTA_L_GND_1    3_G @T6G_MB_LIB.T6G(SCH_1):DELTA_L_GND_1
   1 DELTA_L_85_5INCH_IN5_DP    1_P @T6G_MB_LIB.T6G(SCH_1):DELTA_L_85_5INCH_IN5_DP

PICOPROBE_BXA-DELTA-L 4.0,SMLF,EMPTY,TP33  I78  J116
   2 DELTA_L_85_5INCH_IN5_DP    2_N @T6G_MB_LIB.T6G(SCH_1):DELTA_L_85_5INCH_IN5_DP
   3 DELTA_L_GND_1    3_G @T6G_MB_LIB.T6G(SCH_1):DELTA_L_GND_1
   1 DELTA_L_85_5INCH_IN5_DN    1_P @T6G_MB_LIB.T6G(SCH_1):DELTA_L_85_5INCH_IN5_DN

PICOPROBE_BXA-DELTA-L 4.0,SMLF,EMPTY,TP33  I79  J115
   2 DELTA_L_85_5INCH_IN6_DN    2_N @T6G_MB_LIB.T6G(SCH_1):DELTA_L_85_5INCH_IN6_DN
   3 DELTA_L_GND_1    3_G @T6G_MB_LIB.T6G(SCH_1):DELTA_L_GND_1
   1 DELTA_L_85_5INCH_IN6_DP    1_P @T6G_MB_LIB.T6G(SCH_1):DELTA_L_85_5INCH_IN6_DP

PICOPROBE_BXA-DELTA-L 4.0,SMLF,EMPTY,TP33  I80  J117
   2 DELTA_L_85_5INCH_IN6_DP    2_N @T6G_MB_LIB.T6G(SCH_1):DELTA_L_85_5INCH_IN6_DP
   3 DELTA_L_GND_1    3_G @T6G_MB_LIB.T6G(SCH_1):DELTA_L_GND_1
   1 DELTA_L_85_5INCH_IN6_DN    1_P @T6G_MB_LIB.T6G(SCH_1):DELTA_L_85_5INCH_IN6_DN

PICOPROBE_BXA-DELTA-L 4.0,SMLF,EMPTY,TP33  I81  J75
   2 DELTA_L_85_10INCH_TOP_DN    2_N @T6G_MB_LIB.T6G(SCH_1):DELTA_L_85_10INCH_TOP_DN
   3 DELTA_L_GND_1    3_G @T6G_MB_LIB.T6G(SCH_1):DELTA_L_GND_1
   1 DELTA_L_85_10INCH_TOP_DP    1_P @T6G_MB_LIB.T6G(SCH_1):DELTA_L_85_10INCH_TOP_DP

PICOPROBE_BXA-DELTA-L 4.0,SMLF,EMPTY,TP33  I82  J81
   2 DELTA_L_85_10INCH_TOP_DP    2_N @T6G_MB_LIB.T6G(SCH_1):DELTA_L_85_10INCH_TOP_DP
   3 DELTA_L_GND_1    3_G @T6G_MB_LIB.T6G(SCH_1):DELTA_L_GND_1
   1 DELTA_L_85_10INCH_TOP_DN    1_P @T6G_MB_LIB.T6G(SCH_1):DELTA_L_85_10INCH_TOP_DN

PICOPROBE_BXA-DELTA-L 4.0,SMLF,EMPTY,TP33  I83  J76
   2 DELTA_L_85_10INCH_BOT_DN    2_N @T6G_MB_LIB.T6G(SCH_1):DELTA_L_85_10INCH_BOT_DN
   3 DELTA_L_GND_1    3_G @T6G_MB_LIB.T6G(SCH_1):DELTA_L_GND_1
   1 DELTA_L_85_10INCH_BOT_DP    1_P @T6G_MB_LIB.T6G(SCH_1):DELTA_L_85_10INCH_BOT_DP

PICOPROBE_BXA-DELTA-L 4.0,SMLF,EMPTY,TP33  I84  J82
   2 DELTA_L_85_10INCH_BOT_DP    2_N @T6G_MB_LIB.T6G(SCH_1):DELTA_L_85_10INCH_BOT_DP
   3 DELTA_L_GND_1    3_G @T6G_MB_LIB.T6G(SCH_1):DELTA_L_GND_1
   1 DELTA_L_85_10INCH_BOT_DN    1_P @T6G_MB_LIB.T6G(SCH_1):DELTA_L_85_10INCH_BOT_DN

PICOPROBE_BXA-DELTA-L 4.0,SMLF,EMPTY,TP33  I85  J77
   2 DELTA_L_85_10INCH_IN1_DN    2_N @T6G_MB_LIB.T6G(SCH_1):DELTA_L_85_10INCH_IN1_DN
   3 DELTA_L_GND_1    3_G @T6G_MB_LIB.T6G(SCH_1):DELTA_L_GND_1
   1 DELTA_L_85_10INCH_IN1_DP    1_P @T6G_MB_LIB.T6G(SCH_1):DELTA_L_85_10INCH_IN1_DP

PICOPROBE_BXA-DELTA-L 4.0,SMLF,EMPTY,TP33  I86  J83
   2 DELTA_L_85_10INCH_IN1_DP    2_N @T6G_MB_LIB.T6G(SCH_1):DELTA_L_85_10INCH_IN1_DP
   3 DELTA_L_GND_1    3_G @T6G_MB_LIB.T6G(SCH_1):DELTA_L_GND_1
   1 DELTA_L_85_10INCH_IN1_DN    1_P @T6G_MB_LIB.T6G(SCH_1):DELTA_L_85_10INCH_IN1_DN

PICOPROBE_BXA-DELTA-L 4.0,SMLF,EMPTY,TP33  I87  J78
   2 DELTA_L_85_10INCH_IN2_DN    2_N @T6G_MB_LIB.T6G(SCH_1):DELTA_L_85_10INCH_IN2_DN
   3 DELTA_L_GND_1    3_G @T6G_MB_LIB.T6G(SCH_1):DELTA_L_GND_1
   1 DELTA_L_85_10INCH_IN2_DP    1_P @T6G_MB_LIB.T6G(SCH_1):DELTA_L_85_10INCH_IN2_DP

PICOPROBE_BXA-DELTA-L 4.0,SMLF,EMPTY,TP33  I88  J84
   2 DELTA_L_85_10INCH_IN2_DP    2_N @T6G_MB_LIB.T6G(SCH_1):DELTA_L_85_10INCH_IN2_DP
   3 DELTA_L_GND_1    3_G @T6G_MB_LIB.T6G(SCH_1):DELTA_L_GND_1
   1 DELTA_L_85_10INCH_IN2_DN    1_P @T6G_MB_LIB.T6G(SCH_1):DELTA_L_85_10INCH_IN2_DN

PICOPROBE_BXA-DELTA-L 4.0,SMLF,EMPTY,TP33  I89  J79
   2 DELTA_L_85_10INCH_IN3_DN    2_N @T6G_MB_LIB.T6G(SCH_1):DELTA_L_85_10INCH_IN3_DN
   3 DELTA_L_GND_1    3_G @T6G_MB_LIB.T6G(SCH_1):DELTA_L_GND_1
   1 DELTA_L_85_10INCH_IN3_DP    1_P @T6G_MB_LIB.T6G(SCH_1):DELTA_L_85_10INCH_IN3_DP

PICOPROBE_BXA-DELTA-L 4.0,SMLF,EMPTY,TP33  I90  J85
   2 DELTA_L_85_10INCH_IN3_DP    2_N @T6G_MB_LIB.T6G(SCH_1):DELTA_L_85_10INCH_IN3_DP
   3 DELTA_L_GND_1    3_G @T6G_MB_LIB.T6G(SCH_1):DELTA_L_GND_1
   1 DELTA_L_85_10INCH_IN3_DN    1_P @T6G_MB_LIB.T6G(SCH_1):DELTA_L_85_10INCH_IN3_DN

PICOPROBE_BXA-DELTA-L 4.0,SMLF,EMPTY,TP33  I91  J80
   2 DELTA_L_85_10INCH_IN4_DN    2_N @T6G_MB_LIB.T6G(SCH_1):DELTA_L_85_10INCH_IN4_DN
   3 DELTA_L_GND_1    3_G @T6G_MB_LIB.T6G(SCH_1):DELTA_L_GND_1
   1 DELTA_L_85_10INCH_IN4_DP    1_P @T6G_MB_LIB.T6G(SCH_1):DELTA_L_85_10INCH_IN4_DP

PICOPROBE_BXA-DELTA-L 4.0,SMLF,EMPTY,TP33  I92  J86
   2 DELTA_L_85_10INCH_IN4_DP    2_N @T6G_MB_LIB.T6G(SCH_1):DELTA_L_85_10INCH_IN4_DP
   3 DELTA_L_GND_1    3_G @T6G_MB_LIB.T6G(SCH_1):DELTA_L_GND_1
   1 DELTA_L_85_10INCH_IN4_DN    1_P @T6G_MB_LIB.T6G(SCH_1):DELTA_L_85_10INCH_IN4_DN

PICOPROBE_BXA-DELTA-L 4.0,SMLF,EMPTY,TP33  I93  J118
   2 DELTA_L_85_10INCH_IN5_DN    2_N @T6G_MB_LIB.T6G(SCH_1):DELTA_L_85_10INCH_IN5_DN
   3 DELTA_L_GND_1    3_G @T6G_MB_LIB.T6G(SCH_1):DELTA_L_GND_1
   1 DELTA_L_85_10INCH_IN5_DP    1_P @T6G_MB_LIB.T6G(SCH_1):DELTA_L_85_10INCH_IN5_DP

PICOPROBE_BXA-DELTA-L 4.0,SMLF,EMPTY,TP33  I94  J120
   2 DELTA_L_85_10INCH_IN5_DP    2_N @T6G_MB_LIB.T6G(SCH_1):DELTA_L_85_10INCH_IN5_DP
   3 DELTA_L_GND_1    3_G @T6G_MB_LIB.T6G(SCH_1):DELTA_L_GND_1
   1 DELTA_L_85_10INCH_IN5_DN    1_P @T6G_MB_LIB.T6G(SCH_1):DELTA_L_85_10INCH_IN5_DN

PICOPROBE_BXA-DELTA-L 4.0,SMLF,EMPTY,TP33  I95  J119
   2 DELTA_L_85_10INCH_IN6_DN    2_N @T6G_MB_LIB.T6G(SCH_1):DELTA_L_85_10INCH_IN6_DN
   3 DELTA_L_GND_1    3_G @T6G_MB_LIB.T6G(SCH_1):DELTA_L_GND_1
   1 DELTA_L_85_10INCH_IN6_DP    1_P @T6G_MB_LIB.T6G(SCH_1):DELTA_L_85_10INCH_IN6_DP

PICOPROBE_BXA-DELTA-L 4.0,SMLF,EMPTY,TP33  I96  J121
   2 DELTA_L_85_10INCH_IN6_DP    2_N @T6G_MB_LIB.T6G(SCH_1):DELTA_L_85_10INCH_IN6_DP
   3 DELTA_L_GND_1    3_G @T6G_MB_LIB.T6G(SCH_1):DELTA_L_GND_1
   1 DELTA_L_85_10INCH_IN6_DN    1_P @T6G_MB_LIB.T6G(SCH_1):DELTA_L_85_10INCH_IN6_DN


DRAWING: @T6G_MB_LIB.T6G(SCH_1):PAGE146 

Q_RES_0402LF-30K,1%,1/16W,EMPTY,CS33002FB02  I2  R700
   1 P12V_AUX      A @T6G_MB_LIB.T6G(SCH_1):P12V_AUX
   2 P12V_AUX_DSC_VOL      B @T6G_MB_LIB.T6G(SCH_1):P12V_AUX_DSC_VOL

Q_RES_0402LF-11.5K,1%,1/16W,EMPTY,CS31152FB03  I3  R855
   1 P12V_AUX_DSC_VOL      A @T6G_MB_LIB.T6G(SCH_1):P12V_AUX_DSC_VOL
   2    GND      B @T6G_MB_LIB.T6G(SCH_1):GND

SCHOTTKY_DUAL_12A_3C-BAT54CW,SMLF,EMPTY,BCBAT54CZ13  I5  U57
   2     NC      A     NC
   1 P12V_AUX_DSC_VOL      B @T6G_MB_LIB.T6G(SCH_1):P12V_AUX_DSC_VOL
   3 P12V_AUX_DSC_S1      C @T6G_MB_LIB.T6G(SCH_1):P12V_AUX_DSC_S1

Q_CAP_C0805-22UF,16V,20%,EMPTY,CH6223MEA00  I6  C1113
   1 P12V_AUX_DSC_S1      A @T6G_MB_LIB.T6G(SCH_1):P12V_AUX_DSC_S1
   2    GND      B @T6G_MB_LIB.T6G(SCH_1):GND

MOSFET_PCH_GDS_ESD_PROTECTED-DMP2035U-7,SMLF,EMPTYA  I10  Q7000
   D P12V_AUX_DSC_G2      D @T6G_MB_LIB.T6G(SCH_1):P12V_AUX_DSC_G2
   G P12V_AUX_DSC_G1      G @T6G_MB_LIB.T6G(SCH_1):P12V_AUX_DSC_G1
   S P12V_AUX_DSC_S1      S @T6G_MB_LIB.T6G(SCH_1):P12V_AUX_DSC_S1

Q_RES_0402LF-2K,1%,1/16W,EMPTY,CS22002FB07  I11  R1007
   1 P12V_AUX      A @T6G_MB_LIB.T6G(SCH_1):P12V_AUX
   2 P12V_AUX_DSC_G1      B @T6G_MB_LIB.T6G(SCH_1):P12V_AUX_DSC_G1

Q_RES_0402LF-1K,1%,1/16W,EMPTY,CS21002FB06  I12  R1049
   1 P12V_AUX_DSC_G1      A @T6G_MB_LIB.T6G(SCH_1):P12V_AUX_DSC_G1
   2    GND      B @T6G_MB_LIB.T6G(SCH_1):GND

Q_RES_0402LF-10K,1%,1/16W,EMPTY,CS31002FB08  I14  R1474
   1 P12V_AUX_DSC_G2      A @T6G_MB_LIB.T6G(SCH_1):P12V_AUX_DSC_G2
   2    GND      B @T6G_MB_LIB.T6G(SCH_1):GND

MOSFET_NCH_1D3S-PSMNR58-30YLH,SMLF,EMPTY,BAMNR5800A  I16  Q7001
   3    GND      3 @T6G_MB_LIB.T6G(SCH_1):GND
   5 P12V_AUX_DSC      5 @T6G_MB_LIB.T6G(SCH_1):P12V_AUX_DSC
   2    GND      2 @T6G_MB_LIB.T6G(SCH_1):GND
   4 P12V_AUX_DSC_G2      4 @T6G_MB_LIB.T6G(SCH_1):P12V_AUX_DSC_G2
   1    GND      1 @T6G_MB_LIB.T6G(SCH_1):GND

Q_RES_2512LF-10,1%,2W,EMPTY,CS0100AFR00  I19  R1480
   1 P12V_AUX      A @T6G_MB_LIB.T6G(SCH_1):P12V_AUX
   2 P12V_AUX_DSC      B @T6G_MB_LIB.T6G(SCH_1):P12V_AUX_DSC

Q_RES_2512LF-10,1%,2W,EMPTY,CS0100AFR00  I21  R1481
   1 P3V3_AUX      A @T6G_MB_LIB.T6G(SCH_1):P3V3_AUX
   2 P3V3_AUX_DSC      B @T6G_MB_LIB.T6G(SCH_1):P3V3_AUX_DSC

MOSFET_NCH_1D3S-PSMNR58-30YLH,SMLF,EMPTY,BAMNR5800A  I22  Q7003
   3    GND      3 @T6G_MB_LIB.T6G(SCH_1):GND
   5 P3V3_AUX_DSC      5 @T6G_MB_LIB.T6G(SCH_1):P3V3_AUX_DSC
   2    GND      2 @T6G_MB_LIB.T6G(SCH_1):GND
   4 P3V3_AUX_DSC_G2      4 @T6G_MB_LIB.T6G(SCH_1):P3V3_AUX_DSC_G2
   1    GND      1 @T6G_MB_LIB.T6G(SCH_1):GND

MOSFET_PCH_GDS_ESD_PROTECTED-DMP2035U-7,SMLF,EMPTYA  I23  Q7002
   D P3V3_AUX_DSC_G2      D @T6G_MB_LIB.T6G(SCH_1):P3V3_AUX_DSC_G2
   G P3V3_AUX_DSC_G1      G @T6G_MB_LIB.T6G(SCH_1):P3V3_AUX_DSC_G1
   S P3V3_AUX_DSC_S1      S @T6G_MB_LIB.T6G(SCH_1):P3V3_AUX_DSC_S1

SCHOTTKY_DUAL_12A_3C-BAT54CW,SMLF,EMPTY,BCBAT54CZ13  I25  U60
   2     NC      A     NC
   1 P3V3_AUX_DSC_VOL      B @T6G_MB_LIB.T6G(SCH_1):P3V3_AUX_DSC_VOL
   3 P3V3_AUX_DSC_S1      C @T6G_MB_LIB.T6G(SCH_1):P3V3_AUX_DSC_S1

Q_RES_0402LF-10K,1%,1/16W,EMPTY,CS31002FB08  I28  R1475
   1 P3V3_AUX_DSC_G2      A @T6G_MB_LIB.T6G(SCH_1):P3V3_AUX_DSC_G2
   2    GND      B @T6G_MB_LIB.T6G(SCH_1):GND

Q_CAP_C0805-22UF,16V,20%,EMPTY,CH6223MEA00  I30  C1114
   1 P3V3_AUX_DSC_S1      A @T6G_MB_LIB.T6G(SCH_1):P3V3_AUX_DSC_S1
   2    GND      B @T6G_MB_LIB.T6G(SCH_1):GND

Q_RES_0402LF-30K,1%,1/16W,EMPTY,CS33002FB02  I35  R896
   1 P12V_AUX      A @T6G_MB_LIB.T6G(SCH_1):P12V_AUX
   2 P3V3_AUX_DSC_VOL      B @T6G_MB_LIB.T6G(SCH_1):P3V3_AUX_DSC_VOL

Q_RES_0402LF-11.5K,1%,1/16W,EMPTY,CS31152FB03  I36  R954
   1 P3V3_AUX_DSC_VOL      A @T6G_MB_LIB.T6G(SCH_1):P3V3_AUX_DSC_VOL
   2    GND      B @T6G_MB_LIB.T6G(SCH_1):GND

Q_RES_0402LF-1K,1%,1/16W,EMPTY,CS21002FB06  I38  R1052
   1 P3V3_AUX      A @T6G_MB_LIB.T6G(SCH_1):P3V3_AUX
   2 P3V3_AUX_DSC_G1      B @T6G_MB_LIB.T6G(SCH_1):P3V3_AUX_DSC_G1

Q_RES_0402LF-10M,1%,1/16W,EMPTY,CS61002FB02  I39  R1092
   1 P3V3_AUX_DSC_G1      A @T6G_MB_LIB.T6G(SCH_1):P3V3_AUX_DSC_G1
   2    GND      B @T6G_MB_LIB.T6G(SCH_1):GND

END LOGICAL PART CROSS REFERENCE
GLOBAL SIGNAL CROSS REFERENCE - 14-Sep-2023 AT 16:11:04
ADC128_2_A0 @T6G_MB_LIB.T6G(SCH_1):ADC128_2_A0
 R1242    1      A Q_RES_0402LF-1K,1%,1/16W,CHIP,CS21002FB06    I58 @T6G_MB_LIB.T6G(SCH_1):PAGE263
 R1241    2      B Q_RES_0402LF-1K,1%,1/16W,EMPTY,CS21002FB06    I60 @T6G_MB_LIB.T6G(SCH_1):PAGE263
   U51    7     A0 ADC128D818CIMTXNOPB-ADC128D818CIMTX/NOPB,SMLF,IC,AA   I142 @T6G_MB_LIB.T6G(SCH_1):PAGE263

ADC128_2_A1 @T6G_MB_LIB.T6G(SCH_1):ADC128_2_A1
 R1240    1      A Q_RES_0402LF-1K,1%,1/16W,CHIP,CS21002FB06    I57 @T6G_MB_LIB.T6G(SCH_1):PAGE263
 R1239    2      B Q_RES_0402LF-1K,1%,1/16W,EMPTY,CS21002FB06    I59 @T6G_MB_LIB.T6G(SCH_1):PAGE263
   U51    8     A1 ADC128D818CIMTXNOPB-ADC128D818CIMTX/NOPB,SMLF,IC,AA   I142 @T6G_MB_LIB.T6G(SCH_1):PAGE263

ADC128_2_VREF @T6G_MB_LIB.T6G(SCH_1):ADC128_2_VREF
 R1268    1      A Q_RES_0402LF-4.7K,1%,1/16W,EMPTY,CS24702FB06   I119 @T6G_MB_LIB.T6G(SCH_1):PAGE263
 R1267    2      B Q_RES_0402LF-4.7K,1%,1/16W,EMPTY,CS24702FB06   I131 @T6G_MB_LIB.T6G(SCH_1):PAGE263
   U51    1   VREF ADC128D818CIMTXNOPB-ADC128D818CIMTX/NOPB,SMLF,IC,AA   I142 @T6G_MB_LIB.T6G(SCH_1):PAGE263

ADC128_A0 @T6G_MB_LIB.T6G(SCH_1):ADC128_A0
 R3670    1      A Q_RES_0402LF-1K,1%,1/16W,CHIP,CS21002FB06    I40 @T6G_MB_LIB.T6G(SCH_1):PAGE369
 R3669    2      B Q_RES_0402LF-1K,1%,1/16W,EMPTY,CS21002FB06    I68 @T6G_MB_LIB.T6G(SCH_1):PAGE369
  U269    7     A0 ADC128D818CIMTXNOPB-ADC128D818CIMTX/NOPB,SMLF,IC,AA   I142 @T6G_MB_LIB.T6G(SCH_1):PAGE369

ADC128_A1 @T6G_MB_LIB.T6G(SCH_1):ADC128_A1
 R3668    1      A Q_RES_0402LF-1K,1%,1/16W,CHIP,CS21002FB06    I38 @T6G_MB_LIB.T6G(SCH_1):PAGE369
 R3667    2      B Q_RES_0402LF-1K,1%,1/16W,EMPTY,CS21002FB06    I66 @T6G_MB_LIB.T6G(SCH_1):PAGE369
  U269    8     A1 ADC128D818CIMTXNOPB-ADC128D818CIMTX/NOPB,SMLF,IC,AA   I142 @T6G_MB_LIB.T6G(SCH_1):PAGE369

ADC128_VREF @T6G_MB_LIB.T6G(SCH_1):ADC128_VREF
 R3690    1      A Q_RES_0402LF-4.7K,1%,1/16W,EMPTY,CS24702FB06   I130 @T6G_MB_LIB.T6G(SCH_1):PAGE369
 R3689    2      B Q_RES_0402LF-4.7K,1%,1/16W,EMPTY,CS24702FB06   I131 @T6G_MB_LIB.T6G(SCH_1):PAGE369
  U269    1   VREF ADC128D818CIMTXNOPB-ADC128D818CIMTX/NOPB,SMLF,IC,AA   I142 @T6G_MB_LIB.T6G(SCH_1):PAGE369

AGND_HSC @T6G_MB_LIB.T6G(SCH_1):AGND_HSC
PC2183    2      B Q_CAP_0402-220PF,50V,10%,EMPTY,TMP_QCH12206KB14     I2 @T6G_MB_LIB.T6G(SCH_1):PAGE301
PC2181    2      B Q_CAP_C0402-1UF,25V,10%,X6S,CH5104KEB02     I4 @T6G_MB_LIB.T6G(SCH_1):PAGE301
PR3912    1      A Q_RES_0402LF-120K,1%,1/16W,CHIP,CS41202FB05    I11 @T6G_MB_LIB.T6G(SCH_1):PAGE301
PC2348    2      B Q_CAP_0402-1NF,50V,10%,EMPTY,CH21006KB16    I12 @T6G_MB_LIB.T6G(SCH_1):PAGE301
PR3915    2      B Q_RES_0402LF-2K,0.1%,1/16W,CHIP,CS22002BB07    I13 @T6G_MB_LIB.T6G(SCH_1):PAGE301
PR1101    2      B Q_RES_0402LF-2K,0.1%,1/16W,CHIP,CS22002BB07    I15 @T6G_MB_LIB.T6G(SCH_1):PAGE301
 PU288   20    GND MP5991GLUZ-MP5991GLU-Z,SMLF,IC,AL005991A00    I16 @T6G_MB_LIB.T6G(SCH_1):PAGE301
PC1525    2      B Q_CAP_C0402-1UF,25V,10%,X6S,CH5104KEB02    I20 @T6G_MB_LIB.T6G(SCH_1):PAGE301
PC2182    2      B Q_CAP_0402-220PF,50V,10%,X7R,TMP_QCH12206KB14    I24 @T6G_MB_LIB.T6G(SCH_1):PAGE301
PR1134    1      A Q_RES_0402LF-120K,1%,1/16W,CHIP,CS41202FB05    I29 @T6G_MB_LIB.T6G(SCH_1):PAGE301
PC2347    2      B Q_CAP_0402-1NF,50V,10%,EMPTY,CH21006KB16    I30 @T6G_MB_LIB.T6G(SCH_1):PAGE301
PR3914    2      B Q_RES_0402LF-2K,0.1%,1/16W,CHIP,CS22002BB07    I31 @T6G_MB_LIB.T6G(SCH_1):PAGE301
PR3918    2      B Q_RES_0402LF-2K,0.1%,1/16W,CHIP,CS22002BB07    I34 @T6G_MB_LIB.T6G(SCH_1):PAGE301
 PU287   20    GND MP5991GLUZ-MP5991GLU-Z,SMLF,IC,AL005991A00    I35 @T6G_MB_LIB.T6G(SCH_1):PAGE301
PC2185    2      B Q_CAP_0402-0.068UF,16V,10%,X7R,CH3683K1B09    I38 @T6G_MB_LIB.T6G(SCH_1):PAGE301
PC2184    2      B Q_CAP_0402-0.068UF,16V,10%,X7R,CH3683K1B09    I47 @T6G_MB_LIB.T6G(SCH_1):PAGE301
PC2225    2      B Q_CAP_0402-220PF,50V,10%,EMPTY,TMP_QCH12206KB14     I2 @T6G_MB_LIB.T6G(SCH_1):PAGE325
PC2223    2      B Q_CAP_C0402-1UF,25V,10%,X6S,CH5104KEB02     I4 @T6G_MB_LIB.T6G(SCH_1):PAGE325
PR3984    1      A Q_RES_0402LF-120K,1%,1/16W,CHIP,CS41202FB05    I11 @T6G_MB_LIB.T6G(SCH_1):PAGE325
PC2349    2      B Q_CAP_0402-1NF,50V,10%,EMPTY,CH21006KB16    I12 @T6G_MB_LIB.T6G(SCH_1):PAGE325
PR3987    2      B Q_RES_0402LF-2K,0.1%,1/16W,CHIP,CS22002BB07    I13 @T6G_MB_LIB.T6G(SCH_1):PAGE325
PR3991    2      B Q_RES_0402LF-2K,0.1%,1/16W,CHIP,CS22002BB07    I14 @T6G_MB_LIB.T6G(SCH_1):PAGE325
 PU297   20    GND MP5991GLUZ-MP5991GLU-Z,SMLF,IC,AL005991A00    I17 @T6G_MB_LIB.T6G(SCH_1):PAGE325
PC3272    2      B Q_CAP_C0402-1UF,25V,10%,X6S,CH5104KEB02    I20 @T6G_MB_LIB.T6G(SCH_1):PAGE325
PC2224    2      B Q_CAP_0402-220PF,50V,10%,EMPTY,TMP_QCH12206KB14    I24 @T6G_MB_LIB.T6G(SCH_1):PAGE325
PR3982    1      A Q_RES_0402LF-120K,1%,1/16W,CHIP,CS41202FB05    I28 @T6G_MB_LIB.T6G(SCH_1):PAGE325
PC2350    2      B Q_CAP_0402-1NF,50V,10%,EMPTY,CH21006KB16    I30 @T6G_MB_LIB.T6G(SCH_1):PAGE325
PR3986    2      B Q_RES_0402LF-2K,0.1%,1/16W,CHIP,CS22002BB07    I31 @T6G_MB_LIB.T6G(SCH_1):PAGE325
PR3990    2      B Q_RES_0402LF-2K,0.1%,1/16W,CHIP,CS22002BB07    I34 @T6G_MB_LIB.T6G(SCH_1):PAGE325
 PU296   20    GND MP5991GLUZ-MP5991GLU-Z,SMLF,IC,AL005991A00    I35 @T6G_MB_LIB.T6G(SCH_1):PAGE325
PC2227    2      B Q_CAP_0402-0.068UF,16V,10%,X7R,CH3683K1B09    I38 @T6G_MB_LIB.T6G(SCH_1):PAGE325
PC2226    2      B Q_CAP_0402-0.068UF,16V,10%,X7R,CH3683K1B09    I47 @T6G_MB_LIB.T6G(SCH_1):PAGE325
 R1117    2      B Q_RES_0402LF-6.19K,1%,1/16W,CHIP,CS26192FB03    I22 @T6G_MB_LIB.T6G(SCH_1):PAGE267
PC2186    2      B Q_CAP_C0402-1UF,25V,10%,X6S,CH5104KEB02    I27 @T6G_MB_LIB.T6G(SCH_1):PAGE267
PC2187    2      B Q_CAP_C0402-1UF,25V,10%,X6S,CH5104KEB02    I30 @T6G_MB_LIB.T6G(SCH_1):PAGE267
PR3927    2      B Q_RES_0402LF-4.99K,0.1%,1/16W,CHIP,CS24992BB04    I47 @T6G_MB_LIB.T6G(SCH_1):PAGE267
PC2103    2      B Q_CAP_C0402-1UF,25V,10%,X6S,CH5104KEB02    I50 @T6G_MB_LIB.T6G(SCH_1):PAGE267
PR3930    1      A Q_RES_0402LF-0,5%,1/16W,CHIP,CS00002JB13    I52 @T6G_MB_LIB.T6G(SCH_1):PAGE267
 PU289   18   GND1 MP5990GMA1111Z-MP5990GMA-1111-Z,SMLF,IC,AR0F0TP4023    I58 @T6G_MB_LIB.T6G(SCH_1):PAGE267
 PU289   44   GND2 MP5990GMA1111Z-MP5990GMA-1111-Z,SMLF,IC,AR0F0TP4023    I58 @T6G_MB_LIB.T6G(SCH_1):PAGE267
PC2189    2      B Q_CAP_C0402-0.01UF,50V,10%,X7R,CH31006KB18    I59 @T6G_MB_LIB.T6G(SCH_1):PAGE267
PR1131    2      B Q_RES_0402LF-2K,0.1%,1/16W,CHIP,CS22002BB07    I65 @T6G_MB_LIB.T6G(SCH_1):PAGE267
PR3932    2      B Q_RES_0402LF-4.99K,0.1%,1/16W,CHIP,CS24992BB04    I70 @T6G_MB_LIB.T6G(SCH_1):PAGE267
PC2190    2      B Q_CAP_C0402-0.01UF,50V,10%,X7R,CH31006KB18    I72 @T6G_MB_LIB.T6G(SCH_1):PAGE267
PC2191    2      B Q_CAP_0402-0.068UF,16V,10%,X7R,CH3683K1B09    I75 @T6G_MB_LIB.T6G(SCH_1):PAGE267
PC2192    2      B Q_CAP_C0402-0.001UF,50V,10%,X7R,CH30106KB19    I78 @T6G_MB_LIB.T6G(SCH_1):PAGE267
PR3935    2      B Q_RES_0402LF-10K,1%,1/16W,CHIP,CS31002FB08    I81 @T6G_MB_LIB.T6G(SCH_1):PAGE267
PC2193    2      B Q_CAP_C0402-0.047UF,25V,10%,X7R,CH3474K1B04    I84 @T6G_MB_LIB.T6G(SCH_1):PAGE267
PR3937    2      B Q_RES_0402LF-120K,1%,1/16W,CHIP,CS41202FB05    I85 @T6G_MB_LIB.T6G(SCH_1):PAGE267
PR1133    2      B Q_RES_0402LF-2K,0.1%,1/16W,CHIP,CS22002BB07    I86 @T6G_MB_LIB.T6G(SCH_1):PAGE267
PR3002    2      B Q_RES_0402LF-0,5%,1/16W,CHIP,CS00002JB13    I27 @T6G_MB_LIB.T6G(SCH_1):PAGE372

APML_CPU0_ALERT_N @T6G_MB_LIB.T6G(SCH_1):APML_CPU0_ALERT_N
   U25  A68 ALERT_L GENOA_SP5-SOCKET6096_13568-001,SMLF,IO,DGA^6000030   I227 @T6G_MB_LIB.T6G(SCH_1):PAGE27
  R418    1      A Q_RES_0402LF-2.2K,5%,1/16W,CHIP,CS22202JB07   I378 @T6G_MB_LIB.T6G(SCH_1):PAGE27
  R247    1      A Q_RES_0402LF-33,5%,1/16W,CHIP,CS03302JB10   I401 @T6G_MB_LIB.T6G(SCH_1):PAGE27

APML_CPU0_ALERT_R_N @T6G_MB_LIB.T6G(SCH_1):APML_CPU0_ALERT_R_N
  R247    2      B Q_RES_0402LF-33,5%,1/16W,CHIP,CS03302JB10   I401 @T6G_MB_LIB.T6G(SCH_1):PAGE27
   U18  L17  PR14A LCMXO3LF9400C5BG484C-LCMXO3LF-9400C-5BG484C,SMLF,IA   I217 @T6G_MB_LIB.T6G(SCH_1):PAGE80

APML_CPU1_ALERT_N @T6G_MB_LIB.T6G(SCH_1):APML_CPU1_ALERT_N
   U26  A68 ALERT_L GENOA_SP5-SOCKET6096_13568-001,SMLF,IO,DGA^6000030   I190 @T6G_MB_LIB.T6G(SCH_1):PAGE54
  R535    1      A Q_RES_0402LF-2.2K,5%,1/16W,CHIP,CS22202JB07   I398 @T6G_MB_LIB.T6G(SCH_1):PAGE54
  R497    1      A Q_RES_0402LF-33,5%,1/16W,CHIP,CS03302JB10   I417 @T6G_MB_LIB.T6G(SCH_1):PAGE54

APML_CPU1_ALERT_R_N @T6G_MB_LIB.T6G(SCH_1):APML_CPU1_ALERT_R_N
  R497    2      B Q_RES_0402LF-33,5%,1/16W,CHIP,CS03302JB10   I417 @T6G_MB_LIB.T6G(SCH_1):PAGE54
   U18  K16  PR13D LCMXO3LF9400C5BG484C-LCMXO3LF-9400C-5BG484C,SMLF,IA   I217 @T6G_MB_LIB.T6G(SCH_1):PAGE80

A_HSC_HIGH @T6G_MB_LIB.T6G(SCH_1):A_HSC_HIGH
  U142    4   INB- LT6700CS61TRPBF-LT6700CS6-1#TRPBF,SMLF,EMPTY,AL006A    I50 @T6G_MB_LIB.T6G(SCH_1):PAGE371
 R6234    2      B Q_RES_0402LF-160K,1%,1/16W,EMPTY,CS41602FB05    I55 @T6G_MB_LIB.T6G(SCH_1):PAGE371
 R6235    1      A Q_RES_0402LF-10K,1%,1/16W,EMPTY,CS31002FB08    I58 @T6G_MB_LIB.T6G(SCH_1):PAGE371

A_HSC_LOW @T6G_MB_LIB.T6G(SCH_1):A_HSC_LOW
  U142    3   INA+ LT6700CS61TRPBF-LT6700CS6-1#TRPBF,SMLF,EMPTY,AL006A    I50 @T6G_MB_LIB.T6G(SCH_1):PAGE371
 R6232    2      B Q_RES_0402LF-160K,1%,1/16W,EMPTY,CS41602FB05    I56 @T6G_MB_LIB.T6G(SCH_1):PAGE371
 R6233    1      A Q_RES_0402LF-10K,1%,1/16W,EMPTY,CS31002FB08    I57 @T6G_MB_LIB.T6G(SCH_1):PAGE371

A_HSC_LOW_DRAIN @T6G_MB_LIB.T6G(SCH_1):A_HSC_LOW_DRAIN
 U6004    D      D MOSFET_NCH_GDS_ESD_PROTECTED-2N7002K,SMLF,EMPTY,BAA    I68 @T6G_MB_LIB.T6G(SCH_1):PAGE371
 R6238    1      A Q_RES_0402LF-0,5%,1/16W,EMPTY,CS00002JB13    I72 @T6G_MB_LIB.T6G(SCH_1):PAGE371

A_HSC_LOW_GATE @T6G_MB_LIB.T6G(SCH_1):A_HSC_LOW_GATE
  U142    1   OUTA LT6700CS61TRPBF-LT6700CS6-1#TRPBF,SMLF,EMPTY,AL006A    I50 @T6G_MB_LIB.T6G(SCH_1):PAGE371
 R6236    2      B Q_RES_0402LF-10K,1%,1/16W,EMPTY,CS31002FB08    I63 @T6G_MB_LIB.T6G(SCH_1):PAGE371
 R6237    1      A Q_RES_0402LF-0,5%,1/16W,EMPTY,CS00002JB13    I66 @T6G_MB_LIB.T6G(SCH_1):PAGE371
 U6004    G      G MOSFET_NCH_GDS_ESD_PROTECTED-2N7002K,SMLF,EMPTY,BAA    I68 @T6G_MB_LIB.T6G(SCH_1):PAGE371
 R8110    2      B Q_RES_0402LF-33.2,1%,1/16W,EMPTY,CS03322FB03    I96 @T6G_MB_LIB.T6G(SCH_1):PAGE371
 R8111    2      B Q_RES_0402LF-10K,1%,1/16W,EMPTY,CS31002FB08    I98 @T6G_MB_LIB.T6G(SCH_1):PAGE371

A_P12V_STBY_ADR_TRIGGER @T6G_MB_LIB.T6G(SCH_1):A_P12V_STBY_ADR_TRIGGER
 R2227    1      A Q_RES_0402LF-10K,1%,1/16W,EMPTY,CS31002FB08    I29 @T6G_MB_LIB.T6G(SCH_1):PAGE372
 R2219    2      B Q_RES_0402LF-267K,1%,1/16W,EMPTY,CS42672FB03    I30 @T6G_MB_LIB.T6G(SCH_1):PAGE372
  U206    3   INA+ LT6700CS61TRPBF-LT6700CS6-1#TRPBF,SMLF,EMPTY,AL006A    I49 @T6G_MB_LIB.T6G(SCH_1):PAGE372

A_P12V_STBY_FPH_GATE @T6G_MB_LIB.T6G(SCH_1):A_P12V_STBY_FPH_GATE
  U325    G   GATE MOSFET_N_SMLF-BSS138K,BSS138K,EMPTY,BAM138K0000    I42 @T6G_MB_LIB.T6G(SCH_1):PAGE372
 R2230    2      B Q_RES_0402LF-10K,1%,1/16W,EMPTY,CS31002FB08    I43 @T6G_MB_LIB.T6G(SCH_1):PAGE372
  U206    6   OUTB LT6700CS61TRPBF-LT6700CS6-1#TRPBF,SMLF,EMPTY,AL006A    I49 @T6G_MB_LIB.T6G(SCH_1):PAGE372

A_P12V_STBY_FP_TRIGGER @T6G_MB_LIB.T6G(SCH_1):A_P12V_STBY_FP_TRIGGER
 R2222    1      A Q_RES_0402LF-1K,1%,1/16W,EMPTY,CS21002FB06    I33 @T6G_MB_LIB.T6G(SCH_1):PAGE372
 R2221    2      B Q_RES_0402LF-26.7K,1%,1/16W,EMPTY,CS32672FB03    I35 @T6G_MB_LIB.T6G(SCH_1):PAGE372
  U206    4   INB- LT6700CS61TRPBF-LT6700CS6-1#TRPBF,SMLF,EMPTY,AL006A    I49 @T6G_MB_LIB.T6G(SCH_1):PAGE372

BAT_LDO_EN @T6G_MB_LIB.T6G(SCH_1):BAT_LDO_EN
    U9    3     EN TPS71715DCKR-TPS71715DCKR,SMLF,EMPTY,AL071715001    I91 @T6G_MB_LIB.T6G(SCH_1):PAGE156
    Q8    3     D2 MOSFET_DUAL_6P-2N7002KDW,SMLF,IC,BAM70020047   I104 @T6G_MB_LIB.T6G(SCH_1):PAGE156
 R1777    2      B Q_RES_0402LF-1K,1%,1/16W,CHIP,CS21002FB06   I129 @T6G_MB_LIB.T6G(SCH_1):PAGE156
  U167    4     EN NCP698SQ15T1G-NCP698SQ15T1G,SMLF,EMPTY,AL000698000   I130 @T6G_MB_LIB.T6G(SCH_1):PAGE156

BIC_MONITER @T6G_MB_LIB.T6G(SCH_1):BIC_MONITER
   Q67    2     G1 MOSFET_NCH_DUAL-PJT138K,SMLF,IC,BAM138K0003    I33 @T6G_MB_LIB.T6G(SCH_1):PAGE333
 R2831    1      A Q_RES_0402LF-100K,1%,1/16W,EMPTY,CS41002FB09    I56 @T6G_MB_LIB.T6G(SCH_1):PAGE333
 R2830    2      B Q_RES_0402LF-100K,1%,1/16W,CHIP,CS41002FB09    I68 @T6G_MB_LIB.T6G(SCH_1):PAGE333
  J109   A3     A3 CONN112_10137002101LF-CONN112_10137002-101LF,THLF,A    I76 @T6G_MB_LIB.T6G(SCH_1):PAGE319

BIC_MONITER_ISO @T6G_MB_LIB.T6G(SCH_1):BIC_MONITER_ISO
   Q67    3     D2 MOSFET_NCH_DUAL-PJT138K,SMLF,IC,BAM138K0003    I82 @T6G_MB_LIB.T6G(SCH_1):PAGE333
 C1773    1      A Q_CAP_0402-0.1UF,25V,10%,X7R,CH4104K1B00   I114 @T6G_MB_LIB.T6G(SCH_1):PAGE333
 R2846    2      B Q_RES_0402LF-33.2,1%,1/16W,CHIP,CS03322FB03   I262 @T6G_MB_LIB.T6G(SCH_1):PAGE80
 R2920    2      B Q_RES_0402LF-100K,1%,1/16W,CHIP,CS41002FB09   I177 @T6G_MB_LIB.T6G(SCH_1):PAGE333

BIC_MONITER_ISO_R @T6G_MB_LIB.T6G(SCH_1):BIC_MONITER_ISO_R
   U18  V15  PB38C LCMXO3LF9400C5BG484C-LCMXO3LF-9400C-5BG484C,SMLF,IA   I216 @T6G_MB_LIB.T6G(SCH_1):PAGE80
 R2846    1      A Q_RES_0402LF-33.2,1%,1/16W,CHIP,CS03322FB03   I262 @T6G_MB_LIB.T6G(SCH_1):PAGE80

BIC_MONITER_N @T6G_MB_LIB.T6G(SCH_1):BIC_MONITER_N
 R2835    2      B Q_RES_0402LF-4.7K,5%,1/16W,CHIP,CS24702JB10    I14 @T6G_MB_LIB.T6G(SCH_1):PAGE333
   Q67    6     D1 MOSFET_NCH_DUAL-PJT138K,SMLF,IC,BAM138K0003    I33 @T6G_MB_LIB.T6G(SCH_1):PAGE333
   Q67    5     G2 MOSFET_NCH_DUAL-PJT138K,SMLF,IC,BAM138K0003    I82 @T6G_MB_LIB.T6G(SCH_1):PAGE333

BIOS_DEBUG_MODE @T6G_MB_LIB.T6G(SCH_1):BIOS_DEBUG_MODE
   Q30    G   GATE MOSFET_N_GSD-NX138BK,SMLF,IC,BAM01380023    I81 @T6G_MB_LIB.T6G(SCH_1):PAGE142
 R1264    2      B Q_RES_0402LF-1K,1%,1/16W,EMPTY,CS21002FB06    I44 @T6G_MB_LIB.T6G(SCH_1):PAGE144
 R1203    2      B Q_RES_0402LF-33,5%,1/16W,CHIP,CS03302JB10   I178 @T6G_MB_LIB.T6G(SCH_1):PAGE80
   U25 DE30 AGPIO105 GENOA_SP5-SOCKET6096_13568-001,SMLF,IO,DGA^6000030   I188 @T6G_MB_LIB.T6G(SCH_1):PAGE28
 R6107    2      B Q_RES_0402LF-10K,5%,1/16W,CHIP,CS31002JB08    I83 @T6G_MB_LIB.T6G(SCH_1):PAGE144
   SW1   16     16 SW20S_DHNF10FQTR-SW20S_DHNF-10F-Q-T/R,SMLF,MECH,DHA    I90 @T6G_MB_LIB.T6G(SCH_1):PAGE144

BIOS_DEBUG_MODE_R @T6G_MB_LIB.T6G(SCH_1):BIOS_DEBUG_MODE_R
 R1203    1      A Q_RES_0402LF-33,5%,1/16W,CHIP,CS03302JB10   I178 @T6G_MB_LIB.T6G(SCH_1):PAGE80
   U18  N22  PR19A LCMXO3LF9400C5BG484C-LCMXO3LF-9400C-5BG484C,SMLF,IA   I217 @T6G_MB_LIB.T6G(SCH_1):PAGE80

BMC_FPGA_LED1 @T6G_MB_LIB.T6G(SCH_1):BMC_FPGA_LED1
   U18 AB10 PB22B||PCLKC2_0 LCMXO3LF9400C5BG484C-LCMXO3LF-9400C-5BG484C,SMLF,IA   I216 @T6G_MB_LIB.T6G(SCH_1):PAGE80
   Q28    2     G1 MOSFET_DUAL_6P-2N7002KDW,SMLF,IC,BAM70020047    I48 @T6G_MB_LIB.T6G(SCH_1):PAGE84

BMC_FPGA_LED1_N @T6G_MB_LIB.T6G(SCH_1):BMC_FPGA_LED1_N
   Q28    6     D1 MOSFET_DUAL_6P-2N7002KDW,SMLF,IC,BAM70020047    I48 @T6G_MB_LIB.T6G(SCH_1):PAGE84
    D8    C      C Q_LED_SMLF-LED_YELLOW,LTST-C190KSKT-P,IC,BEYL0159ZA    I97 @T6G_MB_LIB.T6G(SCH_1):PAGE84

BMC_FPGA_LED1_R_N @T6G_MB_LIB.T6G(SCH_1):BMC_FPGA_LED1_R_N
 R1266    2      B Q_RES_0402LF-200,1%,1/16W,CHIP,CS12002FB06    I45 @T6G_MB_LIB.T6G(SCH_1):PAGE84
    D8    A      A Q_LED_SMLF-LED_YELLOW,LTST-C190KSKT-P,IC,BEYL0159ZA    I97 @T6G_MB_LIB.T6G(SCH_1):PAGE84

BMC_FPGA_LED2 @T6G_MB_LIB.T6G(SCH_1):BMC_FPGA_LED2
   U18  Y10  PB21D LCMXO3LF9400C5BG484C-LCMXO3LF-9400C-5BG484C,SMLF,IA   I216 @T6G_MB_LIB.T6G(SCH_1):PAGE80
   Q28    5     G2 MOSFET_DUAL_6P-2N7002KDW,SMLF,IC,BAM70020047    I48 @T6G_MB_LIB.T6G(SCH_1):PAGE84

BMC_FPGA_LED2_N @T6G_MB_LIB.T6G(SCH_1):BMC_FPGA_LED2_N
   Q28    3     D2 MOSFET_DUAL_6P-2N7002KDW,SMLF,IC,BAM70020047    I48 @T6G_MB_LIB.T6G(SCH_1):PAGE84
    D7    C      C Q_LED_SMLF-LED_YELLOW,LTST-C190KSKT-P,IC,BEYL0159ZA    I96 @T6G_MB_LIB.T6G(SCH_1):PAGE84

BMC_FPGA_LED2_R_N @T6G_MB_LIB.T6G(SCH_1):BMC_FPGA_LED2_R_N
 R1194    2      B Q_RES_0402LF-200,1%,1/16W,CHIP,CS12002FB06    I46 @T6G_MB_LIB.T6G(SCH_1):PAGE84
    D7    A      A Q_LED_SMLF-LED_YELLOW,LTST-C190KSKT-P,IC,BEYL0159ZA    I96 @T6G_MB_LIB.T6G(SCH_1):PAGE84

BMC_JTAG_SEL @T6G_MB_LIB.T6G(SCH_1):BMC_JTAG_SEL
 R1359    2      B Q_RES_0402LF-0,5%,1/16W,CHIP,CS00002JB13   I158 @T6G_MB_LIB.T6G(SCH_1):PAGE80
 R1262    2      B Q_RES_0402LF-10K,5%,1/16W,CHIP,CS31002JB08    I30 @T6G_MB_LIB.T6G(SCH_1):PAGE144
   SW1   13     13 SW20S_DHNF10FQTR-SW20S_DHNF-10F-Q-T/R,SMLF,MECH,DHA    I90 @T6G_MB_LIB.T6G(SCH_1):PAGE144

BMC_JTAG_SEL_R @T6G_MB_LIB.T6G(SCH_1):BMC_JTAG_SEL_R
 R1359    1      A Q_RES_0402LF-0,5%,1/16W,CHIP,CS00002JB13   I158 @T6G_MB_LIB.T6G(SCH_1):PAGE80
   U18  U20  PR27D LCMXO3LF9400C5BG484C-LCMXO3LF-9400C-5BG484C,SMLF,IA   I217 @T6G_MB_LIB.T6G(SCH_1):PAGE80

BMC_MONITER @T6G_MB_LIB.T6G(SCH_1):BMC_MONITER
   U18  AB5  PB10B LCMXO3LF9400C5BG484C-LCMXO3LF-9400C-5BG484C,SMLF,IA   I216 @T6G_MB_LIB.T6G(SCH_1):PAGE80
 R2845    2      B Q_RES_0402LF-33.2,1%,1/16W,CHIP,CS03322FB03   I293 @T6G_MB_LIB.T6G(SCH_1):PAGE80

BMC_MONITER_BUF @T6G_MB_LIB.T6G(SCH_1):BMC_MONITER_BUF
 R2917    2      B Q_RES_0402LF-49.9,1%,1/16W,CHIP,CS04992FB07   I154 @T6G_MB_LIB.T6G(SCH_1):PAGE256
  J109   A1     A1 CONN112_10137002101LF-CONN112_10137002-101LF,THLF,A    I76 @T6G_MB_LIB.T6G(SCH_1):PAGE319

BMC_MONITER_BUF_R @T6G_MB_LIB.T6G(SCH_1):BMC_MONITER_BUF_R
  U195    6     B0 74LVC2G17GW-74LVC2G17GW,SMLF,IC,AL2G0017005    I65 @T6G_MB_LIB.T6G(SCH_1):PAGE256
 R2820    2      B Q_RES_0402LF-4.7K,5%,1/16W,EMPTY,CS24702JB10    I78 @T6G_MB_LIB.T6G(SCH_1):PAGE256
 R2926    1      A Q_RES_0402LF-4.7K,5%,1/16W,CHIP,CS24702JB10   I121 @T6G_MB_LIB.T6G(SCH_1):PAGE256
 R2917    1      A Q_RES_0402LF-49.9,1%,1/16W,CHIP,CS04992FB07   I154 @T6G_MB_LIB.T6G(SCH_1):PAGE256

BMC_MONITER_R @T6G_MB_LIB.T6G(SCH_1):BMC_MONITER_R
  U195    1     A0 74LVC2G17GW-74LVC2G17GW,SMLF,IC,AL2G0017005    I65 @T6G_MB_LIB.T6G(SCH_1):PAGE256
 R2815    2      B Q_RES_0402LF-100K,1%,1/16W,EMPTY,CS41002FB09    I68 @T6G_MB_LIB.T6G(SCH_1):PAGE256
 R2915    1      A Q_RES_0402LF-4.7K,5%,1/16W,CHIP,CS24702JB10    I92 @T6G_MB_LIB.T6G(SCH_1):PAGE256
 R2845    1      A Q_RES_0402LF-33.2,1%,1/16W,CHIP,CS03322FB03   I293 @T6G_MB_LIB.T6G(SCH_1):PAGE80

BOOT_RDY_BUF_LED @T6G_MB_LIB.T6G(SCH_1):BOOT_RDY_BUF_LED
  R944    2      B Q_RES_0402LF-4.7K,5%,1/16W,CHIP,CS24702JB10    I15 @T6G_MB_LIB.T6G(SCH_1):PAGE143
    Q2    2     G1 MOSFET_DUAL_6P-2N7002KDW,SMLF,IC,BAM70020047    I16 @T6G_MB_LIB.T6G(SCH_1):PAGE143
  R935    2      B Q_RES_0402LF-0,5%,1/16W,CHIP,CS00002JB13    I21 @T6G_MB_LIB.T6G(SCH_1):PAGE143

BOOT_RDY_BUF_R_LED @T6G_MB_LIB.T6G(SCH_1):BOOT_RDY_BUF_R_LED
  R935    1      A Q_RES_0402LF-0,5%,1/16W,CHIP,CS00002JB13    I21 @T6G_MB_LIB.T6G(SCH_1):PAGE143
   U82    4      Y SN74LVC1G07DBVR_SMLF-SN74LVC1G07DBVR,IC,AL1G0007024    I26 @T6G_MB_LIB.T6G(SCH_1):PAGE143

BOOT_RDY_H @T6G_MB_LIB.T6G(SCH_1):BOOT_RDY_H
  R941    1      A Q_RES_0402LF-0,5%,1/16W,EMPTY,CS00002JB13    I34 @T6G_MB_LIB.T6G(SCH_1):PAGE143
  R938    1      A Q_RES_0402LF-4.7K,5%,1/16W,CHIP,CS24702JB10    I69 @T6G_MB_LIB.T6G(SCH_1):PAGE28
  R940    2      B Q_RES_0402LF-0,5%,1/16W,CHIP,CS00002JB13    I94 @T6G_MB_LIB.T6G(SCH_1):PAGE28

BOOT_RDY_LED @T6G_MB_LIB.T6G(SCH_1):BOOT_RDY_LED
  R946    2      B Q_RES_0402LF-4.7K,5%,1/16W,CHIP,CS24702JB10     I5 @T6G_MB_LIB.T6G(SCH_1):PAGE143
    Q2    6     D1 MOSFET_DUAL_6P-2N7002KDW,SMLF,IC,BAM70020047    I16 @T6G_MB_LIB.T6G(SCH_1):PAGE143
    Q2    5     G2 MOSFET_DUAL_6P-2N7002KDW,SMLF,IC,BAM70020047    I16 @T6G_MB_LIB.T6G(SCH_1):PAGE143

BOOT_RDY_LED_N @T6G_MB_LIB.T6G(SCH_1):BOOT_RDY_LED_N
    D5    C      C Q_LED_SMLF-LED_BLUE,LTST-C281TBKT-5A,IC,BEBL0172Z00     I8 @T6G_MB_LIB.T6G(SCH_1):PAGE143
    Q2    3     D2 MOSFET_DUAL_6P-2N7002KDW,SMLF,IC,BAM70020047    I16 @T6G_MB_LIB.T6G(SCH_1):PAGE143

BOOT_RDY_R1_N @T6G_MB_LIB.T6G(SCH_1):BOOT_RDY_R1_N
   U82    2      A SN74LVC1G07DBVR_SMLF-SN74LVC1G07DBVR,IC,AL1G0007024    I26 @T6G_MB_LIB.T6G(SCH_1):PAGE143
  R934    2      B Q_RES_0402LF-0,5%,1/16W,CHIP,CS00002JB13    I33 @T6G_MB_LIB.T6G(SCH_1):PAGE143
  R941    2      B Q_RES_0402LF-0,5%,1/16W,EMPTY,CS00002JB13    I34 @T6G_MB_LIB.T6G(SCH_1):PAGE143

BOOT_RDY_R_H @T6G_MB_LIB.T6G(SCH_1):BOOT_RDY_R_H
  R940    1      A Q_RES_0402LF-0,5%,1/16W,CHIP,CS00002JB13    I94 @T6G_MB_LIB.T6G(SCH_1):PAGE28
   U25 DH30 AGPIO104 GENOA_SP5-SOCKET6096_13568-001,SMLF,IO,DGA^6000030   I188 @T6G_MB_LIB.T6G(SCH_1):PAGE28

BUF2_VDD @T6G_MB_LIB.T6G(SCH_1):BUF2_VDD
 U6000   21 VDD_21 DS125BR111RTWR-DS125BR111RTWR,SMLF,IC,AL000125003     I1 @T6G_MB_LIB.T6G(SCH_1):PAGE111
 U6000   22 VDD_22 DS125BR111RTWR-DS125BR111RTWR,SMLF,IC,AL000125003     I1 @T6G_MB_LIB.T6G(SCH_1):PAGE111
 C6011    1      A Q_CAP_0402-0.1UF,25V,10%,X7R,CH4104K1B00     I6 @T6G_MB_LIB.T6G(SCH_1):PAGE111
 C6012    1      A Q_CAP_0402-0.1UF,25V,10%,X7R,CH4104K1B00     I7 @T6G_MB_LIB.T6G(SCH_1):PAGE111

CLKREQ_RT_CPU0_P0_N @T6G_MB_LIB.T6G(SCH_1):CLKREQ_RT_CPU0_P0_N
 U6010  G35 CLKREQ_N PT5161LRS-PT5161LRS,SMLF,IC,AJ051610U03    I53 @T6G_MB_LIB.T6G(SCH_1):PAGE385
 R1368    1      A Q_RES_0201LF-4.7K,5%,1/20W,CHIP,CS24701JE04   I119 @T6G_MB_LIB.T6G(SCH_1):PAGE385

CLKREQ_RT_CPU0_P1_N @T6G_MB_LIB.T6G(SCH_1):CLKREQ_RT_CPU0_P1_N
 U6011  G35 CLKREQ_N PT5161LRS-PT5161LRS,SMLF,IC,AJ051610U03    I83 @T6G_MB_LIB.T6G(SCH_1):PAGE408
 R1395    1      A Q_RES_0201LF-4.7K,5%,1/20W,CHIP,CS24701JE04    I94 @T6G_MB_LIB.T6G(SCH_1):PAGE408

CLKREQ_RT_CPU0_P2_N @T6G_MB_LIB.T6G(SCH_1):CLKREQ_RT_CPU0_P2_N
 U6012  G35 CLKREQ_N PT5161LRS-PT5161LRS,SMLF,IC,AJ051610U03    I83 @T6G_MB_LIB.T6G(SCH_1):PAGE419
 R1404    1      A Q_RES_0201LF-4.7K,5%,1/20W,CHIP,CS24701JE04    I99 @T6G_MB_LIB.T6G(SCH_1):PAGE419

CLKREQ_RT_CPU0_P3_N @T6G_MB_LIB.T6G(SCH_1):CLKREQ_RT_CPU0_P3_N
 U6013  G35 CLKREQ_N PT5161LRS-PT5161LRS,SMLF,IC,AJ051610U03    I83 @T6G_MB_LIB.T6G(SCH_1):PAGE430
 R1412    1      A Q_RES_0201LF-4.7K,5%,1/20W,CHIP,CS24701JE04   I101 @T6G_MB_LIB.T6G(SCH_1):PAGE430

CLKREQ_RT_CPU1_P0_N @T6G_MB_LIB.T6G(SCH_1):CLKREQ_RT_CPU1_P0_N
 U6014  G35 CLKREQ_N PT5161LRS-PT5161LRS,SMLF,IC,AJ051610U03     I1 @T6G_MB_LIB.T6G(SCH_1):PAGE401
 R1387    1      A Q_RES_0201LF-4.7K,5%,1/20W,CHIP,CS24701JE04   I108 @T6G_MB_LIB.T6G(SCH_1):PAGE401

CLKREQ_RT_CPU1_P1_N @T6G_MB_LIB.T6G(SCH_1):CLKREQ_RT_CPU1_P1_N
 U6015  G35 CLKREQ_N PT5161LRS-PT5161LRS,SMLF,IC,AJ051610U03    I47 @T6G_MB_LIB.T6G(SCH_1):PAGE392
 R1376    1      A Q_RES_0201LF-4.7K,5%,1/20W,CHIP,CS24701JE04   I111 @T6G_MB_LIB.T6G(SCH_1):PAGE392

CLKREQ_RT_CPU1_P2_N @T6G_MB_LIB.T6G(SCH_1):CLKREQ_RT_CPU1_P2_N
 U6016  G35 CLKREQ_N PT5161LRS-PT5161LRS,SMLF,IC,AJ051610U03    I97 @T6G_MB_LIB.T6G(SCH_1):PAGE451
 R1421    1      A Q_RES_0201LF-4.7K,5%,1/20W,CHIP,CS24701JE04    I98 @T6G_MB_LIB.T6G(SCH_1):PAGE451

CLKREQ_RT_CPU1_P3_N @T6G_MB_LIB.T6G(SCH_1):CLKREQ_RT_CPU1_P3_N
 U6017  G35 CLKREQ_N PT5161LRS-PT5161LRS,SMLF,IC,AJ051610U03    I97 @T6G_MB_LIB.T6G(SCH_1):PAGE462
 R1433    1      A Q_RES_0201LF-4.7K,5%,1/20W,CHIP,CS24701JE04    I98 @T6G_MB_LIB.T6G(SCH_1):PAGE462

CLK_100M_BMC_RC_DN @T6G_MB_LIB.T6G(SCH_1):CLK_100M_BMC_RC_DN
   J41  A69 USB_DATP SCONN168_ME1016810202011-SCONN168_ME1016810202011,A   I176 @T6G_MB_LIB.T6G(SCH_1):PAGE348
 R3336    2      B Q_RES_0402LF-0,5%,1/16W,CHIP,CS00002JB13    I52 @T6G_MB_LIB.T6G(SCH_1):PAGE232

CLK_100M_BMC_RC_DN_R @T6G_MB_LIB.T6G(SCH_1):CLK_100M_BMC_RC_DN_R
 R3336    1      A Q_RES_0402LF-0,5%,1/16W,CHIP,CS00002JB13    I52 @T6G_MB_LIB.T6G(SCH_1):PAGE232
  U247   14  DIF0# 9FGL0251DKILFT-9FGL0251DKILFT,SMLF,IC,AL000251002    I77 @T6G_MB_LIB.T6G(SCH_1):PAGE232

CLK_100M_BMC_RC_DP @T6G_MB_LIB.T6G(SCH_1):CLK_100M_BMC_RC_DP
   J41  A68 USB_DATN SCONN168_ME1016810202011-SCONN168_ME1016810202011,A   I176 @T6G_MB_LIB.T6G(SCH_1):PAGE348
 R3335    2      B Q_RES_0402LF-0,5%,1/16W,CHIP,CS00002JB13    I53 @T6G_MB_LIB.T6G(SCH_1):PAGE232

CLK_100M_BMC_RC_DP_R @T6G_MB_LIB.T6G(SCH_1):CLK_100M_BMC_RC_DP_R
 R3335    1      A Q_RES_0402LF-0,5%,1/16W,CHIP,CS00002JB13    I53 @T6G_MB_LIB.T6G(SCH_1):PAGE232
  U247   13   DIF0 9FGL0251DKILFT-9FGL0251DKILFT,SMLF,IC,AL000251002    I77 @T6G_MB_LIB.T6G(SCH_1):PAGE232

CLK_100M_CPU0_CLK01_DN @T6G_MB_LIB.T6G(SCH_1):CLK_100M_CPU0_CLK01_DN
   J41  A15 REFCLKP1 SCONN168_ME1016810202011-SCONN168_ME1016810202011,A   I176 @T6G_MB_LIB.T6G(SCH_1):PAGE348
 R4536    2      B Q_RES_0402LF-0,5%,1/16W,CHIP,CS00002JB13   I161 @T6G_MB_LIB.T6G(SCH_1):PAGE28

CLK_100M_CPU0_CLK01_DP @T6G_MB_LIB.T6G(SCH_1):CLK_100M_CPU0_CLK01_DP
   J41  A14 REFCLKN1 SCONN168_ME1016810202011-SCONN168_ME1016810202011,A   I176 @T6G_MB_LIB.T6G(SCH_1):PAGE348
 R4535    2      B Q_RES_0402LF-0,5%,1/16W,CHIP,CS00002JB13   I160 @T6G_MB_LIB.T6G(SCH_1):PAGE28

CLK_100M_CPU0_CLK01_R_DN @T6G_MB_LIB.T6G(SCH_1):CLK_100M_CPU0_CLK01_R_DN
 R4536    1      A Q_RES_0402LF-0,5%,1/16W,CHIP,CS00002JB13   I161 @T6G_MB_LIB.T6G(SCH_1):PAGE28
   U25   A7 GPP_CLK01N GENOA_SP5-SOCKET6096_13568-001,SMLF,IO,DGA^6000030   I188 @T6G_MB_LIB.T6G(SCH_1):PAGE28

CLK_100M_CPU0_CLK01_R_DP @T6G_MB_LIB.T6G(SCH_1):CLK_100M_CPU0_CLK01_R_DP
 R4535    1      A Q_RES_0402LF-0,5%,1/16W,CHIP,CS00002JB13   I160 @T6G_MB_LIB.T6G(SCH_1):PAGE28
   U25   A8 GPP_CLK01P GENOA_SP5-SOCKET6096_13568-001,SMLF,IO,DGA^6000030   I188 @T6G_MB_LIB.T6G(SCH_1):PAGE28

CLK_100M_CPU0_CLK02_DN @T6G_MB_LIB.T6G(SCH_1):CLK_100M_CPU0_CLK02_DN
   J38  B14 REFCLKN0 SCONN168_ME1016810202011-SCONN168_ME1016810202011,A   I168 @T6G_MB_LIB.T6G(SCH_1):PAGE335
 R8564    2      B Q_RES_0402LF-0,5%,1/16W,CHIP,CS00002JB13   I156 @T6G_MB_LIB.T6G(SCH_1):PAGE28

CLK_100M_CPU0_CLK02_DP @T6G_MB_LIB.T6G(SCH_1):CLK_100M_CPU0_CLK02_DP
   J38  B15 REFCLKP0 SCONN168_ME1016810202011-SCONN168_ME1016810202011,A   I168 @T6G_MB_LIB.T6G(SCH_1):PAGE335
 R8563    2      B Q_RES_0402LF-0,5%,1/16W,CHIP,CS00002JB13   I157 @T6G_MB_LIB.T6G(SCH_1):PAGE28

CLK_100M_CPU0_CLK02_R_DN @T6G_MB_LIB.T6G(SCH_1):CLK_100M_CPU0_CLK02_R_DN
 R8564    1      A Q_RES_0402LF-0,5%,1/16W,CHIP,CS00002JB13   I156 @T6G_MB_LIB.T6G(SCH_1):PAGE28
   U25   C6 GPP_CLK02N GENOA_SP5-SOCKET6096_13568-001,SMLF,IO,DGA^6000030   I188 @T6G_MB_LIB.T6G(SCH_1):PAGE28

CLK_100M_CPU0_CLK02_R_DP @T6G_MB_LIB.T6G(SCH_1):CLK_100M_CPU0_CLK02_R_DP
 R8563    1      A Q_RES_0402LF-0,5%,1/16W,CHIP,CS00002JB13   I157 @T6G_MB_LIB.T6G(SCH_1):PAGE28
   U25   B6 GPP_CLK02P GENOA_SP5-SOCKET6096_13568-001,SMLF,IO,DGA^6000030   I188 @T6G_MB_LIB.T6G(SCH_1):PAGE28

CLK_100M_CPU0_CLK03_DN @T6G_MB_LIB.T6G(SCH_1):CLK_100M_CPU0_CLK03_DN
   J38  A14 REFCLKN1 SCONN168_ME1016810202011-SCONN168_ME1016810202011,A   I168 @T6G_MB_LIB.T6G(SCH_1):PAGE335
 R8566    2      B Q_RES_0402LF-0,5%,1/16W,CHIP,CS00002JB13   I155 @T6G_MB_LIB.T6G(SCH_1):PAGE28

CLK_100M_CPU0_CLK03_DP @T6G_MB_LIB.T6G(SCH_1):CLK_100M_CPU0_CLK03_DP
   J38  A15 REFCLKP1 SCONN168_ME1016810202011-SCONN168_ME1016810202011,A   I168 @T6G_MB_LIB.T6G(SCH_1):PAGE335
 R8565    2      B Q_RES_0402LF-0,5%,1/16W,CHIP,CS00002JB13   I158 @T6G_MB_LIB.T6G(SCH_1):PAGE28

CLK_100M_CPU0_CLK03_R_DN @T6G_MB_LIB.T6G(SCH_1):CLK_100M_CPU0_CLK03_R_DN
 R8566    1      A Q_RES_0402LF-0,5%,1/16W,CHIP,CS00002JB13   I155 @T6G_MB_LIB.T6G(SCH_1):PAGE28
   U25  A11 GPP_CLK03N GENOA_SP5-SOCKET6096_13568-001,SMLF,IO,DGA^6000030   I188 @T6G_MB_LIB.T6G(SCH_1):PAGE28

CLK_100M_CPU0_CLK03_R_DP @T6G_MB_LIB.T6G(SCH_1):CLK_100M_CPU0_CLK03_R_DP
 R8565    1      A Q_RES_0402LF-0,5%,1/16W,CHIP,CS00002JB13   I158 @T6G_MB_LIB.T6G(SCH_1):PAGE28
   U25  A10 GPP_CLK03P GENOA_SP5-SOCKET6096_13568-001,SMLF,IO,DGA^6000030   I188 @T6G_MB_LIB.T6G(SCH_1):PAGE28

CLK_100M_CPU0_CLK04_DN @T6G_MB_LIB.T6G(SCH_1):CLK_100M_CPU0_CLK04_DN
   J38 OB11 REFCLKN2 SCONN168_ME1016810202011-SCONN168_ME1016810202011,A   I168 @T6G_MB_LIB.T6G(SCH_1):PAGE335
 R9274    2      B Q_RES_0402LF-0,5%,1/16W,CHIP,CS00002JB13   I154 @T6G_MB_LIB.T6G(SCH_1):PAGE28

CLK_100M_CPU0_CLK04_DP @T6G_MB_LIB.T6G(SCH_1):CLK_100M_CPU0_CLK04_DP
   J38 OB12 REFCLKP2 SCONN168_ME1016810202011-SCONN168_ME1016810202011,A   I168 @T6G_MB_LIB.T6G(SCH_1):PAGE335
 R9273    2      B Q_RES_0402LF-0,5%,1/16W,CHIP,CS00002JB13   I153 @T6G_MB_LIB.T6G(SCH_1):PAGE28

CLK_100M_CPU0_CLK04_R_DN @T6G_MB_LIB.T6G(SCH_1):CLK_100M_CPU0_CLK04_R_DN
 R9274    1      A Q_RES_0402LF-0,5%,1/16W,CHIP,CS00002JB13   I154 @T6G_MB_LIB.T6G(SCH_1):PAGE28
   U25  C12 GPP_CLK04N GENOA_SP5-SOCKET6096_13568-001,SMLF,IO,DGA^6000030   I188 @T6G_MB_LIB.T6G(SCH_1):PAGE28

CLK_100M_CPU0_CLK04_R_DP @T6G_MB_LIB.T6G(SCH_1):CLK_100M_CPU0_CLK04_R_DP
 R9273    1      A Q_RES_0402LF-0,5%,1/16W,CHIP,CS00002JB13   I153 @T6G_MB_LIB.T6G(SCH_1):PAGE28
   U25  B12 GPP_CLK04P GENOA_SP5-SOCKET6096_13568-001,SMLF,IO,DGA^6000030   I188 @T6G_MB_LIB.T6G(SCH_1):PAGE28

CLK_100M_CPU0_CLK05_DN @T6G_MB_LIB.T6G(SCH_1):CLK_100M_CPU0_CLK05_DN
   J38 OA11 REFCLKN3 SCONN168_ME1016810202011-SCONN168_ME1016810202011,A   I168 @T6G_MB_LIB.T6G(SCH_1):PAGE335
 R9276    2      B Q_RES_0402LF-0,5%,1/16W,CHIP,CS00002JB13   I168 @T6G_MB_LIB.T6G(SCH_1):PAGE28

CLK_100M_CPU0_CLK05_DP @T6G_MB_LIB.T6G(SCH_1):CLK_100M_CPU0_CLK05_DP
   J38 OA12 REFCLKP3 SCONN168_ME1016810202011-SCONN168_ME1016810202011,A   I168 @T6G_MB_LIB.T6G(SCH_1):PAGE335
 R9275    2      B Q_RES_0402LF-0,5%,1/16W,CHIP,CS00002JB13   I167 @T6G_MB_LIB.T6G(SCH_1):PAGE28

CLK_100M_CPU0_CLK05_R_DN @T6G_MB_LIB.T6G(SCH_1):CLK_100M_CPU0_CLK05_R_DN
 R9276    1      A Q_RES_0402LF-0,5%,1/16W,CHIP,CS00002JB13   I168 @T6G_MB_LIB.T6G(SCH_1):PAGE28
   U25   C9 GPP_CLK05N GENOA_SP5-SOCKET6096_13568-001,SMLF,IO,DGA^6000030   I188 @T6G_MB_LIB.T6G(SCH_1):PAGE28

CLK_100M_CPU0_CLK05_R_DP @T6G_MB_LIB.T6G(SCH_1):CLK_100M_CPU0_CLK05_R_DP
 R9275    1      A Q_RES_0402LF-0,5%,1/16W,CHIP,CS00002JB13   I167 @T6G_MB_LIB.T6G(SCH_1):PAGE28
   U25   B9 GPP_CLK05P GENOA_SP5-SOCKET6096_13568-001,SMLF,IO,DGA^6000030   I188 @T6G_MB_LIB.T6G(SCH_1):PAGE28

CLK_100M_CPU0_CLK11_DN @T6G_MB_LIB.T6G(SCH_1):CLK_100M_CPU0_CLK11_DN
 R2660    2      B Q_RES_0402LF-0,5%,1/16W,CHIP,CS00002JB13   I151 @T6G_MB_LIB.T6G(SCH_1):PAGE28
  J112   N4     N4 CONN160_10131762101LF-CONN160_10131762-101LF,THLF,A   I102 @T6G_MB_LIB.T6G(SCH_1):PAGE329

CLK_100M_CPU0_CLK11_DP @T6G_MB_LIB.T6G(SCH_1):CLK_100M_CPU0_CLK11_DP
 R2659    2      B Q_RES_0402LF-0,5%,1/16W,CHIP,CS00002JB13   I152 @T6G_MB_LIB.T6G(SCH_1):PAGE28
  J112   O4     O4 CONN160_10131762101LF-CONN160_10131762-101LF,THLF,A   I102 @T6G_MB_LIB.T6G(SCH_1):PAGE329

CLK_100M_CPU0_CLK11_R_DN @T6G_MB_LIB.T6G(SCH_1):CLK_100M_CPU0_CLK11_R_DN
 R2660    1      A Q_RES_0402LF-0,5%,1/16W,CHIP,CS00002JB13   I151 @T6G_MB_LIB.T6G(SCH_1):PAGE28
   U25 DJ42 GPP_CLK11N GENOA_SP5-SOCKET6096_13568-001,SMLF,IO,DGA^6000030   I188 @T6G_MB_LIB.T6G(SCH_1):PAGE28

CLK_100M_CPU0_CLK11_R_DP @T6G_MB_LIB.T6G(SCH_1):CLK_100M_CPU0_CLK11_R_DP
 R2659    1      A Q_RES_0402LF-0,5%,1/16W,CHIP,CS00002JB13   I152 @T6G_MB_LIB.T6G(SCH_1):PAGE28
   U25 DJ41 GPP_CLK11P GENOA_SP5-SOCKET6096_13568-001,SMLF,IO,DGA^6000030   I188 @T6G_MB_LIB.T6G(SCH_1):PAGE28

CLK_100M_CPU0_CLK12_DN @T6G_MB_LIB.T6G(SCH_1):CLK_100M_CPU0_CLK12_DN
   J90  B14 REFCLK_N0 SCONN56_123276793-SCONN56_1-2327679-3,SMLF,IO,DFHSA    I90 @T6G_MB_LIB.T6G(SCH_1):PAGE297
 R4304    2      B Q_RES_0402LF-0,5%,1/16W,CHIP,CS00002JB13   I192 @T6G_MB_LIB.T6G(SCH_1):PAGE28

CLK_100M_CPU0_CLK12_DP @T6G_MB_LIB.T6G(SCH_1):CLK_100M_CPU0_CLK12_DP
   J90  B15 REFCLK_P0 SCONN56_123276793-SCONN56_1-2327679-3,SMLF,IO,DFHSA    I90 @T6G_MB_LIB.T6G(SCH_1):PAGE297
 R4303    2      B Q_RES_0402LF-0,5%,1/16W,CHIP,CS00002JB13   I191 @T6G_MB_LIB.T6G(SCH_1):PAGE28

CLK_100M_CPU0_CLK12_R_DN @T6G_MB_LIB.T6G(SCH_1):CLK_100M_CPU0_CLK12_R_DN
   U25 DJ44 GPP_CLK12N GENOA_SP5-SOCKET6096_13568-001,SMLF,IO,DGA^6000030   I188 @T6G_MB_LIB.T6G(SCH_1):PAGE28
 R4304    1      A Q_RES_0402LF-0,5%,1/16W,CHIP,CS00002JB13   I192 @T6G_MB_LIB.T6G(SCH_1):PAGE28

CLK_100M_CPU0_CLK12_R_DP @T6G_MB_LIB.T6G(SCH_1):CLK_100M_CPU0_CLK12_R_DP
   U25 DJ45 GPP_CLK12P GENOA_SP5-SOCKET6096_13568-001,SMLF,IO,DGA^6000030   I188 @T6G_MB_LIB.T6G(SCH_1):PAGE28
 R4303    1      A Q_RES_0402LF-0,5%,1/16W,CHIP,CS00002JB13   I191 @T6G_MB_LIB.T6G(SCH_1):PAGE28

CLK_100M_CPU0_CLK13_DN @T6G_MB_LIB.T6G(SCH_1):CLK_100M_CPU0_CLK13_DN
  U314    4 DIF_IN# 9ZXL0451EKILFT-9ZXL0451EKILFT,SMLF,IC,AL000451003    I63 @T6G_MB_LIB.T6G(SCH_1):PAGE160
 R8306    2      B Q_RES_0402LF-0,5%,1/16W,CHIP,CS00002JB13   I228 @T6G_MB_LIB.T6G(SCH_1):PAGE28

CLK_100M_CPU0_CLK13_DP @T6G_MB_LIB.T6G(SCH_1):CLK_100M_CPU0_CLK13_DP
  U314    3 DIF_IN 9ZXL0451EKILFT-9ZXL0451EKILFT,SMLF,IC,AL000451003    I63 @T6G_MB_LIB.T6G(SCH_1):PAGE160
 R8305    2      B Q_RES_0402LF-0,5%,1/16W,CHIP,CS00002JB13   I229 @T6G_MB_LIB.T6G(SCH_1):PAGE28

CLK_100M_CPU0_CLK13_R_DN @T6G_MB_LIB.T6G(SCH_1):CLK_100M_CPU0_CLK13_R_DN
   U25 DJ54 GPP_CLK13N GENOA_SP5-SOCKET6096_13568-001,SMLF,IO,DGA^6000030   I188 @T6G_MB_LIB.T6G(SCH_1):PAGE28
 R8306    1      A Q_RES_0402LF-0,5%,1/16W,CHIP,CS00002JB13   I228 @T6G_MB_LIB.T6G(SCH_1):PAGE28

CLK_100M_CPU0_CLK13_R_DP @T6G_MB_LIB.T6G(SCH_1):CLK_100M_CPU0_CLK13_R_DP
   U25 DJ53 GPP_CLK13P GENOA_SP5-SOCKET6096_13568-001,SMLF,IO,DGA^6000030   I188 @T6G_MB_LIB.T6G(SCH_1):PAGE28
 R8305    1      A Q_RES_0402LF-0,5%,1/16W,CHIP,CS00002JB13   I229 @T6G_MB_LIB.T6G(SCH_1):PAGE28

CLK_100M_CPU1_CLK01_DN @T6G_MB_LIB.T6G(SCH_1):CLK_100M_CPU1_CLK01_DN
 R3355    2      B Q_RES_0402LF-0,5%,1/16W,CHIP,CS00002JB13   I306 @T6G_MB_LIB.T6G(SCH_1):PAGE55
  J112   O1     O1 CONN160_10131762101LF-CONN160_10131762-101LF,THLF,A   I102 @T6G_MB_LIB.T6G(SCH_1):PAGE329

CLK_100M_CPU1_CLK01_DP @T6G_MB_LIB.T6G(SCH_1):CLK_100M_CPU1_CLK01_DP
 R3354    2      B Q_RES_0402LF-0,5%,1/16W,CHIP,CS00002JB13   I307 @T6G_MB_LIB.T6G(SCH_1):PAGE55
  J112   P1     P1 CONN160_10131762101LF-CONN160_10131762-101LF,THLF,A   I102 @T6G_MB_LIB.T6G(SCH_1):PAGE329

CLK_100M_CPU1_CLK01_R_DN @T6G_MB_LIB.T6G(SCH_1):CLK_100M_CPU1_CLK01_R_DN
   U26   A7 GPP_CLK01N GENOA_SP5-SOCKET6096_13568-001,SMLF,IO,DGA^6000030   I182 @T6G_MB_LIB.T6G(SCH_1):PAGE55
 R3355    1      A Q_RES_0402LF-0,5%,1/16W,CHIP,CS00002JB13   I306 @T6G_MB_LIB.T6G(SCH_1):PAGE55

CLK_100M_CPU1_CLK01_R_DP @T6G_MB_LIB.T6G(SCH_1):CLK_100M_CPU1_CLK01_R_DP
   U26   A8 GPP_CLK01P GENOA_SP5-SOCKET6096_13568-001,SMLF,IO,DGA^6000030   I182 @T6G_MB_LIB.T6G(SCH_1):PAGE55
 R3354    1      A Q_RES_0402LF-0,5%,1/16W,CHIP,CS00002JB13   I307 @T6G_MB_LIB.T6G(SCH_1):PAGE55

CLK_100M_CPU1_CLK02_DN @T6G_MB_LIB.T6G(SCH_1):CLK_100M_CPU1_CLK02_DN
   J35  B14 REFCLKN0 SCONN168_ME1016810202011-SCONN168_ME1016810202011,A   I168 @T6G_MB_LIB.T6G(SCH_1):PAGE341
 R3195    2      B Q_RES_0402LF-0,5%,1/16W,CHIP,CS00002JB13   I309 @T6G_MB_LIB.T6G(SCH_1):PAGE55

CLK_100M_CPU1_CLK02_DP @T6G_MB_LIB.T6G(SCH_1):CLK_100M_CPU1_CLK02_DP
   J35  B15 REFCLKP0 SCONN168_ME1016810202011-SCONN168_ME1016810202011,A   I168 @T6G_MB_LIB.T6G(SCH_1):PAGE341
 R3194    2      B Q_RES_0402LF-0,5%,1/16W,CHIP,CS00002JB13   I308 @T6G_MB_LIB.T6G(SCH_1):PAGE55

CLK_100M_CPU1_CLK02_R_DN @T6G_MB_LIB.T6G(SCH_1):CLK_100M_CPU1_CLK02_R_DN
   U26   C6 GPP_CLK02N GENOA_SP5-SOCKET6096_13568-001,SMLF,IO,DGA^6000030   I182 @T6G_MB_LIB.T6G(SCH_1):PAGE55
 R3195    1      A Q_RES_0402LF-0,5%,1/16W,CHIP,CS00002JB13   I309 @T6G_MB_LIB.T6G(SCH_1):PAGE55

CLK_100M_CPU1_CLK02_R_DP @T6G_MB_LIB.T6G(SCH_1):CLK_100M_CPU1_CLK02_R_DP
   U26   B6 GPP_CLK02P GENOA_SP5-SOCKET6096_13568-001,SMLF,IO,DGA^6000030   I182 @T6G_MB_LIB.T6G(SCH_1):PAGE55
 R3194    1      A Q_RES_0402LF-0,5%,1/16W,CHIP,CS00002JB13   I308 @T6G_MB_LIB.T6G(SCH_1):PAGE55

CLK_100M_CPU1_CLK03_DN @T6G_MB_LIB.T6G(SCH_1):CLK_100M_CPU1_CLK03_DN
   J35  A14 REFCLKN1 SCONN168_ME1016810202011-SCONN168_ME1016810202011,A   I168 @T6G_MB_LIB.T6G(SCH_1):PAGE341
 R3197    2      B Q_RES_0402LF-0,5%,1/16W,CHIP,CS00002JB13   I313 @T6G_MB_LIB.T6G(SCH_1):PAGE55

CLK_100M_CPU1_CLK03_DP @T6G_MB_LIB.T6G(SCH_1):CLK_100M_CPU1_CLK03_DP
   J35  A15 REFCLKP1 SCONN168_ME1016810202011-SCONN168_ME1016810202011,A   I168 @T6G_MB_LIB.T6G(SCH_1):PAGE341
 R3196    2      B Q_RES_0402LF-0,5%,1/16W,CHIP,CS00002JB13   I312 @T6G_MB_LIB.T6G(SCH_1):PAGE55

CLK_100M_CPU1_CLK03_R_DN @T6G_MB_LIB.T6G(SCH_1):CLK_100M_CPU1_CLK03_R_DN
   U26  A11 GPP_CLK03N GENOA_SP5-SOCKET6096_13568-001,SMLF,IO,DGA^6000030   I182 @T6G_MB_LIB.T6G(SCH_1):PAGE55
 R3197    1      A Q_RES_0402LF-0,5%,1/16W,CHIP,CS00002JB13   I313 @T6G_MB_LIB.T6G(SCH_1):PAGE55

CLK_100M_CPU1_CLK03_R_DP @T6G_MB_LIB.T6G(SCH_1):CLK_100M_CPU1_CLK03_R_DP
   U26  A10 GPP_CLK03P GENOA_SP5-SOCKET6096_13568-001,SMLF,IO,DGA^6000030   I182 @T6G_MB_LIB.T6G(SCH_1):PAGE55
 R3196    1      A Q_RES_0402LF-0,5%,1/16W,CHIP,CS00002JB13   I312 @T6G_MB_LIB.T6G(SCH_1):PAGE55

CLK_100M_CPU1_CLK04_DN @T6G_MB_LIB.T6G(SCH_1):CLK_100M_CPU1_CLK04_DN
   J35 OB11 REFCLKN2 SCONN168_ME1016810202011-SCONN168_ME1016810202011,A   I168 @T6G_MB_LIB.T6G(SCH_1):PAGE341
 R3199    2      B Q_RES_0402LF-0,5%,1/16W,CHIP,CS00002JB13   I317 @T6G_MB_LIB.T6G(SCH_1):PAGE55

CLK_100M_CPU1_CLK04_DP @T6G_MB_LIB.T6G(SCH_1):CLK_100M_CPU1_CLK04_DP
   J35 OB12 REFCLKP2 SCONN168_ME1016810202011-SCONN168_ME1016810202011,A   I168 @T6G_MB_LIB.T6G(SCH_1):PAGE341
 R3198    2      B Q_RES_0402LF-0,5%,1/16W,CHIP,CS00002JB13   I316 @T6G_MB_LIB.T6G(SCH_1):PAGE55

CLK_100M_CPU1_CLK04_R_DN @T6G_MB_LIB.T6G(SCH_1):CLK_100M_CPU1_CLK04_R_DN
   U26  C12 GPP_CLK04N GENOA_SP5-SOCKET6096_13568-001,SMLF,IO,DGA^6000030   I182 @T6G_MB_LIB.T6G(SCH_1):PAGE55
 R3199    1      A Q_RES_0402LF-0,5%,1/16W,CHIP,CS00002JB13   I317 @T6G_MB_LIB.T6G(SCH_1):PAGE55

CLK_100M_CPU1_CLK04_R_DP @T6G_MB_LIB.T6G(SCH_1):CLK_100M_CPU1_CLK04_R_DP
   U26  B12 GPP_CLK04P GENOA_SP5-SOCKET6096_13568-001,SMLF,IO,DGA^6000030   I182 @T6G_MB_LIB.T6G(SCH_1):PAGE55
 R3198    1      A Q_RES_0402LF-0,5%,1/16W,CHIP,CS00002JB13   I316 @T6G_MB_LIB.T6G(SCH_1):PAGE55

CLK_100M_CPU1_CLK05_DN @T6G_MB_LIB.T6G(SCH_1):CLK_100M_CPU1_CLK05_DN
   J35 OA11 REFCLKN3 SCONN168_ME1016810202011-SCONN168_ME1016810202011,A   I168 @T6G_MB_LIB.T6G(SCH_1):PAGE341
 R3201    2      B Q_RES_0402LF-0,5%,1/16W,CHIP,CS00002JB13   I321 @T6G_MB_LIB.T6G(SCH_1):PAGE55

CLK_100M_CPU1_CLK05_DP @T6G_MB_LIB.T6G(SCH_1):CLK_100M_CPU1_CLK05_DP
   J35 OA12 REFCLKP3 SCONN168_ME1016810202011-SCONN168_ME1016810202011,A   I168 @T6G_MB_LIB.T6G(SCH_1):PAGE341
 R3200    2      B Q_RES_0402LF-0,5%,1/16W,CHIP,CS00002JB13   I320 @T6G_MB_LIB.T6G(SCH_1):PAGE55

CLK_100M_CPU1_CLK05_R_DN @T6G_MB_LIB.T6G(SCH_1):CLK_100M_CPU1_CLK05_R_DN
   U26   C9 GPP_CLK05N GENOA_SP5-SOCKET6096_13568-001,SMLF,IO,DGA^6000030   I182 @T6G_MB_LIB.T6G(SCH_1):PAGE55
 R3201    1      A Q_RES_0402LF-0,5%,1/16W,CHIP,CS00002JB13   I321 @T6G_MB_LIB.T6G(SCH_1):PAGE55

CLK_100M_CPU1_CLK05_R_DP @T6G_MB_LIB.T6G(SCH_1):CLK_100M_CPU1_CLK05_R_DP
   U26   B9 GPP_CLK05P GENOA_SP5-SOCKET6096_13568-001,SMLF,IO,DGA^6000030   I182 @T6G_MB_LIB.T6G(SCH_1):PAGE55
 R3200    1      A Q_RES_0402LF-0,5%,1/16W,CHIP,CS00002JB13   I320 @T6G_MB_LIB.T6G(SCH_1):PAGE55

CLK_100M_CPU1_CLK11_DN @T6G_MB_LIB.T6G(SCH_1):CLK_100M_CPU1_CLK11_DN
 R3353    2      B Q_RES_0402LF-0,5%,1/16W,CHIP,CS00002JB13   I303 @T6G_MB_LIB.T6G(SCH_1):PAGE55
  J112   O3     O3 CONN160_10131762101LF-CONN160_10131762-101LF,THLF,A   I102 @T6G_MB_LIB.T6G(SCH_1):PAGE329

CLK_100M_CPU1_CLK11_DP @T6G_MB_LIB.T6G(SCH_1):CLK_100M_CPU1_CLK11_DP
 R3352    2      B Q_RES_0402LF-0,5%,1/16W,CHIP,CS00002JB13   I302 @T6G_MB_LIB.T6G(SCH_1):PAGE55
  J112   P3     P3 CONN160_10131762101LF-CONN160_10131762-101LF,THLF,A   I102 @T6G_MB_LIB.T6G(SCH_1):PAGE329

CLK_100M_CPU1_CLK11_R_DN @T6G_MB_LIB.T6G(SCH_1):CLK_100M_CPU1_CLK11_R_DN
   U26 DJ42 GPP_CLK11N GENOA_SP5-SOCKET6096_13568-001,SMLF,IO,DGA^6000030   I182 @T6G_MB_LIB.T6G(SCH_1):PAGE55
 R3353    1      A Q_RES_0402LF-0,5%,1/16W,CHIP,CS00002JB13   I303 @T6G_MB_LIB.T6G(SCH_1):PAGE55

CLK_100M_CPU1_CLK11_R_DP @T6G_MB_LIB.T6G(SCH_1):CLK_100M_CPU1_CLK11_R_DP
   U26 DJ41 GPP_CLK11P GENOA_SP5-SOCKET6096_13568-001,SMLF,IO,DGA^6000030   I182 @T6G_MB_LIB.T6G(SCH_1):PAGE55
 R3352    1      A Q_RES_0402LF-0,5%,1/16W,CHIP,CS00002JB13   I302 @T6G_MB_LIB.T6G(SCH_1):PAGE55

CLK_100M_CPU1_CLK12_DN @T6G_MB_LIB.T6G(SCH_1):CLK_100M_CPU1_CLK12_DN
   J59   53 REFCLKN SCONN75K_APCI0155P004A-SCONN75K_APCI0155-P004A,SMLA    I88 @T6G_MB_LIB.T6G(SCH_1):PAGE345
 R4306    2      B Q_RES_0402LF-0,5%,1/16W,CHIP,CS00002JB13   I326 @T6G_MB_LIB.T6G(SCH_1):PAGE55

CLK_100M_CPU1_CLK12_DP @T6G_MB_LIB.T6G(SCH_1):CLK_100M_CPU1_CLK12_DP
   J59   55 REFCLKP SCONN75K_APCI0155P004A-SCONN75K_APCI0155-P004A,SMLA    I88 @T6G_MB_LIB.T6G(SCH_1):PAGE345
 R4305    2      B Q_RES_0402LF-0,5%,1/16W,CHIP,CS00002JB13   I327 @T6G_MB_LIB.T6G(SCH_1):PAGE55

CLK_100M_CPU1_CLK12_R_DN @T6G_MB_LIB.T6G(SCH_1):CLK_100M_CPU1_CLK12_R_DN
   U26 DJ44 GPP_CLK12N GENOA_SP5-SOCKET6096_13568-001,SMLF,IO,DGA^6000030   I182 @T6G_MB_LIB.T6G(SCH_1):PAGE55
 R4306    1      A Q_RES_0402LF-0,5%,1/16W,CHIP,CS00002JB13   I326 @T6G_MB_LIB.T6G(SCH_1):PAGE55

CLK_100M_CPU1_CLK12_R_DP @T6G_MB_LIB.T6G(SCH_1):CLK_100M_CPU1_CLK12_R_DP
   U26 DJ45 GPP_CLK12P GENOA_SP5-SOCKET6096_13568-001,SMLF,IO,DGA^6000030   I182 @T6G_MB_LIB.T6G(SCH_1):PAGE55
 R4305    1      A Q_RES_0402LF-0,5%,1/16W,CHIP,CS00002JB13   I327 @T6G_MB_LIB.T6G(SCH_1):PAGE55

CLK_100M_CPU1_CLK13_DN @T6G_MB_LIB.T6G(SCH_1):CLK_100M_CPU1_CLK13_DN
   U10    4 DIF_IN# 9ZXL0451EKILFT-9ZXL0451EKILFT,SMLF,IC,AL000451003    I63 @T6G_MB_LIB.T6G(SCH_1):PAGE379
 R8351    2      B Q_RES_0402LF-0,5%,1/16W,CHIP,CS00002JB13   I394 @T6G_MB_LIB.T6G(SCH_1):PAGE55

CLK_100M_CPU1_CLK13_DP @T6G_MB_LIB.T6G(SCH_1):CLK_100M_CPU1_CLK13_DP
   U10    3 DIF_IN 9ZXL0451EKILFT-9ZXL0451EKILFT,SMLF,IC,AL000451003    I63 @T6G_MB_LIB.T6G(SCH_1):PAGE379
 R8350    2      B Q_RES_0402LF-0,5%,1/16W,CHIP,CS00002JB13   I397 @T6G_MB_LIB.T6G(SCH_1):PAGE55

CLK_100M_CPU1_CLK13_R_DN @T6G_MB_LIB.T6G(SCH_1):CLK_100M_CPU1_CLK13_R_DN
   U26 DJ54 GPP_CLK13N GENOA_SP5-SOCKET6096_13568-001,SMLF,IO,DGA^6000030   I182 @T6G_MB_LIB.T6G(SCH_1):PAGE55
 R8351    1      A Q_RES_0402LF-0,5%,1/16W,CHIP,CS00002JB13   I394 @T6G_MB_LIB.T6G(SCH_1):PAGE55

CLK_100M_CPU1_CLK13_R_DP @T6G_MB_LIB.T6G(SCH_1):CLK_100M_CPU1_CLK13_R_DP
   U26 DJ53 GPP_CLK13P GENOA_SP5-SOCKET6096_13568-001,SMLF,IO,DGA^6000030   I182 @T6G_MB_LIB.T6G(SCH_1):PAGE55
 R8350    1      A Q_RES_0402LF-0,5%,1/16W,CHIP,CS00002JB13   I397 @T6G_MB_LIB.T6G(SCH_1):PAGE55

CLK_100M_GPU_FPGA_DN @T6G_MB_LIB.T6G(SCH_1):CLK_100M_GPU_FPGA_DN
 R3338    2      B Q_RES_0402LF-0,5%,1/16W,CHIP,CS00002JB13    I50 @T6G_MB_LIB.T6G(SCH_1):PAGE232
  J112   Q2     Q2 CONN160_10131762101LF-CONN160_10131762-101LF,THLF,A   I102 @T6G_MB_LIB.T6G(SCH_1):PAGE329

CLK_100M_GPU_FPGA_DN_R @T6G_MB_LIB.T6G(SCH_1):CLK_100M_GPU_FPGA_DN_R
 R3338    1      A Q_RES_0402LF-0,5%,1/16W,CHIP,CS00002JB13    I50 @T6G_MB_LIB.T6G(SCH_1):PAGE232
  U247   18  DIF1# 9FGL0251DKILFT-9FGL0251DKILFT,SMLF,IC,AL000251002    I77 @T6G_MB_LIB.T6G(SCH_1):PAGE232

CLK_100M_GPU_FPGA_DP @T6G_MB_LIB.T6G(SCH_1):CLK_100M_GPU_FPGA_DP
 R3337    2      B Q_RES_0402LF-0,5%,1/16W,CHIP,CS00002JB13    I51 @T6G_MB_LIB.T6G(SCH_1):PAGE232
  J112   R2     R2 CONN160_10131762101LF-CONN160_10131762-101LF,THLF,A   I102 @T6G_MB_LIB.T6G(SCH_1):PAGE329

CLK_100M_GPU_FPGA_DP_R @T6G_MB_LIB.T6G(SCH_1):CLK_100M_GPU_FPGA_DP_R
 R3337    1      A Q_RES_0402LF-0,5%,1/16W,CHIP,CS00002JB13    I51 @T6G_MB_LIB.T6G(SCH_1):PAGE232
  U247   17   DIF1 9FGL0251DKILFT-9FGL0251DKILFT,SMLF,IC,AL000251002    I77 @T6G_MB_LIB.T6G(SCH_1):PAGE232

CLK_100M_REF_IN_DN @T6G_MB_LIB.T6G(SCH_1):CLK_100M_REF_IN_DN
   U26  A20 REFCLK100SSC_N||GPP_CLK10N GENOA_SP5-SOCKET6096_13568-001,SMLF,IO,DGA^6000030   I182 @T6G_MB_LIB.T6G(SCH_1):PAGE55
  R436    2      B Q_RES_0402LF-0,5%,1/16W,CHIP,CS00002JB13   I172 @T6G_MB_LIB.T6G(SCH_1):PAGE28

CLK_100M_REF_IN_DP @T6G_MB_LIB.T6G(SCH_1):CLK_100M_REF_IN_DP
   U26  A19 REFCLK100SSC_P||GPP_CLK10P GENOA_SP5-SOCKET6096_13568-001,SMLF,IO,DGA^6000030   I182 @T6G_MB_LIB.T6G(SCH_1):PAGE55
  R435    2      B Q_RES_0402LF-0,5%,1/16W,CHIP,CS00002JB13   I171 @T6G_MB_LIB.T6G(SCH_1):PAGE28

CLK_100M_REF_OUT_DN @T6G_MB_LIB.T6G(SCH_1):CLK_100M_REF_OUT_DN
  R436    1      A Q_RES_0402LF-0,5%,1/16W,CHIP,CS00002JB13   I172 @T6G_MB_LIB.T6G(SCH_1):PAGE28
   U25  A20 REFCLK100SSC_N||GPP_CLK10N GENOA_SP5-SOCKET6096_13568-001,SMLF,IO,DGA^6000030   I188 @T6G_MB_LIB.T6G(SCH_1):PAGE28

CLK_100M_REF_OUT_DP @T6G_MB_LIB.T6G(SCH_1):CLK_100M_REF_OUT_DP
  R435    1      A Q_RES_0402LF-0,5%,1/16W,CHIP,CS00002JB13   I171 @T6G_MB_LIB.T6G(SCH_1):PAGE28
   U25  A19 REFCLK100SSC_P||GPP_CLK10P GENOA_SP5-SOCKET6096_13568-001,SMLF,IO,DGA^6000030   I188 @T6G_MB_LIB.T6G(SCH_1):PAGE28

CLK_100M_RETIMER_CPU0_P0_DN @T6G_MB_LIB.T6G(SCH_1):CLK_100M_RETIMER_CPU0_P0_DN
  R623    1      A Q_RES_0201LF-51.1,1%,1/20W,EMPTY,CS05111FE00    I37 @T6G_MB_LIB.T6G(SCH_1):PAGE385
  R596    2      B Q_RES_0201LF-0,5%,1/20W,CHIP,CS00001JE10    I40 @T6G_MB_LIB.T6G(SCH_1):PAGE385
 U6010 FF18 REFCLKN PT5161LRS-PT5161LRS,SMLF,IC,AJ051610U03    I53 @T6G_MB_LIB.T6G(SCH_1):PAGE385

CLK_100M_RETIMER_CPU0_P0_DP @T6G_MB_LIB.T6G(SCH_1):CLK_100M_RETIMER_CPU0_P0_DP
  R624    1      A Q_RES_0201LF-51.1,1%,1/20W,EMPTY,CS05111FE00    I38 @T6G_MB_LIB.T6G(SCH_1):PAGE385
  R595    2      B Q_RES_0201LF-0,5%,1/20W,CHIP,CS00001JE10    I39 @T6G_MB_LIB.T6G(SCH_1):PAGE385
 U6010 FJ16 REFCLKP PT5161LRS-PT5161LRS,SMLF,IC,AJ051610U03    I53 @T6G_MB_LIB.T6G(SCH_1):PAGE385

CLK_100M_RETIMER_CPU0_P0_R_DN @T6G_MB_LIB.T6G(SCH_1):CLK_100M_RETIMER_CPU0_P0_R_DN
  U314   14  DIF0# 9ZXL0451EKILFT-9ZXL0451EKILFT,SMLF,IC,AL000451003    I63 @T6G_MB_LIB.T6G(SCH_1):PAGE160
  R596    1      A Q_RES_0201LF-0,5%,1/20W,CHIP,CS00001JE10    I40 @T6G_MB_LIB.T6G(SCH_1):PAGE385

CLK_100M_RETIMER_CPU0_P0_R_DP @T6G_MB_LIB.T6G(SCH_1):CLK_100M_RETIMER_CPU0_P0_R_DP
  U314   13   DIF0 9ZXL0451EKILFT-9ZXL0451EKILFT,SMLF,IC,AL000451003    I63 @T6G_MB_LIB.T6G(SCH_1):PAGE160
  R595    1      A Q_RES_0201LF-0,5%,1/20W,CHIP,CS00001JE10    I39 @T6G_MB_LIB.T6G(SCH_1):PAGE385

CLK_100M_RETIMER_CPU0_P1_DN @T6G_MB_LIB.T6G(SCH_1):CLK_100M_RETIMER_CPU0_P1_DN
  R612    2      B Q_RES_0201LF-0,5%,1/20W,CHIP,CS00001JE10    I15 @T6G_MB_LIB.T6G(SCH_1):PAGE408
  R629    1      A Q_RES_0201LF-51.1,1%,1/20W,EMPTY,CS05111FE00    I18 @T6G_MB_LIB.T6G(SCH_1):PAGE408
 U6011 FF18 REFCLKN PT5161LRS-PT5161LRS,SMLF,IC,AJ051610U03    I83 @T6G_MB_LIB.T6G(SCH_1):PAGE408

CLK_100M_RETIMER_CPU0_P1_DP @T6G_MB_LIB.T6G(SCH_1):CLK_100M_RETIMER_CPU0_P1_DP
  R630    1      A Q_RES_0201LF-51.1,1%,1/20W,EMPTY,CS05111FE00    I19 @T6G_MB_LIB.T6G(SCH_1):PAGE408
  R611    2      B Q_RES_0201LF-0,5%,1/20W,CHIP,CS00001JE10    I20 @T6G_MB_LIB.T6G(SCH_1):PAGE408
 U6011 FJ16 REFCLKP PT5161LRS-PT5161LRS,SMLF,IC,AJ051610U03    I83 @T6G_MB_LIB.T6G(SCH_1):PAGE408

CLK_100M_RETIMER_CPU0_P1_R_DN @T6G_MB_LIB.T6G(SCH_1):CLK_100M_RETIMER_CPU0_P1_R_DN
  U314   20  DIF1# 9ZXL0451EKILFT-9ZXL0451EKILFT,SMLF,IC,AL000451003    I63 @T6G_MB_LIB.T6G(SCH_1):PAGE160
  R612    1      A Q_RES_0201LF-0,5%,1/20W,CHIP,CS00001JE10    I15 @T6G_MB_LIB.T6G(SCH_1):PAGE408

CLK_100M_RETIMER_CPU0_P1_R_DP @T6G_MB_LIB.T6G(SCH_1):CLK_100M_RETIMER_CPU0_P1_R_DP
  U314   19   DIF1 9ZXL0451EKILFT-9ZXL0451EKILFT,SMLF,IC,AL000451003    I63 @T6G_MB_LIB.T6G(SCH_1):PAGE160
  R611    1      A Q_RES_0201LF-0,5%,1/20W,CHIP,CS00001JE10    I20 @T6G_MB_LIB.T6G(SCH_1):PAGE408

CLK_100M_RETIMER_CPU0_P2_DN @T6G_MB_LIB.T6G(SCH_1):CLK_100M_RETIMER_CPU0_P2_DN
  R631    1      A Q_RES_0201LF-51.1,1%,1/20W,EMPTY,CS05111FE00    I17 @T6G_MB_LIB.T6G(SCH_1):PAGE419
  R614    2      B Q_RES_0201LF-0,5%,1/20W,CHIP,CS00001JE10    I20 @T6G_MB_LIB.T6G(SCH_1):PAGE419
 U6012 FF18 REFCLKN PT5161LRS-PT5161LRS,SMLF,IC,AJ051610U03    I83 @T6G_MB_LIB.T6G(SCH_1):PAGE419

CLK_100M_RETIMER_CPU0_P2_DP @T6G_MB_LIB.T6G(SCH_1):CLK_100M_RETIMER_CPU0_P2_DP
  R634    1      A Q_RES_0201LF-51.1,1%,1/20W,EMPTY,CS05111FE00    I18 @T6G_MB_LIB.T6G(SCH_1):PAGE419
  R613    2      B Q_RES_0201LF-0,5%,1/20W,CHIP,CS00001JE10    I19 @T6G_MB_LIB.T6G(SCH_1):PAGE419
 U6012 FJ16 REFCLKP PT5161LRS-PT5161LRS,SMLF,IC,AJ051610U03    I83 @T6G_MB_LIB.T6G(SCH_1):PAGE419

CLK_100M_RETIMER_CPU0_P2_R_DN @T6G_MB_LIB.T6G(SCH_1):CLK_100M_RETIMER_CPU0_P2_R_DN
  U314   23  DIF2# 9ZXL0451EKILFT-9ZXL0451EKILFT,SMLF,IC,AL000451003    I63 @T6G_MB_LIB.T6G(SCH_1):PAGE160
  R614    1      A Q_RES_0201LF-0,5%,1/20W,CHIP,CS00001JE10    I20 @T6G_MB_LIB.T6G(SCH_1):PAGE419

CLK_100M_RETIMER_CPU0_P2_R_DP @T6G_MB_LIB.T6G(SCH_1):CLK_100M_RETIMER_CPU0_P2_R_DP
  U314   22   DIF2 9ZXL0451EKILFT-9ZXL0451EKILFT,SMLF,IC,AL000451003    I63 @T6G_MB_LIB.T6G(SCH_1):PAGE160
  R613    1      A Q_RES_0201LF-0,5%,1/20W,CHIP,CS00001JE10    I19 @T6G_MB_LIB.T6G(SCH_1):PAGE419

CLK_100M_RETIMER_CPU0_P3_DN @T6G_MB_LIB.T6G(SCH_1):CLK_100M_RETIMER_CPU0_P3_DN
  R616    2      B Q_RES_0201LF-0,5%,1/20W,CHIP,CS00001JE10    I15 @T6G_MB_LIB.T6G(SCH_1):PAGE430
  R635    1      A Q_RES_0201LF-51.1,1%,1/20W,EMPTY,CS05111FE00    I18 @T6G_MB_LIB.T6G(SCH_1):PAGE430
 U6013 FF18 REFCLKN PT5161LRS-PT5161LRS,SMLF,IC,AJ051610U03    I83 @T6G_MB_LIB.T6G(SCH_1):PAGE430

CLK_100M_RETIMER_CPU0_P3_DP @T6G_MB_LIB.T6G(SCH_1):CLK_100M_RETIMER_CPU0_P3_DP
  R636    1      A Q_RES_0201LF-51.1,1%,1/20W,EMPTY,CS05111FE00    I19 @T6G_MB_LIB.T6G(SCH_1):PAGE430
  R615    2      B Q_RES_0201LF-0,5%,1/20W,CHIP,CS00001JE10    I20 @T6G_MB_LIB.T6G(SCH_1):PAGE430
 U6013 FJ16 REFCLKP PT5161LRS-PT5161LRS,SMLF,IC,AJ051610U03    I83 @T6G_MB_LIB.T6G(SCH_1):PAGE430

CLK_100M_RETIMER_CPU0_P3_R_DN @T6G_MB_LIB.T6G(SCH_1):CLK_100M_RETIMER_CPU0_P3_R_DN
  U314   28  DIF3# 9ZXL0451EKILFT-9ZXL0451EKILFT,SMLF,IC,AL000451003    I63 @T6G_MB_LIB.T6G(SCH_1):PAGE160
  R616    1      A Q_RES_0201LF-0,5%,1/20W,CHIP,CS00001JE10    I15 @T6G_MB_LIB.T6G(SCH_1):PAGE430

CLK_100M_RETIMER_CPU0_P3_R_DP @T6G_MB_LIB.T6G(SCH_1):CLK_100M_RETIMER_CPU0_P3_R_DP
  U314   27   DIF3 9ZXL0451EKILFT-9ZXL0451EKILFT,SMLF,IC,AL000451003    I63 @T6G_MB_LIB.T6G(SCH_1):PAGE160
  R615    1      A Q_RES_0201LF-0,5%,1/20W,CHIP,CS00001JE10    I20 @T6G_MB_LIB.T6G(SCH_1):PAGE430

CLK_100M_RETIMER_CPU1_P0_DN @T6G_MB_LIB.T6G(SCH_1):CLK_100M_RETIMER_CPU1_P0_DN
 U6014 FF18 REFCLKN PT5161LRS-PT5161LRS,SMLF,IC,AJ051610U03     I1 @T6G_MB_LIB.T6G(SCH_1):PAGE401
  R609    2      B Q_RES_0201LF-0,5%,1/20W,CHIP,CS00001JE10     I8 @T6G_MB_LIB.T6G(SCH_1):PAGE401
  R627    1      A Q_RES_0201LF-51.1,1%,1/20W,EMPTY,CS05111FE00    I23 @T6G_MB_LIB.T6G(SCH_1):PAGE401

CLK_100M_RETIMER_CPU1_P0_DP @T6G_MB_LIB.T6G(SCH_1):CLK_100M_RETIMER_CPU1_P0_DP
 U6014 FJ16 REFCLKP PT5161LRS-PT5161LRS,SMLF,IC,AJ051610U03     I1 @T6G_MB_LIB.T6G(SCH_1):PAGE401
  R599    2      B Q_RES_0201LF-0,5%,1/20W,CHIP,CS00001JE10     I9 @T6G_MB_LIB.T6G(SCH_1):PAGE401
  R628    1      A Q_RES_0201LF-51.1,1%,1/20W,EMPTY,CS05111FE00    I24 @T6G_MB_LIB.T6G(SCH_1):PAGE401

CLK_100M_RETIMER_CPU1_P0_R_DN @T6G_MB_LIB.T6G(SCH_1):CLK_100M_RETIMER_CPU1_P0_R_DN
   U10   14  DIF0# 9ZXL0451EKILFT-9ZXL0451EKILFT,SMLF,IC,AL000451003    I63 @T6G_MB_LIB.T6G(SCH_1):PAGE379
  R609    1      A Q_RES_0201LF-0,5%,1/20W,CHIP,CS00001JE10     I8 @T6G_MB_LIB.T6G(SCH_1):PAGE401

CLK_100M_RETIMER_CPU1_P0_R_DP @T6G_MB_LIB.T6G(SCH_1):CLK_100M_RETIMER_CPU1_P0_R_DP
   U10   13   DIF0 9ZXL0451EKILFT-9ZXL0451EKILFT,SMLF,IC,AL000451003    I63 @T6G_MB_LIB.T6G(SCH_1):PAGE379
  R599    1      A Q_RES_0201LF-0,5%,1/20W,CHIP,CS00001JE10     I9 @T6G_MB_LIB.T6G(SCH_1):PAGE401

CLK_100M_RETIMER_CPU1_P1_DN @T6G_MB_LIB.T6G(SCH_1):CLK_100M_RETIMER_CPU1_P1_DN
  R625    1      A Q_RES_0201LF-51.1,1%,1/20W,EMPTY,CS05111FE00    I31 @T6G_MB_LIB.T6G(SCH_1):PAGE392
  R598    2      B Q_RES_0201LF-0,5%,1/20W,CHIP,CS00001JE10    I34 @T6G_MB_LIB.T6G(SCH_1):PAGE392
 U6015 FF18 REFCLKN PT5161LRS-PT5161LRS,SMLF,IC,AJ051610U03    I47 @T6G_MB_LIB.T6G(SCH_1):PAGE392

CLK_100M_RETIMER_CPU1_P1_DP @T6G_MB_LIB.T6G(SCH_1):CLK_100M_RETIMER_CPU1_P1_DP
  R626    1      A Q_RES_0201LF-51.1,1%,1/20W,EMPTY,CS05111FE00    I32 @T6G_MB_LIB.T6G(SCH_1):PAGE392
  R597    2      B Q_RES_0201LF-0,5%,1/20W,CHIP,CS00001JE10    I33 @T6G_MB_LIB.T6G(SCH_1):PAGE392
 U6015 FJ16 REFCLKP PT5161LRS-PT5161LRS,SMLF,IC,AJ051610U03    I47 @T6G_MB_LIB.T6G(SCH_1):PAGE392

CLK_100M_RETIMER_CPU1_P1_R_DN @T6G_MB_LIB.T6G(SCH_1):CLK_100M_RETIMER_CPU1_P1_R_DN
   U10   20  DIF1# 9ZXL0451EKILFT-9ZXL0451EKILFT,SMLF,IC,AL000451003    I63 @T6G_MB_LIB.T6G(SCH_1):PAGE379
  R598    1      A Q_RES_0201LF-0,5%,1/20W,CHIP,CS00001JE10    I34 @T6G_MB_LIB.T6G(SCH_1):PAGE392

CLK_100M_RETIMER_CPU1_P1_R_DP @T6G_MB_LIB.T6G(SCH_1):CLK_100M_RETIMER_CPU1_P1_R_DP
   U10   19   DIF1 9ZXL0451EKILFT-9ZXL0451EKILFT,SMLF,IC,AL000451003    I63 @T6G_MB_LIB.T6G(SCH_1):PAGE379
  R597    1      A Q_RES_0201LF-0,5%,1/20W,CHIP,CS00001JE10    I33 @T6G_MB_LIB.T6G(SCH_1):PAGE392

CLK_100M_RETIMER_CPU1_P2_DN @T6G_MB_LIB.T6G(SCH_1):CLK_100M_RETIMER_CPU1_P2_DN
  R620    2      B Q_RES_0201LF-0,5%,1/20W,CHIP,CS00001JE10    I27 @T6G_MB_LIB.T6G(SCH_1):PAGE451
  R637    1      A Q_RES_0201LF-51.1,1%,1/20W,EMPTY,CS05111FE00    I92 @T6G_MB_LIB.T6G(SCH_1):PAGE451
 U6016 FF18 REFCLKN PT5161LRS-PT5161LRS,SMLF,IC,AJ051610U03    I97 @T6G_MB_LIB.T6G(SCH_1):PAGE451

CLK_100M_RETIMER_CPU1_P2_DP @T6G_MB_LIB.T6G(SCH_1):CLK_100M_RETIMER_CPU1_P2_DP
  R619    2      B Q_RES_0201LF-0,5%,1/20W,CHIP,CS00001JE10    I28 @T6G_MB_LIB.T6G(SCH_1):PAGE451
  R640    1      A Q_RES_0201LF-51.1,1%,1/20W,EMPTY,CS05111FE00    I36 @T6G_MB_LIB.T6G(SCH_1):PAGE451
 U6016 FJ16 REFCLKP PT5161LRS-PT5161LRS,SMLF,IC,AJ051610U03    I97 @T6G_MB_LIB.T6G(SCH_1):PAGE451

CLK_100M_RETIMER_CPU1_P2_R_DN @T6G_MB_LIB.T6G(SCH_1):CLK_100M_RETIMER_CPU1_P2_R_DN
   U10   23  DIF2# 9ZXL0451EKILFT-9ZXL0451EKILFT,SMLF,IC,AL000451003    I63 @T6G_MB_LIB.T6G(SCH_1):PAGE379
  R620    1      A Q_RES_0201LF-0,5%,1/20W,CHIP,CS00001JE10    I27 @T6G_MB_LIB.T6G(SCH_1):PAGE451

CLK_100M_RETIMER_CPU1_P2_R_DP @T6G_MB_LIB.T6G(SCH_1):CLK_100M_RETIMER_CPU1_P2_R_DP
   U10   22   DIF2 9ZXL0451EKILFT-9ZXL0451EKILFT,SMLF,IC,AL000451003    I63 @T6G_MB_LIB.T6G(SCH_1):PAGE379
  R619    1      A Q_RES_0201LF-0,5%,1/20W,CHIP,CS00001JE10    I28 @T6G_MB_LIB.T6G(SCH_1):PAGE451

CLK_100M_RETIMER_CPU1_P3_DN @T6G_MB_LIB.T6G(SCH_1):CLK_100M_RETIMER_CPU1_P3_DN
  R641    1      A Q_RES_0201LF-51.1,1%,1/20W,EMPTY,CS05111FE00    I30 @T6G_MB_LIB.T6G(SCH_1):PAGE462
  R622    2      B Q_RES_0201LF-0,5%,1/20W,CHIP,CS00001JE10    I31 @T6G_MB_LIB.T6G(SCH_1):PAGE462
 U6017 FF18 REFCLKN PT5161LRS-PT5161LRS,SMLF,IC,AJ051610U03    I97 @T6G_MB_LIB.T6G(SCH_1):PAGE462

CLK_100M_RETIMER_CPU1_P3_DP @T6G_MB_LIB.T6G(SCH_1):CLK_100M_RETIMER_CPU1_P3_DP
  R621    2      B Q_RES_0201LF-0,5%,1/20W,CHIP,CS00001JE10    I32 @T6G_MB_LIB.T6G(SCH_1):PAGE462
  R642    1      A Q_RES_0201LF-51.1,1%,1/20W,EMPTY,CS05111FE00    I46 @T6G_MB_LIB.T6G(SCH_1):PAGE462
 U6017 FJ16 REFCLKP PT5161LRS-PT5161LRS,SMLF,IC,AJ051610U03    I97 @T6G_MB_LIB.T6G(SCH_1):PAGE462

CLK_100M_RETIMER_CPU1_P3_R_DN @T6G_MB_LIB.T6G(SCH_1):CLK_100M_RETIMER_CPU1_P3_R_DN
   U10   28  DIF3# 9ZXL0451EKILFT-9ZXL0451EKILFT,SMLF,IC,AL000451003    I63 @T6G_MB_LIB.T6G(SCH_1):PAGE379
  R622    1      A Q_RES_0201LF-0,5%,1/20W,CHIP,CS00001JE10    I31 @T6G_MB_LIB.T6G(SCH_1):PAGE462

CLK_100M_RETIMER_CPU1_P3_R_DP @T6G_MB_LIB.T6G(SCH_1):CLK_100M_RETIMER_CPU1_P3_R_DP
   U10   27   DIF3 9ZXL0451EKILFT-9ZXL0451EKILFT,SMLF,IC,AL000451003    I63 @T6G_MB_LIB.T6G(SCH_1):PAGE379
  R621    1      A Q_RES_0201LF-0,5%,1/20W,CHIP,CS00001JE10    I32 @T6G_MB_LIB.T6G(SCH_1):PAGE462

CLK_50M_BMC_MAC_R @T6G_MB_LIB.T6G(SCH_1):CLK_50M_BMC_MAC_R
   U90    3     Y0 PI6CV304LE-PI6CV304LE,SMLF,IC,AL000304K01    I16 @T6G_MB_LIB.T6G(SCH_1):PAGE337
 R1140    1      A Q_RES_0402LF-27.4,1%,1/16W,CHIP,CS02742FB03    I22 @T6G_MB_LIB.T6G(SCH_1):PAGE337

CLK_50M_EN @T6G_MB_LIB.T6G(SCH_1):CLK_50M_EN
 R1138    2      B Q_RES_0402LF-10K,1%,1/16W,CHIP,CS31002FB08     I1 @T6G_MB_LIB.T6G(SCH_1):PAGE337
  OSC1    1     OE Q_OSC4P_SMLF-50MHZ,OSC,BF650000032     I4 @T6G_MB_LIB.T6G(SCH_1):PAGE337
   U90    2     OE PI6CV304LE-PI6CV304LE,SMLF,IC,AL000304K01    I16 @T6G_MB_LIB.T6G(SCH_1):PAGE337

CLK_50M_NCSI_OCP_1 @T6G_MB_LIB.T6G(SCH_1):CLK_50M_NCSI_OCP_1
   U90    5     Y1 PI6CV304LE-PI6CV304LE,SMLF,IC,AL000304K01    I16 @T6G_MB_LIB.T6G(SCH_1):PAGE337
 R1141    1      A Q_RES_0402LF-27.4,1%,1/16W,CHIP,CS02742FB03    I21 @T6G_MB_LIB.T6G(SCH_1):PAGE337

CLK_50M_NCSI_OCP_2 @T6G_MB_LIB.T6G(SCH_1):CLK_50M_NCSI_OCP_2
   U90    7     Y2 PI6CV304LE-PI6CV304LE,SMLF,IC,AL000304K01    I16 @T6G_MB_LIB.T6G(SCH_1):PAGE337
 R3181    1      A Q_RES_0402LF-27.4,1%,1/16W,CHIP,CS02742FB03    I20 @T6G_MB_LIB.T6G(SCH_1):PAGE337

CLK_50M_NCSI_OCP_SFF @T6G_MB_LIB.T6G(SCH_1):CLK_50M_NCSI_OCP_SFF
 R1141    2      B Q_RES_0402LF-27.4,1%,1/16W,CHIP,CS02742FB03    I21 @T6G_MB_LIB.T6G(SCH_1):PAGE337
  U320    1      Y 74LVC1G66GV-74LVC1G66GV,SMLF,IC,AL001G66000    I82 @T6G_MB_LIB.T6G(SCH_1):PAGE337

CLK_50M_NCSI_OCP_SFF_ISO @T6G_MB_LIB.T6G(SCH_1):CLK_50M_NCSI_OCP_SFF_ISO
   J38 OA14 RBT_CLK_IN SCONN168_ME1016810202011-SCONN168_ME1016810202011,A   I168 @T6G_MB_LIB.T6G(SCH_1):PAGE335
 R4601    1      A Q_RES_0402LF-0,5%,1/16W,CHIP,CS00002JB13    I29 @T6G_MB_LIB.T6G(SCH_1):PAGE337

CLK_50M_NCSI_OCP_SFF_ISO_R @T6G_MB_LIB.T6G(SCH_1):CLK_50M_NCSI_OCP_SFF_ISO_R
 R4601    2      B Q_RES_0402LF-0,5%,1/16W,CHIP,CS00002JB13    I29 @T6G_MB_LIB.T6G(SCH_1):PAGE337
  U320    2      Z 74LVC1G66GV-74LVC1G66GV,SMLF,IC,AL001G66000    I82 @T6G_MB_LIB.T6G(SCH_1):PAGE337

CLK_50M_NCSI_OCP_V3_2 @T6G_MB_LIB.T6G(SCH_1):CLK_50M_NCSI_OCP_V3_2
 R3181    2      B Q_RES_0402LF-27.4,1%,1/16W,CHIP,CS02742FB03    I20 @T6G_MB_LIB.T6G(SCH_1):PAGE337
  U321    1      Y 74LVC1G66GV-74LVC1G66GV,SMLF,IC,AL001G66000    I76 @T6G_MB_LIB.T6G(SCH_1):PAGE342

CLK_50M_NCSI_OCP_V3_2_ISO @T6G_MB_LIB.T6G(SCH_1):CLK_50M_NCSI_OCP_V3_2_ISO
   J35 OA14 RBT_CLK_IN SCONN168_ME1016810202011-SCONN168_ME1016810202011,A   I168 @T6G_MB_LIB.T6G(SCH_1):PAGE341
 R4602    1      A Q_RES_0402LF-0,5%,1/16W,CHIP,CS00002JB13    I36 @T6G_MB_LIB.T6G(SCH_1):PAGE342

CLK_50M_NCSI_OCP_V3_2_ISO_R @T6G_MB_LIB.T6G(SCH_1):CLK_50M_NCSI_OCP_V3_2_ISO_R
 R4602    2      B Q_RES_0402LF-0,5%,1/16W,CHIP,CS00002JB13    I36 @T6G_MB_LIB.T6G(SCH_1):PAGE342
  U321    2      Z 74LVC1G66GV-74LVC1G66GV,SMLF,IC,AL001G66000    I76 @T6G_MB_LIB.T6G(SCH_1):PAGE342

CLK_50M_RMII @T6G_MB_LIB.T6G(SCH_1):CLK_50M_RMII
  OSC1    3    OUT Q_OSC4P_SMLF-50MHZ,OSC,BF650000032     I4 @T6G_MB_LIB.T6G(SCH_1):PAGE337
 R1139    1      A Q_RES_0402LF-0,5%,1/16W,CHIP,CS00002JB13     I7 @T6G_MB_LIB.T6G(SCH_1):PAGE337

CLK_50M_RMII_BMC_OCP @T6G_MB_LIB.T6G(SCH_1):CLK_50M_RMII_BMC_OCP
   J41  B18  PETP0 SCONN168_ME1016810202011-SCONN168_ME1016810202011,A   I176 @T6G_MB_LIB.T6G(SCH_1):PAGE348
 R1140    2      B Q_RES_0402LF-27.4,1%,1/16W,CHIP,CS02742FB03    I22 @T6G_MB_LIB.T6G(SCH_1):PAGE337

CLK_50M_RMII_R @T6G_MB_LIB.T6G(SCH_1):CLK_50M_RMII_R
 R1139    2      B Q_RES_0402LF-0,5%,1/16W,CHIP,CS00002JB13     I7 @T6G_MB_LIB.T6G(SCH_1):PAGE337
   U90    1 CLK_IN PI6CV304LE-PI6CV304LE,SMLF,IC,AL000304K01    I16 @T6G_MB_LIB.T6G(SCH_1):PAGE337

CLK_9ZXL045_P0_HIBW @T6G_MB_LIB.T6G(SCH_1):CLK_9ZXL045_P0_HIBW
 R4492    1      A Q_RES_0402LF-10K,1%,1/16W,CHIP,CS31002FB08    I29 @T6G_MB_LIB.T6G(SCH_1):PAGE160
 R4491    2      B Q_RES_0402LF-10K,1%,1/16W,CHIP,CS31002FB08    I31 @T6G_MB_LIB.T6G(SCH_1):PAGE160
  U314   32 ^HIBW_BYPM_LOBW# 9ZXL0451EKILFT-9ZXL0451EKILFT,SMLF,IC,AL000451003    I63 @T6G_MB_LIB.T6G(SCH_1):PAGE160

CLK_9ZXL045_P0_SADR0 @T6G_MB_LIB.T6G(SCH_1):CLK_9ZXL045_P0_SADR0
 R4490    1      A Q_RES_0402LF-4.75K,1%,1/16W,EMPTY,CS24752FB03     I2 @T6G_MB_LIB.T6G(SCH_1):PAGE160
 R4489    2      B Q_RES_0402LF-4.75K,1%,1/16W,CHIP,CS24752FB03     I3 @T6G_MB_LIB.T6G(SCH_1):PAGE160
  U314    5 VSADR0_TRI 9ZXL0451EKILFT-9ZXL0451EKILFT,SMLF,IC,AL000451003    I63 @T6G_MB_LIB.T6G(SCH_1):PAGE160

CLK_9ZXL045_P1_HIBW @T6G_MB_LIB.T6G(SCH_1):CLK_9ZXL045_P1_HIBW
  R585    1      A Q_RES_0402LF-10K,1%,1/16W,CHIP,CS31002FB08    I15 @T6G_MB_LIB.T6G(SCH_1):PAGE379
  R580    2      B Q_RES_0402LF-10K,1%,1/16W,CHIP,CS31002FB08    I17 @T6G_MB_LIB.T6G(SCH_1):PAGE379
   U10   32 ^HIBW_BYPM_LOBW# 9ZXL0451EKILFT-9ZXL0451EKILFT,SMLF,IC,AL000451003    I63 @T6G_MB_LIB.T6G(SCH_1):PAGE379

CLK_9ZXL045_P1_SADR0 @T6G_MB_LIB.T6G(SCH_1):CLK_9ZXL045_P1_SADR0
   U10    5 VSADR0_TRI 9ZXL0451EKILFT-9ZXL0451EKILFT,SMLF,IC,AL000451003    I63 @T6G_MB_LIB.T6G(SCH_1):PAGE379
  R579    1      A Q_RES_0402LF-4.75K,1%,1/16W,CHIP,CS24752FB03    I64 @T6G_MB_LIB.T6G(SCH_1):PAGE379
  R578    2      B Q_RES_0402LF-4.75K,1%,1/16W,EMPTY,CS24752FB03    I65 @T6G_MB_LIB.T6G(SCH_1):PAGE379

CLK_CPU0_RTCCLK @T6G_MB_LIB.T6G(SCH_1):CLK_CPU0_RTCCLK
  R573    1      A Q_RES_0402LF-0,5%,1/16W,CHIP,CS00002JB13    I26 @T6G_MB_LIB.T6G(SCH_1):PAGE55
  R751    2      B Q_RES_0402LF-10K,5%,1/16W,CHIP,CS31002JB08    I12 @T6G_MB_LIB.T6G(SCH_1):PAGE75
  R740    2      B Q_RES_0402LF-10K,5%,1/16W,EMPTY,CS31002JB08    I44 @T6G_MB_LIB.T6G(SCH_1):PAGE75
   U25  DH9 RTCCLK GENOA_SP5-SOCKET6096_13568-001,SMLF,IO,DGA^6000030   I188 @T6G_MB_LIB.T6G(SCH_1):PAGE28

CLK_CPU1_RTCCLK @T6G_MB_LIB.T6G(SCH_1):CLK_CPU1_RTCCLK
   U26  DH9 RTCCLK GENOA_SP5-SOCKET6096_13568-001,SMLF,IO,DGA^6000030   I182 @T6G_MB_LIB.T6G(SCH_1):PAGE55
 R1501    2      B Q_RES_0402LF-10K,5%,1/16W,EMPTY,CS31002JB08    I90 @T6G_MB_LIB.T6G(SCH_1):PAGE75
 R1502    2      B Q_RES_0402LF-10K,5%,1/16W,CHIP,CS31002JB08    I94 @T6G_MB_LIB.T6G(SCH_1):PAGE75

CLK_ESPI_CPU0_CLK1 @T6G_MB_LIB.T6G(SCH_1):CLK_ESPI_CPU0_CLK1
  R739    2      B Q_RES_0402LF-10K,5%,1/16W,EMPTY,CS31002JB08    I45 @T6G_MB_LIB.T6G(SCH_1):PAGE75
  R750    2      B Q_RES_0402LF-30K,1%,1/16W,CHIP,CS33002FB02    I74 @T6G_MB_LIB.T6G(SCH_1):PAGE75
   J41   B1 +12V_EDGE_B1 SCONN168_ME1016810202011-SCONN168_ME1016810202011,A   I176 @T6G_MB_LIB.T6G(SCH_1):PAGE348
 R1556    2      B Q_RES_0402LF-33,5%,1/16W,CHIP,CS03302JB10   I176 @T6G_MB_LIB.T6G(SCH_1):PAGE80
  R473    1      A Q_RES_0402LF-0,5%,1/16W,CHIP,CS00002JB13   I430 @T6G_MB_LIB.T6G(SCH_1):PAGE29

CLK_ESPI_CPU0_R1_CLK1 @T6G_MB_LIB.T6G(SCH_1):CLK_ESPI_CPU0_R1_CLK1
 R1556    1      A Q_RES_0402LF-33,5%,1/16W,CHIP,CS03302JB10   I176 @T6G_MB_LIB.T6G(SCH_1):PAGE80
   U18  R21  PR20B LCMXO3LF9400C5BG484C-LCMXO3LF-9400C-5BG484C,SMLF,IA   I217 @T6G_MB_LIB.T6G(SCH_1):PAGE80

CLK_ESPI_CPU0_R_CLK1 @T6G_MB_LIB.T6G(SCH_1):CLK_ESPI_CPU0_R_CLK1
   U25 DG23 ESPI_CLK1||SPI_CLK1||AGPIO75 GENOA_SP5-SOCKET6096_13568-001,SMLF,IO,DGA^6000030   I287 @T6G_MB_LIB.T6G(SCH_1):PAGE29
  R473    2      B Q_RES_0402LF-0,5%,1/16W,CHIP,CS00002JB13   I430 @T6G_MB_LIB.T6G(SCH_1):PAGE29

CLK_GEN2_BMC_RC_OE_N @T6G_MB_LIB.T6G(SCH_1):CLK_GEN2_BMC_RC_OE_N
 R4075    1      A Q_RES_0402LF-0,5%,1/16W,CHIP,CS00002JB13    I22 @T6G_MB_LIB.T6G(SCH_1):PAGE232
 R6029    1      A Q_RES_0402LF-33,5%,1/16W,CHIP,CS03302JB10    I65 @T6G_MB_LIB.T6G(SCH_1):PAGE79
 R4521    2      B Q_RES_0402LF-1K,1%,1/16W,CHIP,CS21002FB06    I73 @T6G_MB_LIB.T6G(SCH_1):PAGE232

CLK_GEN2_BMC_RC_OE_R3_N @T6G_MB_LIB.T6G(SCH_1):CLK_GEN2_BMC_RC_OE_R3_N
 R4075    2      B Q_RES_0402LF-0,5%,1/16W,CHIP,CS00002JB13    I22 @T6G_MB_LIB.T6G(SCH_1):PAGE232
  U247   12  VOE0# 9FGL0251DKILFT-9FGL0251DKILFT,SMLF,IC,AL000251002    I77 @T6G_MB_LIB.T6G(SCH_1):PAGE232

CLK_GEN2_BMC_RC_OE_R_N @T6G_MB_LIB.T6G(SCH_1):CLK_GEN2_BMC_RC_OE_R_N
 R6029    2      B Q_RES_0402LF-33,5%,1/16W,CHIP,CS03302JB10    I65 @T6G_MB_LIB.T6G(SCH_1):PAGE79
   U18  C19  PT43C LCMXO3LF9400C5BG484C-LCMXO3LF-9400C-5BG484C,SMLF,IA    I94 @T6G_MB_LIB.T6G(SCH_1):PAGE79

CLK_GEN2_GPU_FPGA_OE_N @T6G_MB_LIB.T6G(SCH_1):CLK_GEN2_GPU_FPGA_OE_N
 R3327    1      A Q_RES_0402LF-0,5%,1/16W,CHIP,CS00002JB13     I6 @T6G_MB_LIB.T6G(SCH_1):PAGE232
 R6030    1      A Q_RES_0402LF-33,5%,1/16W,CHIP,CS03302JB10    I64 @T6G_MB_LIB.T6G(SCH_1):PAGE79

CLK_GEN2_GPU_FPGA_OE_OR_N @T6G_MB_LIB.T6G(SCH_1):CLK_GEN2_GPU_FPGA_OE_OR_N
 R4076    1      A Q_RES_0402LF-0,5%,1/16W,CHIP,CS00002JB13    I16 @T6G_MB_LIB.T6G(SCH_1):PAGE232
  U248    4      O 74LVC1G32GW_SMLF-74LVC1G32GW,IC,ALVC1G32007    I26 @T6G_MB_LIB.T6G(SCH_1):PAGE232
 R4537    2      B Q_RES_0402LF-0,5%,1/16W,CHIP,CS00002JB13    I67 @T6G_MB_LIB.T6G(SCH_1):PAGE110
 R3265    1      A Q_RES_0402LF-4.7K,1%,1/16W,EMPTY,CS24702FB06    I81 @T6G_MB_LIB.T6G(SCH_1):PAGE110
 R3292    2      B Q_RES_0402LF-4.7K,1%,1/16W,CHIP,CS24702FB06    I89 @T6G_MB_LIB.T6G(SCH_1):PAGE110
 R6162    2      B Q_RES_0402LF-0,5%,1/16W,CHIP,CS00002JB13    I23 @T6G_MB_LIB.T6G(SCH_1):PAGE111

CLK_GEN2_GPU_FPGA_OE_R2_N @T6G_MB_LIB.T6G(SCH_1):CLK_GEN2_GPU_FPGA_OE_R2_N
 R3327    2      B Q_RES_0402LF-0,5%,1/16W,CHIP,CS00002JB13     I6 @T6G_MB_LIB.T6G(SCH_1):PAGE232
 R4514    1      A Q_RES_0402LF-4.7K,1%,1/16W,EMPTY,CS24702FB06     I8 @T6G_MB_LIB.T6G(SCH_1):PAGE232
  U248    2     I1 74LVC1G32GW_SMLF-74LVC1G32GW,IC,ALVC1G32007    I26 @T6G_MB_LIB.T6G(SCH_1):PAGE232
 R3322    2      B Q_RES_0402LF-1K,1%,1/16W,CHIP,CS21002FB06    I74 @T6G_MB_LIB.T6G(SCH_1):PAGE232

CLK_GEN2_GPU_FPGA_OE_R_N @T6G_MB_LIB.T6G(SCH_1):CLK_GEN2_GPU_FPGA_OE_R_N
 R6030    2      B Q_RES_0402LF-33,5%,1/16W,CHIP,CS03302JB10    I64 @T6G_MB_LIB.T6G(SCH_1):PAGE79
   U18  C20  PT43D LCMXO3LF9400C5BG484C-LCMXO3LF-9400C-5BG484C,SMLF,IA    I94 @T6G_MB_LIB.T6G(SCH_1):PAGE79

CLK_GEN2_GPU_OE_N @T6G_MB_LIB.T6G(SCH_1):CLK_GEN2_GPU_OE_N
 R4076    2      B Q_RES_0402LF-0,5%,1/16W,CHIP,CS00002JB13    I16 @T6G_MB_LIB.T6G(SCH_1):PAGE232
  U247   19  VOE1# 9FGL0251DKILFT-9FGL0251DKILFT,SMLF,IC,AL000251002    I77 @T6G_MB_LIB.T6G(SCH_1):PAGE232

CLK_GEN2_SMB_SADR @T6G_MB_LIB.T6G(SCH_1):CLK_GEN2_SMB_SADR
 R4082    1      A Q_RES_0402LF-10K,1%,1/16W,EMPTY,CS31002FB08    I55 @T6G_MB_LIB.T6G(SCH_1):PAGE232
 R4081    2      B Q_RES_0402LF-10K,1%,1/16W,CHIP,CS31002FB08    I56 @T6G_MB_LIB.T6G(SCH_1):PAGE232
  U247    4 VSADR||REF3.3 9FGL0251DKILFT-9FGL0251DKILFT,SMLF,IC,AL000251002    I77 @T6G_MB_LIB.T6G(SCH_1):PAGE232

CLK_GEN2_XTAL_IN @T6G_MB_LIB.T6G(SCH_1):CLK_GEN2_XTAL_IN
 R4501    2      B Q_RES_0402LF-0,5%,1/16W,CHIP,CS00002JB13    I31 @T6G_MB_LIB.T6G(SCH_1):PAGE232
  U247    1 XIN||CLKIN_25 9FGL0251DKILFT-9FGL0251DKILFT,SMLF,IC,AL000251002    I77 @T6G_MB_LIB.T6G(SCH_1):PAGE232

CLK_GEN2_XTAL_IN_R @T6G_MB_LIB.T6G(SCH_1):CLK_GEN2_XTAL_IN_R
 Y8003    1     X1 Q_XTAL_4P_13BI_24GND-25MHZ,SMLF,MISC,BG6250000L4    I14 @T6G_MB_LIB.T6G(SCH_1):PAGE232
 R4501    1      A Q_RES_0402LF-0,5%,1/16W,CHIP,CS00002JB13    I31 @T6G_MB_LIB.T6G(SCH_1):PAGE232
   C71    1      A Q_CAP_C0402-4.7PF,50V,0.1P,NPO,CH-4716TB06    I75 @T6G_MB_LIB.T6G(SCH_1):PAGE232

CLK_GEN2_XTAL_OUT @T6G_MB_LIB.T6G(SCH_1):CLK_GEN2_XTAL_OUT
 Y8003    3     X2 Q_XTAL_4P_13BI_24GND-25MHZ,SMLF,MISC,BG6250000L4    I14 @T6G_MB_LIB.T6G(SCH_1):PAGE232
   C94    1      A Q_CAP_C0402-4.7PF,50V,0.1P,NPO,CH-4716TB06    I76 @T6G_MB_LIB.T6G(SCH_1):PAGE232
  U247    2     X2 9FGL0251DKILFT-9FGL0251DKILFT,SMLF,IC,AL000251002    I77 @T6G_MB_LIB.T6G(SCH_1):PAGE232

CLR_CMOS @T6G_MB_LIB.T6G(SCH_1):CLR_CMOS
  R275    1      A Q_RES_0402LF-33,5%,1/16W,CHIP,CS03302JB10    I84 @T6G_MB_LIB.T6G(SCH_1):PAGE81
 R1776    1      A Q_RES_0402LF-1K,1%,1/16W,CHIP,CS21002FB06    I94 @T6G_MB_LIB.T6G(SCH_1):PAGE156
 C1563    1      A Q_CAP_C0402-0.1UF,16V,10%,X7R,CH4103K1B08    I95 @T6G_MB_LIB.T6G(SCH_1):PAGE156
    Q8    2     G1 MOSFET_DUAL_6P-2N7002KDW,SMLF,IC,BAM70020047   I104 @T6G_MB_LIB.T6G(SCH_1):PAGE156
    Q8    5     G2 MOSFET_DUAL_6P-2N7002KDW,SMLF,IC,BAM70020047   I104 @T6G_MB_LIB.T6G(SCH_1):PAGE156

CLR_CMOS_N @T6G_MB_LIB.T6G(SCH_1):CLR_CMOS_N
    Q8    6     D1 MOSFET_DUAL_6P-2N7002KDW,SMLF,IC,BAM70020047   I104 @T6G_MB_LIB.T6G(SCH_1):PAGE156
 R1779    1      A Q_RES_0402LF-100,1%,1/16W,CHIP,CS11002FB07   I116 @T6G_MB_LIB.T6G(SCH_1):PAGE156

CPLD_JTAG_EN @T6G_MB_LIB.T6G(SCH_1):CPLD_JTAG_EN
  R638    1      A Q_RES_0402LF-1K,1%,1/16W,CHIP,CS21002FB06    I35 @T6G_MB_LIB.T6G(SCH_1):PAGE82
   U18  E14 PT31C||JTAGENB LCMXO3LF9400C5BG484C-LCMXO3LF-9400C-5BG484C,SMLF,IA    I25 @T6G_MB_LIB.T6G(SCH_1):PAGE79

CPLD_PROGRAMN @T6G_MB_LIB.T6G(SCH_1):CPLD_PROGRAMN
   U18  E15 PT31D||PROGRAMN LCMXO3LF9400C5BG484C-LCMXO3LF-9400C-5BG484C,SMLF,IA    I25 @T6G_MB_LIB.T6G(SCH_1):PAGE79
  R639    1      A Q_RES_0402LF-1K,1%,1/16W,CHIP,CS21002FB06    I33 @T6G_MB_LIB.T6G(SCH_1):PAGE82

CPU0_BP0 @T6G_MB_LIB.T6G(SCH_1):CPU0_BP0
   U25  C63    BP0 GENOA_SP5-SOCKET6096_13568-001,SMLF,IO,DGA^6000030   I227 @T6G_MB_LIB.T6G(SCH_1):PAGE27
  R408    1      A Q_RES_0402LF-2.2K,5%,1/16W,CHIP,CS22202JB07   I380 @T6G_MB_LIB.T6G(SCH_1):PAGE27
   J48    1      1 SCONN8_G802M0083150RD3HR-SCONN8_G802M0083150RD3HR,A   I424 @T6G_MB_LIB.T6G(SCH_1):PAGE27

CPU0_BP1 @T6G_MB_LIB.T6G(SCH_1):CPU0_BP1
   U25  C62    BP1 GENOA_SP5-SOCKET6096_13568-001,SMLF,IO,DGA^6000030   I227 @T6G_MB_LIB.T6G(SCH_1):PAGE27
  R409    1      A Q_RES_0402LF-2.2K,5%,1/16W,CHIP,CS22202JB07   I381 @T6G_MB_LIB.T6G(SCH_1):PAGE27
   J48    3      3 SCONN8_G802M0083150RD3HR-SCONN8_G802M0083150RD3HR,A   I424 @T6G_MB_LIB.T6G(SCH_1):PAGE27

CPU0_BP2 @T6G_MB_LIB.T6G(SCH_1):CPU0_BP2
   U25  A63    BP2 GENOA_SP5-SOCKET6096_13568-001,SMLF,IO,DGA^6000030   I227 @T6G_MB_LIB.T6G(SCH_1):PAGE27
  R410    1      A Q_RES_0402LF-2.2K,5%,1/16W,CHIP,CS22202JB07   I382 @T6G_MB_LIB.T6G(SCH_1):PAGE27
   J48    5      5 SCONN8_G802M0083150RD3HR-SCONN8_G802M0083150RD3HR,A   I424 @T6G_MB_LIB.T6G(SCH_1):PAGE27

CPU0_BP3 @T6G_MB_LIB.T6G(SCH_1):CPU0_BP3
   U25  A62    BP3 GENOA_SP5-SOCKET6096_13568-001,SMLF,IO,DGA^6000030   I227 @T6G_MB_LIB.T6G(SCH_1):PAGE27
  R411    1      A Q_RES_0402LF-2.2K,5%,1/16W,CHIP,CS22202JB07   I383 @T6G_MB_LIB.T6G(SCH_1):PAGE27
   J48    7      7 SCONN8_G802M0083150RD3HR-SCONN8_G802M0083150RD3HR,A   I424 @T6G_MB_LIB.T6G(SCH_1):PAGE27

CPU0_CORETYPE0 @T6G_MB_LIB.T6G(SCH_1):CPU0_CORETYPE0
   U25  C70 CORETYPE0 GENOA_SP5-SOCKET6096_13568-001,SMLF,IO,DGA^6000030   I227 @T6G_MB_LIB.T6G(SCH_1):PAGE27
  R390    2      B Q_RES_0402LF-2.2K,5%,1/16W,CHIP,CS22202JB07   I390 @T6G_MB_LIB.T6G(SCH_1):PAGE27
  R183    1      A Q_RES_0402LF-0,5%,1/16W,CHIP,CS00002JB13    I82 @T6G_MB_LIB.T6G(SCH_1):PAGE81

CPU0_CORETYPE1 @T6G_MB_LIB.T6G(SCH_1):CPU0_CORETYPE1
   U25  B69 CORETYPE1 GENOA_SP5-SOCKET6096_13568-001,SMLF,IO,DGA^6000030   I227 @T6G_MB_LIB.T6G(SCH_1):PAGE27
  R388    2      B Q_RES_0402LF-2.2K,5%,1/16W,CHIP,CS22202JB07   I389 @T6G_MB_LIB.T6G(SCH_1):PAGE27
  R184    1      A Q_RES_0402LF-0,5%,1/16W,CHIP,CS00002JB13    I48 @T6G_MB_LIB.T6G(SCH_1):PAGE81

CPU0_CORETYPE2 @T6G_MB_LIB.T6G(SCH_1):CPU0_CORETYPE2
   U25  D68 CORETYPE2 GENOA_SP5-SOCKET6096_13568-001,SMLF,IO,DGA^6000030   I227 @T6G_MB_LIB.T6G(SCH_1):PAGE27
  R387    2      B Q_RES_0402LF-2.2K,5%,1/16W,CHIP,CS22202JB07   I388 @T6G_MB_LIB.T6G(SCH_1):PAGE27
  R185    1      A Q_RES_0402LF-0,5%,1/16W,CHIP,CS00002JB13    I80 @T6G_MB_LIB.T6G(SCH_1):PAGE81

CPU0_ESPI0_ALERT_N @T6G_MB_LIB.T6G(SCH_1):CPU0_ESPI0_ALERT_N
   U25 DJ22 ESPI0_ALERT_L||AGPIO108 GENOA_SP5-SOCKET6096_13568-001,SMLF,IO,DGA^6000030   I287 @T6G_MB_LIB.T6G(SCH_1):PAGE29
 R1593    2      B Q_RES_0402LF-33,5%,1/16W,CHIP,CS03302JB10   I427 @T6G_MB_LIB.T6G(SCH_1):PAGE29

CPU0_ESPI_CS0_N @T6G_MB_LIB.T6G(SCH_1):CPU0_ESPI_CS0_N
   U25 DG28 ESPI_CS0_L||AGPIO124 GENOA_SP5-SOCKET6096_13568-001,SMLF,IO,DGA^6000030   I287 @T6G_MB_LIB.T6G(SCH_1):PAGE29
 R1592    2      B Q_RES_0402LF-33,5%,1/16W,CHIP,CS03302JB10   I426 @T6G_MB_LIB.T6G(SCH_1):PAGE29

CPU0_FORCE_SELFREFRESH @T6G_MB_LIB.T6G(SCH_1):CPU0_FORCE_SELFREFRESH
  R186    2      B Q_RES_0402LF-33,5%,1/16W,CHIP,CS03302JB10   I129 @T6G_MB_LIB.T6G(SCH_1):PAGE80
   U25  B63 FORCE_SELFREFRESH GENOA_SP5-SOCKET6096_13568-001,SMLF,IO,DGA^6000030   I188 @T6G_MB_LIB.T6G(SCH_1):PAGE28
  R438    1      A Q_RES_0402LF-4.7K,5%,1/16W,EMPTY,CS24702JB10   I222 @T6G_MB_LIB.T6G(SCH_1):PAGE28
 R6502    1      A Q_RES_0402LF-2.2K,5%,1/16W,CHIP,CS22202JB07   I224 @T6G_MB_LIB.T6G(SCH_1):PAGE28

CPU0_HDT_BYPASS_SEL @T6G_MB_LIB.T6G(SCH_1):CPU0_HDT_BYPASS_SEL
  U153    7     1C SN74AUC2G66DCTR-SN74AUC2G66DCTR,SMLF,IC,AL2G0066C00     I1 @T6G_MB_LIB.T6G(SCH_1):PAGE151
 R1646    2      B Q_RES_0402LF-1K,1%,1/16W,CHIP,CS21002FB06    I10 @T6G_MB_LIB.T6G(SCH_1):PAGE151
   U13    7     1C SN74AUC2G66DCTR-SN74AUC2G66DCTR,SMLF,IC,AL2G0066C00    I17 @T6G_MB_LIB.T6G(SCH_1):PAGE151
   Q63    G   GATE MOSFET_N_SMLF-BSS138K,BSS138K,IC,BAM138K0000    I45 @T6G_MB_LIB.T6G(SCH_1):PAGE151
  R158    2      B Q_RES_0402LF-33,5%,1/16W,CHIP,CS03302JB10   I154 @T6G_MB_LIB.T6G(SCH_1):PAGE80

CPU0_HDT_CONN_TESTEN @T6G_MB_LIB.T6G(SCH_1):CPU0_HDT_CONN_TESTEN
 R1632    2      B Q_RES_0402LF-33,5%,1/16W,CHIP,CS03302JB10   I114 @T6G_MB_LIB.T6G(SCH_1):PAGE149
  C551    1      A Q_CAP_C0402-0.01UF,50V,10%,X7R,CH31006KB18   I123 @T6G_MB_LIB.T6G(SCH_1):PAGE149
  R258    2      B Q_RES_0402LF-0,5%,1/16W,CHIP,CS00002JB13   I177 @T6G_MB_LIB.T6G(SCH_1):PAGE80

CPU0_JTAG_BUF_OE @T6G_MB_LIB.T6G(SCH_1):CPU0_JTAG_BUF_OE
  U150    9     OE SN74AVC4T774PWR-SN74AVC4T774PWR,SMLF,IC,AL04T774K00     I8 @T6G_MB_LIB.T6G(SCH_1):PAGE150
  R159    1      A Q_RES_0402LF-33,5%,1/16W,CHIP,CS03302JB10   I111 @T6G_MB_LIB.T6G(SCH_1):PAGE80

CPU0_JTAG_BUF_R_OE @T6G_MB_LIB.T6G(SCH_1):CPU0_JTAG_BUF_R_OE
  R159    2      B Q_RES_0402LF-33,5%,1/16W,CHIP,CS03302JB10   I111 @T6G_MB_LIB.T6G(SCH_1):PAGE80
   U18  H20   PR7D LCMXO3LF9400C5BG484C-LCMXO3LF-9400C-5BG484C,SMLF,IA   I217 @T6G_MB_LIB.T6G(SCH_1):PAGE80

CPU0_NMI_SYNC_FLOOD_N @T6G_MB_LIB.T6G(SCH_1):CPU0_NMI_SYNC_FLOOD_N
  R219    1      A Q_RES_0402LF-33,5%,1/16W,CHIP,CS03302JB10   I108 @T6G_MB_LIB.T6G(SCH_1):PAGE80
  R441    1      A Q_RES_0402LF-2.2K,5%,1/16W,CHIP,CS22202JB07    I55 @T6G_MB_LIB.T6G(SCH_1):PAGE28
   U25 DJ31 NMI_SYNC_FLOOD_L GENOA_SP5-SOCKET6096_13568-001,SMLF,IO,DGA^6000030   I188 @T6G_MB_LIB.T6G(SCH_1):PAGE28

CPU0_NV_SAVE_N @T6G_MB_LIB.T6G(SCH_1):CPU0_NV_SAVE_N
  R253    1      A Q_RES_0402LF-0,5%,1/16W,CHIP,CS00002JB13   I116 @T6G_MB_LIB.T6G(SCH_1):PAGE80
  R452    1      A Q_RES_0402LF-4.7K,5%,1/16W,CHIP,CS24702JB10    I45 @T6G_MB_LIB.T6G(SCH_1):PAGE28
   U25  B64 NV_SAVE_L GENOA_SP5-SOCKET6096_13568-001,SMLF,IO,DGA^6000030   I188 @T6G_MB_LIB.T6G(SCH_1):PAGE28

CPU0_PROCHOT_N @T6G_MB_LIB.T6G(SCH_1):CPU0_PROCHOT_N
   U25  A69 PROCHOT_L GENOA_SP5-SOCKET6096_13568-001,SMLF,IO,DGA^6000030   I227 @T6G_MB_LIB.T6G(SCH_1):PAGE27
  R412    1      A Q_RES_0402LF-2.2K,5%,1/16W,CHIP,CS22202JB07   I377 @T6G_MB_LIB.T6G(SCH_1):PAGE27
  R179    2      B Q_RES_0402LF-33,5%,1/16W,CHIP,CS03302JB10   I110 @T6G_MB_LIB.T6G(SCH_1):PAGE81

CPU0_PWR_BTN_N @T6G_MB_LIB.T6G(SCH_1):CPU0_PWR_BTN_N
  R215    1      A Q_RES_0402LF-33,5%,1/16W,CHIP,CS03302JB10   I104 @T6G_MB_LIB.T6G(SCH_1):PAGE80
    J6    1      1 CONN6_HBC1031L200D8H-CONN6_HBC1031-L200D-8H,THLF,IA    I28 @T6G_MB_LIB.T6G(SCH_1):PAGE28
  R424    2      B Q_RES_0402LF-2.2K,5%,1/16W,CHIP,CS22202JB07    I30 @T6G_MB_LIB.T6G(SCH_1):PAGE28
   U25  DH7 PWR_BTN_L||AGPIO0 GENOA_SP5-SOCKET6096_13568-001,SMLF,IO,DGA^6000030   I188 @T6G_MB_LIB.T6G(SCH_1):PAGE28

CPU0_PWR_GD_OUT @T6G_MB_LIB.T6G(SCH_1):CPU0_PWR_GD_OUT
  R440    2      B Q_RES_0402LF-4.7K,5%,1/16W,EMPTY,CS24702JB10    I37 @T6G_MB_LIB.T6G(SCH_1):PAGE28
  R288    1      A Q_RES_0402LF-4.7K,5%,1/16W,EMPTY,CS24702JB10    I42 @T6G_MB_LIB.T6G(SCH_1):PAGE28
  R434    1      A Q_RES_0402LF-33,5%,1/16W,CHIP,CS03302JB10   I165 @T6G_MB_LIB.T6G(SCH_1):PAGE28
   U25 DH36 PWRGD_OUT||AGPIO12 GENOA_SP5-SOCKET6096_13568-001,SMLF,IO,DGA^6000030   I188 @T6G_MB_LIB.T6G(SCH_1):PAGE28

CPU0_PWR_GOOD @T6G_MB_LIB.T6G(SCH_1):CPU0_PWR_GOOD
  R218    1      A Q_RES_0402LF-33,5%,1/16W,CHIP,CS03302JB10    I32 @T6G_MB_LIB.T6G(SCH_1):PAGE80
  R287    2      B Q_RES_0402LF-4.7K,5%,1/16W,EMPTY,CS24702JB10    I36 @T6G_MB_LIB.T6G(SCH_1):PAGE28
  R276    1      A Q_RES_0402LF-4.7K,5%,1/16W,CHIP,CS24702JB10    I41 @T6G_MB_LIB.T6G(SCH_1):PAGE28
   U25  DJ8 PWR_GOOD GENOA_SP5-SOCKET6096_13568-001,SMLF,IO,DGA^6000030   I188 @T6G_MB_LIB.T6G(SCH_1):PAGE28

CPU0_ROM_TYPE_SELECT @T6G_MB_LIB.T6G(SCH_1):CPU0_ROM_TYPE_SELECT
  R748    2      B Q_RES_0402LF-10K,5%,1/16W,EMPTY,CS31002JB08     I9 @T6G_MB_LIB.T6G(SCH_1):PAGE75
  R737    2      B Q_RES_0402LF-10K,5%,1/16W,CHIP,CS31002JB08    I43 @T6G_MB_LIB.T6G(SCH_1):PAGE75
   U25 DG32 AGPIO109 GENOA_SP5-SOCKET6096_13568-001,SMLF,IO,DGA^6000030   I188 @T6G_MB_LIB.T6G(SCH_1):PAGE28

CPU0_RTC_LDO_SELECT @T6G_MB_LIB.T6G(SCH_1):CPU0_RTC_LDO_SELECT
   U25  DH8 RTC_LDO_SELECT GENOA_SP5-SOCKET6096_13568-001,SMLF,IO,DGA^6000030   I227 @T6G_MB_LIB.T6G(SCH_1):PAGE27
 R5055    2      B Q_RES_0402LF-10K,5%,1/16W,CHIP,CS31002JB08   I427 @T6G_MB_LIB.T6G(SCH_1):PAGE27
 R5056    1      A Q_RES_0402LF-10K,5%,1/16W,EMPTY,CS31002JB08   I428 @T6G_MB_LIB.T6G(SCH_1):PAGE27

CPU0_SA0 @T6G_MB_LIB.T6G(SCH_1):CPU0_SA0
   U25 DJ55    SA0 GENOA_SP5-SOCKET6096_13568-001,SMLF,IO,DGA^6000030   I227 @T6G_MB_LIB.T6G(SCH_1):PAGE27
  R392    2      B Q_RES_0402LF-2.2K,5%,1/16W,EMPTY,CS22202JB07   I395 @T6G_MB_LIB.T6G(SCH_1):PAGE27
  R393    1      A Q_RES_0402LF-2.2K,5%,1/16W,CHIP,CS22202JB07   I396 @T6G_MB_LIB.T6G(SCH_1):PAGE27
  R220    2      B Q_RES_0402LF-33,5%,1/16W,CHIP,CS03302JB10   I109 @T6G_MB_LIB.T6G(SCH_1):PAGE81

CPU0_SA1 @T6G_MB_LIB.T6G(SCH_1):CPU0_SA1
   U25 DJ56    SA1 GENOA_SP5-SOCKET6096_13568-001,SMLF,IO,DGA^6000030   I227 @T6G_MB_LIB.T6G(SCH_1):PAGE27
  R394    1      A Q_RES_0402LF-2.2K,5%,1/16W,CHIP,CS22202JB07   I397 @T6G_MB_LIB.T6G(SCH_1):PAGE27
  R221    2      B Q_RES_0402LF-33,5%,1/16W,CHIP,CS03302JB10   I107 @T6G_MB_LIB.T6G(SCH_1):PAGE81

CPU0_SLP_S3_N @T6G_MB_LIB.T6G(SCH_1):CPU0_SLP_S3_N
  R449    1      A Q_RES_0402LF-4.7K,5%,1/16W,EMPTY,CS24702JB10    I48 @T6G_MB_LIB.T6G(SCH_1):PAGE28
  R249    2      B Q_RES_0402LF-33,5%,1/16W,CHIP,CS03302JB10   I135 @T6G_MB_LIB.T6G(SCH_1):PAGE28
   U25  DJ5 SLP_S3_L GENOA_SP5-SOCKET6096_13568-001,SMLF,IO,DGA^6000030   I188 @T6G_MB_LIB.T6G(SCH_1):PAGE28

CPU0_SLP_S5_N @T6G_MB_LIB.T6G(SCH_1):CPU0_SLP_S5_N
  R248    2      B Q_RES_0402LF-33,5%,1/16W,CHIP,CS03302JB10   I136 @T6G_MB_LIB.T6G(SCH_1):PAGE28
  R448    1      A Q_RES_0402LF-4.7K,5%,1/16W,EMPTY,CS24702JB10    I49 @T6G_MB_LIB.T6G(SCH_1):PAGE28
   U25  DG4 SLP_S5_L GENOA_SP5-SOCKET6096_13568-001,SMLF,IO,DGA^6000030   I188 @T6G_MB_LIB.T6G(SCH_1):PAGE28

CPU0_SMERR_N @T6G_MB_LIB.T6G(SCH_1):CPU0_SMERR_N
  R250    2      B Q_RES_0402LF-0,5%,1/16W,CHIP,CS00002JB13   I180 @T6G_MB_LIB.T6G(SCH_1):PAGE80
  R450    1      A Q_RES_0402LF-4.7K,5%,1/16W,CHIP,CS24702JB10    I47 @T6G_MB_LIB.T6G(SCH_1):PAGE28
   U25 DJ11 SMERR_L||AGPIO24 GENOA_SP5-SOCKET6096_13568-001,SMLF,IO,DGA^6000030   I188 @T6G_MB_LIB.T6G(SCH_1):PAGE28

CPU0_SP5R1 @T6G_MB_LIB.T6G(SCH_1):CPU0_SP5R1
   U25  C19  SP5R1 GENOA_SP5-SOCKET6096_13568-001,SMLF,IO,DGA^6000030   I227 @T6G_MB_LIB.T6G(SCH_1):PAGE27
  R397    2      B Q_RES_0402LF-2.2K,5%,1/16W,CHIP,CS22202JB07   I394 @T6G_MB_LIB.T6G(SCH_1):PAGE27
  R180    1      A Q_RES_0402LF-0,5%,1/16W,CHIP,CS00002JB13    I45 @T6G_MB_LIB.T6G(SCH_1):PAGE81

CPU0_SP5R2 @T6G_MB_LIB.T6G(SCH_1):CPU0_SP5R2
   U25  C68  SP5R2 GENOA_SP5-SOCKET6096_13568-001,SMLF,IO,DGA^6000030   I227 @T6G_MB_LIB.T6G(SCH_1):PAGE27
  R396    2      B Q_RES_0402LF-2.2K,5%,1/16W,CHIP,CS22202JB07   I393 @T6G_MB_LIB.T6G(SCH_1):PAGE27
  R181    1      A Q_RES_0402LF-0,5%,1/16W,CHIP,CS00002JB13    I46 @T6G_MB_LIB.T6G(SCH_1):PAGE81

CPU0_SP5R3 @T6G_MB_LIB.T6G(SCH_1):CPU0_SP5R3
   U25 DH73  SP5R3 GENOA_SP5-SOCKET6096_13568-001,SMLF,IO,DGA^6000030   I227 @T6G_MB_LIB.T6G(SCH_1):PAGE27
  R391    2      B Q_RES_0402LF-2.2K,5%,1/16W,CHIP,CS22202JB07   I392 @T6G_MB_LIB.T6G(SCH_1):PAGE27
  R222    1      A Q_RES_0402LF-0,5%,1/16W,CHIP,CS00002JB13    I52 @T6G_MB_LIB.T6G(SCH_1):PAGE81

CPU0_SP5R4 @T6G_MB_LIB.T6G(SCH_1):CPU0_SP5R4
   U25 DH10  SP5R4 GENOA_SP5-SOCKET6096_13568-001,SMLF,IO,DGA^6000030   I227 @T6G_MB_LIB.T6G(SCH_1):PAGE27
  R389    2      B Q_RES_0402LF-2.2K,5%,1/16W,CHIP,CS22202JB07   I391 @T6G_MB_LIB.T6G(SCH_1):PAGE27
  R223    2      B Q_RES_0402LF-0,5%,1/16W,CHIP,CS00002JB13   I100 @T6G_MB_LIB.T6G(SCH_1):PAGE81

CPU0_SPD_HOST_CTRL_N @T6G_MB_LIB.T6G(SCH_1):CPU0_SPD_HOST_CTRL_N
  R251    2      B Q_RES_0402LF-0,5%,1/16W,CHIP,CS00002JB13   I162 @T6G_MB_LIB.T6G(SCH_1):PAGE80
  R451    1      A Q_RES_0402LF-4.7K,5%,1/16W,CHIP,CS24702JB10    I46 @T6G_MB_LIB.T6G(SCH_1):PAGE28
   U25 DE36 AGPIO3||SPD_HOST_CTRL_L GENOA_SP5-SOCKET6096_13568-001,SMLF,IO,DGA^6000030   I188 @T6G_MB_LIB.T6G(SCH_1):PAGE28

CPU0_SPD_HOST_CTRL_R1_N @T6G_MB_LIB.T6G(SCH_1):CPU0_SPD_HOST_CTRL_R1_N
  R251    1      A Q_RES_0402LF-0,5%,1/16W,CHIP,CS00002JB13   I162 @T6G_MB_LIB.T6G(SCH_1):PAGE80
   U18  R18  PR26A LCMXO3LF9400C5BG484C-LCMXO3LF-9400C-5BG484C,SMLF,IA   I217 @T6G_MB_LIB.T6G(SCH_1):PAGE80

CPU0_THERMTRIP_N @T6G_MB_LIB.T6G(SCH_1):CPU0_THERMTRIP_N
   U25  DJ9 THERMTRIP_L GENOA_SP5-SOCKET6096_13568-001,SMLF,IO,DGA^6000030   I227 @T6G_MB_LIB.T6G(SCH_1):PAGE27
  R417    1      A Q_RES_0402LF-2.2K,5%,1/16W,CHIP,CS22202JB07   I379 @T6G_MB_LIB.T6G(SCH_1):PAGE27
  R489    1      A Q_RES_0402LF-33,5%,1/16W,CHIP,CS03302JB10   I399 @T6G_MB_LIB.T6G(SCH_1):PAGE27

CPU0_THERMTRIP_R_N @T6G_MB_LIB.T6G(SCH_1):CPU0_THERMTRIP_R_N
  R489    2      B Q_RES_0402LF-33,5%,1/16W,CHIP,CS03302JB10   I399 @T6G_MB_LIB.T6G(SCH_1):PAGE27
   U18   H2  PL10A LCMXO3LF9400C5BG484C-LCMXO3LF-9400C-5BG484C,SMLF,IA   I143 @T6G_MB_LIB.T6G(SCH_1):PAGE81
 R1533    1      A Q_RES_0402LF-0,5%,1/16W,CHIP,CS00002JB13   I429 @T6G_MB_LIB.T6G(SCH_1):PAGE27

CPU0_XTRIG_L4 @T6G_MB_LIB.T6G(SCH_1):CPU0_XTRIG_L4
  R481    1      A Q_RES_0402LF-0,5%,1/16W,CHIP,CS00002JB13   I335 @T6G_MB_LIB.T6G(SCH_1):PAGE27
  R156    2      B Q_RES_0402LF-0,5%,1/16W,CHIP,CS00002JB13   I346 @T6G_MB_LIB.T6G(SCH_1):PAGE27
  R413    1      A Q_RES_0402LF-2.2K,5%,1/16W,CHIP,CS22202JB07   I384 @T6G_MB_LIB.T6G(SCH_1):PAGE27
  R236    1      A Q_RES_0402LF-0,5%,1/16W,CHIP,CS00002JB13    I66 @T6G_MB_LIB.T6G(SCH_1):PAGE81
  J212    1      1 CONN10_HBC1051L300D8H-CONN10_HBC1051-L300D-8H,THLFA   I423 @T6G_MB_LIB.T6G(SCH_1):PAGE27

CPU0_XTRIG_L5 @T6G_MB_LIB.T6G(SCH_1):CPU0_XTRIG_L5
  R483    1      A Q_RES_0402LF-0,5%,1/16W,CHIP,CS00002JB13   I334 @T6G_MB_LIB.T6G(SCH_1):PAGE27
  R157    2      B Q_RES_0402LF-0,5%,1/16W,CHIP,CS00002JB13   I347 @T6G_MB_LIB.T6G(SCH_1):PAGE27
  R414    1      A Q_RES_0402LF-2.2K,5%,1/16W,CHIP,CS22202JB07   I385 @T6G_MB_LIB.T6G(SCH_1):PAGE27
  R478    1      A Q_RES_0402LF-33,5%,1/16W,CHIP,CS03302JB10   I150 @T6G_MB_LIB.T6G(SCH_1):PAGE149
  R237    1      A Q_RES_0402LF-0,5%,1/16W,CHIP,CS00002JB13    I69 @T6G_MB_LIB.T6G(SCH_1):PAGE81
  J212    3      3 CONN10_HBC1051L300D8H-CONN10_HBC1051-L300D-8H,THLFA   I423 @T6G_MB_LIB.T6G(SCH_1):PAGE27

CPU0_XTRIG_L6 @T6G_MB_LIB.T6G(SCH_1):CPU0_XTRIG_L6
  R484    1      A Q_RES_0402LF-0,5%,1/16W,CHIP,CS00002JB13   I336 @T6G_MB_LIB.T6G(SCH_1):PAGE27
  R356    2      B Q_RES_0402LF-0,5%,1/16W,CHIP,CS00002JB13   I349 @T6G_MB_LIB.T6G(SCH_1):PAGE27
  R415    1      A Q_RES_0402LF-2.2K,5%,1/16W,CHIP,CS22202JB07   I386 @T6G_MB_LIB.T6G(SCH_1):PAGE27
  R476    1      A Q_RES_0402LF-33,5%,1/16W,CHIP,CS03302JB10   I148 @T6G_MB_LIB.T6G(SCH_1):PAGE149
  R238    1      A Q_RES_0402LF-0,5%,1/16W,CHIP,CS00002JB13    I71 @T6G_MB_LIB.T6G(SCH_1):PAGE81
  J212    5      5 CONN10_HBC1051L300D8H-CONN10_HBC1051-L300D-8H,THLFA   I423 @T6G_MB_LIB.T6G(SCH_1):PAGE27

CPU0_XTRIG_L7 @T6G_MB_LIB.T6G(SCH_1):CPU0_XTRIG_L7
  R485    1      A Q_RES_0402LF-0,5%,1/16W,CHIP,CS00002JB13   I337 @T6G_MB_LIB.T6G(SCH_1):PAGE27
  R357    2      B Q_RES_0402LF-0,5%,1/16W,CHIP,CS00002JB13   I348 @T6G_MB_LIB.T6G(SCH_1):PAGE27
  R416    1      A Q_RES_0402LF-2.2K,5%,1/16W,CHIP,CS22202JB07   I387 @T6G_MB_LIB.T6G(SCH_1):PAGE27
  R477    1      A Q_RES_0402LF-33,5%,1/16W,CHIP,CS03302JB10   I147 @T6G_MB_LIB.T6G(SCH_1):PAGE149
  R239    1      A Q_RES_0402LF-0,5%,1/16W,CHIP,CS00002JB13    I62 @T6G_MB_LIB.T6G(SCH_1):PAGE81
  J212    7      7 CONN10_HBC1051L300D8H-CONN10_HBC1051-L300D-8H,THLFA   I423 @T6G_MB_LIB.T6G(SCH_1):PAGE27

CPU0_XTRIG_R1_L4 @T6G_MB_LIB.T6G(SCH_1):CPU0_XTRIG_R1_L4
  R481    2      B Q_RES_0402LF-0,5%,1/16W,CHIP,CS00002JB13   I335 @T6G_MB_LIB.T6G(SCH_1):PAGE27
    J5    1      1 SCONN8_G802M0083150RD3HR-SCONN8_G802M0083150RD3HR,A   I425 @T6G_MB_LIB.T6G(SCH_1):PAGE27

CPU0_XTRIG_R1_L5 @T6G_MB_LIB.T6G(SCH_1):CPU0_XTRIG_R1_L5
  R483    2      B Q_RES_0402LF-0,5%,1/16W,CHIP,CS00002JB13   I334 @T6G_MB_LIB.T6G(SCH_1):PAGE27
    J5    3      3 SCONN8_G802M0083150RD3HR-SCONN8_G802M0083150RD3HR,A   I425 @T6G_MB_LIB.T6G(SCH_1):PAGE27

CPU0_XTRIG_R1_L6 @T6G_MB_LIB.T6G(SCH_1):CPU0_XTRIG_R1_L6
  R484    2      B Q_RES_0402LF-0,5%,1/16W,CHIP,CS00002JB13   I336 @T6G_MB_LIB.T6G(SCH_1):PAGE27
    J5    5      5 SCONN8_G802M0083150RD3HR-SCONN8_G802M0083150RD3HR,A   I425 @T6G_MB_LIB.T6G(SCH_1):PAGE27

CPU0_XTRIG_R1_L7 @T6G_MB_LIB.T6G(SCH_1):CPU0_XTRIG_R1_L7
  R485    2      B Q_RES_0402LF-0,5%,1/16W,CHIP,CS00002JB13   I337 @T6G_MB_LIB.T6G(SCH_1):PAGE27
    J5    7      7 SCONN8_G802M0083150RD3HR-SCONN8_G802M0083150RD3HR,A   I425 @T6G_MB_LIB.T6G(SCH_1):PAGE27

CPU0_XTRIG_R2_L4 @T6G_MB_LIB.T6G(SCH_1):CPU0_XTRIG_R2_L4
   U25  C66 XTRIG_L4 GENOA_SP5-SOCKET6096_13568-001,SMLF,IO,DGA^6000030   I227 @T6G_MB_LIB.T6G(SCH_1):PAGE27
  R156    1      A Q_RES_0402LF-0,5%,1/16W,CHIP,CS00002JB13   I346 @T6G_MB_LIB.T6G(SCH_1):PAGE27

CPU0_XTRIG_R2_L5 @T6G_MB_LIB.T6G(SCH_1):CPU0_XTRIG_R2_L5
   U25  C65 XTRIG_L5 GENOA_SP5-SOCKET6096_13568-001,SMLF,IO,DGA^6000030   I227 @T6G_MB_LIB.T6G(SCH_1):PAGE27
  R157    1      A Q_RES_0402LF-0,5%,1/16W,CHIP,CS00002JB13   I347 @T6G_MB_LIB.T6G(SCH_1):PAGE27

CPU0_XTRIG_R2_L6 @T6G_MB_LIB.T6G(SCH_1):CPU0_XTRIG_R2_L6
   U25  A66 XTRIG_L6 GENOA_SP5-SOCKET6096_13568-001,SMLF,IO,DGA^6000030   I227 @T6G_MB_LIB.T6G(SCH_1):PAGE27
  R356    1      A Q_RES_0402LF-0,5%,1/16W,CHIP,CS00002JB13   I349 @T6G_MB_LIB.T6G(SCH_1):PAGE27

CPU0_XTRIG_R2_L7 @T6G_MB_LIB.T6G(SCH_1):CPU0_XTRIG_R2_L7
   U25  A65 XTRIG_L7 GENOA_SP5-SOCKET6096_13568-001,SMLF,IO,DGA^6000030   I227 @T6G_MB_LIB.T6G(SCH_1):PAGE27
  R357    1      A Q_RES_0402LF-0,5%,1/16W,CHIP,CS00002JB13   I348 @T6G_MB_LIB.T6G(SCH_1):PAGE27

CPU1_BP0 @T6G_MB_LIB.T6G(SCH_1):CPU1_BP0
   U26  C63    BP0 GENOA_SP5-SOCKET6096_13568-001,SMLF,IO,DGA^6000030   I190 @T6G_MB_LIB.T6G(SCH_1):PAGE54
  R531    1      A Q_RES_0402LF-2.2K,5%,1/16W,CHIP,CS22202JB07   I406 @T6G_MB_LIB.T6G(SCH_1):PAGE54
   J49    1      1 SCONN8_G802M0083150RD3HR-SCONN8_G802M0083150RD3HR,A   I419 @T6G_MB_LIB.T6G(SCH_1):PAGE54

CPU1_BP1 @T6G_MB_LIB.T6G(SCH_1):CPU1_BP1
   U26  C62    BP1 GENOA_SP5-SOCKET6096_13568-001,SMLF,IO,DGA^6000030   I190 @T6G_MB_LIB.T6G(SCH_1):PAGE54
  R532    1      A Q_RES_0402LF-2.2K,5%,1/16W,CHIP,CS22202JB07   I407 @T6G_MB_LIB.T6G(SCH_1):PAGE54
   J49    3      3 SCONN8_G802M0083150RD3HR-SCONN8_G802M0083150RD3HR,A   I419 @T6G_MB_LIB.T6G(SCH_1):PAGE54

CPU1_BP2 @T6G_MB_LIB.T6G(SCH_1):CPU1_BP2
   U26  A63    BP2 GENOA_SP5-SOCKET6096_13568-001,SMLF,IO,DGA^6000030   I190 @T6G_MB_LIB.T6G(SCH_1):PAGE54
  R533    1      A Q_RES_0402LF-2.2K,5%,1/16W,CHIP,CS22202JB07   I408 @T6G_MB_LIB.T6G(SCH_1):PAGE54
   J49    5      5 SCONN8_G802M0083150RD3HR-SCONN8_G802M0083150RD3HR,A   I419 @T6G_MB_LIB.T6G(SCH_1):PAGE54

CPU1_BP3 @T6G_MB_LIB.T6G(SCH_1):CPU1_BP3
   U26  A62    BP3 GENOA_SP5-SOCKET6096_13568-001,SMLF,IO,DGA^6000030   I190 @T6G_MB_LIB.T6G(SCH_1):PAGE54
  R534    1      A Q_RES_0402LF-2.2K,5%,1/16W,CHIP,CS22202JB07   I409 @T6G_MB_LIB.T6G(SCH_1):PAGE54
   J49    7      7 SCONN8_G802M0083150RD3HR-SCONN8_G802M0083150RD3HR,A   I419 @T6G_MB_LIB.T6G(SCH_1):PAGE54

CPU1_CORETYPE0 @T6G_MB_LIB.T6G(SCH_1):CPU1_CORETYPE0
   U26  C70 CORETYPE0 GENOA_SP5-SOCKET6096_13568-001,SMLF,IO,DGA^6000030   I190 @T6G_MB_LIB.T6G(SCH_1):PAGE54
  R516    2      B Q_RES_0402LF-2.2K,5%,1/16W,CHIP,CS22202JB07   I402 @T6G_MB_LIB.T6G(SCH_1):PAGE54
  R262    1      A Q_RES_0402LF-0,5%,1/16W,CHIP,CS00002JB13    I44 @T6G_MB_LIB.T6G(SCH_1):PAGE81

CPU1_CORETYPE1 @T6G_MB_LIB.T6G(SCH_1):CPU1_CORETYPE1
   U26  B69 CORETYPE1 GENOA_SP5-SOCKET6096_13568-001,SMLF,IO,DGA^6000030   I190 @T6G_MB_LIB.T6G(SCH_1):PAGE54
  R514    2      B Q_RES_0402LF-2.2K,5%,1/16W,CHIP,CS22202JB07   I401 @T6G_MB_LIB.T6G(SCH_1):PAGE54
  R263    1      A Q_RES_0402LF-0,5%,1/16W,CHIP,CS00002JB13    I47 @T6G_MB_LIB.T6G(SCH_1):PAGE81

CPU1_CORETYPE2 @T6G_MB_LIB.T6G(SCH_1):CPU1_CORETYPE2
   U26  D68 CORETYPE2 GENOA_SP5-SOCKET6096_13568-001,SMLF,IO,DGA^6000030   I190 @T6G_MB_LIB.T6G(SCH_1):PAGE54
  R512    2      B Q_RES_0402LF-2.2K,5%,1/16W,CHIP,CS22202JB07   I400 @T6G_MB_LIB.T6G(SCH_1):PAGE54
  R264    1      A Q_RES_0402LF-0,5%,1/16W,CHIP,CS00002JB13    I53 @T6G_MB_LIB.T6G(SCH_1):PAGE81

CPU1_FORCE_SELFREFRESH @T6G_MB_LIB.T6G(SCH_1):CPU1_FORCE_SELFREFRESH
   U26  B63 FORCE_SELFREFRESH GENOA_SP5-SOCKET6096_13568-001,SMLF,IO,DGA^6000030   I182 @T6G_MB_LIB.T6G(SCH_1):PAGE55
  R265    2      B Q_RES_0402LF-33,5%,1/16W,CHIP,CS03302JB10   I126 @T6G_MB_LIB.T6G(SCH_1):PAGE80
  R558    1      A Q_RES_0402LF-4.7K,5%,1/16W,EMPTY,CS24702JB10   I390 @T6G_MB_LIB.T6G(SCH_1):PAGE55
 R6503    1      A Q_RES_0402LF-2.2K,5%,1/16W,CHIP,CS22202JB07   I392 @T6G_MB_LIB.T6G(SCH_1):PAGE55

CPU1_HDT_BYPASS_SEL @T6G_MB_LIB.T6G(SCH_1):CPU1_HDT_BYPASS_SEL
   U14    7     1C SN74AUC2G66DCTR-SN74AUC2G66DCTR,SMLF,IC,AL2G0066C00    I23 @T6G_MB_LIB.T6G(SCH_1):PAGE151
 R1649    2      B Q_RES_0402LF-1K,1%,1/16W,CHIP,CS21002FB06    I25 @T6G_MB_LIB.T6G(SCH_1):PAGE151
  U154    7     1C SN74AUC2G66DCTR-SN74AUC2G66DCTR,SMLF,IC,AL2G0066C00    I31 @T6G_MB_LIB.T6G(SCH_1):PAGE151
   Q64    G   GATE MOSFET_N_SMLF-BSS138K,BSS138K,IC,BAM138K0000    I46 @T6G_MB_LIB.T6G(SCH_1):PAGE151
  R173    2      B Q_RES_0402LF-33,5%,1/16W,CHIP,CS03302JB10   I163 @T6G_MB_LIB.T6G(SCH_1):PAGE80

CPU1_JTAG_BUF_OE @T6G_MB_LIB.T6G(SCH_1):CPU1_JTAG_BUF_OE
  U151    9     OE SN74AVC4T774PWR-SN74AVC4T774PWR,SMLF,IC,AL04T774K00    I28 @T6G_MB_LIB.T6G(SCH_1):PAGE150
  R161    2      B Q_RES_0402LF-33,5%,1/16W,CHIP,CS03302JB10   I161 @T6G_MB_LIB.T6G(SCH_1):PAGE80

CPU1_JTAG_BUF_R_OE @T6G_MB_LIB.T6G(SCH_1):CPU1_JTAG_BUF_R_OE
  R161    1      A Q_RES_0402LF-33,5%,1/16W,CHIP,CS03302JB10   I161 @T6G_MB_LIB.T6G(SCH_1):PAGE80
   U18  R16  PR26C LCMXO3LF9400C5BG484C-LCMXO3LF-9400C-5BG484C,SMLF,IA   I217 @T6G_MB_LIB.T6G(SCH_1):PAGE80

CPU1_NMI_SYNC_FLOOD_N @T6G_MB_LIB.T6G(SCH_1):CPU1_NMI_SYNC_FLOOD_N
   U26 DJ31 NMI_SYNC_FLOOD_L GENOA_SP5-SOCKET6096_13568-001,SMLF,IO,DGA^6000030   I182 @T6G_MB_LIB.T6G(SCH_1):PAGE55
  R277    2      B Q_RES_0402LF-33,5%,1/16W,CHIP,CS03302JB10   I165 @T6G_MB_LIB.T6G(SCH_1):PAGE80
  R562    2      B Q_RES_0402LF-2.2K,5%,1/16W,CHIP,CS22202JB07   I355 @T6G_MB_LIB.T6G(SCH_1):PAGE55

CPU1_NV_SAVE_N @T6G_MB_LIB.T6G(SCH_1):CPU1_NV_SAVE_N
   U26  B64 NV_SAVE_L GENOA_SP5-SOCKET6096_13568-001,SMLF,IO,DGA^6000030   I182 @T6G_MB_LIB.T6G(SCH_1):PAGE55
  R196    1      A Q_RES_0402LF-0,5%,1/16W,CHIP,CS00002JB13   I109 @T6G_MB_LIB.T6G(SCH_1):PAGE80
  R553    1      A Q_RES_0402LF-4.7K,5%,1/16W,CHIP,CS24702JB10   I359 @T6G_MB_LIB.T6G(SCH_1):PAGE55

CPU1_PROCHOT_N @T6G_MB_LIB.T6G(SCH_1):CPU1_PROCHOT_N
   U26  A69 PROCHOT_L GENOA_SP5-SOCKET6096_13568-001,SMLF,IO,DGA^6000030   I190 @T6G_MB_LIB.T6G(SCH_1):PAGE54
  R520    1      A Q_RES_0402LF-2.2K,5%,1/16W,CHIP,CS22202JB07   I396 @T6G_MB_LIB.T6G(SCH_1):PAGE54
  R270    2      B Q_RES_0402LF-33,5%,1/16W,CHIP,CS03302JB10   I112 @T6G_MB_LIB.T6G(SCH_1):PAGE81

CPU1_PWRGD_OUT @T6G_MB_LIB.T6G(SCH_1):CPU1_PWRGD_OUT
   U26 DH36 PWRGD_OUT||AGPIO12 GENOA_SP5-SOCKET6096_13568-001,SMLF,IO,DGA^6000030   I182 @T6G_MB_LIB.T6G(SCH_1):PAGE55
  R491    2      B Q_RES_0402LF-4.7K,5%,1/16W,EMPTY,CS24702JB10   I335 @T6G_MB_LIB.T6G(SCH_1):PAGE55
  R456    1      A Q_RES_0402LF-4.7K,5%,1/16W,EMPTY,CS24702JB10   I339 @T6G_MB_LIB.T6G(SCH_1):PAGE55
  R195    2      B Q_RES_0402LF-33,5%,1/16W,CHIP,CS03302JB10   I303 @T6G_MB_LIB.T6G(SCH_1):PAGE80

CPU1_PWR_GD_IN @T6G_MB_LIB.T6G(SCH_1):CPU1_PWR_GD_IN
   U26  DJ8 PWR_GOOD GENOA_SP5-SOCKET6096_13568-001,SMLF,IO,DGA^6000030   I182 @T6G_MB_LIB.T6G(SCH_1):PAGE55
  R252    2      B Q_RES_0402LF-0,5%,1/16W,CHIP,CS00002JB13   I128 @T6G_MB_LIB.T6G(SCH_1):PAGE80
  R434    2      B Q_RES_0402LF-33,5%,1/16W,CHIP,CS03302JB10   I165 @T6G_MB_LIB.T6G(SCH_1):PAGE28

CPU1_SA0 @T6G_MB_LIB.T6G(SCH_1):CPU1_SA0
   U26 DJ55    SA0 GENOA_SP5-SOCKET6096_13568-001,SMLF,IO,DGA^6000030   I190 @T6G_MB_LIB.T6G(SCH_1):PAGE54
  R518    2      B Q_RES_0402LF-2.2K,5%,1/16W,CHIP,CS22202JB07   I403 @T6G_MB_LIB.T6G(SCH_1):PAGE54
  R519    1      A Q_RES_0402LF-2.2K,5%,1/16W,EMPTY,CS22202JB07   I404 @T6G_MB_LIB.T6G(SCH_1):PAGE54
  R266    2      B Q_RES_0402LF-33,5%,1/16W,CHIP,CS03302JB10   I108 @T6G_MB_LIB.T6G(SCH_1):PAGE81

CPU1_SA1 @T6G_MB_LIB.T6G(SCH_1):CPU1_SA1
   U26 DJ56    SA1 GENOA_SP5-SOCKET6096_13568-001,SMLF,IO,DGA^6000030   I190 @T6G_MB_LIB.T6G(SCH_1):PAGE54
  R521    1      A Q_RES_0402LF-2.2K,5%,1/16W,CHIP,CS22202JB07   I405 @T6G_MB_LIB.T6G(SCH_1):PAGE54
  R267    1      A Q_RES_0402LF-33,5%,1/16W,CHIP,CS03302JB10    I73 @T6G_MB_LIB.T6G(SCH_1):PAGE81

CPU1_SLP_S3_N @T6G_MB_LIB.T6G(SCH_1):CPU1_SLP_S3_N
   U26  DJ5 SLP_S3_L GENOA_SP5-SOCKET6096_13568-001,SMLF,IO,DGA^6000030   I182 @T6G_MB_LIB.T6G(SCH_1):PAGE55
  R192    2      B Q_RES_0402LF-0,5%,1/16W,EMPTY,CS00002JB13   I298 @T6G_MB_LIB.T6G(SCH_1):PAGE55
  R549    1      A Q_RES_0402LF-4.7K,5%,1/16W,EMPTY,CS24702JB10   I353 @T6G_MB_LIB.T6G(SCH_1):PAGE55

CPU1_SLP_S5_N @T6G_MB_LIB.T6G(SCH_1):CPU1_SLP_S5_N
   U26  DG4 SLP_S5_L GENOA_SP5-SOCKET6096_13568-001,SMLF,IO,DGA^6000030   I182 @T6G_MB_LIB.T6G(SCH_1):PAGE55
  R191    2      B Q_RES_0402LF-0,5%,1/16W,EMPTY,CS00002JB13   I297 @T6G_MB_LIB.T6G(SCH_1):PAGE55
  R548    1      A Q_RES_0402LF-4.7K,5%,1/16W,EMPTY,CS24702JB10   I352 @T6G_MB_LIB.T6G(SCH_1):PAGE55

CPU1_SMERR_N @T6G_MB_LIB.T6G(SCH_1):CPU1_SMERR_N
   U26 DJ11 SMERR_L||AGPIO24 GENOA_SP5-SOCKET6096_13568-001,SMLF,IO,DGA^6000030   I182 @T6G_MB_LIB.T6G(SCH_1):PAGE55
  R550    1      A Q_RES_0402LF-4.7K,5%,1/16W,CHIP,CS24702JB10   I363 @T6G_MB_LIB.T6G(SCH_1):PAGE55
  R193    2      B Q_RES_0402LF-0,5%,1/16W,CHIP,CS00002JB13   I179 @T6G_MB_LIB.T6G(SCH_1):PAGE80

CPU1_SP5R1 @T6G_MB_LIB.T6G(SCH_1):CPU1_SP5R1
   U26  C19  SP5R1 GENOA_SP5-SOCKET6096_13568-001,SMLF,IO,DGA^6000030   I190 @T6G_MB_LIB.T6G(SCH_1):PAGE54
  R522    2      B Q_RES_0402LF-2.2K,5%,1/16W,CHIP,CS22202JB07   I388 @T6G_MB_LIB.T6G(SCH_1):PAGE54
  R260    1      A Q_RES_0402LF-0,5%,1/16W,CHIP,CS00002JB13    I49 @T6G_MB_LIB.T6G(SCH_1):PAGE81

CPU1_SP5R2 @T6G_MB_LIB.T6G(SCH_1):CPU1_SP5R2
   U26  C68  SP5R2 GENOA_SP5-SOCKET6096_13568-001,SMLF,IO,DGA^6000030   I190 @T6G_MB_LIB.T6G(SCH_1):PAGE54
  R517    2      B Q_RES_0402LF-2.2K,5%,1/16W,CHIP,CS22202JB07   I387 @T6G_MB_LIB.T6G(SCH_1):PAGE54
  R261    1      A Q_RES_0402LF-0,5%,1/16W,CHIP,CS00002JB13    I50 @T6G_MB_LIB.T6G(SCH_1):PAGE81

CPU1_SP5R3 @T6G_MB_LIB.T6G(SCH_1):CPU1_SP5R3
   U26 DH73  SP5R3 GENOA_SP5-SOCKET6096_13568-001,SMLF,IO,DGA^6000030   I190 @T6G_MB_LIB.T6G(SCH_1):PAGE54
  R515    2      B Q_RES_0402LF-2.2K,5%,1/16W,CHIP,CS22202JB07   I391 @T6G_MB_LIB.T6G(SCH_1):PAGE54
  R268    1      A Q_RES_0402LF-0,5%,1/16W,CHIP,CS00002JB13    I55 @T6G_MB_LIB.T6G(SCH_1):PAGE81

CPU1_SP5R4 @T6G_MB_LIB.T6G(SCH_1):CPU1_SP5R4
   U26 DH10  SP5R4 GENOA_SP5-SOCKET6096_13568-001,SMLF,IO,DGA^6000030   I190 @T6G_MB_LIB.T6G(SCH_1):PAGE54
  R513    2      B Q_RES_0402LF-2.2K,5%,1/16W,CHIP,CS22202JB07   I390 @T6G_MB_LIB.T6G(SCH_1):PAGE54
  R269    1      A Q_RES_0402LF-0,5%,1/16W,CHIP,CS00002JB13    I56 @T6G_MB_LIB.T6G(SCH_1):PAGE81

CPU1_SPD_HOST_CTRL_N @T6G_MB_LIB.T6G(SCH_1):CPU1_SPD_HOST_CTRL_N
  R570    1      A Q_RES_0402LF-0,5%,1/16W,CHIP,CS00002JB13   I236 @T6G_MB_LIB.T6G(SCH_1):PAGE55
  R194    1      A Q_RES_0402LF-0,5%,1/16W,CHIP,CS00002JB13   I100 @T6G_MB_LIB.T6G(SCH_1):PAGE80
  R551    1      A Q_RES_0402LF-4.7K,5%,1/16W,CHIP,CS24702JB10   I360 @T6G_MB_LIB.T6G(SCH_1):PAGE55

CPU1_SPD_HOST_CTRL_R1_N @T6G_MB_LIB.T6G(SCH_1):CPU1_SPD_HOST_CTRL_R1_N
  R194    2      B Q_RES_0402LF-0,5%,1/16W,CHIP,CS00002JB13   I100 @T6G_MB_LIB.T6G(SCH_1):PAGE80
   U18  L16  PR14B LCMXO3LF9400C5BG484C-LCMXO3LF-9400C-5BG484C,SMLF,IA   I217 @T6G_MB_LIB.T6G(SCH_1):PAGE80

CPU1_SPD_HOST_CTRL_R_N @T6G_MB_LIB.T6G(SCH_1):CPU1_SPD_HOST_CTRL_R_N
   U26 DE36 AGPIO3||SPD_HOST_CTRL_L GENOA_SP5-SOCKET6096_13568-001,SMLF,IO,DGA^6000030   I182 @T6G_MB_LIB.T6G(SCH_1):PAGE55
  R570    2      B Q_RES_0402LF-0,5%,1/16W,CHIP,CS00002JB13   I236 @T6G_MB_LIB.T6G(SCH_1):PAGE55

CPU1_THERMTRIP_N @T6G_MB_LIB.T6G(SCH_1):CPU1_THERMTRIP_N
   U26  DJ9 THERMTRIP_L GENOA_SP5-SOCKET6096_13568-001,SMLF,IO,DGA^6000030   I190 @T6G_MB_LIB.T6G(SCH_1):PAGE54
  R488    1      A Q_RES_0402LF-33,5%,1/16W,CHIP,CS03302JB10   I415 @T6G_MB_LIB.T6G(SCH_1):PAGE54
  R536    1      A Q_RES_0402LF-2.2K,5%,1/16W,EMPTY,CS22202JB07   I421 @T6G_MB_LIB.T6G(SCH_1):PAGE54

CPU1_THERMTRIP_R_N @T6G_MB_LIB.T6G(SCH_1):CPU1_THERMTRIP_R_N
  R488    2      B Q_RES_0402LF-33,5%,1/16W,CHIP,CS03302JB10   I415 @T6G_MB_LIB.T6G(SCH_1):PAGE54
   U18   J5  PL11B LCMXO3LF9400C5BG484C-LCMXO3LF-9400C-5BG484C,SMLF,IA   I143 @T6G_MB_LIB.T6G(SCH_1):PAGE81
 R1533    2      B Q_RES_0402LF-0,5%,1/16W,CHIP,CS00002JB13   I429 @T6G_MB_LIB.T6G(SCH_1):PAGE27

CPU1_VDDBT_RTC_G @T6G_MB_LIB.T6G(SCH_1):CPU1_VDDBT_RTC_G
   U26 BN23 VDDBT_RTC_G GENOA_SP5-SOCKET6096_13568-001,SMLF,IO,DGA^6000030    I45 @T6G_MB_LIB.T6G(SCH_1):PAGE57
  R374    2      B Q_RES_0402LF-0,5%,1/16W,CHIP,CS00002JB13    I51 @T6G_MB_LIB.T6G(SCH_1):PAGE57
  R373    2      B Q_RES_0402LF-0,5%,1/16W,EMPTY,CS00002JB13    I52 @T6G_MB_LIB.T6G(SCH_1):PAGE57

CPU1_XTRIG_L4 @T6G_MB_LIB.T6G(SCH_1):CPU1_XTRIG_L4
  R486    2      B Q_RES_0402LF-0,5%,1/16W,CHIP,CS00002JB13   I362 @T6G_MB_LIB.T6G(SCH_1):PAGE54
  R929    1      A Q_RES_0402LF-0,5%,1/16W,CHIP,CS00002JB13   I371 @T6G_MB_LIB.T6G(SCH_1):PAGE54
  R537    1      A Q_RES_0402LF-2.2K,5%,1/16W,CHIP,CS22202JB07   I410 @T6G_MB_LIB.T6G(SCH_1):PAGE54
  R204    1      A Q_RES_0402LF-0,5%,1/16W,CHIP,CS00002JB13    I77 @T6G_MB_LIB.T6G(SCH_1):PAGE81
  J212    2      2 CONN10_HBC1051L300D8H-CONN10_HBC1051-L300D-8H,THLFA   I423 @T6G_MB_LIB.T6G(SCH_1):PAGE27

CPU1_XTRIG_L5 @T6G_MB_LIB.T6G(SCH_1):CPU1_XTRIG_L5
  R618    2      B Q_RES_0402LF-0,5%,1/16W,CHIP,CS00002JB13   I361 @T6G_MB_LIB.T6G(SCH_1):PAGE54
  R930    1      A Q_RES_0402LF-0,5%,1/16W,CHIP,CS00002JB13   I372 @T6G_MB_LIB.T6G(SCH_1):PAGE54
  R538    1      A Q_RES_0402LF-2.2K,5%,1/16W,CHIP,CS22202JB07   I411 @T6G_MB_LIB.T6G(SCH_1):PAGE54
  R205    1      A Q_RES_0402LF-0,5%,1/16W,CHIP,CS00002JB13    I74 @T6G_MB_LIB.T6G(SCH_1):PAGE81
  J212    4      4 CONN10_HBC1051L300D8H-CONN10_HBC1051-L300D-8H,THLFA   I423 @T6G_MB_LIB.T6G(SCH_1):PAGE27

CPU1_XTRIG_L6 @T6G_MB_LIB.T6G(SCH_1):CPU1_XTRIG_L6
  R862    2      B Q_RES_0402LF-0,5%,1/16W,CHIP,CS00002JB13   I364 @T6G_MB_LIB.T6G(SCH_1):PAGE54
  R931    1      A Q_RES_0402LF-0,5%,1/16W,CHIP,CS00002JB13   I374 @T6G_MB_LIB.T6G(SCH_1):PAGE54
  R539    1      A Q_RES_0402LF-2.2K,5%,1/16W,CHIP,CS22202JB07   I412 @T6G_MB_LIB.T6G(SCH_1):PAGE54
  R234    1      A Q_RES_0402LF-0,5%,1/16W,CHIP,CS00002JB13    I75 @T6G_MB_LIB.T6G(SCH_1):PAGE81
  J212    6      6 CONN10_HBC1051L300D8H-CONN10_HBC1051-L300D-8H,THLFA   I423 @T6G_MB_LIB.T6G(SCH_1):PAGE27

CPU1_XTRIG_L7 @T6G_MB_LIB.T6G(SCH_1):CPU1_XTRIG_L7
  R928    2      B Q_RES_0402LF-0,5%,1/16W,CHIP,CS00002JB13   I363 @T6G_MB_LIB.T6G(SCH_1):PAGE54
  R932    1      A Q_RES_0402LF-0,5%,1/16W,CHIP,CS00002JB13   I373 @T6G_MB_LIB.T6G(SCH_1):PAGE54
  R540    1      A Q_RES_0402LF-2.2K,5%,1/16W,CHIP,CS22202JB07   I413 @T6G_MB_LIB.T6G(SCH_1):PAGE54
  R235    1      A Q_RES_0402LF-0,5%,1/16W,CHIP,CS00002JB13    I70 @T6G_MB_LIB.T6G(SCH_1):PAGE81
  J212    8      8 CONN10_HBC1051L300D8H-CONN10_HBC1051-L300D-8H,THLFA   I423 @T6G_MB_LIB.T6G(SCH_1):PAGE27

CPU1_XTRIG_R1_L4 @T6G_MB_LIB.T6G(SCH_1):CPU1_XTRIG_R1_L4
  R929    2      B Q_RES_0402LF-0,5%,1/16W,CHIP,CS00002JB13   I371 @T6G_MB_LIB.T6G(SCH_1):PAGE54
    J7    1      1 SCONN8_G802M0083150RD3HR-SCONN8_G802M0083150RD3HR,A   I418 @T6G_MB_LIB.T6G(SCH_1):PAGE54

CPU1_XTRIG_R1_L5 @T6G_MB_LIB.T6G(SCH_1):CPU1_XTRIG_R1_L5
  R930    2      B Q_RES_0402LF-0,5%,1/16W,CHIP,CS00002JB13   I372 @T6G_MB_LIB.T6G(SCH_1):PAGE54
    J7    3      3 SCONN8_G802M0083150RD3HR-SCONN8_G802M0083150RD3HR,A   I418 @T6G_MB_LIB.T6G(SCH_1):PAGE54

CPU1_XTRIG_R1_L6 @T6G_MB_LIB.T6G(SCH_1):CPU1_XTRIG_R1_L6
  R931    2      B Q_RES_0402LF-0,5%,1/16W,CHIP,CS00002JB13   I374 @T6G_MB_LIB.T6G(SCH_1):PAGE54
    J7    5      5 SCONN8_G802M0083150RD3HR-SCONN8_G802M0083150RD3HR,A   I418 @T6G_MB_LIB.T6G(SCH_1):PAGE54

CPU1_XTRIG_R1_L7 @T6G_MB_LIB.T6G(SCH_1):CPU1_XTRIG_R1_L7
  R932    2      B Q_RES_0402LF-0,5%,1/16W,CHIP,CS00002JB13   I373 @T6G_MB_LIB.T6G(SCH_1):PAGE54
    J7    7      7 SCONN8_G802M0083150RD3HR-SCONN8_G802M0083150RD3HR,A   I418 @T6G_MB_LIB.T6G(SCH_1):PAGE54

CPU1_XTRIG_R2_L4 @T6G_MB_LIB.T6G(SCH_1):CPU1_XTRIG_R2_L4
   U26  C66 XTRIG_L4 GENOA_SP5-SOCKET6096_13568-001,SMLF,IO,DGA^6000030   I190 @T6G_MB_LIB.T6G(SCH_1):PAGE54
  R486    1      A Q_RES_0402LF-0,5%,1/16W,CHIP,CS00002JB13   I362 @T6G_MB_LIB.T6G(SCH_1):PAGE54

CPU1_XTRIG_R2_L5 @T6G_MB_LIB.T6G(SCH_1):CPU1_XTRIG_R2_L5
   U26  C65 XTRIG_L5 GENOA_SP5-SOCKET6096_13568-001,SMLF,IO,DGA^6000030   I190 @T6G_MB_LIB.T6G(SCH_1):PAGE54
  R618    1      A Q_RES_0402LF-0,5%,1/16W,CHIP,CS00002JB13   I361 @T6G_MB_LIB.T6G(SCH_1):PAGE54

CPU1_XTRIG_R2_L6 @T6G_MB_LIB.T6G(SCH_1):CPU1_XTRIG_R2_L6
   U26  A66 XTRIG_L6 GENOA_SP5-SOCKET6096_13568-001,SMLF,IO,DGA^6000030   I190 @T6G_MB_LIB.T6G(SCH_1):PAGE54
  R862    1      A Q_RES_0402LF-0,5%,1/16W,CHIP,CS00002JB13   I364 @T6G_MB_LIB.T6G(SCH_1):PAGE54

CPU1_XTRIG_R2_L7 @T6G_MB_LIB.T6G(SCH_1):CPU1_XTRIG_R2_L7
   U26  A65 XTRIG_L7 GENOA_SP5-SOCKET6096_13568-001,SMLF,IO,DGA^6000030   I190 @T6G_MB_LIB.T6G(SCH_1):PAGE54
  R928    1      A Q_RES_0402LF-0,5%,1/16W,CHIP,CS00002JB13   I363 @T6G_MB_LIB.T6G(SCH_1):PAGE54

CPU_FRU_ADDR0 @T6G_MB_LIB.T6G(SCH_1):CPU_FRU_ADDR0
    U1    1     E0 M24128BWMN6TP-M24128-BWMN6TP,SMLF,IC,AKE30Z00613    I97 @T6G_MB_LIB.T6G(SCH_1):PAGE361
   R68    2      B Q_RES_0402LF-1K,1%,1/16W,EMPTY,CS21002FB06   I120 @T6G_MB_LIB.T6G(SCH_1):PAGE361
   R69    1      A Q_RES_0402LF-10K,1%,1/16W,CHIP,CS31002FB08   I121 @T6G_MB_LIB.T6G(SCH_1):PAGE361

CPU_FRU_ADDR1 @T6G_MB_LIB.T6G(SCH_1):CPU_FRU_ADDR1
    U1    2     E1 M24128BWMN6TP-M24128-BWMN6TP,SMLF,IC,AKE30Z00613    I97 @T6G_MB_LIB.T6G(SCH_1):PAGE361
   R60    2      B Q_RES_0402LF-10K,1%,1/16W,EMPTY,CS31002FB08   I101 @T6G_MB_LIB.T6G(SCH_1):PAGE361
   R62    1      A Q_RES_0402LF-1K,1%,1/16W,CHIP,CS21002FB06   I104 @T6G_MB_LIB.T6G(SCH_1):PAGE361

CPU_FRU_ADDR2 @T6G_MB_LIB.T6G(SCH_1):CPU_FRU_ADDR2
   R52    2      B Q_RES_0402LF-10K,1%,1/16W,EMPTY,CS31002FB08   I103 @T6G_MB_LIB.T6G(SCH_1):PAGE361
    U1    3     E2 M24128BWMN6TP-M24128-BWMN6TP,SMLF,IC,AKE30Z00613    I97 @T6G_MB_LIB.T6G(SCH_1):PAGE361
   R54    1      A Q_RES_0402LF-1K,1%,1/16W,CHIP,CS21002FB06   I107 @T6G_MB_LIB.T6G(SCH_1):PAGE361

DELTA_L_85_10INCH_BOT_DN @T6G_MB_LIB.T6G(SCH_1):DELTA_L_85_10INCH_BOT_DN
   J76    2    2_N PICOPROBE_BXA-DELTA-L 4.0,SMLF,EMPTY,TP33    I83 @T6G_MB_LIB.T6G(SCH_1):PAGE211
   J82    1    1_P PICOPROBE_BXA-DELTA-L 4.0,SMLF,EMPTY,TP33    I84 @T6G_MB_LIB.T6G(SCH_1):PAGE211

DELTA_L_85_10INCH_BOT_DP @T6G_MB_LIB.T6G(SCH_1):DELTA_L_85_10INCH_BOT_DP
   J76    1    1_P PICOPROBE_BXA-DELTA-L 4.0,SMLF,EMPTY,TP33    I83 @T6G_MB_LIB.T6G(SCH_1):PAGE211
   J82    2    2_N PICOPROBE_BXA-DELTA-L 4.0,SMLF,EMPTY,TP33    I84 @T6G_MB_LIB.T6G(SCH_1):PAGE211

DELTA_L_85_10INCH_IN1_DN @T6G_MB_LIB.T6G(SCH_1):DELTA_L_85_10INCH_IN1_DN
   J77    2    2_N PICOPROBE_BXA-DELTA-L 4.0,SMLF,EMPTY,TP33    I85 @T6G_MB_LIB.T6G(SCH_1):PAGE211
   J83    1    1_P PICOPROBE_BXA-DELTA-L 4.0,SMLF,EMPTY,TP33    I86 @T6G_MB_LIB.T6G(SCH_1):PAGE211

DELTA_L_85_10INCH_IN1_DP @T6G_MB_LIB.T6G(SCH_1):DELTA_L_85_10INCH_IN1_DP
   J77    1    1_P PICOPROBE_BXA-DELTA-L 4.0,SMLF,EMPTY,TP33    I85 @T6G_MB_LIB.T6G(SCH_1):PAGE211
   J83    2    2_N PICOPROBE_BXA-DELTA-L 4.0,SMLF,EMPTY,TP33    I86 @T6G_MB_LIB.T6G(SCH_1):PAGE211

DELTA_L_85_10INCH_IN2_DN @T6G_MB_LIB.T6G(SCH_1):DELTA_L_85_10INCH_IN2_DN
   J78    2    2_N PICOPROBE_BXA-DELTA-L 4.0,SMLF,EMPTY,TP33    I87 @T6G_MB_LIB.T6G(SCH_1):PAGE211
   J84    1    1_P PICOPROBE_BXA-DELTA-L 4.0,SMLF,EMPTY,TP33    I88 @T6G_MB_LIB.T6G(SCH_1):PAGE211

DELTA_L_85_10INCH_IN2_DP @T6G_MB_LIB.T6G(SCH_1):DELTA_L_85_10INCH_IN2_DP
   J78    1    1_P PICOPROBE_BXA-DELTA-L 4.0,SMLF,EMPTY,TP33    I87 @T6G_MB_LIB.T6G(SCH_1):PAGE211
   J84    2    2_N PICOPROBE_BXA-DELTA-L 4.0,SMLF,EMPTY,TP33    I88 @T6G_MB_LIB.T6G(SCH_1):PAGE211

DELTA_L_85_10INCH_IN3_DN @T6G_MB_LIB.T6G(SCH_1):DELTA_L_85_10INCH_IN3_DN
   J79    2    2_N PICOPROBE_BXA-DELTA-L 4.0,SMLF,EMPTY,TP33    I89 @T6G_MB_LIB.T6G(SCH_1):PAGE211
   J85    1    1_P PICOPROBE_BXA-DELTA-L 4.0,SMLF,EMPTY,TP33    I90 @T6G_MB_LIB.T6G(SCH_1):PAGE211

DELTA_L_85_10INCH_IN3_DP @T6G_MB_LIB.T6G(SCH_1):DELTA_L_85_10INCH_IN3_DP
   J79    1    1_P PICOPROBE_BXA-DELTA-L 4.0,SMLF,EMPTY,TP33    I89 @T6G_MB_LIB.T6G(SCH_1):PAGE211
   J85    2    2_N PICOPROBE_BXA-DELTA-L 4.0,SMLF,EMPTY,TP33    I90 @T6G_MB_LIB.T6G(SCH_1):PAGE211

DELTA_L_85_10INCH_IN4_DN @T6G_MB_LIB.T6G(SCH_1):DELTA_L_85_10INCH_IN4_DN
   J80    2    2_N PICOPROBE_BXA-DELTA-L 4.0,SMLF,EMPTY,TP33    I91 @T6G_MB_LIB.T6G(SCH_1):PAGE211
   J86    1    1_P PICOPROBE_BXA-DELTA-L 4.0,SMLF,EMPTY,TP33    I92 @T6G_MB_LIB.T6G(SCH_1):PAGE211

DELTA_L_85_10INCH_IN4_DP @T6G_MB_LIB.T6G(SCH_1):DELTA_L_85_10INCH_IN4_DP
   J80    1    1_P PICOPROBE_BXA-DELTA-L 4.0,SMLF,EMPTY,TP33    I91 @T6G_MB_LIB.T6G(SCH_1):PAGE211
   J86    2    2_N PICOPROBE_BXA-DELTA-L 4.0,SMLF,EMPTY,TP33    I92 @T6G_MB_LIB.T6G(SCH_1):PAGE211

DELTA_L_85_10INCH_IN5_DN @T6G_MB_LIB.T6G(SCH_1):DELTA_L_85_10INCH_IN5_DN
  J118    2    2_N PICOPROBE_BXA-DELTA-L 4.0,SMLF,EMPTY,TP33    I93 @T6G_MB_LIB.T6G(SCH_1):PAGE211
  J120    1    1_P PICOPROBE_BXA-DELTA-L 4.0,SMLF,EMPTY,TP33    I94 @T6G_MB_LIB.T6G(SCH_1):PAGE211

DELTA_L_85_10INCH_IN5_DP @T6G_MB_LIB.T6G(SCH_1):DELTA_L_85_10INCH_IN5_DP
  J118    1    1_P PICOPROBE_BXA-DELTA-L 4.0,SMLF,EMPTY,TP33    I93 @T6G_MB_LIB.T6G(SCH_1):PAGE211
  J120    2    2_N PICOPROBE_BXA-DELTA-L 4.0,SMLF,EMPTY,TP33    I94 @T6G_MB_LIB.T6G(SCH_1):PAGE211

DELTA_L_85_10INCH_IN6_DN @T6G_MB_LIB.T6G(SCH_1):DELTA_L_85_10INCH_IN6_DN
  J119    2    2_N PICOPROBE_BXA-DELTA-L 4.0,SMLF,EMPTY,TP33    I95 @T6G_MB_LIB.T6G(SCH_1):PAGE211
  J121    1    1_P PICOPROBE_BXA-DELTA-L 4.0,SMLF,EMPTY,TP33    I96 @T6G_MB_LIB.T6G(SCH_1):PAGE211

DELTA_L_85_10INCH_IN6_DP @T6G_MB_LIB.T6G(SCH_1):DELTA_L_85_10INCH_IN6_DP
  J119    1    1_P PICOPROBE_BXA-DELTA-L 4.0,SMLF,EMPTY,TP33    I95 @T6G_MB_LIB.T6G(SCH_1):PAGE211
  J121    2    2_N PICOPROBE_BXA-DELTA-L 4.0,SMLF,EMPTY,TP33    I96 @T6G_MB_LIB.T6G(SCH_1):PAGE211

DELTA_L_85_10INCH_TOP_DN @T6G_MB_LIB.T6G(SCH_1):DELTA_L_85_10INCH_TOP_DN
   J75    2    2_N PICOPROBE_BXA-DELTA-L 4.0,SMLF,EMPTY,TP33    I81 @T6G_MB_LIB.T6G(SCH_1):PAGE211
   J81    1    1_P PICOPROBE_BXA-DELTA-L 4.0,SMLF,EMPTY,TP33    I82 @T6G_MB_LIB.T6G(SCH_1):PAGE211

DELTA_L_85_10INCH_TOP_DP @T6G_MB_LIB.T6G(SCH_1):DELTA_L_85_10INCH_TOP_DP
   J75    1    1_P PICOPROBE_BXA-DELTA-L 4.0,SMLF,EMPTY,TP33    I81 @T6G_MB_LIB.T6G(SCH_1):PAGE211
   J81    2    2_N PICOPROBE_BXA-DELTA-L 4.0,SMLF,EMPTY,TP33    I82 @T6G_MB_LIB.T6G(SCH_1):PAGE211

DELTA_L_85_5INCH_BOT_DN @T6G_MB_LIB.T6G(SCH_1):DELTA_L_85_5INCH_BOT_DN
   J64    2    2_N PICOPROBE_BXA-DELTA-L 4.0,SMLF,EMPTY,TP33    I67 @T6G_MB_LIB.T6G(SCH_1):PAGE211
   J70    1    1_P PICOPROBE_BXA-DELTA-L 4.0,SMLF,EMPTY,TP33    I68 @T6G_MB_LIB.T6G(SCH_1):PAGE211

DELTA_L_85_5INCH_BOT_DP @T6G_MB_LIB.T6G(SCH_1):DELTA_L_85_5INCH_BOT_DP
   J64    1    1_P PICOPROBE_BXA-DELTA-L 4.0,SMLF,EMPTY,TP33    I67 @T6G_MB_LIB.T6G(SCH_1):PAGE211
   J70    2    2_N PICOPROBE_BXA-DELTA-L 4.0,SMLF,EMPTY,TP33    I68 @T6G_MB_LIB.T6G(SCH_1):PAGE211

DELTA_L_85_5INCH_IN1_DN @T6G_MB_LIB.T6G(SCH_1):DELTA_L_85_5INCH_IN1_DN
   J65    2    2_N PICOPROBE_BXA-DELTA-L 4.0,SMLF,EMPTY,TP33    I69 @T6G_MB_LIB.T6G(SCH_1):PAGE211
   J71    1    1_P PICOPROBE_BXA-DELTA-L 4.0,SMLF,EMPTY,TP33    I70 @T6G_MB_LIB.T6G(SCH_1):PAGE211

DELTA_L_85_5INCH_IN1_DP @T6G_MB_LIB.T6G(SCH_1):DELTA_L_85_5INCH_IN1_DP
   J65    1    1_P PICOPROBE_BXA-DELTA-L 4.0,SMLF,EMPTY,TP33    I69 @T6G_MB_LIB.T6G(SCH_1):PAGE211
   J71    2    2_N PICOPROBE_BXA-DELTA-L 4.0,SMLF,EMPTY,TP33    I70 @T6G_MB_LIB.T6G(SCH_1):PAGE211

DELTA_L_85_5INCH_IN2_DN @T6G_MB_LIB.T6G(SCH_1):DELTA_L_85_5INCH_IN2_DN
   J66    2    2_N PICOPROBE_BXA-DELTA-L 4.0,SMLF,EMPTY,TP33    I71 @T6G_MB_LIB.T6G(SCH_1):PAGE211
   J72    1    1_P PICOPROBE_BXA-DELTA-L 4.0,SMLF,EMPTY,TP33    I72 @T6G_MB_LIB.T6G(SCH_1):PAGE211

DELTA_L_85_5INCH_IN2_DP @T6G_MB_LIB.T6G(SCH_1):DELTA_L_85_5INCH_IN2_DP
   J66    1    1_P PICOPROBE_BXA-DELTA-L 4.0,SMLF,EMPTY,TP33    I71 @T6G_MB_LIB.T6G(SCH_1):PAGE211
   J72    2    2_N PICOPROBE_BXA-DELTA-L 4.0,SMLF,EMPTY,TP33    I72 @T6G_MB_LIB.T6G(SCH_1):PAGE211

DELTA_L_85_5INCH_IN3_DN @T6G_MB_LIB.T6G(SCH_1):DELTA_L_85_5INCH_IN3_DN
 J8067    2    2_N PICOPROBE_BXA-DELTA-L 4.0,SMLF,EMPTY,TP33    I73 @T6G_MB_LIB.T6G(SCH_1):PAGE211
   J73    1    1_P PICOPROBE_BXA-DELTA-L 4.0,SMLF,EMPTY,TP33    I74 @T6G_MB_LIB.T6G(SCH_1):PAGE211

DELTA_L_85_5INCH_IN3_DP @T6G_MB_LIB.T6G(SCH_1):DELTA_L_85_5INCH_IN3_DP
 J8067    1    1_P PICOPROBE_BXA-DELTA-L 4.0,SMLF,EMPTY,TP33    I73 @T6G_MB_LIB.T6G(SCH_1):PAGE211
   J73    2    2_N PICOPROBE_BXA-DELTA-L 4.0,SMLF,EMPTY,TP33    I74 @T6G_MB_LIB.T6G(SCH_1):PAGE211

DELTA_L_85_5INCH_IN4_DN @T6G_MB_LIB.T6G(SCH_1):DELTA_L_85_5INCH_IN4_DN
 J8068    2    2_N PICOPROBE_BXA-DELTA-L 4.0,SMLF,EMPTY,TP33    I75 @T6G_MB_LIB.T6G(SCH_1):PAGE211
   J74    1    1_P PICOPROBE_BXA-DELTA-L 4.0,SMLF,EMPTY,TP33    I76 @T6G_MB_LIB.T6G(SCH_1):PAGE211

DELTA_L_85_5INCH_IN4_DP @T6G_MB_LIB.T6G(SCH_1):DELTA_L_85_5INCH_IN4_DP
 J8068    1    1_P PICOPROBE_BXA-DELTA-L 4.0,SMLF,EMPTY,TP33    I75 @T6G_MB_LIB.T6G(SCH_1):PAGE211
   J74    2    2_N PICOPROBE_BXA-DELTA-L 4.0,SMLF,EMPTY,TP33    I76 @T6G_MB_LIB.T6G(SCH_1):PAGE211

DELTA_L_85_5INCH_IN5_DN @T6G_MB_LIB.T6G(SCH_1):DELTA_L_85_5INCH_IN5_DN
  J114    2    2_N PICOPROBE_BXA-DELTA-L 4.0,SMLF,EMPTY,TP33    I77 @T6G_MB_LIB.T6G(SCH_1):PAGE211
  J116    1    1_P PICOPROBE_BXA-DELTA-L 4.0,SMLF,EMPTY,TP33    I78 @T6G_MB_LIB.T6G(SCH_1):PAGE211

DELTA_L_85_5INCH_IN5_DP @T6G_MB_LIB.T6G(SCH_1):DELTA_L_85_5INCH_IN5_DP
  J114    1    1_P PICOPROBE_BXA-DELTA-L 4.0,SMLF,EMPTY,TP33    I77 @T6G_MB_LIB.T6G(SCH_1):PAGE211
  J116    2    2_N PICOPROBE_BXA-DELTA-L 4.0,SMLF,EMPTY,TP33    I78 @T6G_MB_LIB.T6G(SCH_1):PAGE211

DELTA_L_85_5INCH_IN6_DN @T6G_MB_LIB.T6G(SCH_1):DELTA_L_85_5INCH_IN6_DN
  J115    2    2_N PICOPROBE_BXA-DELTA-L 4.0,SMLF,EMPTY,TP33    I79 @T6G_MB_LIB.T6G(SCH_1):PAGE211
  J117    1    1_P PICOPROBE_BXA-DELTA-L 4.0,SMLF,EMPTY,TP33    I80 @T6G_MB_LIB.T6G(SCH_1):PAGE211

DELTA_L_85_5INCH_IN6_DP @T6G_MB_LIB.T6G(SCH_1):DELTA_L_85_5INCH_IN6_DP
  J115    1    1_P PICOPROBE_BXA-DELTA-L 4.0,SMLF,EMPTY,TP33    I79 @T6G_MB_LIB.T6G(SCH_1):PAGE211
  J117    2    2_N PICOPROBE_BXA-DELTA-L 4.0,SMLF,EMPTY,TP33    I80 @T6G_MB_LIB.T6G(SCH_1):PAGE211

DELTA_L_85_5INCH_TOP_DN @T6G_MB_LIB.T6G(SCH_1):DELTA_L_85_5INCH_TOP_DN
   J63    2    2_N PICOPROBE_BXA-DELTA-L 4.0,SMLF,EMPTY,TP33    I65 @T6G_MB_LIB.T6G(SCH_1):PAGE211
 J8069    1    1_P PICOPROBE_BXA-DELTA-L 4.0,SMLF,EMPTY,TP33    I66 @T6G_MB_LIB.T6G(SCH_1):PAGE211

DELTA_L_85_5INCH_TOP_DP @T6G_MB_LIB.T6G(SCH_1):DELTA_L_85_5INCH_TOP_DP
   J63    1    1_P PICOPROBE_BXA-DELTA-L 4.0,SMLF,EMPTY,TP33    I65 @T6G_MB_LIB.T6G(SCH_1):PAGE211
 J8069    2    2_N PICOPROBE_BXA-DELTA-L 4.0,SMLF,EMPTY,TP33    I66 @T6G_MB_LIB.T6G(SCH_1):PAGE211

DELTA_L_GND_1 @T6G_MB_LIB.T6G(SCH_1):DELTA_L_GND_1
   J63    3    3_G PICOPROBE_BXA-DELTA-L 4.0,SMLF,EMPTY,TP33    I65 @T6G_MB_LIB.T6G(SCH_1):PAGE211
 J8069    3    3_G PICOPROBE_BXA-DELTA-L 4.0,SMLF,EMPTY,TP33    I66 @T6G_MB_LIB.T6G(SCH_1):PAGE211
   J64    3    3_G PICOPROBE_BXA-DELTA-L 4.0,SMLF,EMPTY,TP33    I67 @T6G_MB_LIB.T6G(SCH_1):PAGE211
   J70    3    3_G PICOPROBE_BXA-DELTA-L 4.0,SMLF,EMPTY,TP33    I68 @T6G_MB_LIB.T6G(SCH_1):PAGE211
   J65    3    3_G PICOPROBE_BXA-DELTA-L 4.0,SMLF,EMPTY,TP33    I69 @T6G_MB_LIB.T6G(SCH_1):PAGE211
   J71    3    3_G PICOPROBE_BXA-DELTA-L 4.0,SMLF,EMPTY,TP33    I70 @T6G_MB_LIB.T6G(SCH_1):PAGE211
   J66    3    3_G PICOPROBE_BXA-DELTA-L 4.0,SMLF,EMPTY,TP33    I71 @T6G_MB_LIB.T6G(SCH_1):PAGE211
   J72    3    3_G PICOPROBE_BXA-DELTA-L 4.0,SMLF,EMPTY,TP33    I72 @T6G_MB_LIB.T6G(SCH_1):PAGE211
 J8067    3    3_G PICOPROBE_BXA-DELTA-L 4.0,SMLF,EMPTY,TP33    I73 @T6G_MB_LIB.T6G(SCH_1):PAGE211
   J73    3    3_G PICOPROBE_BXA-DELTA-L 4.0,SMLF,EMPTY,TP33    I74 @T6G_MB_LIB.T6G(SCH_1):PAGE211
 J8068    3    3_G PICOPROBE_BXA-DELTA-L 4.0,SMLF,EMPTY,TP33    I75 @T6G_MB_LIB.T6G(SCH_1):PAGE211
   J74    3    3_G PICOPROBE_BXA-DELTA-L 4.0,SMLF,EMPTY,TP33    I76 @T6G_MB_LIB.T6G(SCH_1):PAGE211
  J114    3    3_G PICOPROBE_BXA-DELTA-L 4.0,SMLF,EMPTY,TP33    I77 @T6G_MB_LIB.T6G(SCH_1):PAGE211
  J116    3    3_G PICOPROBE_BXA-DELTA-L 4.0,SMLF,EMPTY,TP33    I78 @T6G_MB_LIB.T6G(SCH_1):PAGE211
  J115    3    3_G PICOPROBE_BXA-DELTA-L 4.0,SMLF,EMPTY,TP33    I79 @T6G_MB_LIB.T6G(SCH_1):PAGE211
  J117    3    3_G PICOPROBE_BXA-DELTA-L 4.0,SMLF,EMPTY,TP33    I80 @T6G_MB_LIB.T6G(SCH_1):PAGE211
   J75    3    3_G PICOPROBE_BXA-DELTA-L 4.0,SMLF,EMPTY,TP33    I81 @T6G_MB_LIB.T6G(SCH_1):PAGE211
   J81    3    3_G PICOPROBE_BXA-DELTA-L 4.0,SMLF,EMPTY,TP33    I82 @T6G_MB_LIB.T6G(SCH_1):PAGE211
   J76    3    3_G PICOPROBE_BXA-DELTA-L 4.0,SMLF,EMPTY,TP33    I83 @T6G_MB_LIB.T6G(SCH_1):PAGE211
   J82    3    3_G PICOPROBE_BXA-DELTA-L 4.0,SMLF,EMPTY,TP33    I84 @T6G_MB_LIB.T6G(SCH_1):PAGE211
   J77    3    3_G PICOPROBE_BXA-DELTA-L 4.0,SMLF,EMPTY,TP33    I85 @T6G_MB_LIB.T6G(SCH_1):PAGE211
   J83    3    3_G PICOPROBE_BXA-DELTA-L 4.0,SMLF,EMPTY,TP33    I86 @T6G_MB_LIB.T6G(SCH_1):PAGE211
   J78    3    3_G PICOPROBE_BXA-DELTA-L 4.0,SMLF,EMPTY,TP33    I87 @T6G_MB_LIB.T6G(SCH_1):PAGE211
   J84    3    3_G PICOPROBE_BXA-DELTA-L 4.0,SMLF,EMPTY,TP33    I88 @T6G_MB_LIB.T6G(SCH_1):PAGE211
   J79    3    3_G PICOPROBE_BXA-DELTA-L 4.0,SMLF,EMPTY,TP33    I89 @T6G_MB_LIB.T6G(SCH_1):PAGE211
   J85    3    3_G PICOPROBE_BXA-DELTA-L 4.0,SMLF,EMPTY,TP33    I90 @T6G_MB_LIB.T6G(SCH_1):PAGE211
   J80    3    3_G PICOPROBE_BXA-DELTA-L 4.0,SMLF,EMPTY,TP33    I91 @T6G_MB_LIB.T6G(SCH_1):PAGE211
   J86    3    3_G PICOPROBE_BXA-DELTA-L 4.0,SMLF,EMPTY,TP33    I92 @T6G_MB_LIB.T6G(SCH_1):PAGE211
  J118    3    3_G PICOPROBE_BXA-DELTA-L 4.0,SMLF,EMPTY,TP33    I93 @T6G_MB_LIB.T6G(SCH_1):PAGE211
  J120    3    3_G PICOPROBE_BXA-DELTA-L 4.0,SMLF,EMPTY,TP33    I94 @T6G_MB_LIB.T6G(SCH_1):PAGE211
  J119    3    3_G PICOPROBE_BXA-DELTA-L 4.0,SMLF,EMPTY,TP33    I95 @T6G_MB_LIB.T6G(SCH_1):PAGE211
  J121    3    3_G PICOPROBE_BXA-DELTA-L 4.0,SMLF,EMPTY,TP33    I96 @T6G_MB_LIB.T6G(SCH_1):PAGE211

E1S_0_P12V_EN @T6G_MB_LIB.T6G(SCH_1):E1S_0_P12V_EN
 R3943    1      A Q_RES_0402LF-0,5%,1/16W,CHIP,CS00002JB13    I19 @T6G_MB_LIB.T6G(SCH_1):PAGE323
  R199    1      A Q_RES_0402LF-33,5%,1/16W,CHIP,CS03302JB10    I22 @T6G_MB_LIB.T6G(SCH_1):PAGE80
 R1314    1      A Q_RES_0402LF-4.7K,5%,1/16W,EMPTY,CS24702JB10    I54 @T6G_MB_LIB.T6G(SCH_1):PAGE82
 R4064    1      A Q_RES_0402LF-0,5%,1/16W,CHIP,CS00002JB13    I24 @T6G_MB_LIB.T6G(SCH_1):PAGE324

E1S_0_P3V3_ADC_ALERT_R @T6G_MB_LIB.T6G(SCH_1):E1S_0_P3V3_ADC_ALERT_R
 R3752    1      A Q_RES_0402LF-0,5%,1/16W,CHIP,CS00002JB13   I122 @T6G_MB_LIB.T6G(SCH_1):PAGE295
  U276    3 EXT_CLK||INT ISL28022FRZT-ISL28022FRZ-T,SMLF,IC,AL028022003   I129 @T6G_MB_LIB.T6G(SCH_1):PAGE295
 R4093    2      B Q_RES_0402LF-1K,1%,1/16W,CHIP,CS21002FB06   I149 @T6G_MB_LIB.T6G(SCH_1):PAGE295

E1S_0_P3V3_EN @T6G_MB_LIB.T6G(SCH_1):E1S_0_P3V3_EN
 R3946    1      A Q_RES_0402LF-0,5%,1/16W,CHIP,CS00002JB13     I5 @T6G_MB_LIB.T6G(SCH_1):PAGE323
 R4063    1      A Q_RES_0402LF-0,5%,1/16W,CHIP,CS00002JB13     I2 @T6G_MB_LIB.T6G(SCH_1):PAGE324
  R648    1      A Q_RES_0402LF-33,5%,1/16W,CHIP,CS03302JB10    I25 @T6G_MB_LIB.T6G(SCH_1):PAGE80
  R757    1      A Q_RES_0402LF-4.7K,5%,1/16W,EMPTY,CS24702JB10    I41 @T6G_MB_LIB.T6G(SCH_1):PAGE82

E1S_0_P3V3_P12V_ADC_ALERT @T6G_MB_LIB.T6G(SCH_1):E1S_0_P3V3_P12V_ADC_ALERT
   U18   K3  PL13D LCMXO3LF9400C5BG484C-LCMXO3LF-9400C-5BG484C,SMLF,IA   I143 @T6G_MB_LIB.T6G(SCH_1):PAGE81
 R1329    2      B Q_RES_0402LF-0,5%,1/16W,CHIP,CS00002JB13   I178 @T6G_MB_LIB.T6G(SCH_1):PAGE81

E1S_0_P3V3_P12V_ADC_R_ALERT @T6G_MB_LIB.T6G(SCH_1):E1S_0_P3V3_P12V_ADC_R_ALERT
 R3752    2      B Q_RES_0402LF-0,5%,1/16W,CHIP,CS00002JB13   I122 @T6G_MB_LIB.T6G(SCH_1):PAGE295
 R1269    2      B Q_RES_0402LF-0,5%,1/16W,CHIP,CS00002JB13    I62 @T6G_MB_LIB.T6G(SCH_1):PAGE466
 R1329    1      A Q_RES_0402LF-0,5%,1/16W,CHIP,CS00002JB13   I178 @T6G_MB_LIB.T6G(SCH_1):PAGE81
 R1326    2      B Q_RES_0402LF-1K,1%,1/16W,EMPTY,CS21002FB06    I90 @T6G_MB_LIB.T6G(SCH_1):PAGE466

E1S_0_PERST1_CLKREQ_N @T6G_MB_LIB.T6G(SCH_1):E1S_0_PERST1_CLKREQ_N
 R2426    1      A Q_RES_0402LF-100,1%,1/16W,EMPTY,CS11002FB07    I75 @T6G_MB_LIB.T6G(SCH_1):PAGE297
R10287    2      B Q_RES_0402LF-10K,1%,1/16W,CHIP,CS31002FB08    I79 @T6G_MB_LIB.T6G(SCH_1):PAGE297
   J90  A11 PERST1#_CLKREQ# SCONN56_123276793-SCONN56_1-2327679-3,SMLF,IO,DFHSA    I90 @T6G_MB_LIB.T6G(SCH_1):PAGE297
 R6094    2      B Q_RES_0402LF-0,5%,1/16W,EMPTY,CS00002JB13   I128 @T6G_MB_LIB.T6G(SCH_1):PAGE79

E1S_0_PERST1_CLKREQ_R_N @T6G_MB_LIB.T6G(SCH_1):E1S_0_PERST1_CLKREQ_R_N
   U18   A6  PT13B LCMXO3LF9400C5BG484C-LCMXO3LF-9400C-5BG484C,SMLF,IA    I94 @T6G_MB_LIB.T6G(SCH_1):PAGE79
 R6094    1      A Q_RES_0402LF-0,5%,1/16W,EMPTY,CS00002JB13   I128 @T6G_MB_LIB.T6G(SCH_1):PAGE79
 R6116    1      A Q_RES_0402LF-0,5%,1/16W,CHIP,CS00002JB13   I129 @T6G_MB_LIB.T6G(SCH_1):PAGE79

E1S_0_PRSNT_N @T6G_MB_LIB.T6G(SCH_1):E1S_0_PRSNT_N
   J90  A12 PRSNT0# SCONN56_123276793-SCONN56_1-2327679-3,SMLF,IO,DFHSA    I90 @T6G_MB_LIB.T6G(SCH_1):PAGE297
 R6052    2      B Q_RES_0402LF-0,5%,1/16W,CHIP,CS00002JB13    I99 @T6G_MB_LIB.T6G(SCH_1):PAGE81
 R6116    2      B Q_RES_0402LF-0,5%,1/16W,CHIP,CS00002JB13   I129 @T6G_MB_LIB.T6G(SCH_1):PAGE79
 R1304    1      A Q_RES_0402LF-10K,1%,1/16W,CHIP,CS31002FB08   I171 @T6G_MB_LIB.T6G(SCH_1):PAGE82

E1S_0_PRSNT_R_N @T6G_MB_LIB.T6G(SCH_1):E1S_0_PRSNT_R_N
 R6052    1      A Q_RES_0402LF-0,5%,1/16W,CHIP,CS00002JB13    I99 @T6G_MB_LIB.T6G(SCH_1):PAGE81
   U18   U3  PL27C LCMXO3LF9400C5BG484C-LCMXO3LF-9400C-5BG484C,SMLF,IA   I143 @T6G_MB_LIB.T6G(SCH_1):PAGE81

E1S_0_PWRDIS @T6G_MB_LIB.T6G(SCH_1):E1S_0_PWRDIS
R10296    1      A Q_RES_0402LF-1K,1%,1/16W,CHIP,CS21002FB06     I6 @T6G_MB_LIB.T6G(SCH_1):PAGE297
 R3771    2      B Q_RES_0402LF-10K,1%,1/16W,CHIP,CS31002FB08     I7 @T6G_MB_LIB.T6G(SCH_1):PAGE297
   J90  B12 PWRDIS SCONN56_123276793-SCONN56_1-2327679-3,SMLF,IO,DFHSA    I90 @T6G_MB_LIB.T6G(SCH_1):PAGE297

ESPI_CPU0_ALERT_N @T6G_MB_LIB.T6G(SCH_1):ESPI_CPU0_ALERT_N
   J41   B3 +12V_EDGE_B3 SCONN168_ME1016810202011-SCONN168_ME1016810202011,A   I176 @T6G_MB_LIB.T6G(SCH_1):PAGE348
 R8035    2      B Q_RES_0402LF-4.7K,5%,1/16W,EMPTY,CS24702JB10    I11 @T6G_MB_LIB.T6G(SCH_1):PAGE130
 R8034    2      B Q_RES_0402LF-0,5%,1/16W,CHIP,CS00002JB13    I23 @T6G_MB_LIB.T6G(SCH_1):PAGE130
 R1197    2      B Q_RES_0402LF-0,5%,1/16W,EMPTY,CS00002JB13    I24 @T6G_MB_LIB.T6G(SCH_1):PAGE130

ESPI_CPU0_ALERT_P0_N @T6G_MB_LIB.T6G(SCH_1):ESPI_CPU0_ALERT_P0_N
  R458    2      B Q_RES_0402LF-30K,1%,1/16W,EMPTY,CS33002FB02   I405 @T6G_MB_LIB.T6G(SCH_1):PAGE29
 R1593    1      A Q_RES_0402LF-33,5%,1/16W,CHIP,CS03302JB10   I427 @T6G_MB_LIB.T6G(SCH_1):PAGE29
  R472    1      A Q_RES_0402LF-33,5%,1/16W,EMPTY,CS03302JB10   I428 @T6G_MB_LIB.T6G(SCH_1):PAGE29
 U8000    4      A NC7SB3157P6X-NC7SB3157P6X,SMLF,IC,ALSB3157000     I1 @T6G_MB_LIB.T6G(SCH_1):PAGE130
 R1197    1      A Q_RES_0402LF-0,5%,1/16W,EMPTY,CS00002JB13    I24 @T6G_MB_LIB.T6G(SCH_1):PAGE130

ESPI_CPU0_ALERT_PLD_N @T6G_MB_LIB.T6G(SCH_1):ESPI_CPU0_ALERT_PLD_N
 R1557    2      B Q_RES_0402LF-33,5%,1/16W,CHIP,CS03302JB10   I175 @T6G_MB_LIB.T6G(SCH_1):PAGE80
 U8000    3     B0 NC7SB3157P6X-NC7SB3157P6X,SMLF,IC,ALSB3157000     I1 @T6G_MB_LIB.T6G(SCH_1):PAGE130
 R8036    2      B Q_RES_0402LF-4.7K,5%,1/16W,EMPTY,CS24702JB10    I12 @T6G_MB_LIB.T6G(SCH_1):PAGE130

ESPI_CPU0_ALERT_R1_N @T6G_MB_LIB.T6G(SCH_1):ESPI_CPU0_ALERT_R1_N
 U8000    1     B1 NC7SB3157P6X-NC7SB3157P6X,SMLF,IC,ALSB3157000     I1 @T6G_MB_LIB.T6G(SCH_1):PAGE130
 R8034    1      A Q_RES_0402LF-0,5%,1/16W,CHIP,CS00002JB13    I23 @T6G_MB_LIB.T6G(SCH_1):PAGE130

ESPI_CPU0_ALERT_R_N @T6G_MB_LIB.T6G(SCH_1):ESPI_CPU0_ALERT_R_N
 R1557    1      A Q_RES_0402LF-33,5%,1/16W,CHIP,CS03302JB10   I175 @T6G_MB_LIB.T6G(SCH_1):PAGE80
   U18  P20  PR20D LCMXO3LF9400C5BG484C-LCMXO3LF-9400C-5BG484C,SMLF,IA   I217 @T6G_MB_LIB.T6G(SCH_1):PAGE80

ESPI_CPU0_CS1_N @T6G_MB_LIB.T6G(SCH_1):ESPI_CPU0_CS1_N
  R455    2      B Q_RES_0402LF-4.7K,5%,1/16W,EMPTY,CS24702JB10   I284 @T6G_MB_LIB.T6G(SCH_1):PAGE29
   J41   B2 +12V_EDGE_B2 SCONN168_ME1016810202011-SCONN168_ME1016810202011,A   I176 @T6G_MB_LIB.T6G(SCH_1):PAGE348
 R1553    2      B Q_RES_0402LF-33,5%,1/16W,CHIP,CS03302JB10   I174 @T6G_MB_LIB.T6G(SCH_1):PAGE80
  R462    1      A Q_RES_0402LF-33,5%,1/16W,EMPTY,CS03302JB10   I425 @T6G_MB_LIB.T6G(SCH_1):PAGE29
 R1592    1      A Q_RES_0402LF-33,5%,1/16W,CHIP,CS03302JB10   I426 @T6G_MB_LIB.T6G(SCH_1):PAGE29

ESPI_CPU0_CS1_R_N @T6G_MB_LIB.T6G(SCH_1):ESPI_CPU0_CS1_R_N
 R1553    1      A Q_RES_0402LF-33,5%,1/16W,CHIP,CS03302JB10   I174 @T6G_MB_LIB.T6G(SCH_1):PAGE80
   U18  P22  PR20C LCMXO3LF9400C5BG484C-LCMXO3LF-9400C-5BG484C,SMLF,IA   I217 @T6G_MB_LIB.T6G(SCH_1):PAGE80

ESPI_CPU0_D0 @T6G_MB_LIB.T6G(SCH_1):ESPI_CPU0_D0
  R468    1      A Q_RES_0402LF-33,5%,1/16W,CHIP,CS03302JB10   I329 @T6G_MB_LIB.T6G(SCH_1):PAGE29
 R1503    2      B Q_RES_0402LF-30K,1%,1/16W,CHIP,CS33002FB02   I396 @T6G_MB_LIB.T6G(SCH_1):PAGE29
   J41   B5 +12V_EDGE_B5 SCONN168_ME1016810202011-SCONN168_ME1016810202011,A   I176 @T6G_MB_LIB.T6G(SCH_1):PAGE348
 R1549    2      B Q_RES_0402LF-33,5%,1/16W,CHIP,CS03302JB10   I173 @T6G_MB_LIB.T6G(SCH_1):PAGE80

ESPI_CPU0_D1 @T6G_MB_LIB.T6G(SCH_1):ESPI_CPU0_D1
  R469    1      A Q_RES_0402LF-33,5%,1/16W,CHIP,CS03302JB10   I328 @T6G_MB_LIB.T6G(SCH_1):PAGE29
 R1504    2      B Q_RES_0402LF-30K,1%,1/16W,CHIP,CS33002FB02   I397 @T6G_MB_LIB.T6G(SCH_1):PAGE29
   J41   B6 +12V_EDGE_B6 SCONN168_ME1016810202011-SCONN168_ME1016810202011,A   I176 @T6G_MB_LIB.T6G(SCH_1):PAGE348
 R1550    2      B Q_RES_0402LF-33,5%,1/16W,CHIP,CS03302JB10   I171 @T6G_MB_LIB.T6G(SCH_1):PAGE80

ESPI_CPU0_D2 @T6G_MB_LIB.T6G(SCH_1):ESPI_CPU0_D2
  R470    1      A Q_RES_0402LF-33,5%,1/16W,CHIP,CS03302JB10   I327 @T6G_MB_LIB.T6G(SCH_1):PAGE29
 R1505    2      B Q_RES_0402LF-30K,1%,1/16W,CHIP,CS33002FB02   I398 @T6G_MB_LIB.T6G(SCH_1):PAGE29
   J41   B7  BIF0# SCONN168_ME1016810202011-SCONN168_ME1016810202011,A   I176 @T6G_MB_LIB.T6G(SCH_1):PAGE348
 R1551    2      B Q_RES_0402LF-33,5%,1/16W,CHIP,CS03302JB10   I169 @T6G_MB_LIB.T6G(SCH_1):PAGE80

ESPI_CPU0_D3 @T6G_MB_LIB.T6G(SCH_1):ESPI_CPU0_D3
  R471    1      A Q_RES_0402LF-33,5%,1/16W,CHIP,CS03302JB10   I330 @T6G_MB_LIB.T6G(SCH_1):PAGE29
 R1506    2      B Q_RES_0402LF-30K,1%,1/16W,CHIP,CS33002FB02   I399 @T6G_MB_LIB.T6G(SCH_1):PAGE29
   J41   B8  BIF1# SCONN168_ME1016810202011-SCONN168_ME1016810202011,A   I176 @T6G_MB_LIB.T6G(SCH_1):PAGE348
 R1552    2      B Q_RES_0402LF-33,5%,1/16W,CHIP,CS03302JB10   I170 @T6G_MB_LIB.T6G(SCH_1):PAGE80

ESPI_CPU0_R1_D0 @T6G_MB_LIB.T6G(SCH_1):ESPI_CPU0_R1_D0
 R1549    1      A Q_RES_0402LF-33,5%,1/16W,CHIP,CS03302JB10   I173 @T6G_MB_LIB.T6G(SCH_1):PAGE80
   U18  T21  PR21B LCMXO3LF9400C5BG484C-LCMXO3LF-9400C-5BG484C,SMLF,IA   I217 @T6G_MB_LIB.T6G(SCH_1):PAGE80

ESPI_CPU0_R1_D1 @T6G_MB_LIB.T6G(SCH_1):ESPI_CPU0_R1_D1
 R1550    1      A Q_RES_0402LF-33,5%,1/16W,CHIP,CS03302JB10   I171 @T6G_MB_LIB.T6G(SCH_1):PAGE80
   U18  P19  PR21C LCMXO3LF9400C5BG484C-LCMXO3LF-9400C-5BG484C,SMLF,IA   I217 @T6G_MB_LIB.T6G(SCH_1):PAGE80

ESPI_CPU0_R1_D2 @T6G_MB_LIB.T6G(SCH_1):ESPI_CPU0_R1_D2
 R1551    1      A Q_RES_0402LF-33,5%,1/16W,CHIP,CS03302JB10   I169 @T6G_MB_LIB.T6G(SCH_1):PAGE80
   U18  P18  PR21D LCMXO3LF9400C5BG484C-LCMXO3LF-9400C-5BG484C,SMLF,IA   I217 @T6G_MB_LIB.T6G(SCH_1):PAGE80

ESPI_CPU0_R1_D3 @T6G_MB_LIB.T6G(SCH_1):ESPI_CPU0_R1_D3
 R1552    1      A Q_RES_0402LF-33,5%,1/16W,CHIP,CS03302JB10   I170 @T6G_MB_LIB.T6G(SCH_1):PAGE80
   U18  P17  PR24A LCMXO3LF9400C5BG484C-LCMXO3LF-9400C-5BG484C,SMLF,IA   I217 @T6G_MB_LIB.T6G(SCH_1):PAGE80

ESPI_CPU0_R_ALERT_N @T6G_MB_LIB.T6G(SCH_1):ESPI_CPU0_R_ALERT_N
   U25 DF24 ESPI1_ALERT_L||AGPIO110 GENOA_SP5-SOCKET6096_13568-001,SMLF,IO,DGA^6000030   I287 @T6G_MB_LIB.T6G(SCH_1):PAGE29
  R472    2      B Q_RES_0402LF-33,5%,1/16W,EMPTY,CS03302JB10   I428 @T6G_MB_LIB.T6G(SCH_1):PAGE29

ESPI_CPU0_R_CS1_N @T6G_MB_LIB.T6G(SCH_1):ESPI_CPU0_R_CS1_N
   U25 DJ23 ESPI_CS1_L||AGPIO125 GENOA_SP5-SOCKET6096_13568-001,SMLF,IO,DGA^6000030   I287 @T6G_MB_LIB.T6G(SCH_1):PAGE29
  R462    2      B Q_RES_0402LF-33,5%,1/16W,EMPTY,CS03302JB10   I425 @T6G_MB_LIB.T6G(SCH_1):PAGE29

ESPI_CPU0_R_D0 @T6G_MB_LIB.T6G(SCH_1):ESPI_CPU0_R_D0
   U25 DH24 ESPI1_DAT0||SPI1_DAT0||AGPIO131 GENOA_SP5-SOCKET6096_13568-001,SMLF,IO,DGA^6000030   I287 @T6G_MB_LIB.T6G(SCH_1):PAGE29
  R468    2      B Q_RES_0402LF-33,5%,1/16W,CHIP,CS03302JB10   I329 @T6G_MB_LIB.T6G(SCH_1):PAGE29

ESPI_CPU0_R_D1 @T6G_MB_LIB.T6G(SCH_1):ESPI_CPU0_R_D1
   U25 DE24 ESPI1_DAT1||SPI1_DAT1||AGPIO132 GENOA_SP5-SOCKET6096_13568-001,SMLF,IO,DGA^6000030   I287 @T6G_MB_LIB.T6G(SCH_1):PAGE29
  R469    2      B Q_RES_0402LF-33,5%,1/16W,CHIP,CS03302JB10   I328 @T6G_MB_LIB.T6G(SCH_1):PAGE29

ESPI_CPU0_R_D2 @T6G_MB_LIB.T6G(SCH_1):ESPI_CPU0_R_D2
   U25 DF25 ESPI1_DAT2||SPI1_DAT2||AGPIO133 GENOA_SP5-SOCKET6096_13568-001,SMLF,IO,DGA^6000030   I287 @T6G_MB_LIB.T6G(SCH_1):PAGE29
  R470    2      B Q_RES_0402LF-33,5%,1/16W,CHIP,CS03302JB10   I327 @T6G_MB_LIB.T6G(SCH_1):PAGE29

ESPI_CPU0_R_D3 @T6G_MB_LIB.T6G(SCH_1):ESPI_CPU0_R_D3
   U25 DG25 ESPI1_DAT3||SPI1_DAT3||AGPIO134 GENOA_SP5-SOCKET6096_13568-001,SMLF,IO,DGA^6000030   I287 @T6G_MB_LIB.T6G(SCH_1):PAGE29
  R471    2      B Q_RES_0402LF-33,5%,1/16W,CHIP,CS03302JB10   I330 @T6G_MB_LIB.T6G(SCH_1):PAGE29

FAB_BMC_REV_ID0 @T6G_MB_LIB.T6G(SCH_1):FAB_BMC_REV_ID0
   U18   J1  PL12B LCMXO3LF9400C5BG484C-LCMXO3LF-9400C-5BG484C,SMLF,IA   I143 @T6G_MB_LIB.T6G(SCH_1):PAGE81
 R6151    1      A Q_RES_0402LF-1K,1%,1/16W,CHIP,CS21002FB06   I141 @T6G_MB_LIB.T6G(SCH_1):PAGE83
 R6148    2      B Q_RES_0402LF-1K,1%,1/16W,EMPTY,CS21002FB06   I142 @T6G_MB_LIB.T6G(SCH_1):PAGE83

FAB_BMC_REV_ID1 @T6G_MB_LIB.T6G(SCH_1):FAB_BMC_REV_ID1
   U18   K7  PL12C LCMXO3LF9400C5BG484C-LCMXO3LF-9400C-5BG484C,SMLF,IA   I143 @T6G_MB_LIB.T6G(SCH_1):PAGE81
 R6150    1      A Q_RES_0402LF-1K,1%,1/16W,CHIP,CS21002FB06   I139 @T6G_MB_LIB.T6G(SCH_1):PAGE83
 R6147    2      B Q_RES_0402LF-1K,1%,1/16W,EMPTY,CS21002FB06   I140 @T6G_MB_LIB.T6G(SCH_1):PAGE83

FAB_BMC_REV_ID2 @T6G_MB_LIB.T6G(SCH_1):FAB_BMC_REV_ID2
   U18   K6  PL12D LCMXO3LF9400C5BG484C-LCMXO3LF-9400C-5BG484C,SMLF,IA   I143 @T6G_MB_LIB.T6G(SCH_1):PAGE81
 R6149    1      A Q_RES_0402LF-1K,1%,1/16W,EMPTY,CS21002FB06   I137 @T6G_MB_LIB.T6G(SCH_1):PAGE83
 R6146    2      B Q_RES_0402LF-1K,1%,1/16W,CHIP,CS21002FB06   I138 @T6G_MB_LIB.T6G(SCH_1):PAGE83

FAB_REV_ID0 @T6G_MB_LIB.T6G(SCH_1):FAB_REV_ID0
   U25  A14 AGPIO256||SGPIO0_CLK GENOA_SP5-SOCKET6096_13568-001,SMLF,IO,DGA^6000030   I188 @T6G_MB_LIB.T6G(SCH_1):PAGE28
 R6132    2      B Q_RES_0402LF-1K,1%,1/16W,EMPTY,CS21002FB06   I135 @T6G_MB_LIB.T6G(SCH_1):PAGE83
 R6135    1      A Q_RES_0402LF-1K,1%,1/16W,CHIP,CS21002FB06   I136 @T6G_MB_LIB.T6G(SCH_1):PAGE83

FAB_REV_ID1 @T6G_MB_LIB.T6G(SCH_1):FAB_REV_ID1
   U25  C14 AGPIO257||SGPIO1_CLK||CLK_REQ01_L GENOA_SP5-SOCKET6096_13568-001,SMLF,IO,DGA^6000030   I188 @T6G_MB_LIB.T6G(SCH_1):PAGE28
 R6134    1      A Q_RES_0402LF-1K,1%,1/16W,CHIP,CS21002FB06   I133 @T6G_MB_LIB.T6G(SCH_1):PAGE83
 R6131    2      B Q_RES_0402LF-1K,1%,1/16W,EMPTY,CS21002FB06   I134 @T6G_MB_LIB.T6G(SCH_1):PAGE83

FAB_REV_ID2 @T6G_MB_LIB.T6G(SCH_1):FAB_REV_ID2
   U25  A13 AGPIO258||SGPIO2_CLK||CLK_REQ02_L GENOA_SP5-SOCKET6096_13568-001,SMLF,IO,DGA^6000030   I188 @T6G_MB_LIB.T6G(SCH_1):PAGE28
 R6130    2      B Q_RES_0402LF-1K,1%,1/16W,CHIP,CS21002FB06   I131 @T6G_MB_LIB.T6G(SCH_1):PAGE83
 R6133    1      A Q_RES_0402LF-1K,1%,1/16W,EMPTY,CS21002FB06   I132 @T6G_MB_LIB.T6G(SCH_1):PAGE83

FB_BMC_ISOLATE @T6G_MB_LIB.T6G(SCH_1):FB_BMC_ISOLATE
   U67    1    1OE 74CBTLV3126PW-74CBTLV3126PW,SMLF,IC,AL003126K08     I1 @T6G_MB_LIB.T6G(SCH_1):PAGE336
   U67    4    2OE 74CBTLV3126PW-74CBTLV3126PW,SMLF,IC,AL003126K08     I1 @T6G_MB_LIB.T6G(SCH_1):PAGE336
   U67   10    3OE 74CBTLV3126PW-74CBTLV3126PW,SMLF,IC,AL003126K08     I1 @T6G_MB_LIB.T6G(SCH_1):PAGE336
   U67   13    4OE 74CBTLV3126PW-74CBTLV3126PW,SMLF,IC,AL003126K08     I1 @T6G_MB_LIB.T6G(SCH_1):PAGE336
    U7    1    1OE 74CBTLV3126PW-74CBTLV3126PW,SMLF,IC,AL003126K08     I2 @T6G_MB_LIB.T6G(SCH_1):PAGE336
    U7    4    2OE 74CBTLV3126PW-74CBTLV3126PW,SMLF,IC,AL003126K08     I2 @T6G_MB_LIB.T6G(SCH_1):PAGE336
    U7   10    3OE 74CBTLV3126PW-74CBTLV3126PW,SMLF,IC,AL003126K08     I2 @T6G_MB_LIB.T6G(SCH_1):PAGE336
    U7   13    4OE 74CBTLV3126PW-74CBTLV3126PW,SMLF,IC,AL003126K08     I2 @T6G_MB_LIB.T6G(SCH_1):PAGE336
 R1289    1      A Q_RES_0402LF-100K,1%,1/16W,CHIP,CS41002FB09    I56 @T6G_MB_LIB.T6G(SCH_1):PAGE336
  U320    4      E 74LVC1G66GV-74LVC1G66GV,SMLF,IC,AL001G66000    I82 @T6G_MB_LIB.T6G(SCH_1):PAGE337
 R2473    2      B Q_RES_0402LF-0,5%,1/16W,CHIP,CS00002JB13   I164 @T6G_MB_LIB.T6G(SCH_1):PAGE336
 R2474    2      B Q_RES_0402LF-0,5%,1/16W,EMPTY,CS00002JB13   I165 @T6G_MB_LIB.T6G(SCH_1):PAGE336

FB_BMC_ISOLATE1 @T6G_MB_LIB.T6G(SCH_1):FB_BMC_ISOLATE1
 R3207    1      A Q_RES_0402LF-100K,1%,1/16W,CHIP,CS41002FB09    I15 @T6G_MB_LIB.T6G(SCH_1):PAGE307
  U222    1    1OE 74CBTLV3126PW-74CBTLV3126PW,SMLF,IC,AL003126K08    I32 @T6G_MB_LIB.T6G(SCH_1):PAGE307
  U222    4    2OE 74CBTLV3126PW-74CBTLV3126PW,SMLF,IC,AL003126K08    I32 @T6G_MB_LIB.T6G(SCH_1):PAGE307
  U222   10    3OE 74CBTLV3126PW-74CBTLV3126PW,SMLF,IC,AL003126K08    I32 @T6G_MB_LIB.T6G(SCH_1):PAGE307
  U222   13    4OE 74CBTLV3126PW-74CBTLV3126PW,SMLF,IC,AL003126K08    I32 @T6G_MB_LIB.T6G(SCH_1):PAGE307
  U223    1    1OE 74CBTLV3126PW-74CBTLV3126PW,SMLF,IC,AL003126K08    I78 @T6G_MB_LIB.T6G(SCH_1):PAGE307
  U223    4    2OE 74CBTLV3126PW-74CBTLV3126PW,SMLF,IC,AL003126K08    I78 @T6G_MB_LIB.T6G(SCH_1):PAGE307
  U223   10    3OE 74CBTLV3126PW-74CBTLV3126PW,SMLF,IC,AL003126K08    I78 @T6G_MB_LIB.T6G(SCH_1):PAGE307
  U223   13    4OE 74CBTLV3126PW-74CBTLV3126PW,SMLF,IC,AL003126K08    I78 @T6G_MB_LIB.T6G(SCH_1):PAGE307
  U321    4      E 74LVC1G66GV-74LVC1G66GV,SMLF,IC,AL001G66000    I76 @T6G_MB_LIB.T6G(SCH_1):PAGE342
 R3206    2      B Q_RES_0402LF-0,5%,1/16W,EMPTY,CS00002JB13    I85 @T6G_MB_LIB.T6G(SCH_1):PAGE307
 R3205    2      B Q_RES_0402LF-0,5%,1/16W,CHIP,CS00002JB13    I86 @T6G_MB_LIB.T6G(SCH_1):PAGE307

FB_BMC_ISOLATE_R1 @T6G_MB_LIB.T6G(SCH_1):FB_BMC_ISOLATE_R1
   U66    4      Y 74LVC1G126SE7-74LVC1G126SE-7,SMLF,IC,AL1G0126009   I157 @T6G_MB_LIB.T6G(SCH_1):PAGE336
 R2473    1      A Q_RES_0402LF-0,5%,1/16W,CHIP,CS00002JB13   I164 @T6G_MB_LIB.T6G(SCH_1):PAGE336

FB_BMC_ISOLATE_R2 @T6G_MB_LIB.T6G(SCH_1):FB_BMC_ISOLATE_R2
  U286    4      Y 74LVC1G126SE7-74LVC1G126SE-7,SMLF,IC,AL1G0126009    I80 @T6G_MB_LIB.T6G(SCH_1):PAGE307
 R3205    1      A Q_RES_0402LF-0,5%,1/16W,CHIP,CS00002JB13    I86 @T6G_MB_LIB.T6G(SCH_1):PAGE307

FG_SS_EN @T6G_MB_LIB.T6G(SCH_1):FG_SS_EN
 R4079    1      A Q_RES_0402LF-10K,1%,1/16W,CHIP,CS31002FB08    I46 @T6G_MB_LIB.T6G(SCH_1):PAGE232
 R4078    2      B Q_RES_0402LF-10K,1%,1/16W,EMPTY,CS31002FB08    I47 @T6G_MB_LIB.T6G(SCH_1):PAGE232
  U247   23 ^VSS_EN_TRI 9FGL0251DKILFT-9FGL0251DKILFT,SMLF,IC,AL000251002    I77 @T6G_MB_LIB.T6G(SCH_1):PAGE232

FM_9ZXL045_P0_0_OE_N @T6G_MB_LIB.T6G(SCH_1):FM_9ZXL045_P0_0_OE_N
 R4520    1      A Q_RES_0402LF-10K,1%,1/16W,CHIP,CS31002FB08    I55 @T6G_MB_LIB.T6G(SCH_1):PAGE160
  U314   15  VOE0# 9ZXL0451EKILFT-9ZXL0451EKILFT,SMLF,IC,AL000451003    I63 @T6G_MB_LIB.T6G(SCH_1):PAGE160

FM_9ZXL045_P0_1_OE_N @T6G_MB_LIB.T6G(SCH_1):FM_9ZXL045_P0_1_OE_N
 R4519    1      A Q_RES_0402LF-10K,1%,1/16W,CHIP,CS31002FB08    I53 @T6G_MB_LIB.T6G(SCH_1):PAGE160
  U314   18  VOE1# 9ZXL0451EKILFT-9ZXL0451EKILFT,SMLF,IC,AL000451003    I63 @T6G_MB_LIB.T6G(SCH_1):PAGE160

FM_9ZXL045_P0_2_OE_N @T6G_MB_LIB.T6G(SCH_1):FM_9ZXL045_P0_2_OE_N
 R4518    1      A Q_RES_0402LF-10K,1%,1/16W,CHIP,CS31002FB08    I52 @T6G_MB_LIB.T6G(SCH_1):PAGE160
  U314   24  VOE2# 9ZXL0451EKILFT-9ZXL0451EKILFT,SMLF,IC,AL000451003    I63 @T6G_MB_LIB.T6G(SCH_1):PAGE160

FM_9ZXL045_P0_3_OE_N @T6G_MB_LIB.T6G(SCH_1):FM_9ZXL045_P0_3_OE_N
  U314   26  VOE3# 9ZXL0451EKILFT-9ZXL0451EKILFT,SMLF,IC,AL000451003    I63 @T6G_MB_LIB.T6G(SCH_1):PAGE160
 R6802    1      A Q_RES_0402LF-10K,1%,1/16W,CHIP,CS31002FB08    I68 @T6G_MB_LIB.T6G(SCH_1):PAGE160

FM_9ZXL045_P0_DEV_EN @T6G_MB_LIB.T6G(SCH_1):FM_9ZXL045_P0_DEV_EN
  U314    1 ^CKPWRGD_PD# 9ZXL0451EKILFT-9ZXL0451EKILFT,SMLF,IC,AL000451003    I63 @T6G_MB_LIB.T6G(SCH_1):PAGE160
 R4476    2      B Q_RES_0402LF-10K,1%,1/16W,CHIP,CS31002FB08    I73 @T6G_MB_LIB.T6G(SCH_1):PAGE160

FM_9ZXL045_P1_0_OE_N @T6G_MB_LIB.T6G(SCH_1):FM_9ZXL045_P1_0_OE_N
  R594    1      A Q_RES_0402LF-10K,1%,1/16W,CHIP,CS31002FB08    I51 @T6G_MB_LIB.T6G(SCH_1):PAGE379
   U10   15  VOE0# 9ZXL0451EKILFT-9ZXL0451EKILFT,SMLF,IC,AL000451003    I63 @T6G_MB_LIB.T6G(SCH_1):PAGE379

FM_9ZXL045_P1_1_OE_N @T6G_MB_LIB.T6G(SCH_1):FM_9ZXL045_P1_1_OE_N
  R593    1      A Q_RES_0402LF-10K,1%,1/16W,CHIP,CS31002FB08    I50 @T6G_MB_LIB.T6G(SCH_1):PAGE379
   U10   18  VOE1# 9ZXL0451EKILFT-9ZXL0451EKILFT,SMLF,IC,AL000451003    I63 @T6G_MB_LIB.T6G(SCH_1):PAGE379

FM_9ZXL045_P1_2_OE_N @T6G_MB_LIB.T6G(SCH_1):FM_9ZXL045_P1_2_OE_N
  R592    1      A Q_RES_0402LF-10K,1%,1/16W,CHIP,CS31002FB08    I49 @T6G_MB_LIB.T6G(SCH_1):PAGE379
   U10   24  VOE2# 9ZXL0451EKILFT-9ZXL0451EKILFT,SMLF,IC,AL000451003    I63 @T6G_MB_LIB.T6G(SCH_1):PAGE379

FM_9ZXL045_P1_3_OE_N @T6G_MB_LIB.T6G(SCH_1):FM_9ZXL045_P1_3_OE_N
   U10   26  VOE3# 9ZXL0451EKILFT-9ZXL0451EKILFT,SMLF,IC,AL000451003    I63 @T6G_MB_LIB.T6G(SCH_1):PAGE379
 R6803    1      A Q_RES_0402LF-10K,1%,1/16W,CHIP,CS31002FB08    I76 @T6G_MB_LIB.T6G(SCH_1):PAGE379

FM_9ZXL045_P1_DEV_EN @T6G_MB_LIB.T6G(SCH_1):FM_9ZXL045_P1_DEV_EN
   U10    1 ^CKPWRGD_PD# 9ZXL0451EKILFT-9ZXL0451EKILFT,SMLF,IC,AL000451003    I63 @T6G_MB_LIB.T6G(SCH_1):PAGE379
  R560    2      B Q_RES_0402LF-10K,1%,1/16W,CHIP,CS31002FB08    I81 @T6G_MB_LIB.T6G(SCH_1):PAGE379

FM_AC_PWR_BTN_N @T6G_MB_LIB.T6G(SCH_1):FM_AC_PWR_BTN_N
   J41  B42 PRSNTB0# SCONN168_ME1016810202011-SCONN168_ME1016810202011,A   I176 @T6G_MB_LIB.T6G(SCH_1):PAGE348
 R8101    2      B Q_RES_0402LF-0,5%,1/16W,CHIP,CS00002JB13   I215 @T6G_MB_LIB.T6G(SCH_1):PAGE348

FM_AC_PWR_BTN_PDB_N @T6G_MB_LIB.T6G(SCH_1):FM_AC_PWR_BTN_PDB_N
   J45   A2     A2 CONN60_101062636003K02LF-CONN60_10106263-6003K02LFA   I466 @T6G_MB_LIB.T6G(SCH_1):PAGE363
 R8102    2      B Q_RES_0402LF-0,5%,1/16W,CHIP,CS00002JB13   I467 @T6G_MB_LIB.T6G(SCH_1):PAGE363
 C8011    1      A Q_CAP_0402-0.1UF,25V,10%,EMPTY,CH4104K1B00   I469 @T6G_MB_LIB.T6G(SCH_1):PAGE363

FM_AC_PWR_BTN_PLD_ISO_N @T6G_MB_LIB.T6G(SCH_1):FM_AC_PWR_BTN_PLD_ISO_N
   U18  W18  PB44D LCMXO3LF9400C5BG484C-LCMXO3LF-9400C-5BG484C,SMLF,IA   I216 @T6G_MB_LIB.T6G(SCH_1):PAGE80
 R8105    2      B Q_RES_0402LF-0,5%,1/16W,EMPTY,CS00002JB13    I20 @T6G_MB_LIB.T6G(SCH_1):PAGE365
 R8106    2      B Q_RES_0402LF-1K,1%,1/16W,CHIP,CS21002FB06    I31 @T6G_MB_LIB.T6G(SCH_1):PAGE365

FM_AC_PWR_BTN_PLD_ISO_R_N @T6G_MB_LIB.T6G(SCH_1):FM_AC_PWR_BTN_PLD_ISO_R_N
 U8004    6     1Y 74LVC2G07DW7-74LVC2G07DW-7,SMLF,EMPTY,AL002G07003    I16 @T6G_MB_LIB.T6G(SCH_1):PAGE365
 R8105    1      A Q_RES_0402LF-0,5%,1/16W,EMPTY,CS00002JB13    I20 @T6G_MB_LIB.T6G(SCH_1):PAGE365

FM_AC_PWR_BTN_PLD_N @T6G_MB_LIB.T6G(SCH_1):FM_AC_PWR_BTN_PLD_N
 U8004    1     1A 74LVC2G07DW7-74LVC2G07DW-7,SMLF,EMPTY,AL002G07003    I16 @T6G_MB_LIB.T6G(SCH_1):PAGE365
 R8104    2      B Q_RES_0402LF-0,5%,1/16W,EMPTY,CS00002JB13    I18 @T6G_MB_LIB.T6G(SCH_1):PAGE365

FM_AC_PWR_BTN_R_N @T6G_MB_LIB.T6G(SCH_1):FM_AC_PWR_BTN_R_N
 R8101    1      A Q_RES_0402LF-0,5%,1/16W,CHIP,CS00002JB13   I215 @T6G_MB_LIB.T6G(SCH_1):PAGE348
 R8102    1      A Q_RES_0402LF-0,5%,1/16W,CHIP,CS00002JB13   I467 @T6G_MB_LIB.T6G(SCH_1):PAGE363
 R8104    1      A Q_RES_0402LF-0,5%,1/16W,EMPTY,CS00002JB13    I18 @T6G_MB_LIB.T6G(SCH_1):PAGE365
 C8012    1      A Q_CAP_C0402-1UF,25V,10%,EMPTY,CH5104KEB02    I25 @T6G_MB_LIB.T6G(SCH_1):PAGE365
 R8103    2      B Q_RES_0402LF-8.45K,1%,1/16W,EMPTY,CS28452FB06    I27 @T6G_MB_LIB.T6G(SCH_1):PAGE365

FM_APML_MUX2_OE_N @T6G_MB_LIB.T6G(SCH_1):FM_APML_MUX2_OE_N
  R132    1      A Q_RES_0402LF-0,5%,1/16W,CHIP,CS00002JB13   I168 @T6G_MB_LIB.T6G(SCH_1):PAGE81
  R134    1      A Q_RES_0402LF-4.7K,5%,1/16W,EMPTY,CS24702JB10   I156 @T6G_MB_LIB.T6G(SCH_1):PAGE82
  R126    1      A Q_RES_0402LF-10K,1%,1/16W,CHIP,CS31002FB08   I163 @T6G_MB_LIB.T6G(SCH_1):PAGE82
    U4    6    OE# PI3CSW12ZUAEX-PI3CSW12ZUAEX,SMLF,IC,AL3CSW12000   I114 @T6G_MB_LIB.T6G(SCH_1):PAGE138

FM_APML_MUX2_OE_R_N @T6G_MB_LIB.T6G(SCH_1):FM_APML_MUX2_OE_R_N
   U18   P6  PL21D LCMXO3LF9400C5BG484C-LCMXO3LF-9400C-5BG484C,SMLF,IA   I143 @T6G_MB_LIB.T6G(SCH_1):PAGE81
  R132    2      B Q_RES_0402LF-0,5%,1/16W,CHIP,CS00002JB13   I168 @T6G_MB_LIB.T6G(SCH_1):PAGE81

FM_APML_MUX2_SEL @T6G_MB_LIB.T6G(SCH_1):FM_APML_MUX2_SEL
  R133    1      A Q_RES_0402LF-0,5%,1/16W,CHIP,CS00002JB13   I169 @T6G_MB_LIB.T6G(SCH_1):PAGE81
  R135    1      A Q_RES_0402LF-4.7K,5%,1/16W,EMPTY,CS24702JB10   I157 @T6G_MB_LIB.T6G(SCH_1):PAGE82
  R136    1      A Q_RES_0402LF-10K,1%,1/16W,EMPTY,CS31002FB08   I162 @T6G_MB_LIB.T6G(SCH_1):PAGE82
    U4    9      S PI3CSW12ZUAEX-PI3CSW12ZUAEX,SMLF,IC,AL3CSW12000   I114 @T6G_MB_LIB.T6G(SCH_1):PAGE138

FM_APML_MUX2_SEL_R @T6G_MB_LIB.T6G(SCH_1):FM_APML_MUX2_SEL_R
   U18   P5  PL21C LCMXO3LF9400C5BG484C-LCMXO3LF-9400C-5BG484C,SMLF,IA   I143 @T6G_MB_LIB.T6G(SCH_1):PAGE81
  R133    2      B Q_RES_0402LF-0,5%,1/16W,CHIP,CS00002JB13   I169 @T6G_MB_LIB.T6G(SCH_1):PAGE81

FM_BIOS_POST_CMPLT_BUF_N @T6G_MB_LIB.T6G(SCH_1):FM_BIOS_POST_CMPLT_BUF_N
  R937    2      B Q_RES_0402LF-0,5%,1/16W,CHIP,CS00002JB13   I166 @T6G_MB_LIB.T6G(SCH_1):PAGE80
 C5000    1      A Q_CAP_0402-1000PF,50V,5%,X7R,TMP_QCH21006JB10   I124 @T6G_MB_LIB.T6G(SCH_1):PAGE34
 R6100    2      B Q_RES_0402LF-49.9,1%,1/16W,CHIP,CS04992FB07   I125 @T6G_MB_LIB.T6G(SCH_1):PAGE34

FM_BIOS_POST_CMPLT_BUF_R1_N @T6G_MB_LIB.T6G(SCH_1):FM_BIOS_POST_CMPLT_BUF_R1_N
  R943    2      B Q_RES_0402LF-4.7K,5%,1/16W,CHIP,CS24702JB10    I53 @T6G_MB_LIB.T6G(SCH_1):PAGE34
  U101    4      Y SN74LVC1G07DBVR_SMLF-SN74LVC1G07DBVR,IC,AL1G0007024    I55 @T6G_MB_LIB.T6G(SCH_1):PAGE34
 R6100    1      A Q_RES_0402LF-49.9,1%,1/16W,CHIP,CS04992FB07   I125 @T6G_MB_LIB.T6G(SCH_1):PAGE34

FM_BIOS_POST_CMPLT_BUF_R_N @T6G_MB_LIB.T6G(SCH_1):FM_BIOS_POST_CMPLT_BUF_R_N
  R937    1      A Q_RES_0402LF-0,5%,1/16W,CHIP,CS00002JB13   I166 @T6G_MB_LIB.T6G(SCH_1):PAGE80
   U18  U21  PR24D LCMXO3LF9400C5BG484C-LCMXO3LF-9400C-5BG484C,SMLF,IA   I217 @T6G_MB_LIB.T6G(SCH_1):PAGE80

FM_BIOS_POST_CMPLT_N @T6G_MB_LIB.T6G(SCH_1):FM_BIOS_POST_CMPLT_N
  U101    2      A SN74LVC1G07DBVR_SMLF-SN74LVC1G07DBVR,IC,AL1G0007024    I55 @T6G_MB_LIB.T6G(SCH_1):PAGE34
  R942    2      B Q_RES_0402LF-4.7K,5%,1/16W,CHIP,CS24702JB10    I60 @T6G_MB_LIB.T6G(SCH_1):PAGE34
  R934    1      A Q_RES_0402LF-0,5%,1/16W,CHIP,CS00002JB13    I33 @T6G_MB_LIB.T6G(SCH_1):PAGE143
  R939    2      B Q_RES_0402LF-0,5%,1/16W,CHIP,CS00002JB13    I93 @T6G_MB_LIB.T6G(SCH_1):PAGE28

FM_BIOS_POST_CMPLT_R_N @T6G_MB_LIB.T6G(SCH_1):FM_BIOS_POST_CMPLT_R_N
  R939    1      A Q_RES_0402LF-0,5%,1/16W,CHIP,CS00002JB13    I93 @T6G_MB_LIB.T6G(SCH_1):PAGE28
   U25 DJ29 AGPIO88 GENOA_SP5-SOCKET6096_13568-001,SMLF,IO,DGA^6000030   I188 @T6G_MB_LIB.T6G(SCH_1):PAGE28

FM_BIOS_USB_RECOVERY @T6G_MB_LIB.T6G(SCH_1):FM_BIOS_USB_RECOVERY
 R1204    2      B Q_RES_0402LF-0,5%,1/16W,CHIP,CS00002JB13   I353 @T6G_MB_LIB.T6G(SCH_1):PAGE27
 R1265    1      A Q_RES_0402LF-10K,5%,1/16W,CHIP,CS31002JB08    I52 @T6G_MB_LIB.T6G(SCH_1):PAGE144
   U18  V22  PR25A LCMXO3LF9400C5BG484C-LCMXO3LF-9400C-5BG484C,SMLF,IA   I217 @T6G_MB_LIB.T6G(SCH_1):PAGE80
   SW1   14     14 SW20S_DHNF10FQTR-SW20S_DHNF-10F-Q-T/R,SMLF,MECH,DHA    I90 @T6G_MB_LIB.T6G(SCH_1):PAGE144

FM_BIOS_USB_RECOVERY_R @T6G_MB_LIB.T6G(SCH_1):FM_BIOS_USB_RECOVERY_R
   U25 DJ33 UART0_CTS_L||UART2_TXD||AGPIO135 GENOA_SP5-SOCKET6096_13568-001,SMLF,IO,DGA^6000030   I227 @T6G_MB_LIB.T6G(SCH_1):PAGE27
 R1204    1      A Q_RES_0402LF-0,5%,1/16W,CHIP,CS00002JB13   I353 @T6G_MB_LIB.T6G(SCH_1):PAGE27

FM_BMC_READY_N @T6G_MB_LIB.T6G(SCH_1):FM_BMC_READY_N
   U26 DE40 AGPIO6||DEVSLP1||SATA_ZP1_L GENOA_SP5-SOCKET6096_13568-001,SMLF,IO,DGA^6000030   I182 @T6G_MB_LIB.T6G(SCH_1):PAGE55
  R188    1      A Q_RES_0402LF-0,5%,1/16W,CHIP,CS00002JB13    I61 @T6G_MB_LIB.T6G(SCH_1):PAGE81
 R5031    2      B Q_RES_0402LF-4.7K,5%,1/16W,EMPTY,CS24702JB10   I331 @T6G_MB_LIB.T6G(SCH_1):PAGE55
  R545    1      A Q_RES_0402LF-4.7K,5%,1/16W,CHIP,CS24702JB10   I337 @T6G_MB_LIB.T6G(SCH_1):PAGE55

FM_BMC_READY_R_N @T6G_MB_LIB.T6G(SCH_1):FM_BMC_READY_R_N
  R188    2      B Q_RES_0402LF-0,5%,1/16W,CHIP,CS00002JB13    I61 @T6G_MB_LIB.T6G(SCH_1):PAGE81
   U18   F4   PL5D LCMXO3LF9400C5BG484C-LCMXO3LF-9400C-5BG484C,SMLF,IA   I143 @T6G_MB_LIB.T6G(SCH_1):PAGE81

FM_BMC_TPM_PRES_N @T6G_MB_LIB.T6G(SCH_1):FM_BMC_TPM_PRES_N
   U26 DH16 AGPIO115||CLK_REQ11_L GENOA_SP5-SOCKET6096_13568-001,SMLF,IO,DGA^6000030   I182 @T6G_MB_LIB.T6G(SCH_1):PAGE55
  R189    1      A Q_RES_0402LF-0,5%,1/16W,CHIP,CS00002JB13    I58 @T6G_MB_LIB.T6G(SCH_1):PAGE81
 R5030    2      B Q_RES_0402LF-4.7K,5%,1/16W,EMPTY,CS24702JB10   I334 @T6G_MB_LIB.T6G(SCH_1):PAGE55
  R546    1      A Q_RES_0402LF-4.7K,5%,1/16W,CHIP,CS24702JB10   I338 @T6G_MB_LIB.T6G(SCH_1):PAGE55

FM_BMC_TPM_PRES_N_R @T6G_MB_LIB.T6G(SCH_1):FM_BMC_TPM_PRES_N_R
  R189    2      B Q_RES_0402LF-0,5%,1/16W,CHIP,CS00002JB13    I58 @T6G_MB_LIB.T6G(SCH_1):PAGE81
   U18   E1   PL6A LCMXO3LF9400C5BG484C-LCMXO3LF-9400C-5BG484C,SMLF,IA   I143 @T6G_MB_LIB.T6G(SCH_1):PAGE81

FM_BOARD_BMC_SKU_ID0 @T6G_MB_LIB.T6G(SCH_1):FM_BOARD_BMC_SKU_ID0
 R6145    1      A Q_RES_0402LF-1K,1%,1/16W,CHIP,CS21002FB06    I54 @T6G_MB_LIB.T6G(SCH_1):PAGE83
   U18   C5  PT12D LCMXO3LF9400C5BG484C-LCMXO3LF-9400C-5BG484C,SMLF,IA    I94 @T6G_MB_LIB.T6G(SCH_1):PAGE79
 R6140    2      B Q_RES_0402LF-1K,1%,1/16W,EMPTY,CS21002FB06    I56 @T6G_MB_LIB.T6G(SCH_1):PAGE83

FM_BOARD_BMC_SKU_ID1 @T6G_MB_LIB.T6G(SCH_1):FM_BOARD_BMC_SKU_ID1
   U18   G9  PT21D LCMXO3LF9400C5BG484C-LCMXO3LF-9400C-5BG484C,SMLF,IA    I94 @T6G_MB_LIB.T6G(SCH_1):PAGE79
 R6144    1      A Q_RES_0402LF-1K,1%,1/16W,CHIP,CS21002FB06    I52 @T6G_MB_LIB.T6G(SCH_1):PAGE83
 R6139    2      B Q_RES_0402LF-1K,1%,1/16W,EMPTY,CS21002FB06    I55 @T6G_MB_LIB.T6G(SCH_1):PAGE83

FM_BOARD_BMC_SKU_ID2 @T6G_MB_LIB.T6G(SCH_1):FM_BOARD_BMC_SKU_ID2
   U18  F10  PT22A LCMXO3LF9400C5BG484C-LCMXO3LF-9400C-5BG484C,SMLF,IA    I94 @T6G_MB_LIB.T6G(SCH_1):PAGE79
 R6143    1      A Q_RES_0402LF-1K,1%,1/16W,CHIP,CS21002FB06    I36 @T6G_MB_LIB.T6G(SCH_1):PAGE83
 R6138    2      B Q_RES_0402LF-1K,1%,1/16W,EMPTY,CS21002FB06    I39 @T6G_MB_LIB.T6G(SCH_1):PAGE83

FM_BOARD_BMC_SKU_ID3 @T6G_MB_LIB.T6G(SCH_1):FM_BOARD_BMC_SKU_ID3
   U18  B11  PT24A LCMXO3LF9400C5BG484C-LCMXO3LF-9400C-5BG484C,SMLF,IA    I94 @T6G_MB_LIB.T6G(SCH_1):PAGE79
 R6137    2      B Q_RES_0402LF-1K,1%,1/16W,EMPTY,CS21002FB06   I121 @T6G_MB_LIB.T6G(SCH_1):PAGE83
 R6142    1      A Q_RES_0402LF-1K,1%,1/16W,CHIP,CS21002FB06   I122 @T6G_MB_LIB.T6G(SCH_1):PAGE83

FM_BOARD_BMC_SKU_ID4 @T6G_MB_LIB.T6G(SCH_1):FM_BOARD_BMC_SKU_ID4
   U18  A11  PT24B LCMXO3LF9400C5BG484C-LCMXO3LF-9400C-5BG484C,SMLF,IA    I94 @T6G_MB_LIB.T6G(SCH_1):PAGE79
 R6136    2      B Q_RES_0402LF-1K,1%,1/16W,CHIP,CS21002FB06   I117 @T6G_MB_LIB.T6G(SCH_1):PAGE83
 R6141    1      A Q_RES_0402LF-1K,1%,1/16W,EMPTY,CS21002FB06   I118 @T6G_MB_LIB.T6G(SCH_1):PAGE83

FM_BOARD_SKU_ID0 @T6G_MB_LIB.T6G(SCH_1):FM_BOARD_SKU_ID0
   U25 DF33 AGPIO21 GENOA_SP5-SOCKET6096_13568-001,SMLF,IO,DGA^6000030   I188 @T6G_MB_LIB.T6G(SCH_1):PAGE28
 R6129    1      A Q_RES_0402LF-1K,1%,1/16W,CHIP,CS21002FB06    I65 @T6G_MB_LIB.T6G(SCH_1):PAGE83
 R6124    2      B Q_RES_0402LF-1K,1%,1/16W,EMPTY,CS21002FB06    I72 @T6G_MB_LIB.T6G(SCH_1):PAGE83

FM_BOARD_SKU_ID1 @T6G_MB_LIB.T6G(SCH_1):FM_BOARD_SKU_ID1
   U25 DE32 AGPIO22 GENOA_SP5-SOCKET6096_13568-001,SMLF,IO,DGA^6000030   I188 @T6G_MB_LIB.T6G(SCH_1):PAGE28
 R6128    1      A Q_RES_0402LF-1K,1%,1/16W,CHIP,CS21002FB06    I64 @T6G_MB_LIB.T6G(SCH_1):PAGE83
 R6123    2      B Q_RES_0402LF-1K,1%,1/16W,EMPTY,CS21002FB06    I71 @T6G_MB_LIB.T6G(SCH_1):PAGE83

FM_BOARD_SKU_ID2 @T6G_MB_LIB.T6G(SCH_1):FM_BOARD_SKU_ID2
 R6122    2      B Q_RES_0402LF-1K,1%,1/16W,EMPTY,CS21002FB06    I50 @T6G_MB_LIB.T6G(SCH_1):PAGE83
   U25 DF31 AGPIO106 GENOA_SP5-SOCKET6096_13568-001,SMLF,IO,DGA^6000030   I188 @T6G_MB_LIB.T6G(SCH_1):PAGE28
 R6127    1      A Q_RES_0402LF-1K,1%,1/16W,CHIP,CS21002FB06    I46 @T6G_MB_LIB.T6G(SCH_1):PAGE83

FM_BOARD_SKU_ID3 @T6G_MB_LIB.T6G(SCH_1):FM_BOARD_SKU_ID3
   U25 DG31 AGPIO107 GENOA_SP5-SOCKET6096_13568-001,SMLF,IO,DGA^6000030   I188 @T6G_MB_LIB.T6G(SCH_1):PAGE28
 R6126    1      A Q_RES_0402LF-1K,1%,1/16W,CHIP,CS21002FB06   I119 @T6G_MB_LIB.T6G(SCH_1):PAGE83
 R6121    2      B Q_RES_0402LF-1K,1%,1/16W,EMPTY,CS21002FB06   I120 @T6G_MB_LIB.T6G(SCH_1):PAGE83

FM_BOARD_SKU_ID4 @T6G_MB_LIB.T6G(SCH_1):FM_BOARD_SKU_ID4
   U25  DH4 AGPIO7 GENOA_SP5-SOCKET6096_13568-001,SMLF,IO,DGA^6000030   I188 @T6G_MB_LIB.T6G(SCH_1):PAGE28
 R6120    2      B Q_RES_0402LF-1K,1%,1/16W,CHIP,CS21002FB06   I115 @T6G_MB_LIB.T6G(SCH_1):PAGE83
 R6125    1      A Q_RES_0402LF-1K,1%,1/16W,EMPTY,CS21002FB06   I116 @T6G_MB_LIB.T6G(SCH_1):PAGE83

FM_CLKREQ_M2_1_N @T6G_MB_LIB.T6G(SCH_1):FM_CLKREQ_M2_1_N
   U18   N2  PL18A LCMXO3LF9400C5BG484C-LCMXO3LF-9400C-5BG484C,SMLF,IA   I143 @T6G_MB_LIB.T6G(SCH_1):PAGE81
 R6053    2      B Q_RES_0402LF-0,5%,1/16W,CHIP,CS00002JB13    I85 @T6G_MB_LIB.T6G(SCH_1):PAGE81

FM_CLR_CMOS @T6G_MB_LIB.T6G(SCH_1):FM_CLR_CMOS
   U18   N3  PL18C LCMXO3LF9400C5BG484C-LCMXO3LF-9400C-5BG484C,SMLF,IA   I143 @T6G_MB_LIB.T6G(SCH_1):PAGE81
  R275    2      B Q_RES_0402LF-33,5%,1/16W,CHIP,CS03302JB10    I84 @T6G_MB_LIB.T6G(SCH_1):PAGE81

FM_CPU0_CORETYPE0 @T6G_MB_LIB.T6G(SCH_1):FM_CPU0_CORETYPE0
  R183    2      B Q_RES_0402LF-0,5%,1/16W,CHIP,CS00002JB13    I82 @T6G_MB_LIB.T6G(SCH_1):PAGE81
   U18   R1  PL19B LCMXO3LF9400C5BG484C-LCMXO3LF-9400C-5BG484C,SMLF,IA   I143 @T6G_MB_LIB.T6G(SCH_1):PAGE81

FM_CPU0_CORETYPE1 @T6G_MB_LIB.T6G(SCH_1):FM_CPU0_CORETYPE1
  R184    2      B Q_RES_0402LF-0,5%,1/16W,CHIP,CS00002JB13    I48 @T6G_MB_LIB.T6G(SCH_1):PAGE81
   U18   R2  PL21A LCMXO3LF9400C5BG484C-LCMXO3LF-9400C-5BG484C,SMLF,IA   I143 @T6G_MB_LIB.T6G(SCH_1):PAGE81

FM_CPU0_CORETYPE2 @T6G_MB_LIB.T6G(SCH_1):FM_CPU0_CORETYPE2
  R185    2      B Q_RES_0402LF-0,5%,1/16W,CHIP,CS00002JB13    I80 @T6G_MB_LIB.T6G(SCH_1):PAGE81
   U18   P3  PL19C LCMXO3LF9400C5BG484C-LCMXO3LF-9400C-5BG484C,SMLF,IA   I143 @T6G_MB_LIB.T6G(SCH_1):PAGE81

FM_CPU0_FORCE_SELFREFRESH @T6G_MB_LIB.T6G(SCH_1):FM_CPU0_FORCE_SELFREFRESH
  R186    1      A Q_RES_0402LF-33,5%,1/16W,CHIP,CS03302JB10   I129 @T6G_MB_LIB.T6G(SCH_1):PAGE80
   U18  U17  PR29C LCMXO3LF9400C5BG484C-LCMXO3LF-9400C-5BG484C,SMLF,IA   I217 @T6G_MB_LIB.T6G(SCH_1):PAGE80

FM_CPU0_HDT_CONN_TESTEN @T6G_MB_LIB.T6G(SCH_1):FM_CPU0_HDT_CONN_TESTEN
  R258    1      A Q_RES_0402LF-0,5%,1/16W,CHIP,CS00002JB13   I177 @T6G_MB_LIB.T6G(SCH_1):PAGE80
   U18  P21  PR19B LCMXO3LF9400C5BG484C-LCMXO3LF-9400C-5BG484C,SMLF,IA   I217 @T6G_MB_LIB.T6G(SCH_1):PAGE80

FM_CPU0_NMI_SYNC_FLOOD_N @T6G_MB_LIB.T6G(SCH_1):FM_CPU0_NMI_SYNC_FLOOD_N
  R219    2      B Q_RES_0402LF-33,5%,1/16W,CHIP,CS03302JB10   I108 @T6G_MB_LIB.T6G(SCH_1):PAGE80
   U18  J16  PR11A LCMXO3LF9400C5BG484C-LCMXO3LF-9400C-5BG484C,SMLF,IA   I217 @T6G_MB_LIB.T6G(SCH_1):PAGE80

FM_CPU0_NV_SAVE_N @T6G_MB_LIB.T6G(SCH_1):FM_CPU0_NV_SAVE_N
  R253    2      B Q_RES_0402LF-0,5%,1/16W,CHIP,CS00002JB13   I116 @T6G_MB_LIB.T6G(SCH_1):PAGE80
   U18  G20   PR6B LCMXO3LF9400C5BG484C-LCMXO3LF-9400C-5BG484C,SMLF,IA   I217 @T6G_MB_LIB.T6G(SCH_1):PAGE80

FM_CPU0_PROCHOT_R_N @T6G_MB_LIB.T6G(SCH_1):FM_CPU0_PROCHOT_R_N
   U18   J6  PL10D LCMXO3LF9400C5BG484C-LCMXO3LF-9400C-5BG484C,SMLF,IA   I143 @T6G_MB_LIB.T6G(SCH_1):PAGE81
  R179    1      A Q_RES_0402LF-33,5%,1/16W,CHIP,CS03302JB10   I110 @T6G_MB_LIB.T6G(SCH_1):PAGE81

FM_CPU0_PWR_BTN_N @T6G_MB_LIB.T6G(SCH_1):FM_CPU0_PWR_BTN_N
  R215    2      B Q_RES_0402LF-33,5%,1/16W,CHIP,CS03302JB10   I104 @T6G_MB_LIB.T6G(SCH_1):PAGE80
   U18  J22  PR12B LCMXO3LF9400C5BG484C-LCMXO3LF-9400C-5BG484C,SMLF,IA   I217 @T6G_MB_LIB.T6G(SCH_1):PAGE80

FM_CPU0_PWR_GOOD @T6G_MB_LIB.T6G(SCH_1):FM_CPU0_PWR_GOOD
  R218    2      B Q_RES_0402LF-33,5%,1/16W,CHIP,CS03302JB10    I32 @T6G_MB_LIB.T6G(SCH_1):PAGE80
   U18   W9  PB18D LCMXO3LF9400C5BG484C-LCMXO3LF-9400C-5BG484C,SMLF,IA   I216 @T6G_MB_LIB.T6G(SCH_1):PAGE80

FM_CPU0_RSMRST_N @T6G_MB_LIB.T6G(SCH_1):FM_CPU0_RSMRST_N
  R217    2      B Q_RES_0402LF-33,5%,1/16W,CHIP,CS03302JB10   I118 @T6G_MB_LIB.T6G(SCH_1):PAGE80
   U18  G22   PR5B LCMXO3LF9400C5BG484C-LCMXO3LF-9400C-5BG484C,SMLF,IA   I217 @T6G_MB_LIB.T6G(SCH_1):PAGE80

FM_CPU0_SA0 @T6G_MB_LIB.T6G(SCH_1):FM_CPU0_SA0
   U18   H5  PL11A LCMXO3LF9400C5BG484C-LCMXO3LF-9400C-5BG484C,SMLF,IA   I143 @T6G_MB_LIB.T6G(SCH_1):PAGE81
  R220    1      A Q_RES_0402LF-33,5%,1/16W,CHIP,CS03302JB10   I109 @T6G_MB_LIB.T6G(SCH_1):PAGE81

FM_CPU0_SA1 @T6G_MB_LIB.T6G(SCH_1):FM_CPU0_SA1
   U18   J2  PL12A LCMXO3LF9400C5BG484C-LCMXO3LF-9400C-5BG484C,SMLF,IA   I143 @T6G_MB_LIB.T6G(SCH_1):PAGE81
  R221    1      A Q_RES_0402LF-33,5%,1/16W,CHIP,CS03302JB10   I107 @T6G_MB_LIB.T6G(SCH_1):PAGE81

FM_CPU0_SLP_S3_N @T6G_MB_LIB.T6G(SCH_1):FM_CPU0_SLP_S3_N
   U18  C22 PR2B||R_GPLLC_FB LCMXO3LF9400C5BG484C-LCMXO3LF-9400C-5BG484C,SMLF,IA   I217 @T6G_MB_LIB.T6G(SCH_1):PAGE80
  R249    1      A Q_RES_0402LF-33,5%,1/16W,CHIP,CS03302JB10   I135 @T6G_MB_LIB.T6G(SCH_1):PAGE28

FM_CPU0_SLP_S5_N @T6G_MB_LIB.T6G(SCH_1):FM_CPU0_SLP_S5_N
  R248    1      A Q_RES_0402LF-33,5%,1/16W,CHIP,CS03302JB10   I136 @T6G_MB_LIB.T6G(SCH_1):PAGE28
   U18  C21 PR2A||R_GPLLT_FB LCMXO3LF9400C5BG484C-LCMXO3LF-9400C-5BG484C,SMLF,IA   I217 @T6G_MB_LIB.T6G(SCH_1):PAGE80

FM_CPU0_SMERR_N @T6G_MB_LIB.T6G(SCH_1):FM_CPU0_SMERR_N
  R250    1      A Q_RES_0402LF-0,5%,1/16W,CHIP,CS00002JB13   I180 @T6G_MB_LIB.T6G(SCH_1):PAGE80
   U18  M21 PR17B||PCLKC1_0 LCMXO3LF9400C5BG484C-LCMXO3LF-9400C-5BG484C,SMLF,IA   I217 @T6G_MB_LIB.T6G(SCH_1):PAGE80

FM_CPU0_SP5R1 @T6G_MB_LIB.T6G(SCH_1):FM_CPU0_SP5R1
  R180    2      B Q_RES_0402LF-0,5%,1/16W,CHIP,CS00002JB13    I45 @T6G_MB_LIB.T6G(SCH_1):PAGE81
   U18   N5  PL20B LCMXO3LF9400C5BG484C-LCMXO3LF-9400C-5BG484C,SMLF,IA   I143 @T6G_MB_LIB.T6G(SCH_1):PAGE81

FM_CPU0_SP5R2 @T6G_MB_LIB.T6G(SCH_1):FM_CPU0_SP5R2
  R181    2      B Q_RES_0402LF-0,5%,1/16W,CHIP,CS00002JB13    I46 @T6G_MB_LIB.T6G(SCH_1):PAGE81
   U18   N6  PL20C LCMXO3LF9400C5BG484C-LCMXO3LF-9400C-5BG484C,SMLF,IA   I143 @T6G_MB_LIB.T6G(SCH_1):PAGE81

FM_CPU0_SP5R3 @T6G_MB_LIB.T6G(SCH_1):FM_CPU0_SP5R3
  R222    2      B Q_RES_0402LF-0,5%,1/16W,CHIP,CS00002JB13    I52 @T6G_MB_LIB.T6G(SCH_1):PAGE81
   U18   U1  PL25B LCMXO3LF9400C5BG484C-LCMXO3LF-9400C-5BG484C,SMLF,IA   I143 @T6G_MB_LIB.T6G(SCH_1):PAGE81

FM_CPU0_SP5R4 @T6G_MB_LIB.T6G(SCH_1):FM_CPU0_SP5R4
  R223    1      A Q_RES_0402LF-0,5%,1/16W,CHIP,CS00002JB13   I100 @T6G_MB_LIB.T6G(SCH_1):PAGE81
   U18   U2 PL27A||PCLKT3_0 LCMXO3LF9400C5BG484C-LCMXO3LF-9400C-5BG484C,SMLF,IA   I143 @T6G_MB_LIB.T6G(SCH_1):PAGE81

FM_CPU0_SYS_RESET_N @T6G_MB_LIB.T6G(SCH_1):FM_CPU0_SYS_RESET_N
  R216    2      B Q_RES_0402LF-33,5%,1/16W,CHIP,CS03302JB10   I117 @T6G_MB_LIB.T6G(SCH_1):PAGE80
   U18  F19   PR5D LCMXO3LF9400C5BG484C-LCMXO3LF-9400C-5BG484C,SMLF,IA   I217 @T6G_MB_LIB.T6G(SCH_1):PAGE80

FM_CPU0_XTRIG_L4 @T6G_MB_LIB.T6G(SCH_1):FM_CPU0_XTRIG_L4
  R236    2      B Q_RES_0402LF-0,5%,1/16W,CHIP,CS00002JB13    I66 @T6G_MB_LIB.T6G(SCH_1):PAGE81
   U18   D2 PL4B||L_GPLLC_IN LCMXO3LF9400C5BG484C-LCMXO3LF-9400C-5BG484C,SMLF,IA   I143 @T6G_MB_LIB.T6G(SCH_1):PAGE81

FM_CPU0_XTRIG_L5 @T6G_MB_LIB.T6G(SCH_1):FM_CPU0_XTRIG_L5
  R237    2      B Q_RES_0402LF-0,5%,1/16W,CHIP,CS00002JB13    I69 @T6G_MB_LIB.T6G(SCH_1):PAGE81
   U18   C1 PL4A||L_GPLLT_IN LCMXO3LF9400C5BG484C-LCMXO3LF-9400C-5BG484C,SMLF,IA   I143 @T6G_MB_LIB.T6G(SCH_1):PAGE81

FM_CPU0_XTRIG_L6 @T6G_MB_LIB.T6G(SCH_1):FM_CPU0_XTRIG_L6
  R238    2      B Q_RES_0402LF-0,5%,1/16W,CHIP,CS00002JB13    I71 @T6G_MB_LIB.T6G(SCH_1):PAGE81
   U18   E4 PL3A||L_GPLLT_FB LCMXO3LF9400C5BG484C-LCMXO3LF-9400C-5BG484C,SMLF,IA   I143 @T6G_MB_LIB.T6G(SCH_1):PAGE81

FM_CPU0_XTRIG_L7 @T6G_MB_LIB.T6G(SCH_1):FM_CPU0_XTRIG_L7
  R239    2      B Q_RES_0402LF-0,5%,1/16W,CHIP,CS00002JB13    I62 @T6G_MB_LIB.T6G(SCH_1):PAGE81
   U18   E3   PL5C LCMXO3LF9400C5BG484C-LCMXO3LF-9400C-5BG484C,SMLF,IA   I143 @T6G_MB_LIB.T6G(SCH_1):PAGE81

FM_CPU1_BMC_RST_N @T6G_MB_LIB.T6G(SCH_1):FM_CPU1_BMC_RST_N
   U26 DH15 AGPIO116||CLK_REQ12_L GENOA_SP5-SOCKET6096_13568-001,SMLF,IO,DGA^6000030   I182 @T6G_MB_LIB.T6G(SCH_1):PAGE55
  R190    1      A Q_RES_0402LF-0,5%,1/16W,CHIP,CS00002JB13    I64 @T6G_MB_LIB.T6G(SCH_1):PAGE81
  R547    1      A Q_RES_0402LF-4.7K,5%,1/16W,CHIP,CS24702JB10   I362 @T6G_MB_LIB.T6G(SCH_1):PAGE55

FM_CPU1_BMC_RST_R_N @T6G_MB_LIB.T6G(SCH_1):FM_CPU1_BMC_RST_R_N
  R190    2      B Q_RES_0402LF-0,5%,1/16W,CHIP,CS00002JB13    I64 @T6G_MB_LIB.T6G(SCH_1):PAGE81
   U18   E2   PL5B LCMXO3LF9400C5BG484C-LCMXO3LF-9400C-5BG484C,SMLF,IA   I143 @T6G_MB_LIB.T6G(SCH_1):PAGE81

FM_CPU1_CORETYPE0 @T6G_MB_LIB.T6G(SCH_1):FM_CPU1_CORETYPE0
  R262    2      B Q_RES_0402LF-0,5%,1/16W,CHIP,CS00002JB13    I44 @T6G_MB_LIB.T6G(SCH_1):PAGE81
   U18   P4  PL20A LCMXO3LF9400C5BG484C-LCMXO3LF-9400C-5BG484C,SMLF,IA   I143 @T6G_MB_LIB.T6G(SCH_1):PAGE81

FM_CPU1_CORETYPE1 @T6G_MB_LIB.T6G(SCH_1):FM_CPU1_CORETYPE1
  R263    2      B Q_RES_0402LF-0,5%,1/16W,CHIP,CS00002JB13    I47 @T6G_MB_LIB.T6G(SCH_1):PAGE81
   U18   T1  PL21B LCMXO3LF9400C5BG484C-LCMXO3LF-9400C-5BG484C,SMLF,IA   I143 @T6G_MB_LIB.T6G(SCH_1):PAGE81

FM_CPU1_CORETYPE2 @T6G_MB_LIB.T6G(SCH_1):FM_CPU1_CORETYPE2
  R264    2      B Q_RES_0402LF-0,5%,1/16W,CHIP,CS00002JB13    I53 @T6G_MB_LIB.T6G(SCH_1):PAGE81
   U18   T2  PL25A LCMXO3LF9400C5BG484C-LCMXO3LF-9400C-5BG484C,SMLF,IA   I143 @T6G_MB_LIB.T6G(SCH_1):PAGE81

FM_CPU1_FORCE_SELFREFRESH @T6G_MB_LIB.T6G(SCH_1):FM_CPU1_FORCE_SELFREFRESH
  R265    1      A Q_RES_0402LF-33,5%,1/16W,CHIP,CS03302JB10   I126 @T6G_MB_LIB.T6G(SCH_1):PAGE80
   U18  W19  PR30C LCMXO3LF9400C5BG484C-LCMXO3LF-9400C-5BG484C,SMLF,IA   I217 @T6G_MB_LIB.T6G(SCH_1):PAGE80

FM_CPU1_NMI_SYNC_FLOOD_N @T6G_MB_LIB.T6G(SCH_1):FM_CPU1_NMI_SYNC_FLOOD_N
  R277    1      A Q_RES_0402LF-33,5%,1/16W,CHIP,CS03302JB10   I165 @T6G_MB_LIB.T6G(SCH_1):PAGE80
   U18  W22  PR25B LCMXO3LF9400C5BG484C-LCMXO3LF-9400C-5BG484C,SMLF,IA   I217 @T6G_MB_LIB.T6G(SCH_1):PAGE80

FM_CPU1_NV_SAVE_N @T6G_MB_LIB.T6G(SCH_1):FM_CPU1_NV_SAVE_N
  R196    2      B Q_RES_0402LF-0,5%,1/16W,CHIP,CS00002JB13   I109 @T6G_MB_LIB.T6G(SCH_1):PAGE80
   U18  H18  PR10B LCMXO3LF9400C5BG484C-LCMXO3LF-9400C-5BG484C,SMLF,IA   I217 @T6G_MB_LIB.T6G(SCH_1):PAGE80

FM_CPU1_PROCHOT_R_N @T6G_MB_LIB.T6G(SCH_1):FM_CPU1_PROCHOT_R_N
   U18   G1 PL7B||PCLKC5_0 LCMXO3LF9400C5BG484C-LCMXO3LF-9400C-5BG484C,SMLF,IA   I143 @T6G_MB_LIB.T6G(SCH_1):PAGE81
  R270    1      A Q_RES_0402LF-33,5%,1/16W,CHIP,CS03302JB10   I112 @T6G_MB_LIB.T6G(SCH_1):PAGE81

FM_CPU1_PWRGD_OUT @T6G_MB_LIB.T6G(SCH_1):FM_CPU1_PWRGD_OUT
   U18 AA22  PR29A LCMXO3LF9400C5BG484C-LCMXO3LF-9400C-5BG484C,SMLF,IA   I217 @T6G_MB_LIB.T6G(SCH_1):PAGE80
  R195    1      A Q_RES_0402LF-33,5%,1/16W,CHIP,CS03302JB10   I303 @T6G_MB_LIB.T6G(SCH_1):PAGE80

FM_CPU1_PWR_GD_IN @T6G_MB_LIB.T6G(SCH_1):FM_CPU1_PWR_GD_IN
  R252    1      A Q_RES_0402LF-0,5%,1/16W,CHIP,CS00002JB13   I128 @T6G_MB_LIB.T6G(SCH_1):PAGE80
   U18  Y21  PR29B LCMXO3LF9400C5BG484C-LCMXO3LF-9400C-5BG484C,SMLF,IA   I217 @T6G_MB_LIB.T6G(SCH_1):PAGE80

FM_CPU1_RSMRST_N @T6G_MB_LIB.T6G(SCH_1):FM_CPU1_RSMRST_N
  R273    2      B Q_RES_0402LF-33,5%,1/16W,CHIP,CS03302JB10   I119 @T6G_MB_LIB.T6G(SCH_1):PAGE80
   U18  F22   PR5A LCMXO3LF9400C5BG484C-LCMXO3LF-9400C-5BG484C,SMLF,IA   I217 @T6G_MB_LIB.T6G(SCH_1):PAGE80

FM_CPU1_SA0 @T6G_MB_LIB.T6G(SCH_1):FM_CPU1_SA0
   U18   J7  PL10C LCMXO3LF9400C5BG484C-LCMXO3LF-9400C-5BG484C,SMLF,IA   I143 @T6G_MB_LIB.T6G(SCH_1):PAGE81
  R266    1      A Q_RES_0402LF-33,5%,1/16W,CHIP,CS03302JB10   I108 @T6G_MB_LIB.T6G(SCH_1):PAGE81

FM_CPU1_SA1 @T6G_MB_LIB.T6G(SCH_1):FM_CPU1_SA1
  R267    2      B Q_RES_0402LF-33,5%,1/16W,CHIP,CS03302JB10    I73 @T6G_MB_LIB.T6G(SCH_1):PAGE81
   U18   G7   PL2D LCMXO3LF9400C5BG484C-LCMXO3LF-9400C-5BG484C,SMLF,IA   I143 @T6G_MB_LIB.T6G(SCH_1):PAGE81

FM_CPU1_SLP_S3_N @T6G_MB_LIB.T6G(SCH_1):FM_CPU1_SLP_S3_N
  R192    1      A Q_RES_0402LF-0,5%,1/16W,EMPTY,CS00002JB13   I298 @T6G_MB_LIB.T6G(SCH_1):PAGE55
   U18  D21 PR3B||R_GPLLC_IN LCMXO3LF9400C5BG484C-LCMXO3LF-9400C-5BG484C,SMLF,IA   I217 @T6G_MB_LIB.T6G(SCH_1):PAGE80

FM_CPU1_SLP_S5_N @T6G_MB_LIB.T6G(SCH_1):FM_CPU1_SLP_S5_N
  R191    1      A Q_RES_0402LF-0,5%,1/16W,EMPTY,CS00002JB13   I297 @T6G_MB_LIB.T6G(SCH_1):PAGE55
   U18  D22 PR3A||R_GPLLT_IN LCMXO3LF9400C5BG484C-LCMXO3LF-9400C-5BG484C,SMLF,IA   I217 @T6G_MB_LIB.T6G(SCH_1):PAGE80

FM_CPU1_SMERR_N @T6G_MB_LIB.T6G(SCH_1):FM_CPU1_SMERR_N
  R193    1      A Q_RES_0402LF-0,5%,1/16W,CHIP,CS00002JB13   I179 @T6G_MB_LIB.T6G(SCH_1):PAGE80
   U18  N16  PR18B LCMXO3LF9400C5BG484C-LCMXO3LF-9400C-5BG484C,SMLF,IA   I217 @T6G_MB_LIB.T6G(SCH_1):PAGE80

FM_CPU1_SP5R1 @T6G_MB_LIB.T6G(SCH_1):FM_CPU1_SP5R1
  R260    2      B Q_RES_0402LF-0,5%,1/16W,CHIP,CS00002JB13    I49 @T6G_MB_LIB.T6G(SCH_1):PAGE81
   U18   R3  PL24A LCMXO3LF9400C5BG484C-LCMXO3LF-9400C-5BG484C,SMLF,IA   I143 @T6G_MB_LIB.T6G(SCH_1):PAGE81

FM_CPU1_SP5R2 @T6G_MB_LIB.T6G(SCH_1):FM_CPU1_SP5R2
  R261    2      B Q_RES_0402LF-0,5%,1/16W,CHIP,CS00002JB13    I50 @T6G_MB_LIB.T6G(SCH_1):PAGE81
   U18   R4  PL24B LCMXO3LF9400C5BG484C-LCMXO3LF-9400C-5BG484C,SMLF,IA   I143 @T6G_MB_LIB.T6G(SCH_1):PAGE81

FM_CPU1_SP5R3 @T6G_MB_LIB.T6G(SCH_1):FM_CPU1_SP5R3
  R268    2      B Q_RES_0402LF-0,5%,1/16W,CHIP,CS00002JB13    I55 @T6G_MB_LIB.T6G(SCH_1):PAGE81
   U18   T3  PL26A LCMXO3LF9400C5BG484C-LCMXO3LF-9400C-5BG484C,SMLF,IA   I143 @T6G_MB_LIB.T6G(SCH_1):PAGE81

FM_CPU1_SP5R4 @T6G_MB_LIB.T6G(SCH_1):FM_CPU1_SP5R4
  R269    2      B Q_RES_0402LF-0,5%,1/16W,CHIP,CS00002JB13    I56 @T6G_MB_LIB.T6G(SCH_1):PAGE81
   U18   T4  PL26B LCMXO3LF9400C5BG484C-LCMXO3LF-9400C-5BG484C,SMLF,IA   I143 @T6G_MB_LIB.T6G(SCH_1):PAGE81

FM_CPU1_SYS_RESET_N @T6G_MB_LIB.T6G(SCH_1):FM_CPU1_SYS_RESET_N
  R272    2      B Q_RES_0402LF-0,5%,1/16W,EMPTY,CS00002JB13   I115 @T6G_MB_LIB.T6G(SCH_1):PAGE80
   U18  G21   PR6A LCMXO3LF9400C5BG484C-LCMXO3LF-9400C-5BG484C,SMLF,IA   I217 @T6G_MB_LIB.T6G(SCH_1):PAGE80

FM_CPU1_XTRIG_L4 @T6G_MB_LIB.T6G(SCH_1):FM_CPU1_XTRIG_L4
  R204    2      B Q_RES_0402LF-0,5%,1/16W,CHIP,CS00002JB13    I77 @T6G_MB_LIB.T6G(SCH_1):PAGE81
   U18   D3   PL2A LCMXO3LF9400C5BG484C-LCMXO3LF-9400C-5BG484C,SMLF,IA   I143 @T6G_MB_LIB.T6G(SCH_1):PAGE81

FM_CPU1_XTRIG_L5 @T6G_MB_LIB.T6G(SCH_1):FM_CPU1_XTRIG_L5
   U18   D4   PL2B LCMXO3LF9400C5BG484C-LCMXO3LF-9400C-5BG484C,SMLF,IA   I143 @T6G_MB_LIB.T6G(SCH_1):PAGE81
  R205    2      B Q_RES_0402LF-0,5%,1/16W,CHIP,CS00002JB13    I74 @T6G_MB_LIB.T6G(SCH_1):PAGE81

FM_CPU1_XTRIG_L6 @T6G_MB_LIB.T6G(SCH_1):FM_CPU1_XTRIG_L6
  R234    2      B Q_RES_0402LF-0,5%,1/16W,CHIP,CS00002JB13    I75 @T6G_MB_LIB.T6G(SCH_1):PAGE81
   U18   F6   PL2C LCMXO3LF9400C5BG484C-LCMXO3LF-9400C-5BG484C,SMLF,IA   I143 @T6G_MB_LIB.T6G(SCH_1):PAGE81

FM_CPU1_XTRIG_L7 @T6G_MB_LIB.T6G(SCH_1):FM_CPU1_XTRIG_L7
  R235    2      B Q_RES_0402LF-0,5%,1/16W,CHIP,CS00002JB13    I70 @T6G_MB_LIB.T6G(SCH_1):PAGE81
   U18   G6   PL3C LCMXO3LF9400C5BG484C-LCMXO3LF-9400C-5BG484C,SMLF,IA   I143 @T6G_MB_LIB.T6G(SCH_1):PAGE81

FM_ESPI_CPU0_ALERT_R_SEL @T6G_MB_LIB.T6G(SCH_1):FM_ESPI_CPU0_ALERT_R_SEL
 U8000    6      S NC7SB3157P6X-NC7SB3157P6X,SMLF,IC,ALSB3157000     I1 @T6G_MB_LIB.T6G(SCH_1):PAGE130
 R8032    2      B Q_RES_0402LF-0,5%,1/16W,CHIP,CS00002JB13   I319 @T6G_MB_LIB.T6G(SCH_1):PAGE80
 R8033    1      A Q_RES_0402LF-1K,1%,1/16W,CHIP,CS21002FB06   I170 @T6G_MB_LIB.T6G(SCH_1):PAGE82

FM_ESPI_CPU0_ALERT_SEL @T6G_MB_LIB.T6G(SCH_1):FM_ESPI_CPU0_ALERT_SEL
   U18  N17  PR18C LCMXO3LF9400C5BG484C-LCMXO3LF-9400C-5BG484C,SMLF,IA   I217 @T6G_MB_LIB.T6G(SCH_1):PAGE80
 R8032    1      A Q_RES_0402LF-0,5%,1/16W,CHIP,CS00002JB13   I319 @T6G_MB_LIB.T6G(SCH_1):PAGE80

FM_FAN_PWR_EN @T6G_MB_LIB.T6G(SCH_1):FM_FAN_PWR_EN
 R2803    2      B Q_RES_0402LF-0,5%,1/16W,CHIP,CS00002JB13   I388 @T6G_MB_LIB.T6G(SCH_1):PAGE363
   U18  D12  PT27A LCMXO3LF9400C5BG484C-LCMXO3LF-9400C-5BG484C,SMLF,IA    I94 @T6G_MB_LIB.T6G(SCH_1):PAGE79
 R9000    2      B Q_RES_0402LF-1K,1%,1/16W,CHIP,CS21002FB06   I472 @T6G_MB_LIB.T6G(SCH_1):PAGE363

FM_FAN_PWR_EN_R @T6G_MB_LIB.T6G(SCH_1):FM_FAN_PWR_EN_R
 R2803    1      A Q_RES_0402LF-0,5%,1/16W,CHIP,CS00002JB13   I388 @T6G_MB_LIB.T6G(SCH_1):PAGE363
   C66    1      A Q_CAP_0402-0.1UF,25V,10%,EMPTY,CH4104K1B00   I455 @T6G_MB_LIB.T6G(SCH_1):PAGE363
   J45   D1     D1 CONN60_101062636003K02LF-CONN60_10106263-6003K02LFA   I466 @T6G_MB_LIB.T6G(SCH_1):PAGE363

FM_FORCE_ALL_PWRON @T6G_MB_LIB.T6G(SCH_1):FM_FORCE_ALL_PWRON
 R1202    2      B Q_RES_0402LF-0,5%,1/16W,CHIP,CS00002JB13   I127 @T6G_MB_LIB.T6G(SCH_1):PAGE80
 R6044    1      A Q_RES_0402LF-10K,5%,1/16W,CHIP,CS31002JB08    I33 @T6G_MB_LIB.T6G(SCH_1):PAGE144
   SW1   12     12 SW20S_DHNF10FQTR-SW20S_DHNF-10F-Q-T/R,SMLF,MECH,DHA    I90 @T6G_MB_LIB.T6G(SCH_1):PAGE144

FM_FORCE_ALL_PWRON_ON @T6G_MB_LIB.T6G(SCH_1):FM_FORCE_ALL_PWRON_ON
 R5071    2      B Q_RES_0402LF-100,1%,1/16W,CHIP,CS11002FB07    I34 @T6G_MB_LIB.T6G(SCH_1):PAGE144
   SW1    2      2 SW20S_DHNF10FQTR-SW20S_DHNF-10F-Q-T/R,SMLF,MECH,DHA    I90 @T6G_MB_LIB.T6G(SCH_1):PAGE144

FM_FORCE_ALL_PWRON_R @T6G_MB_LIB.T6G(SCH_1):FM_FORCE_ALL_PWRON_R
 R1202    1      A Q_RES_0402LF-0,5%,1/16W,CHIP,CS00002JB13   I127 @T6G_MB_LIB.T6G(SCH_1):PAGE80
   U18  W20  PR30B LCMXO3LF9400C5BG484C-LCMXO3LF-9400C-5BG484C,SMLF,IA   I217 @T6G_MB_LIB.T6G(SCH_1):PAGE80

FM_FPGA_DEBUG_LED_CTRL @T6G_MB_LIB.T6G(SCH_1):FM_FPGA_DEBUG_LED_CTRL
  R371    2      B Q_RES_0402LF-33,5%,1/16W,CHIP,CS03302JB10   I107 @T6G_MB_LIB.T6G(SCH_1):PAGE80
   U18  J17  PR11B LCMXO3LF9400C5BG484C-LCMXO3LF-9400C-5BG484C,SMLF,IA   I217 @T6G_MB_LIB.T6G(SCH_1):PAGE80

FM_FPGA_DEBUG_SW_SPARE @T6G_MB_LIB.T6G(SCH_1):FM_FPGA_DEBUG_SW_SPARE
 R5099    2      B Q_RES_0402LF-0,5%,1/16W,CHIP,CS00002JB13    I35 @T6G_MB_LIB.T6G(SCH_1):PAGE80
   U18   U8  PB13D LCMXO3LF9400C5BG484C-LCMXO3LF-9400C-5BG484C,SMLF,IA   I216 @T6G_MB_LIB.T6G(SCH_1):PAGE80

FM_G751_0_ALERT_N @T6G_MB_LIB.T6G(SCH_1):FM_G751_0_ALERT_N
 R4215    2      B Q_RES_0402LF-0,5%,1/16W,CHIP,CS00002JB13    I79 @T6G_MB_LIB.T6G(SCH_1):PAGE359
  U270    3     OS LM75BD-LM75BD,SMLF,IC,AL0075BD000   I164 @T6G_MB_LIB.T6G(SCH_1):PAGE359

FM_G751_1_ALERT_N @T6G_MB_LIB.T6G(SCH_1):FM_G751_1_ALERT_N
 R4214    2      B Q_RES_0402LF-0,5%,1/16W,CHIP,CS00002JB13   I108 @T6G_MB_LIB.T6G(SCH_1):PAGE359
  U271    3     OS LM75BD-LM75BD,SMLF,IC,AL0075BD000   I165 @T6G_MB_LIB.T6G(SCH_1):PAGE359

FM_GPU_HSC_EN @T6G_MB_LIB.T6G(SCH_1):FM_GPU_HSC_EN
 R2940    2      B Q_RES_0402LF-4.7K,5%,1/16W,EMPTY,CS24702JB10    I28 @T6G_MB_LIB.T6G(SCH_1):PAGE364
 R2941    1      A Q_RES_0402LF-100K,1%,1/16W,CHIP,CS41002FB09    I29 @T6G_MB_LIB.T6G(SCH_1):PAGE364
  U278    1      A 74LVC1G08W57-74LVC1G08W5-7,SMLF,IC,AL1G0008020    I31 @T6G_MB_LIB.T6G(SCH_1):PAGE364
 R2939    1      A Q_RES_0402LF-33.2,1%,1/16W,CHIP,CS03322FB03   I311 @T6G_MB_LIB.T6G(SCH_1):PAGE80

FM_GPU_HSC_EN_BUF @T6G_MB_LIB.T6G(SCH_1):FM_GPU_HSC_EN_BUF
 R2906    2      B Q_RES_0402LF-0,5%,1/16W,CHIP,CS00002JB13   I440 @T6G_MB_LIB.T6G(SCH_1):PAGE363
 R2944    2      B Q_RES_0402LF-33.2,1%,1/16W,CHIP,CS03322FB03    I24 @T6G_MB_LIB.T6G(SCH_1):PAGE364

FM_GPU_HSC_EN_BUF_R @T6G_MB_LIB.T6G(SCH_1):FM_GPU_HSC_EN_BUF_R
 R2944    1      A Q_RES_0402LF-33.2,1%,1/16W,CHIP,CS03322FB03    I24 @T6G_MB_LIB.T6G(SCH_1):PAGE364
 R2946    2      B Q_RES_0402LF-4.7K,5%,1/16W,EMPTY,CS24702JB10    I25 @T6G_MB_LIB.T6G(SCH_1):PAGE364
 R2948    1      A Q_RES_0402LF-4.7K,5%,1/16W,EMPTY,CS24702JB10    I30 @T6G_MB_LIB.T6G(SCH_1):PAGE364
  U278    4      Y 74LVC1G08W57-74LVC1G08W5-7,SMLF,IC,AL1G0008020    I31 @T6G_MB_LIB.T6G(SCH_1):PAGE364

FM_GPU_HSC_EN_BUF_R1 @T6G_MB_LIB.T6G(SCH_1):FM_GPU_HSC_EN_BUF_R1
 R2906    1      A Q_RES_0402LF-0,5%,1/16W,CHIP,CS00002JB13   I440 @T6G_MB_LIB.T6G(SCH_1):PAGE363
   C67    1      A Q_CAP_0402-0.1UF,25V,10%,EMPTY,CH4104K1B00   I456 @T6G_MB_LIB.T6G(SCH_1):PAGE363
   J45   D2     D2 CONN60_101062636003K02LF-CONN60_10106263-6003K02LFA   I466 @T6G_MB_LIB.T6G(SCH_1):PAGE363

FM_GPU_HSC_EN_R @T6G_MB_LIB.T6G(SCH_1):FM_GPU_HSC_EN_R
   U18  T10  PB19C LCMXO3LF9400C5BG484C-LCMXO3LF-9400C-5BG484C,SMLF,IA   I216 @T6G_MB_LIB.T6G(SCH_1):PAGE80
 R2939    2      B Q_RES_0402LF-33.2,1%,1/16W,CHIP,CS03322FB03   I311 @T6G_MB_LIB.T6G(SCH_1):PAGE80

FM_GPU_PWRGD @T6G_MB_LIB.T6G(SCH_1):FM_GPU_PWRGD
   Q72    2     G1 MOSFET_NCH_DUAL-PJT138K,SMLF,IC,BAM138K0003    I37 @T6G_MB_LIB.T6G(SCH_1):PAGE333
 R3513    1      A Q_RES_0402LF-54.9K,1%,1/16W,CHIP,CS35492FB03   I173 @T6G_MB_LIB.T6G(SCH_1):PAGE333
 R3512    2      B Q_RES_0402LF-100K,1%,1/16W,EMPTY,CS41002FB09   I174 @T6G_MB_LIB.T6G(SCH_1):PAGE333
  J111   N6     N6 CONN112_10137002101LF-CONN112_10137002-101LF,THLF,A    I38 @T6G_MB_LIB.T6G(SCH_1):PAGE328

FM_GPU_PWRGD_ISO @T6G_MB_LIB.T6G(SCH_1):FM_GPU_PWRGD_ISO
 C1756    1      A Q_CAP_0402-0.1UF,25V,10%,X7R,CH4104K1B00   I105 @T6G_MB_LIB.T6G(SCH_1):PAGE333
 R2935    2      B Q_RES_0402LF-100K,1%,1/16W,CHIP,CS41002FB09   I109 @T6G_MB_LIB.T6G(SCH_1):PAGE333
   Q72    3     D2 MOSFET_NCH_DUAL-PJT138K,SMLF,IC,BAM138K0003   I119 @T6G_MB_LIB.T6G(SCH_1):PAGE333
 R2664    2      B Q_RES_0402LF-33.2,1%,1/16W,CHIP,CS03322FB03   I272 @T6G_MB_LIB.T6G(SCH_1):PAGE80

FM_GPU_PWRGD_ISO_R @T6G_MB_LIB.T6G(SCH_1):FM_GPU_PWRGD_ISO_R
   U18 AA18  PB41B LCMXO3LF9400C5BG484C-LCMXO3LF-9400C-5BG484C,SMLF,IA   I216 @T6G_MB_LIB.T6G(SCH_1):PAGE80
 R2664    1      A Q_RES_0402LF-33.2,1%,1/16W,CHIP,CS03322FB03   I272 @T6G_MB_LIB.T6G(SCH_1):PAGE80

FM_GPU_PWRGD_N @T6G_MB_LIB.T6G(SCH_1):FM_GPU_PWRGD_N
 R2842    2      B Q_RES_0402LF-4.7K,5%,1/16W,CHIP,CS24702JB10    I30 @T6G_MB_LIB.T6G(SCH_1):PAGE333
   Q72    6     D1 MOSFET_NCH_DUAL-PJT138K,SMLF,IC,BAM138K0003    I37 @T6G_MB_LIB.T6G(SCH_1):PAGE333
   Q72    5     G2 MOSFET_NCH_DUAL-PJT138K,SMLF,IC,BAM138K0003   I119 @T6G_MB_LIB.T6G(SCH_1):PAGE333

FM_GPU_PWR_EN @T6G_MB_LIB.T6G(SCH_1):FM_GPU_PWR_EN
   U18   W6  PB11C LCMXO3LF9400C5BG484C-LCMXO3LF-9400C-5BG484C,SMLF,IA   I216 @T6G_MB_LIB.T6G(SCH_1):PAGE80
 R2262    2      B Q_RES_0402LF-33.2,1%,1/16W,CHIP,CS03322FB03   I294 @T6G_MB_LIB.T6G(SCH_1):PAGE80

FM_GPU_PWR_EN_R @T6G_MB_LIB.T6G(SCH_1):FM_GPU_PWR_EN_R
  U196    1     A0 74LVC2G17GW-74LVC2G17GW,SMLF,IC,AL2G0017005   I127 @T6G_MB_LIB.T6G(SCH_1):PAGE256
 R2937    1      A Q_RES_0402LF-4.7K,5%,1/16W,CHIP,CS24702JB10   I160 @T6G_MB_LIB.T6G(SCH_1):PAGE256
 R2936    2      B Q_RES_0402LF-100K,1%,1/16W,EMPTY,CS41002FB09   I162 @T6G_MB_LIB.T6G(SCH_1):PAGE256
 R2262    1      A Q_RES_0402LF-33.2,1%,1/16W,CHIP,CS03322FB03   I294 @T6G_MB_LIB.T6G(SCH_1):PAGE80

FM_GPU_PWR_EN_R1 @T6G_MB_LIB.T6G(SCH_1):FM_GPU_PWR_EN_R1
  U196    6     B0 74LVC2G17GW-74LVC2G17GW,SMLF,IC,AL2G0017005   I127 @T6G_MB_LIB.T6G(SCH_1):PAGE256
 R2912    2      B Q_RES_0402LF-4.7K,5%,1/16W,EMPTY,CS24702JB10   I147 @T6G_MB_LIB.T6G(SCH_1):PAGE256
 R2925    1      A Q_RES_0402LF-49.9,1%,1/16W,CHIP,CS04992FB07   I156 @T6G_MB_LIB.T6G(SCH_1):PAGE256
 R3508    1      A Q_RES_0402LF-54.9K,1%,1/16W,CHIP,CS35492FB03   I194 @T6G_MB_LIB.T6G(SCH_1):PAGE256

FM_GPU_PWR_EN_R_BUF @T6G_MB_LIB.T6G(SCH_1):FM_GPU_PWR_EN_R_BUF
 R2925    2      B Q_RES_0402LF-49.9,1%,1/16W,CHIP,CS04992FB07   I156 @T6G_MB_LIB.T6G(SCH_1):PAGE256
  J111   N4     N4 CONN112_10137002101LF-CONN112_10137002-101LF,THLF,A    I76 @T6G_MB_LIB.T6G(SCH_1):PAGE328

FM_HDT_HDR_PWROK @T6G_MB_LIB.T6G(SCH_1):FM_HDT_HDR_PWROK
  R708    1      A Q_RES_0402LF-33,5%,1/16W,CHIP,CS03302JB10   I168 @T6G_MB_LIB.T6G(SCH_1):PAGE80
   U18  P16  PR24B LCMXO3LF9400C5BG484C-LCMXO3LF-9400C-5BG484C,SMLF,IA   I217 @T6G_MB_LIB.T6G(SCH_1):PAGE80

FM_HDT_HDR_RESET_N @T6G_MB_LIB.T6G(SCH_1):FM_HDT_HDR_RESET_N
  R856    1      A Q_RES_0402LF-0,5%,1/16W,CHIP,CS00002JB13   I167 @T6G_MB_LIB.T6G(SCH_1):PAGE80
   U18  U22  PR24C LCMXO3LF9400C5BG484C-LCMXO3LF-9400C-5BG484C,SMLF,IA   I217 @T6G_MB_LIB.T6G(SCH_1):PAGE80

FM_I3C_CPU0_MUX0_OE_N @T6G_MB_LIB.T6G(SCH_1):FM_I3C_CPU0_MUX0_OE_N
  U105    6    OE# PI3CSW12ZUAEX-PI3CSW12ZUAEX,SMLF,IC,AL3CSW12000    I47 @T6G_MB_LIB.T6G(SCH_1):PAGE136
  R163    2      B Q_RES_0402LF-33,5%,1/16W,CHIP,CS03302JB10    I54 @T6G_MB_LIB.T6G(SCH_1):PAGE79
   R10    1      A Q_RES_0402LF-10K,1%,1/16W,CHIP,CS31002FB08    I93 @T6G_MB_LIB.T6G(SCH_1):PAGE82

FM_I3C_CPU0_MUX0_OE_R_N @T6G_MB_LIB.T6G(SCH_1):FM_I3C_CPU0_MUX0_OE_R_N
  R163    1      A Q_RES_0402LF-33,5%,1/16W,CHIP,CS03302JB10    I54 @T6G_MB_LIB.T6G(SCH_1):PAGE79
   U18   B1 PT9A||L_GPLLT LCMXO3LF9400C5BG484C-LCMXO3LF-9400C-5BG484C,SMLF,IA    I94 @T6G_MB_LIB.T6G(SCH_1):PAGE79

FM_I3C_CPU0_MUX0_R_SEL @T6G_MB_LIB.T6G(SCH_1):FM_I3C_CPU0_MUX0_R_SEL
  R164    1      A Q_RES_0402LF-33,5%,1/16W,CHIP,CS03302JB10    I50 @T6G_MB_LIB.T6G(SCH_1):PAGE79
   U18   C3  PT10C LCMXO3LF9400C5BG484C-LCMXO3LF-9400C-5BG484C,SMLF,IA    I94 @T6G_MB_LIB.T6G(SCH_1):PAGE79

FM_I3C_CPU0_MUX0_SEL @T6G_MB_LIB.T6G(SCH_1):FM_I3C_CPU0_MUX0_SEL
  U105    9      S PI3CSW12ZUAEX-PI3CSW12ZUAEX,SMLF,IC,AL3CSW12000    I47 @T6G_MB_LIB.T6G(SCH_1):PAGE136
  R164    2      B Q_RES_0402LF-33,5%,1/16W,CHIP,CS03302JB10    I50 @T6G_MB_LIB.T6G(SCH_1):PAGE79

FM_I3C_CPU0_MUX1_OE_N @T6G_MB_LIB.T6G(SCH_1):FM_I3C_CPU0_MUX1_OE_N
  U106    6    OE# PI3CSW12ZUAEX-PI3CSW12ZUAEX,SMLF,IC,AL3CSW12000    I54 @T6G_MB_LIB.T6G(SCH_1):PAGE136
  R165    2      B Q_RES_0402LF-33,5%,1/16W,CHIP,CS03302JB10    I47 @T6G_MB_LIB.T6G(SCH_1):PAGE79
   R11    1      A Q_RES_0402LF-10K,1%,1/16W,CHIP,CS31002FB08    I94 @T6G_MB_LIB.T6G(SCH_1):PAGE82

FM_I3C_CPU0_MUX1_OE_R_N @T6G_MB_LIB.T6G(SCH_1):FM_I3C_CPU0_MUX1_OE_R_N
  R165    1      A Q_RES_0402LF-33,5%,1/16W,CHIP,CS03302JB10    I47 @T6G_MB_LIB.T6G(SCH_1):PAGE79
   U18   C4  PT10D LCMXO3LF9400C5BG484C-LCMXO3LF-9400C-5BG484C,SMLF,IA    I94 @T6G_MB_LIB.T6G(SCH_1):PAGE79

FM_I3C_CPU0_MUX1_R_SEL @T6G_MB_LIB.T6G(SCH_1):FM_I3C_CPU0_MUX1_R_SEL
  R166    1      A Q_RES_0402LF-33,5%,1/16W,CHIP,CS03302JB10    I51 @T6G_MB_LIB.T6G(SCH_1):PAGE79
   U18   F7   PT9D LCMXO3LF9400C5BG484C-LCMXO3LF-9400C-5BG484C,SMLF,IA    I94 @T6G_MB_LIB.T6G(SCH_1):PAGE79

FM_I3C_CPU0_MUX1_SEL @T6G_MB_LIB.T6G(SCH_1):FM_I3C_CPU0_MUX1_SEL
  U106    9      S PI3CSW12ZUAEX-PI3CSW12ZUAEX,SMLF,IC,AL3CSW12000    I54 @T6G_MB_LIB.T6G(SCH_1):PAGE136
  R166    2      B Q_RES_0402LF-33,5%,1/16W,CHIP,CS03302JB10    I51 @T6G_MB_LIB.T6G(SCH_1):PAGE79

FM_I3C_CPU1_MUX0_OE_N @T6G_MB_LIB.T6G(SCH_1):FM_I3C_CPU1_MUX0_OE_N
  U107    6    OE# PI3CSW12ZUAEX-PI3CSW12ZUAEX,SMLF,IC,AL3CSW12000    I63 @T6G_MB_LIB.T6G(SCH_1):PAGE136
  R169    2      B Q_RES_0402LF-33,5%,1/16W,CHIP,CS03302JB10    I48 @T6G_MB_LIB.T6G(SCH_1):PAGE79
   R12    1      A Q_RES_0402LF-10K,1%,1/16W,CHIP,CS31002FB08    I95 @T6G_MB_LIB.T6G(SCH_1):PAGE82

FM_I3C_CPU1_MUX0_OE_R_N @T6G_MB_LIB.T6G(SCH_1):FM_I3C_CPU1_MUX0_OE_R_N
  R169    1      A Q_RES_0402LF-33,5%,1/16W,CHIP,CS03302JB10    I48 @T6G_MB_LIB.T6G(SCH_1):PAGE79
   U18   B2  PT10A LCMXO3LF9400C5BG484C-LCMXO3LF-9400C-5BG484C,SMLF,IA    I94 @T6G_MB_LIB.T6G(SCH_1):PAGE79

FM_I3C_CPU1_MUX0_R_SEL @T6G_MB_LIB.T6G(SCH_1):FM_I3C_CPU1_MUX0_R_SEL
  R170    1      A Q_RES_0402LF-33,5%,1/16W,CHIP,CS03302JB10    I53 @T6G_MB_LIB.T6G(SCH_1):PAGE79
   U18   A2 PT9B||L_GPLLC LCMXO3LF9400C5BG484C-LCMXO3LF-9400C-5BG484C,SMLF,IA    I94 @T6G_MB_LIB.T6G(SCH_1):PAGE79

FM_I3C_CPU1_MUX0_SEL @T6G_MB_LIB.T6G(SCH_1):FM_I3C_CPU1_MUX0_SEL
  U107    9      S PI3CSW12ZUAEX-PI3CSW12ZUAEX,SMLF,IC,AL3CSW12000    I63 @T6G_MB_LIB.T6G(SCH_1):PAGE136
  R170    2      B Q_RES_0402LF-33,5%,1/16W,CHIP,CS03302JB10    I53 @T6G_MB_LIB.T6G(SCH_1):PAGE79

FM_I3C_CPU1_MUX1_OE_N @T6G_MB_LIB.T6G(SCH_1):FM_I3C_CPU1_MUX1_OE_N
  U108    6    OE# PI3CSW12ZUAEX-PI3CSW12ZUAEX,SMLF,IC,AL3CSW12000    I68 @T6G_MB_LIB.T6G(SCH_1):PAGE136
  R171    2      B Q_RES_0402LF-33,5%,1/16W,CHIP,CS03302JB10    I52 @T6G_MB_LIB.T6G(SCH_1):PAGE79
   R25    1      A Q_RES_0402LF-10K,1%,1/16W,CHIP,CS31002FB08    I97 @T6G_MB_LIB.T6G(SCH_1):PAGE82

FM_I3C_CPU1_MUX1_OE_R_N @T6G_MB_LIB.T6G(SCH_1):FM_I3C_CPU1_MUX1_OE_R_N
  R171    1      A Q_RES_0402LF-33,5%,1/16W,CHIP,CS03302JB10    I52 @T6G_MB_LIB.T6G(SCH_1):PAGE79
   U18   E6   PT9C LCMXO3LF9400C5BG484C-LCMXO3LF-9400C-5BG484C,SMLF,IA    I94 @T6G_MB_LIB.T6G(SCH_1):PAGE79

FM_I3C_CPU1_MUX1_R_SEL @T6G_MB_LIB.T6G(SCH_1):FM_I3C_CPU1_MUX1_R_SEL
  R172    1      A Q_RES_0402LF-33,5%,1/16W,CHIP,CS03302JB10    I43 @T6G_MB_LIB.T6G(SCH_1):PAGE79
   U18   D5  PT12C LCMXO3LF9400C5BG484C-LCMXO3LF-9400C-5BG484C,SMLF,IA    I94 @T6G_MB_LIB.T6G(SCH_1):PAGE79

FM_I3C_CPU1_MUX1_SEL @T6G_MB_LIB.T6G(SCH_1):FM_I3C_CPU1_MUX1_SEL
  U108    9      S PI3CSW12ZUAEX-PI3CSW12ZUAEX,SMLF,IC,AL3CSW12000    I68 @T6G_MB_LIB.T6G(SCH_1):PAGE136
  R172    2      B Q_RES_0402LF-33,5%,1/16W,CHIP,CS03302JB10    I43 @T6G_MB_LIB.T6G(SCH_1):PAGE79

FM_INT_CPU0_HP_UBM_N @T6G_MB_LIB.T6G(SCH_1):FM_INT_CPU0_HP_UBM_N
   R81    2      B Q_RES_0402LF-33,5%,1/16W,CHIP,CS03302JB10   I106 @T6G_MB_LIB.T6G(SCH_1):PAGE81
  R207    1      A Q_RES_0402LF-2.2K,5%,1/16W,CHIP,CS22202JB07    I44 @T6G_MB_LIB.T6G(SCH_1):PAGE28
   U25 DJ35 GENINT_L||PM_INTR_L||UBM_CPRSNT_CHANGE_DET_L||AGPIO89 GENOA_SP5-SOCKET6096_13568-001,SMLF,IO,DGA^6000030   I188 @T6G_MB_LIB.T6G(SCH_1):PAGE28

FM_INT_CPU0_HP_UBM_R_N @T6G_MB_LIB.T6G(SCH_1):FM_INT_CPU0_HP_UBM_R_N
   U18   J3  PL11D LCMXO3LF9400C5BG484C-LCMXO3LF-9400C-5BG484C,SMLF,IA   I143 @T6G_MB_LIB.T6G(SCH_1):PAGE81
   R81    1      A Q_RES_0402LF-33,5%,1/16W,CHIP,CS03302JB10   I106 @T6G_MB_LIB.T6G(SCH_1):PAGE81

FM_JTAG_BMC_OE @T6G_MB_LIB.T6G(SCH_1):FM_JTAG_BMC_OE
   U18  R22  PR20A LCMXO3LF9400C5BG484C-LCMXO3LF-9400C-5BG484C,SMLF,IA   I217 @T6G_MB_LIB.T6G(SCH_1):PAGE80
 R8021    1      A Q_RES_0402LF-0,5%,1/16W,CHIP,CS00002JB13   I318 @T6G_MB_LIB.T6G(SCH_1):PAGE80

FM_JTAG_BMC_R_OE @T6G_MB_LIB.T6G(SCH_1):FM_JTAG_BMC_R_OE
  U124    2      A SN74LVC1G07DBVR_SMLF-SN74LVC1G07DBVR,IC,AL1G0007024    I38 @T6G_MB_LIB.T6G(SCH_1):PAGE144
  R733    2      B Q_RES_0402LF-100,1%,1/16W,EMPTY,CS11002FB07    I50 @T6G_MB_LIB.T6G(SCH_1):PAGE144
 R8021    2      B Q_RES_0402LF-0,5%,1/16W,CHIP,CS00002JB13   I318 @T6G_MB_LIB.T6G(SCH_1):PAGE80
 R8019    2      B Q_RES_0402LF-100,1%,1/16W,EMPTY,CS11002FB07    I89 @T6G_MB_LIB.T6G(SCH_1):PAGE144

FM_LED_ACTIVE_E1S_0 @T6G_MB_LIB.T6G(SCH_1):FM_LED_ACTIVE_E1S_0
  R955    1      A Q_RES_0402LF-0,5%,1/16W,CHIP,CS00002JB13    I94 @T6G_MB_LIB.T6G(SCH_1):PAGE297
   U18  E10  PT22B LCMXO3LF9400C5BG484C-LCMXO3LF-9400C-5BG484C,SMLF,IA    I94 @T6G_MB_LIB.T6G(SCH_1):PAGE79

FM_LED_ACTIVE_E1S_0_BUF @T6G_MB_LIB.T6G(SCH_1):FM_LED_ACTIVE_E1S_0_BUF
   J90  A10 LED#_ACTIVITY SCONN56_123276793-SCONN56_1-2327679-3,SMLF,IO,DFHSA    I90 @T6G_MB_LIB.T6G(SCH_1):PAGE297
 R1038    2      B Q_RES_0402LF-0,5%,1/16W,CHIP,CS00002JB13   I101 @T6G_MB_LIB.T6G(SCH_1):PAGE297
 R1000    1      A Q_RES_0402LF-4.7K,5%,1/16W,CHIP,CS24702JB10   I102 @T6G_MB_LIB.T6G(SCH_1):PAGE297

FM_LED_ACTIVE_E1S_0_R @T6G_MB_LIB.T6G(SCH_1):FM_LED_ACTIVE_E1S_0_R
  R955    2      B Q_RES_0402LF-0,5%,1/16W,CHIP,CS00002JB13    I94 @T6G_MB_LIB.T6G(SCH_1):PAGE297
  R999    1      A Q_RES_0402LF-4.7K,5%,1/16W,CHIP,CS24702JB10    I95 @T6G_MB_LIB.T6G(SCH_1):PAGE297
   U44    2      A 74LVC1G17GW-74LVC1G17GW,SMLF,IC,AL1G0017K01    I97 @T6G_MB_LIB.T6G(SCH_1):PAGE297

FM_LED_ACTIVE_E1S_0_R_BUF @T6G_MB_LIB.T6G(SCH_1):FM_LED_ACTIVE_E1S_0_R_BUF
   U44    4      Y 74LVC1G17GW-74LVC1G17GW,SMLF,IC,AL1G0017K01    I97 @T6G_MB_LIB.T6G(SCH_1):PAGE297
 R1038    1      A Q_RES_0402LF-0,5%,1/16W,CHIP,CS00002JB13   I101 @T6G_MB_LIB.T6G(SCH_1):PAGE297

FM_LED_PWRGD_PVDD11_S3_P0 @T6G_MB_LIB.T6G(SCH_1):FM_LED_PWRGD_PVDD11_S3_P0
   U18  Y12  PB27A LCMXO3LF9400C5BG484C-LCMXO3LF-9400C-5BG484C,SMLF,IA   I216 @T6G_MB_LIB.T6G(SCH_1):PAGE80
   Q81    5     G2 MOSFET_NCH_DUAL-PJT138K,SMLF,IC,BAM138K0003    I27 @T6G_MB_LIB.T6G(SCH_1):PAGE374

FM_LED_PWRGD_PVDD11_S3_P1 @T6G_MB_LIB.T6G(SCH_1):FM_LED_PWRGD_PVDD11_S3_P1
   U18  B19  PT41B LCMXO3LF9400C5BG484C-LCMXO3LF-9400C-5BG484C,SMLF,IA    I94 @T6G_MB_LIB.T6G(SCH_1):PAGE79
   Q86    2     G1 MOSFET_NCH_DUAL-PJT138K,SMLF,IC,BAM138K0003    I30 @T6G_MB_LIB.T6G(SCH_1):PAGE375

FM_LED_PWRGD_PVDD18_S5_P0 @T6G_MB_LIB.T6G(SCH_1):FM_LED_PWRGD_PVDD18_S5_P0
   U18 AB11  PB24B LCMXO3LF9400C5BG484C-LCMXO3LF-9400C-5BG484C,SMLF,IA   I216 @T6G_MB_LIB.T6G(SCH_1):PAGE80
   Q83    2     G1 MOSFET_NCH_DUAL-PJT138K,SMLF,IC,BAM138K0003    I23 @T6G_MB_LIB.T6G(SCH_1):PAGE374

FM_LED_PWRGD_PVDD18_S5_P1 @T6G_MB_LIB.T6G(SCH_1):FM_LED_PWRGD_PVDD18_S5_P1
   U18  A19  PT42A LCMXO3LF9400C5BG484C-LCMXO3LF-9400C-5BG484C,SMLF,IA    I94 @T6G_MB_LIB.T6G(SCH_1):PAGE79
   Q86    5     G2 MOSFET_NCH_DUAL-PJT138K,SMLF,IC,BAM138K0003    I29 @T6G_MB_LIB.T6G(SCH_1):PAGE375

FM_LED_PWRGD_PVDD33_S5 @T6G_MB_LIB.T6G(SCH_1):FM_LED_PWRGD_PVDD33_S5
   U18  T11  PB22C LCMXO3LF9400C5BG484C-LCMXO3LF-9400C-5BG484C,SMLF,IA   I216 @T6G_MB_LIB.T6G(SCH_1):PAGE80
   Q79    2     G1 MOSFET_NCH_DUAL-PJT138K,SMLF,IC,BAM138K0003    I18 @T6G_MB_LIB.T6G(SCH_1):PAGE374

FM_LED_PWRGD_PVDDCR_CPU0_P0 @T6G_MB_LIB.T6G(SCH_1):FM_LED_PWRGD_PVDDCR_CPU0_P0
   U18   U5  PL28D LCMXO3LF9400C5BG484C-LCMXO3LF-9400C-5BG484C,SMLF,IA   I143 @T6G_MB_LIB.T6G(SCH_1):PAGE81
   Q79    5     G2 MOSFET_NCH_DUAL-PJT138K,SMLF,IC,BAM138K0003     I8 @T6G_MB_LIB.T6G(SCH_1):PAGE374

FM_LED_PWRGD_PVDDCR_CPU0_P1 @T6G_MB_LIB.T6G(SCH_1):FM_LED_PWRGD_PVDDCR_CPU0_P1
   U18  V10  PB21A LCMXO3LF9400C5BG484C-LCMXO3LF-9400C-5BG484C,SMLF,IA   I216 @T6G_MB_LIB.T6G(SCH_1):PAGE80
   Q84    2     G1 MOSFET_NCH_DUAL-PJT138K,SMLF,IC,BAM138K0003    I11 @T6G_MB_LIB.T6G(SCH_1):PAGE375

FM_LED_PWRGD_PVDDCR_CPU1_P0 @T6G_MB_LIB.T6G(SCH_1):FM_LED_PWRGD_PVDDCR_CPU1_P0
   U18   R5  PL24C LCMXO3LF9400C5BG484C-LCMXO3LF-9400C-5BG484C,SMLF,IA   I143 @T6G_MB_LIB.T6G(SCH_1):PAGE81
   Q80    5     G2 MOSFET_NCH_DUAL-PJT138K,SMLF,IC,BAM138K0003     I3 @T6G_MB_LIB.T6G(SCH_1):PAGE374

FM_LED_PWRGD_PVDDCR_CPU1_P1 @T6G_MB_LIB.T6G(SCH_1):FM_LED_PWRGD_PVDDCR_CPU1_P1
   U18  E16  PT40C LCMXO3LF9400C5BG484C-LCMXO3LF-9400C-5BG484C,SMLF,IA    I94 @T6G_MB_LIB.T6G(SCH_1):PAGE79
   Q85    2     G1 MOSFET_NCH_DUAL-PJT138K,SMLF,IC,BAM138K0003     I7 @T6G_MB_LIB.T6G(SCH_1):PAGE375

FM_LED_PWRGD_PVDDCR_SOC_P0 @T6G_MB_LIB.T6G(SCH_1):FM_LED_PWRGD_PVDDCR_SOC_P0
   U18   V4  PL28C LCMXO3LF9400C5BG484C-LCMXO3LF-9400C-5BG484C,SMLF,IA   I143 @T6G_MB_LIB.T6G(SCH_1):PAGE81
   Q80    2     G1 MOSFET_NCH_DUAL-PJT138K,SMLF,IC,BAM138K0003     I6 @T6G_MB_LIB.T6G(SCH_1):PAGE374

FM_LED_PWRGD_PVDDCR_SOC_P1 @T6G_MB_LIB.T6G(SCH_1):FM_LED_PWRGD_PVDDCR_SOC_P1
   U18  B18  PT40B LCMXO3LF9400C5BG484C-LCMXO3LF-9400C-5BG484C,SMLF,IA    I94 @T6G_MB_LIB.T6G(SCH_1):PAGE79
   Q84    5     G2 MOSFET_NCH_DUAL-PJT138K,SMLF,IC,BAM138K0003    I10 @T6G_MB_LIB.T6G(SCH_1):PAGE375

FM_LED_PWRGD_PVDDIO_P0 @T6G_MB_LIB.T6G(SCH_1):FM_LED_PWRGD_PVDDIO_P0
   U18  Y11  PB24D LCMXO3LF9400C5BG484C-LCMXO3LF-9400C-5BG484C,SMLF,IA   I216 @T6G_MB_LIB.T6G(SCH_1):PAGE80
   Q81    2     G1 MOSFET_NCH_DUAL-PJT138K,SMLF,IC,BAM138K0003    I35 @T6G_MB_LIB.T6G(SCH_1):PAGE374

FM_LED_PWRGD_PVDDIO_P1 @T6G_MB_LIB.T6G(SCH_1):FM_LED_PWRGD_PVDDIO_P1
   U18  A18  PT41A LCMXO3LF9400C5BG484C-LCMXO3LF-9400C-5BG484C,SMLF,IA    I94 @T6G_MB_LIB.T6G(SCH_1):PAGE79
   Q85    5     G2 MOSFET_NCH_DUAL-PJT138K,SMLF,IC,BAM138K0003     I2 @T6G_MB_LIB.T6G(SCH_1):PAGE375

FM_LM75_2_ALERT_N @T6G_MB_LIB.T6G(SCH_1):FM_LM75_2_ALERT_N
 R4213    2      B Q_RES_0402LF-0,5%,1/16W,CHIP,CS00002JB13   I115 @T6G_MB_LIB.T6G(SCH_1):PAGE359
  U272    3     OS LM75BD-LM75BD,SMLF,IC,AL0075BD000   I166 @T6G_MB_LIB.T6G(SCH_1):PAGE359

FM_LM75_3_ALERT_N @T6G_MB_LIB.T6G(SCH_1):FM_LM75_3_ALERT_N
 R4212    2      B Q_RES_0402LF-0,5%,1/16W,CHIP,CS00002JB13   I135 @T6G_MB_LIB.T6G(SCH_1):PAGE359
  U273    3     OS LM75BD-LM75BD,SMLF,IC,AL0075BD000   I167 @T6G_MB_LIB.T6G(SCH_1):PAGE359

FM_LPC_ESPI_SEL @T6G_MB_LIB.T6G(SCH_1):FM_LPC_ESPI_SEL
   J41   B9  BIF2# SCONN168_ME1016810202011-SCONN168_ME1016810202011,A   I176 @T6G_MB_LIB.T6G(SCH_1):PAGE348
 R6028    1      A Q_RES_0402LF-0,5%,1/16W,CHIP,CS00002JB13   I174 @T6G_MB_LIB.T6G(SCH_1):PAGE348

FM_M2_SSD_0_PEDET @T6G_MB_LIB.T6G(SCH_1):FM_M2_SSD_0_PEDET
   J59   69  PEDET SCONN75K_APCI0155P004A-SCONN75K_APCI0155-P004A,SMLA    I88 @T6G_MB_LIB.T6G(SCH_1):PAGE345
 R1396    1      A Q_RES_0402LF-10K,1%,1/16W,CHIP,CS31002FB08    I66 @T6G_MB_LIB.T6G(SCH_1):PAGE345

FM_NCSI_OCP_SFF_R_OE @T6G_MB_LIB.T6G(SCH_1):FM_NCSI_OCP_SFF_R_OE
 R1282    1      A Q_RES_0402LF-33,5%,1/16W,CHIP,CS03302JB10    I29 @T6G_MB_LIB.T6G(SCH_1):PAGE80
 R2474    1      A Q_RES_0402LF-0,5%,1/16W,EMPTY,CS00002JB13   I165 @T6G_MB_LIB.T6G(SCH_1):PAGE336

FM_NCSI_OCP_V3_2_R_OE @T6G_MB_LIB.T6G(SCH_1):FM_NCSI_OCP_V3_2_R_OE
   U18  U16  PB43D LCMXO3LF9400C5BG484C-LCMXO3LF-9400C-5BG484C,SMLF,IA   I216 @T6G_MB_LIB.T6G(SCH_1):PAGE80
 R3206    1      A Q_RES_0402LF-0,5%,1/16W,EMPTY,CS00002JB13    I85 @T6G_MB_LIB.T6G(SCH_1):PAGE307

FM_OCP_SFF_PWR_GOOD @T6G_MB_LIB.T6G(SCH_1):FM_OCP_SFF_PWR_GOOD
 R3132    2      B Q_RES_0402LF-100K,1%,1/16W,CHIP,CS41002FB09     I6 @T6G_MB_LIB.T6G(SCH_1):PAGE335
   J38  OB1 NIC_PWR_GOOD SCONN168_ME1016810202011-SCONN168_ME1016810202011,A   I168 @T6G_MB_LIB.T6G(SCH_1):PAGE335
   U66    2      A 74LVC1G126SE7-74LVC1G126SE-7,SMLF,IC,AL1G0126009   I157 @T6G_MB_LIB.T6G(SCH_1):PAGE336
 R6054    1      A Q_RES_0402LF-0,5%,1/16W,CHIP,CS00002JB13    I83 @T6G_MB_LIB.T6G(SCH_1):PAGE81

FM_OCP_V3_2_AUX_PWR_EN @T6G_MB_LIB.T6G(SCH_1):FM_OCP_V3_2_AUX_PWR_EN
   U18  C18  PT41C LCMXO3LF9400C5BG484C-LCMXO3LF-9400C-5BG484C,SMLF,IA    I94 @T6G_MB_LIB.T6G(SCH_1):PAGE79
 R1179    2      B Q_RES_0402LF-0,5%,1/16W,CHIP,CS00002JB13   I155 @T6G_MB_LIB.T6G(SCH_1):PAGE79

FM_OCP_V3_2_AUX_PWR_R_EN @T6G_MB_LIB.T6G(SCH_1):FM_OCP_V3_2_AUX_PWR_R_EN
 R1176    2      B Q_RES_0402LF-10K,1%,1/16W,CHIP,CS31002FB08    I10 @T6G_MB_LIB.T6G(SCH_1):PAGE257
 R1147    2      B Q_RES_0402LF-0,5%,1/16W,EMPTY,CS00002JB13    I39 @T6G_MB_LIB.T6G(SCH_1):PAGE257
   U37    2     I1 74LVC1G32GW_SMLF-74LVC1G32GW,IC,ALVC1G32007    I40 @T6G_MB_LIB.T6G(SCH_1):PAGE257
 R1179    1      A Q_RES_0402LF-0,5%,1/16W,CHIP,CS00002JB13   I155 @T6G_MB_LIB.T6G(SCH_1):PAGE79

FM_OCP_V3_2_PWR_GOOD @T6G_MB_LIB.T6G(SCH_1):FM_OCP_V3_2_PWR_GOOD
  U286    2      A 74LVC1G126SE7-74LVC1G126SE-7,SMLF,IC,AL1G0126009    I80 @T6G_MB_LIB.T6G(SCH_1):PAGE307
 R8413    2      B Q_RES_0402LF-100K,1%,1/16W,CHIP,CS41002FB09    I33 @T6G_MB_LIB.T6G(SCH_1):PAGE341
   J35  OB1 NIC_PWR_GOOD SCONN168_ME1016810202011-SCONN168_ME1016810202011,A   I168 @T6G_MB_LIB.T6G(SCH_1):PAGE341
   U18  B22 PT44B||R_GPLLC LCMXO3LF9400C5BG484C-LCMXO3LF-9400C-5BG484C,SMLF,IA    I94 @T6G_MB_LIB.T6G(SCH_1):PAGE79

FM_P0_PCC0_N @T6G_MB_LIB.T6G(SCH_1):FM_P0_PCC0_N
   U25  C22 PCC0_L GENOA_SP5-SOCKET6096_13568-001,SMLF,IO,DGA^6000030   I227 @T6G_MB_LIB.T6G(SCH_1):PAGE27
 R1280    1      A Q_RES_0402LF-33,5%,1/16W,CHIP,CS03302JB10   I102 @T6G_MB_LIB.T6G(SCH_1):PAGE80
 R1287    1      A Q_RES_0402LF-4.7K,5%,1/16W,CHIP,CS24702JB10    I74 @T6G_MB_LIB.T6G(SCH_1):PAGE82

FM_P0_PCC0_R_N @T6G_MB_LIB.T6G(SCH_1):FM_P0_PCC0_R_N
 R1280    2      B Q_RES_0402LF-33,5%,1/16W,CHIP,CS03302JB10   I102 @T6G_MB_LIB.T6G(SCH_1):PAGE80
   U18  K17  PR13C LCMXO3LF9400C5BG484C-LCMXO3LF-9400C-5BG484C,SMLF,IA   I217 @T6G_MB_LIB.T6G(SCH_1):PAGE80

FM_P0_PCC1_N @T6G_MB_LIB.T6G(SCH_1):FM_P0_PCC1_N
   U25 DG72 PCC1_L GENOA_SP5-SOCKET6096_13568-001,SMLF,IO,DGA^6000030   I227 @T6G_MB_LIB.T6G(SCH_1):PAGE27
 R1281    1      A Q_RES_0402LF-33,5%,1/16W,CHIP,CS03302JB10   I101 @T6G_MB_LIB.T6G(SCH_1):PAGE80
 R1288    1      A Q_RES_0402LF-4.7K,5%,1/16W,CHIP,CS24702JB10    I73 @T6G_MB_LIB.T6G(SCH_1):PAGE82

FM_P0_PCC1_R_N @T6G_MB_LIB.T6G(SCH_1):FM_P0_PCC1_R_N
 R1281    2      B Q_RES_0402LF-33,5%,1/16W,CHIP,CS03302JB10   I101 @T6G_MB_LIB.T6G(SCH_1):PAGE80
   U18  K18  PR13B LCMXO3LF9400C5BG484C-LCMXO3LF-9400C-5BG484C,SMLF,IA   I217 @T6G_MB_LIB.T6G(SCH_1):PAGE80

FM_P12V_HSC_EN_N @T6G_MB_LIB.T6G(SCH_1):FM_P12V_HSC_EN_N
  U158    D      D MOSFET_NCH_GDS_ESD_PROTECTED-2N7002K,SMLF,IC,BAM70A     I6 @T6G_MB_LIB.T6G(SCH_1):PAGE365
 R2529    1      A Q_RES_0402LF-0,5%,1/16W,CHIP,CS00002JB13     I7 @T6G_MB_LIB.T6G(SCH_1):PAGE365
 R2528    2      B Q_RES_0402LF-100K,1%,1/16W,CHIP,CS41002FB09     I8 @T6G_MB_LIB.T6G(SCH_1):PAGE365

FM_P12V_HSC_EN_R @T6G_MB_LIB.T6G(SCH_1):FM_P12V_HSC_EN_R
 R2531    2      B Q_RES_0402LF-0,5%,1/16W,CHIP,CS00002JB13     I3 @T6G_MB_LIB.T6G(SCH_1):PAGE365
  U158    G      G MOSFET_NCH_GDS_ESD_PROTECTED-2N7002K,SMLF,IC,BAM70A     I6 @T6G_MB_LIB.T6G(SCH_1):PAGE365

FM_P12V_HSC_EN_R_N @T6G_MB_LIB.T6G(SCH_1):FM_P12V_HSC_EN_R_N
 R2529    2      B Q_RES_0402LF-0,5%,1/16W,CHIP,CS00002JB13     I7 @T6G_MB_LIB.T6G(SCH_1):PAGE365
   Q54    G      G MOSFET_NCH_GDS_ESD_PROTECTED-2N7002K,SMLF,IC,BAM70A    I14 @T6G_MB_LIB.T6G(SCH_1):PAGE365

FM_P1_PCC0_N @T6G_MB_LIB.T6G(SCH_1):FM_P1_PCC0_N
   U26  C22 PCC0_L GENOA_SP5-SOCKET6096_13568-001,SMLF,IO,DGA^6000030   I190 @T6G_MB_LIB.T6G(SCH_1):PAGE54
 R1278    1      A Q_RES_0402LF-33,5%,1/16W,CHIP,CS03302JB10   I105 @T6G_MB_LIB.T6G(SCH_1):PAGE80
 R1285    1      A Q_RES_0402LF-4.7K,5%,1/16W,CHIP,CS24702JB10    I77 @T6G_MB_LIB.T6G(SCH_1):PAGE82

FM_P1_PCC0_R_N @T6G_MB_LIB.T6G(SCH_1):FM_P1_PCC0_R_N
 R1278    2      B Q_RES_0402LF-33,5%,1/16W,CHIP,CS03302JB10   I105 @T6G_MB_LIB.T6G(SCH_1):PAGE80
   U18  J19  PR11D LCMXO3LF9400C5BG484C-LCMXO3LF-9400C-5BG484C,SMLF,IA   I217 @T6G_MB_LIB.T6G(SCH_1):PAGE80

FM_P1_PCC1_N @T6G_MB_LIB.T6G(SCH_1):FM_P1_PCC1_N
   U26 DG72 PCC1_L GENOA_SP5-SOCKET6096_13568-001,SMLF,IO,DGA^6000030   I190 @T6G_MB_LIB.T6G(SCH_1):PAGE54
 R1279    1      A Q_RES_0402LF-33,5%,1/16W,CHIP,CS03302JB10   I103 @T6G_MB_LIB.T6G(SCH_1):PAGE80
 R1286    1      A Q_RES_0402LF-4.7K,5%,1/16W,CHIP,CS24702JB10    I76 @T6G_MB_LIB.T6G(SCH_1):PAGE82

FM_P1_PCC1_R_N @T6G_MB_LIB.T6G(SCH_1):FM_P1_PCC1_R_N
 R1279    2      B Q_RES_0402LF-33,5%,1/16W,CHIP,CS03302JB10   I103 @T6G_MB_LIB.T6G(SCH_1):PAGE80
   U18  J20  PR12C LCMXO3LF9400C5BG484C-LCMXO3LF-9400C-5BG484C,SMLF,IA   I217 @T6G_MB_LIB.T6G(SCH_1):PAGE80

FM_P2E_BUF2_EQA0 @T6G_MB_LIB.T6G(SCH_1):FM_P2E_BUF2_EQA0
 U6000   10 EQA0||AD0 DS125BR111RTWR-DS125BR111RTWR,SMLF,IC,AL000125003     I1 @T6G_MB_LIB.T6G(SCH_1):PAGE111
 R6173    2      B Q_RES_0402LF-1K,1%,1/16W,EMPTY,CS21002FB06    I44 @T6G_MB_LIB.T6G(SCH_1):PAGE111
 R6174    1      A Q_RES_0402LF-1K,1%,1/16W,EMPTY,CS21002FB06    I45 @T6G_MB_LIB.T6G(SCH_1):PAGE111

FM_P2E_BUF2_EQA1 @T6G_MB_LIB.T6G(SCH_1):FM_P2E_BUF2_EQA1
 U6000    9 EQA1||AD1 DS125BR111RTWR-DS125BR111RTWR,SMLF,IC,AL000125003     I1 @T6G_MB_LIB.T6G(SCH_1):PAGE111
 R6171    2      B Q_RES_0402LF-1K,1%,1/16W,EMPTY,CS21002FB06    I48 @T6G_MB_LIB.T6G(SCH_1):PAGE111
 R6172    1      A Q_RES_0402LF-1K,1%,1/16W,CHIP,CS21002FB06    I49 @T6G_MB_LIB.T6G(SCH_1):PAGE111

FM_P2E_BUF2_EQB0 @T6G_MB_LIB.T6G(SCH_1):FM_P2E_BUF2_EQB0
 U6000    1 EQB0||AD3 DS125BR111RTWR-DS125BR111RTWR,SMLF,IC,AL000125003     I1 @T6G_MB_LIB.T6G(SCH_1):PAGE111
 R6166    1      A Q_RES_0402LF-1K,1%,1/16W,EMPTY,CS21002FB06    I40 @T6G_MB_LIB.T6G(SCH_1):PAGE111
 R6165    2      B Q_RES_0402LF-1K,1%,1/16W,EMPTY,CS21002FB06    I41 @T6G_MB_LIB.T6G(SCH_1):PAGE111

FM_P2E_BUF2_EQB1 @T6G_MB_LIB.T6G(SCH_1):FM_P2E_BUF2_EQB1
 U6000    2 EQB1||AD2 DS125BR111RTWR-DS125BR111RTWR,SMLF,IC,AL000125003     I1 @T6G_MB_LIB.T6G(SCH_1):PAGE111
 R6164    1      A Q_RES_0402LF-1K,1%,1/16W,CHIP,CS21002FB06    I32 @T6G_MB_LIB.T6G(SCH_1):PAGE111
 R6163    2      B Q_RES_0402LF-1K,1%,1/16W,EMPTY,CS21002FB06    I39 @T6G_MB_LIB.T6G(SCH_1):PAGE111

FM_P2E_BUF2_RXDET @T6G_MB_LIB.T6G(SCH_1):FM_P2E_BUF2_RXDET
 U6000   18 RXDET||DONE# DS125BR111RTWR-DS125BR111RTWR,SMLF,IC,AL000125003     I1 @T6G_MB_LIB.T6G(SCH_1):PAGE111
 R6175    2      B Q_RES_0402LF-1K,1%,1/16W,EMPTY,CS21002FB06    I63 @T6G_MB_LIB.T6G(SCH_1):PAGE111
 R6176    1      A Q_RES_0402LF-1K,1%,1/16W,EMPTY,CS21002FB06    I64 @T6G_MB_LIB.T6G(SCH_1):PAGE111

FM_P2E_BUF2_SD_TH @T6G_MB_LIB.T6G(SCH_1):FM_P2E_BUF2_SD_TH
 U6000   14  SD_TH DS125BR111RTWR-DS125BR111RTWR,SMLF,IC,AL000125003     I1 @T6G_MB_LIB.T6G(SCH_1):PAGE111
 R6178    1      A Q_RES_0402LF-1K,1%,1/16W,EMPTY,CS21002FB06    I68 @T6G_MB_LIB.T6G(SCH_1):PAGE111
 R6177    2      B Q_RES_0402LF-1K,1%,1/16W,CHIP,CS21002FB06    I77 @T6G_MB_LIB.T6G(SCH_1):PAGE111

FM_P2E_BUF2_VODA_DB @T6G_MB_LIB.T6G(SCH_1):FM_P2E_BUF2_VODA_DB
 U6000    4 SDA||VODA_DB DS125BR111RTWR-DS125BR111RTWR,SMLF,IC,AL000125003     I1 @T6G_MB_LIB.T6G(SCH_1):PAGE111
 R6169    2      B Q_RES_0402LF-1K,1%,1/16W,EMPTY,CS21002FB06    I53 @T6G_MB_LIB.T6G(SCH_1):PAGE111
 R6170    1      A Q_RES_0402LF-1K,1%,1/16W,CHIP,CS21002FB06    I60 @T6G_MB_LIB.T6G(SCH_1):PAGE111

FM_P2E_BUF2_VODB_DB @T6G_MB_LIB.T6G(SCH_1):FM_P2E_BUF2_VODB_DB
 U6000    5 SCL||VODB_DB DS125BR111RTWR-DS125BR111RTWR,SMLF,IC,AL000125003     I1 @T6G_MB_LIB.T6G(SCH_1):PAGE111
 R6167    2      B Q_RES_0402LF-1K,1%,1/16W,EMPTY,CS21002FB06    I57 @T6G_MB_LIB.T6G(SCH_1):PAGE111
 R6168    1      A Q_RES_0402LF-1K,1%,1/16W,CHIP,CS21002FB06    I58 @T6G_MB_LIB.T6G(SCH_1):PAGE111

FM_P2E_BUF2_VOD_SEL @T6G_MB_LIB.T6G(SCH_1):FM_P2E_BUF2_VOD_SEL
 U6000   17 VOD_SEL||READEN# DS125BR111RTWR-DS125BR111RTWR,SMLF,IC,AL000125003     I1 @T6G_MB_LIB.T6G(SCH_1):PAGE111
 R6180    1      A Q_RES_0402LF-1K,1%,1/16W,EMPTY,CS21002FB06    I73 @T6G_MB_LIB.T6G(SCH_1):PAGE111
 R6179    2      B Q_RES_0402LF-1K,1%,1/16W,CHIP,CS21002FB06    I78 @T6G_MB_LIB.T6G(SCH_1):PAGE111

FM_P2E_EN2_N @T6G_MB_LIB.T6G(SCH_1):FM_P2E_EN2_N
 U6000    6   PWDN DS125BR111RTWR-DS125BR111RTWR,SMLF,IC,AL000125003     I1 @T6G_MB_LIB.T6G(SCH_1):PAGE111
 R6162    1      A Q_RES_0402LF-0,5%,1/16W,CHIP,CS00002JB13    I23 @T6G_MB_LIB.T6G(SCH_1):PAGE111

FM_P2E_EN_N @T6G_MB_LIB.T6G(SCH_1):FM_P2E_EN_N
  U237   11    EN# PI3EQX12902AZLEX-PI3EQX12902AZLEX,SMLF,IC,AL012902A    I63 @T6G_MB_LIB.T6G(SCH_1):PAGE110
 R4537    1      A Q_RES_0402LF-0,5%,1/16W,CHIP,CS00002JB13    I67 @T6G_MB_LIB.T6G(SCH_1):PAGE110

FM_P2E_EQA0 @T6G_MB_LIB.T6G(SCH_1):FM_P2E_EQA0
 R3274    1      A Q_RES_0402LF-68K,1%,1/16W,EMPTY,CS36802FB04    I16 @T6G_MB_LIB.T6G(SCH_1):PAGE110
 R3278    1      A Q_RES_0402LF-1K,1%,1/16W,CHIP,CS21002FB06    I18 @T6G_MB_LIB.T6G(SCH_1):PAGE110
 R3277    2      B Q_RES_0402LF-1K,1%,1/16W,EMPTY,CS21002FB06    I19 @T6G_MB_LIB.T6G(SCH_1):PAGE110
  U237   21   EQA0 PI3EQX12902AZLEX-PI3EQX12902AZLEX,SMLF,IC,AL012902A    I63 @T6G_MB_LIB.T6G(SCH_1):PAGE110

FM_P2E_EQA1 @T6G_MB_LIB.T6G(SCH_1):FM_P2E_EQA1
 R3268    1      A Q_RES_0402LF-68K,1%,1/16W,EMPTY,CS36802FB04     I2 @T6G_MB_LIB.T6G(SCH_1):PAGE110
 R3272    1      A Q_RES_0402LF-1K,1%,1/16W,EMPTY,CS21002FB06     I4 @T6G_MB_LIB.T6G(SCH_1):PAGE110
 R3271    2      B Q_RES_0402LF-1K,1%,1/16W,EMPTY,CS21002FB06     I5 @T6G_MB_LIB.T6G(SCH_1):PAGE110
  U237   26   EQA1 PI3EQX12902AZLEX-PI3EQX12902AZLEX,SMLF,IC,AL012902A    I63 @T6G_MB_LIB.T6G(SCH_1):PAGE110

FM_P2E_EQB0 @T6G_MB_LIB.T6G(SCH_1):FM_P2E_EQB0
 R3282    1      A Q_RES_0402LF-68K,1%,1/16W,EMPTY,CS36802FB04    I34 @T6G_MB_LIB.T6G(SCH_1):PAGE110
 R3284    1      A Q_RES_0402LF-1K,1%,1/16W,CHIP,CS21002FB06    I36 @T6G_MB_LIB.T6G(SCH_1):PAGE110
 R3283    2      B Q_RES_0402LF-1K,1%,1/16W,EMPTY,CS21002FB06    I37 @T6G_MB_LIB.T6G(SCH_1):PAGE110
  U237   20   EQB0 PI3EQX12902AZLEX-PI3EQX12902AZLEX,SMLF,IC,AL012902A    I63 @T6G_MB_LIB.T6G(SCH_1):PAGE110

FM_P2E_EQB1 @T6G_MB_LIB.T6G(SCH_1):FM_P2E_EQB1
 R3279    1      A Q_RES_0402LF-68K,1%,1/16W,EMPTY,CS36802FB04    I22 @T6G_MB_LIB.T6G(SCH_1):PAGE110
 R3281    1      A Q_RES_0402LF-1K,1%,1/16W,EMPTY,CS21002FB06    I25 @T6G_MB_LIB.T6G(SCH_1):PAGE110
 R3280    2      B Q_RES_0402LF-1K,1%,1/16W,EMPTY,CS21002FB06    I26 @T6G_MB_LIB.T6G(SCH_1):PAGE110
  U237   15   EQB1 PI3EQX12902AZLEX-PI3EQX12902AZLEX,SMLF,IC,AL012902A    I63 @T6G_MB_LIB.T6G(SCH_1):PAGE110

FM_P2E_FGA @T6G_MB_LIB.T6G(SCH_1):FM_P2E_FGA
 R3273    1      A Q_RES_0402LF-68K,1%,1/16W,EMPTY,CS36802FB04    I12 @T6G_MB_LIB.T6G(SCH_1):PAGE110
 R3276    1      A Q_RES_0402LF-1K,1%,1/16W,EMPTY,CS21002FB06    I29 @T6G_MB_LIB.T6G(SCH_1):PAGE110
 R3275    2      B Q_RES_0402LF-1K,1%,1/16W,EMPTY,CS21002FB06    I32 @T6G_MB_LIB.T6G(SCH_1):PAGE110
  U237   27    FGA PI3EQX12902AZLEX-PI3EQX12902AZLEX,SMLF,IC,AL012902A    I63 @T6G_MB_LIB.T6G(SCH_1):PAGE110

FM_P2E_FGB @T6G_MB_LIB.T6G(SCH_1):FM_P2E_FGB
 R3267    1      A Q_RES_0402LF-68K,1%,1/16W,EMPTY,CS36802FB04     I8 @T6G_MB_LIB.T6G(SCH_1):PAGE110
 R3270    1      A Q_RES_0402LF-1K,1%,1/16W,EMPTY,CS21002FB06     I9 @T6G_MB_LIB.T6G(SCH_1):PAGE110
 R3269    2      B Q_RES_0402LF-1K,1%,1/16W,EMPTY,CS21002FB06    I14 @T6G_MB_LIB.T6G(SCH_1):PAGE110
  U237   14    FGB PI3EQX12902AZLEX-PI3EQX12902AZLEX,SMLF,IC,AL012902A    I63 @T6G_MB_LIB.T6G(SCH_1):PAGE110

FM_P2E_MODE @T6G_MB_LIB.T6G(SCH_1):FM_P2E_MODE
  U237   30   MODE PI3EQX12902AZLEX-PI3EQX12902AZLEX,SMLF,IC,AL012902A    I63 @T6G_MB_LIB.T6G(SCH_1):PAGE110
 R3293    1      A Q_RES_0402LF-4.7K,1%,1/16W,EMPTY,CS24702FB06    I92 @T6G_MB_LIB.T6G(SCH_1):PAGE110
 R3266    2      B Q_RES_0402LF-4.7K,1%,1/16W,CHIP,CS24702FB06    I93 @T6G_MB_LIB.T6G(SCH_1):PAGE110

FM_P2E_SWA @T6G_MB_LIB.T6G(SCH_1):FM_P2E_SWA
  U237   29    SWA PI3EQX12902AZLEX-PI3EQX12902AZLEX,SMLF,IC,AL012902A    I63 @T6G_MB_LIB.T6G(SCH_1):PAGE110
 R3288    1      A Q_RES_0402LF-68K,1%,1/16W,EMPTY,CS36802FB04    I74 @T6G_MB_LIB.T6G(SCH_1):PAGE110
 R3290    1      A Q_RES_0402LF-1K,1%,1/16W,EMPTY,CS21002FB06    I76 @T6G_MB_LIB.T6G(SCH_1):PAGE110
 R3289    2      B Q_RES_0402LF-1K,1%,1/16W,EMPTY,CS21002FB06    I77 @T6G_MB_LIB.T6G(SCH_1):PAGE110

FM_P2E_SWB @T6G_MB_LIB.T6G(SCH_1):FM_P2E_SWB
 R3285    1      A Q_RES_0402LF-68K,1%,1/16W,EMPTY,CS36802FB04    I42 @T6G_MB_LIB.T6G(SCH_1):PAGE110
 R3287    1      A Q_RES_0402LF-1K,1%,1/16W,EMPTY,CS21002FB06    I44 @T6G_MB_LIB.T6G(SCH_1):PAGE110
 R3286    2      B Q_RES_0402LF-1K,1%,1/16W,EMPTY,CS21002FB06    I45 @T6G_MB_LIB.T6G(SCH_1):PAGE110
  U237   12    SWB PI3EQX12902AZLEX-PI3EQX12902AZLEX,SMLF,IC,AL012902A    I63 @T6G_MB_LIB.T6G(SCH_1):PAGE110

FM_P5V_EN @T6G_MB_LIB.T6G(SCH_1):FM_P5V_EN
  R333    1      A Q_RES_0402LF-0,5%,1/16W,CHIP,CS00002JB13     I4 @T6G_MB_LIB.T6G(SCH_1):PAGE273
   U18  T16  PB46D LCMXO3LF9400C5BG484C-LCMXO3LF-9400C-5BG484C,SMLF,IA   I216 @T6G_MB_LIB.T6G(SCH_1):PAGE80

FM_PASSWORD_CLEAR_N @T6G_MB_LIB.T6G(SCH_1):FM_PASSWORD_CLEAR_N
 R1358    2      B Q_RES_0402LF-10K,5%,1/16W,EMPTY,CS31002JB08    I72 @T6G_MB_LIB.T6G(SCH_1):PAGE144
 R1205    2      B Q_RES_0402LF-0,5%,1/16W,CHIP,CS00002JB13   I100 @T6G_MB_LIB.T6G(SCH_1):PAGE28
 R6106    2      B Q_RES_0402LF-10K,5%,1/16W,CHIP,CS31002JB08    I81 @T6G_MB_LIB.T6G(SCH_1):PAGE144
   SW1   19     19 SW20S_DHNF10FQTR-SW20S_DHNF-10F-Q-T/R,SMLF,MECH,DHA    I90 @T6G_MB_LIB.T6G(SCH_1):PAGE144

FM_PASSWORD_CLEAR_R_N @T6G_MB_LIB.T6G(SCH_1):FM_PASSWORD_CLEAR_R_N
 R1205    1      A Q_RES_0402LF-0,5%,1/16W,CHIP,CS00002JB13   I100 @T6G_MB_LIB.T6G(SCH_1):PAGE28
   U25 DF36 AGPIO4||SATA_ACT_L GENOA_SP5-SOCKET6096_13568-001,SMLF,IO,DGA^6000030   I188 @T6G_MB_LIB.T6G(SCH_1):PAGE28

FM_PDB_BUF_EN_N @T6G_MB_LIB.T6G(SCH_1):FM_PDB_BUF_EN_N
   U18   T5  PL26C LCMXO3LF9400C5BG484C-LCMXO3LF-9400C-5BG484C,SMLF,IA   I143 @T6G_MB_LIB.T6G(SCH_1):PAGE81
 R6073    2      B Q_RES_0402LF-0,5%,1/16W,CHIP,CS00002JB13   I146 @T6G_MB_LIB.T6G(SCH_1):PAGE81

FM_PDB_BUF_EN_R1 @T6G_MB_LIB.T6G(SCH_1):FM_PDB_BUF_EN_R1
 R3063    1      A Q_RES_0402LF-0,5%,1/16W,CHIP,CS00002JB13   I171 @T6G_MB_LIB.T6G(SCH_1):PAGE256
  U190    D      D MOSFET_NCH_GDS_ESD_PROTECTED-2N7002K,SMLF,IC,BAM70A   I392 @T6G_MB_LIB.T6G(SCH_1):PAGE363
 R2794    2      B Q_RES_0402LF-4.7K,5%,1/16W,CHIP,CS24702JB10   I396 @T6G_MB_LIB.T6G(SCH_1):PAGE363
 R2796    1      A Q_RES_0402LF-0,5%,1/16W,CHIP,CS00002JB13   I420 @T6G_MB_LIB.T6G(SCH_1):PAGE363

FM_PDB_BUF_EN_R1_N @T6G_MB_LIB.T6G(SCH_1):FM_PDB_BUF_EN_R1_N
  U190    G      G MOSFET_NCH_GDS_ESD_PROTECTED-2N7002K,SMLF,IC,BAM70A   I392 @T6G_MB_LIB.T6G(SCH_1):PAGE363
 R2793    2      B Q_RES_0402LF-0,5%,1/16W,CHIP,CS00002JB13   I394 @T6G_MB_LIB.T6G(SCH_1):PAGE363
 R2950    2      B Q_RES_0402LF-1K,1%,1/16W,CHIP,CS21002FB06   I475 @T6G_MB_LIB.T6G(SCH_1):PAGE363

FM_PDB_BUF_EN_R_N @T6G_MB_LIB.T6G(SCH_1):FM_PDB_BUF_EN_R_N
 R2793    1      A Q_RES_0402LF-0,5%,1/16W,CHIP,CS00002JB13   I394 @T6G_MB_LIB.T6G(SCH_1):PAGE363
 R6073    1      A Q_RES_0402LF-0,5%,1/16W,CHIP,CS00002JB13   I146 @T6G_MB_LIB.T6G(SCH_1):PAGE81

FM_PLD_CPU0_PRSNT_HDT @T6G_MB_LIB.T6G(SCH_1):FM_PLD_CPU0_PRSNT_HDT
  R158    1      A Q_RES_0402LF-33,5%,1/16W,CHIP,CS03302JB10   I154 @T6G_MB_LIB.T6G(SCH_1):PAGE80
   U18  U18  PR28D LCMXO3LF9400C5BG484C-LCMXO3LF-9400C-5BG484C,SMLF,IA   I217 @T6G_MB_LIB.T6G(SCH_1):PAGE80

FM_PLD_CPU0_PRSNT_HDT_N @T6G_MB_LIB.T6G(SCH_1):FM_PLD_CPU0_PRSNT_HDT_N
  U153    3     2C SN74AUC2G66DCTR-SN74AUC2G66DCTR,SMLF,IC,AL2G0066C00     I1 @T6G_MB_LIB.T6G(SCH_1):PAGE151
 R1647    2      B Q_RES_0402LF-1K,1%,1/16W,CHIP,CS21002FB06    I11 @T6G_MB_LIB.T6G(SCH_1):PAGE151
   U13    3     2C SN74AUC2G66DCTR-SN74AUC2G66DCTR,SMLF,IC,AL2G0066C00    I17 @T6G_MB_LIB.T6G(SCH_1):PAGE151
   Q63    D  DRAIN MOSFET_N_SMLF-BSS138K,BSS138K,IC,BAM138K0000    I45 @T6G_MB_LIB.T6G(SCH_1):PAGE151

FM_PLD_CPU1_PRSNT_HDT @T6G_MB_LIB.T6G(SCH_1):FM_PLD_CPU1_PRSNT_HDT
  R173    1      A Q_RES_0402LF-33,5%,1/16W,CHIP,CS03302JB10   I163 @T6G_MB_LIB.T6G(SCH_1):PAGE80
   U18  R17  PR26B LCMXO3LF9400C5BG484C-LCMXO3LF-9400C-5BG484C,SMLF,IA   I217 @T6G_MB_LIB.T6G(SCH_1):PAGE80

FM_PLD_CPU1_PRSNT_HDT_N @T6G_MB_LIB.T6G(SCH_1):FM_PLD_CPU1_PRSNT_HDT_N
   U14    3     2C SN74AUC2G66DCTR-SN74AUC2G66DCTR,SMLF,IC,AL2G0066C00    I23 @T6G_MB_LIB.T6G(SCH_1):PAGE151
 R1650    2      B Q_RES_0402LF-1K,1%,1/16W,CHIP,CS21002FB06    I27 @T6G_MB_LIB.T6G(SCH_1):PAGE151
  U154    3     2C SN74AUC2G66DCTR-SN74AUC2G66DCTR,SMLF,IC,AL2G0066C00    I31 @T6G_MB_LIB.T6G(SCH_1):PAGE151
   Q64    D  DRAIN MOSFET_N_SMLF-BSS138K,BSS138K,IC,BAM138K0000    I46 @T6G_MB_LIB.T6G(SCH_1):PAGE151

FM_PLD_OCP_SFF_AUX_PWR_EN @T6G_MB_LIB.T6G(SCH_1):FM_PLD_OCP_SFF_AUX_PWR_EN
  R958    1      A Q_RES_0402LF-33,5%,1/16W,CHIP,CS03302JB10    I86 @T6G_MB_LIB.T6G(SCH_1):PAGE81
 R9032    2      B Q_RES_0402LF-10K,1%,1/16W,CHIP,CS31002FB08     I2 @T6G_MB_LIB.T6G(SCH_1):PAGE340
 R9030    2      B Q_RES_0402LF-0,5%,1/16W,EMPTY,CS00002JB13    I15 @T6G_MB_LIB.T6G(SCH_1):PAGE340
 U9002    2     I1 74LVC1G32GW_SMLF-74LVC1G32GW,IC,ALVC1G32007    I74 @T6G_MB_LIB.T6G(SCH_1):PAGE340

FM_PLD_OCP_SFF_AUX_PWR_R_EN @T6G_MB_LIB.T6G(SCH_1):FM_PLD_OCP_SFF_AUX_PWR_R_EN
   U18   M6  PL17C LCMXO3LF9400C5BG484C-LCMXO3LF-9400C-5BG484C,SMLF,IA   I143 @T6G_MB_LIB.T6G(SCH_1):PAGE81
  R958    2      B Q_RES_0402LF-33,5%,1/16W,CHIP,CS03302JB10    I86 @T6G_MB_LIB.T6G(SCH_1):PAGE81

FM_PLD_OCP_SFF_MAIN_PWR_EN_R @T6G_MB_LIB.T6G(SCH_1):FM_PLD_OCP_SFF_MAIN_PWR_EN_R
  R959    2      B Q_RES_0402LF-33,5%,1/16W,CHIP,CS03302JB10    I81 @T6G_MB_LIB.T6G(SCH_1):PAGE81
   U18   M7  PL19D LCMXO3LF9400C5BG484C-LCMXO3LF-9400C-5BG484C,SMLF,IA   I143 @T6G_MB_LIB.T6G(SCH_1):PAGE81

FM_PLD_OCP_SFF_PWR_GOOD_R @T6G_MB_LIB.T6G(SCH_1):FM_PLD_OCP_SFF_PWR_GOOD_R
 R1282    2      B Q_RES_0402LF-33,5%,1/16W,CHIP,CS03302JB10    I29 @T6G_MB_LIB.T6G(SCH_1):PAGE80
   U18  W10  PB21B LCMXO3LF9400C5BG484C-LCMXO3LF-9400C-5BG484C,SMLF,IA   I216 @T6G_MB_LIB.T6G(SCH_1):PAGE80

FM_PRSNT_CPU0_N @T6G_MB_LIB.T6G(SCH_1):FM_PRSNT_CPU0_N
  R734    2      B Q_RES_0402LF-0,5%,1/16W,CHIP,CS00002JB13    I19 @T6G_MB_LIB.T6G(SCH_1):PAGE144
 R1356    2      B Q_RES_0402LF-4.7K,5%,1/16W,CHIP,CS24702JB10    I77 @T6G_MB_LIB.T6G(SCH_1):PAGE144
  R182    2      B Q_RES_0402LF-0,5%,1/16W,CHIP,CS00002JB13   I101 @T6G_MB_LIB.T6G(SCH_1):PAGE81
   SW1   17     17 SW20S_DHNF10FQTR-SW20S_DHNF-10F-Q-T/R,SMLF,MECH,DHA    I90 @T6G_MB_LIB.T6G(SCH_1):PAGE144

FM_PRSNT_CPU0_R_N @T6G_MB_LIB.T6G(SCH_1):FM_PRSNT_CPU0_R_N
  R182    1      A Q_RES_0402LF-0,5%,1/16W,CHIP,CS00002JB13   I101 @T6G_MB_LIB.T6G(SCH_1):PAGE81
   U18   V1 PL27B||PCLKC3_0 LCMXO3LF9400C5BG484C-LCMXO3LF-9400C-5BG484C,SMLF,IA   I143 @T6G_MB_LIB.T6G(SCH_1):PAGE81

FM_PRSNT_CPU1_N @T6G_MB_LIB.T6G(SCH_1):FM_PRSNT_CPU1_N
  R744    2      B Q_RES_0402LF-0,5%,1/16W,CHIP,CS00002JB13    I17 @T6G_MB_LIB.T6G(SCH_1):PAGE144
 R1357    2      B Q_RES_0402LF-2.2K,5%,1/16W,CHIP,CS22202JB07    I74 @T6G_MB_LIB.T6G(SCH_1):PAGE144
  R271    2      B Q_RES_0402LF-0,5%,1/16W,CHIP,CS00002JB13   I104 @T6G_MB_LIB.T6G(SCH_1):PAGE81
   SW1   18     18 SW20S_DHNF10FQTR-SW20S_DHNF-10F-Q-T/R,SMLF,MECH,DHA    I90 @T6G_MB_LIB.T6G(SCH_1):PAGE144

FM_PRSNT_CPU1_R_N @T6G_MB_LIB.T6G(SCH_1):FM_PRSNT_CPU1_R_N
   U18   V5  PL30C LCMXO3LF9400C5BG484C-LCMXO3LF-9400C-5BG484C,SMLF,IA   I143 @T6G_MB_LIB.T6G(SCH_1):PAGE81
  R271    1      A Q_RES_0402LF-0,5%,1/16W,CHIP,CS00002JB13   I104 @T6G_MB_LIB.T6G(SCH_1):PAGE81

FM_PVDD11_S3_P0_EN @T6G_MB_LIB.T6G(SCH_1):FM_PVDD11_S3_P0_EN
  R227    1      A Q_RES_0402LF-33,5%,1/16W,CHIP,CS03302JB10   I103 @T6G_MB_LIB.T6G(SCH_1):PAGE81
   U18   W4  PL30B LCMXO3LF9400C5BG484C-LCMXO3LF-9400C-5BG484C,SMLF,IA   I143 @T6G_MB_LIB.T6G(SCH_1):PAGE81

FM_PVDD11_S3_P0_OCP_N @T6G_MB_LIB.T6G(SCH_1):FM_PVDD11_S3_P0_OCP_N
   U18   H3   PL7D LCMXO3LF9400C5BG484C-LCMXO3LF-9400C-5BG484C,SMLF,IA   I143 @T6G_MB_LIB.T6G(SCH_1):PAGE81
  R226    1      A Q_RES_0402LF-0,5%,1/16W,CHIP,CS00002JB13   I111 @T6G_MB_LIB.T6G(SCH_1):PAGE81

FM_PVDD11_S3_P1_EN @T6G_MB_LIB.T6G(SCH_1):FM_PVDD11_S3_P1_EN
  R279    2      B Q_RES_0402LF-33,5%,1/16W,CHIP,CS03302JB10    I58 @T6G_MB_LIB.T6G(SCH_1):PAGE80
   U18  AA7  PB13A LCMXO3LF9400C5BG484C-LCMXO3LF-9400C-5BG484C,SMLF,IA   I216 @T6G_MB_LIB.T6G(SCH_1):PAGE80

FM_PVDD11_S3_P1_OCP_N @T6G_MB_LIB.T6G(SCH_1):FM_PVDD11_S3_P1_OCP_N
   U18   H4   PL7C LCMXO3LF9400C5BG484C-LCMXO3LF-9400C-5BG484C,SMLF,IA   I143 @T6G_MB_LIB.T6G(SCH_1):PAGE81
  R278    1      A Q_RES_0402LF-0,5%,1/16W,CHIP,CS00002JB13   I113 @T6G_MB_LIB.T6G(SCH_1):PAGE81

FM_PVDD18_S5_P0_EN @T6G_MB_LIB.T6G(SCH_1):FM_PVDD18_S5_P0_EN
  R176    2      B Q_RES_0402LF-33,5%,1/16W,CHIP,CS03302JB10    I33 @T6G_MB_LIB.T6G(SCH_1):PAGE80
   U18  AA8  PB18A LCMXO3LF9400C5BG484C-LCMXO3LF-9400C-5BG484C,SMLF,IA   I216 @T6G_MB_LIB.T6G(SCH_1):PAGE80

FM_PVDD33_S5_EN @T6G_MB_LIB.T6G(SCH_1):FM_PVDD33_S5_EN
  R224    2      B Q_RES_0402LF-33,5%,1/16W,CHIP,CS03302JB10    I36 @T6G_MB_LIB.T6G(SCH_1):PAGE80
   U18   V9  PB16C LCMXO3LF9400C5BG484C-LCMXO3LF-9400C-5BG484C,SMLF,IA   I216 @T6G_MB_LIB.T6G(SCH_1):PAGE80

FM_PVDDCR_CPU0_P0_OCP_N @T6G_MB_LIB.T6G(SCH_1):FM_PVDDCR_CPU0_P0_OCP_N
  R231    2      B Q_RES_0402LF-0,5%,1/16W,CHIP,CS00002JB13    I60 @T6G_MB_LIB.T6G(SCH_1):PAGE81
   U18   F1   PL6B LCMXO3LF9400C5BG484C-LCMXO3LF-9400C-5BG484C,SMLF,IA   I143 @T6G_MB_LIB.T6G(SCH_1):PAGE81

FM_PVDDCR_CPU0_P1_OCP_N @T6G_MB_LIB.T6G(SCH_1):FM_PVDDCR_CPU0_P1_OCP_N
   U18   G2 PL7A||PCLKT5_0 LCMXO3LF9400C5BG484C-LCMXO3LF-9400C-5BG484C,SMLF,IA   I143 @T6G_MB_LIB.T6G(SCH_1):PAGE81
  R284    1      A Q_RES_0402LF-0,5%,1/16W,CHIP,CS00002JB13   I140 @T6G_MB_LIB.T6G(SCH_1):PAGE81

FM_PVDDCR_CPU0_P1_R_EN @T6G_MB_LIB.T6G(SCH_1):FM_PVDDCR_CPU0_P1_R_EN
  R208    2      B Q_RES_0402LF-33,5%,1/16W,CHIP,CS03302JB10    I65 @T6G_MB_LIB.T6G(SCH_1):PAGE80
   U18   W5   PB7D LCMXO3LF9400C5BG484C-LCMXO3LF-9400C-5BG484C,SMLF,IA   I216 @T6G_MB_LIB.T6G(SCH_1):PAGE80

FM_PVDDCR_CPU1_P0_EN @T6G_MB_LIB.T6G(SCH_1):FM_PVDDCR_CPU1_P0_EN
  R232    1      A Q_RES_0402LF-33,5%,1/16W,CHIP,CS03302JB10    I51 @T6G_MB_LIB.T6G(SCH_1):PAGE81
 R8058    1      A Q_RES_0402LF-0,5%,1/16W,CHIP,CS00002JB13    I88 @T6G_MB_LIB.T6G(SCH_1):PAGE175

FM_PVDDCR_CPU1_P0_OCP_N @T6G_MB_LIB.T6G(SCH_1):FM_PVDDCR_CPU1_P0_OCP_N
  R137    2      B Q_RES_0402LF-0,5%,1/16W,CHIP,CS00002JB13    I59 @T6G_MB_LIB.T6G(SCH_1):PAGE81
   U18   G3   PL6C LCMXO3LF9400C5BG484C-LCMXO3LF-9400C-5BG484C,SMLF,IA   I143 @T6G_MB_LIB.T6G(SCH_1):PAGE81

FM_PVDDCR_CPU1_P0_R_EN @T6G_MB_LIB.T6G(SCH_1):FM_PVDDCR_CPU1_P0_R_EN
  R232    2      B Q_RES_0402LF-33,5%,1/16W,CHIP,CS03302JB10    I51 @T6G_MB_LIB.T6G(SCH_1):PAGE81
   U18   P7  PL24D LCMXO3LF9400C5BG484C-LCMXO3LF-9400C-5BG484C,SMLF,IA   I143 @T6G_MB_LIB.T6G(SCH_1):PAGE81

FM_PVDDCR_CPU1_P1_EN @T6G_MB_LIB.T6G(SCH_1):FM_PVDDCR_CPU1_P1_EN
 R8235    1      A Q_RES_0402LF-0,5%,1/16W,CHIP,CS00002JB13    I87 @T6G_MB_LIB.T6G(SCH_1):PAGE192
  R285    2      B Q_RES_0402LF-33,5%,1/16W,CHIP,CS03302JB10   I105 @T6G_MB_LIB.T6G(SCH_1):PAGE81

FM_PVDDCR_CPU1_P1_OCP_N @T6G_MB_LIB.T6G(SCH_1):FM_PVDDCR_CPU1_P1_OCP_N
  R141    2      B Q_RES_0402LF-0,5%,1/16W,CHIP,CS00002JB13    I57 @T6G_MB_LIB.T6G(SCH_1):PAGE81
   U18   G4   PL6D LCMXO3LF9400C5BG484C-LCMXO3LF-9400C-5BG484C,SMLF,IA   I143 @T6G_MB_LIB.T6G(SCH_1):PAGE81

FM_PVDDCR_CPU1_P1_R_EN @T6G_MB_LIB.T6G(SCH_1):FM_PVDDCR_CPU1_P1_R_EN
   U18   T7  PL30D LCMXO3LF9400C5BG484C-LCMXO3LF-9400C-5BG484C,SMLF,IA   I143 @T6G_MB_LIB.T6G(SCH_1):PAGE81
  R285    1      A Q_RES_0402LF-33,5%,1/16W,CHIP,CS03302JB10   I105 @T6G_MB_LIB.T6G(SCH_1):PAGE81

FM_PVDDIO_P0_EN @T6G_MB_LIB.T6G(SCH_1):FM_PVDDIO_P0_EN
  R229    2      B Q_RES_0402LF-33,5%,1/16W,CHIP,CS03302JB10    I68 @T6G_MB_LIB.T6G(SCH_1):PAGE80
   U18   V6   PB5C LCMXO3LF9400C5BG484C-LCMXO3LF-9400C-5BG484C,SMLF,IA   I216 @T6G_MB_LIB.T6G(SCH_1):PAGE80

FM_PVDDIO_P1_EN @T6G_MB_LIB.T6G(SCH_1):FM_PVDDIO_P1_EN
  R282    2      B Q_RES_0402LF-33,5%,1/16W,CHIP,CS03302JB10    I31 @T6G_MB_LIB.T6G(SCH_1):PAGE80
   U18  AA9  PB19A LCMXO3LF9400C5BG484C-LCMXO3LF-9400C-5BG484C,SMLF,IA   I216 @T6G_MB_LIB.T6G(SCH_1):PAGE80

FM_PWRGD_CPU0_PWROK @T6G_MB_LIB.T6G(SCH_1):FM_PWRGD_CPU0_PWROK
  R242    2      B Q_RES_0402LF-0,5%,1/16W,CHIP,CS00002JB13   I110 @T6G_MB_LIB.T6G(SCH_1):PAGE80
   U18  H19  PR10A LCMXO3LF9400C5BG484C-LCMXO3LF-9400C-5BG484C,SMLF,IA   I217 @T6G_MB_LIB.T6G(SCH_1):PAGE80

FM_PWRGD_CPU1_PWROK @T6G_MB_LIB.T6G(SCH_1):FM_PWRGD_CPU1_PWROK
  R203    2      B Q_RES_0402LF-0,5%,1/16W,CHIP,CS00002JB13   I106 @T6G_MB_LIB.T6G(SCH_1):PAGE80
   U18  J18  PR11C LCMXO3LF9400C5BG484C-LCMXO3LF-9400C-5BG484C,SMLF,IA   I217 @T6G_MB_LIB.T6G(SCH_1):PAGE80

FM_PWRGD_P1V8_RETIMER_CPU0 @T6G_MB_LIB.T6G(SCH_1):FM_PWRGD_P1V8_RETIMER_CPU0
   U18   T9 PB16A||MCLK||CCLK LCMXO3LF9400C5BG484C-LCMXO3LF-9400C-5BG484C,SMLF,IA   I216 @T6G_MB_LIB.T6G(SCH_1):PAGE80
 R6506    2      B Q_RES_0402LF-33,5%,1/16W,CHIP,CS03302JB10    I37 @T6G_MB_LIB.T6G(SCH_1):PAGE469
 C6758    1      A Q_CAP_0402-1000PF,50V,5%,X7R,TMP_QCH21006JB10    I42 @T6G_MB_LIB.T6G(SCH_1):PAGE469

FM_PWRGD_P1V8_RETIMER_CPU1 @T6G_MB_LIB.T6G(SCH_1):FM_PWRGD_P1V8_RETIMER_CPU1
   U18   U9 PB16B||SO||SPISO LCMXO3LF9400C5BG484C-LCMXO3LF-9400C-5BG484C,SMLF,IA   I216 @T6G_MB_LIB.T6G(SCH_1):PAGE80
  R645    2      B Q_RES_0402LF-33,5%,1/16W,CHIP,CS03302JB10    I36 @T6G_MB_LIB.T6G(SCH_1):PAGE470
  C109    1      A Q_CAP_0402-1000PF,50V,5%,X7R,TMP_QCH21006JB10    I39 @T6G_MB_LIB.T6G(SCH_1):PAGE470

FM_PWRGD_PVDD11_S3_P0 @T6G_MB_LIB.T6G(SCH_1):FM_PWRGD_PVDD11_S3_P0
  R228    2      B Q_RES_0402LF-0,5%,1/16W,CHIP,CS00002JB13    I66 @T6G_MB_LIB.T6G(SCH_1):PAGE80
   U18   Y4   PB7C LCMXO3LF9400C5BG484C-LCMXO3LF-9400C-5BG484C,SMLF,IA   I216 @T6G_MB_LIB.T6G(SCH_1):PAGE80

FM_PWRGD_PVDD11_S3_P1 @T6G_MB_LIB.T6G(SCH_1):FM_PWRGD_PVDD11_S3_P1
  R280    2      B Q_RES_0402LF-0,5%,1/16W,CHIP,CS00002JB13    I59 @T6G_MB_LIB.T6G(SCH_1):PAGE80
   U18  AB7  PB13B LCMXO3LF9400C5BG484C-LCMXO3LF-9400C-5BG484C,SMLF,IA   I216 @T6G_MB_LIB.T6G(SCH_1):PAGE80

FM_PWRGD_PVDD18_S5_P0 @T6G_MB_LIB.T6G(SCH_1):FM_PWRGD_PVDD18_S5_P0
  R177    2      B Q_RES_0402LF-33,5%,1/16W,CHIP,CS03302JB10    I52 @T6G_MB_LIB.T6G(SCH_1):PAGE184
   U18  AB8  PB18B LCMXO3LF9400C5BG484C-LCMXO3LF-9400C-5BG484C,SMLF,IA   I216 @T6G_MB_LIB.T6G(SCH_1):PAGE80
 C5001    1      A Q_CAP_0402-1000PF,50V,5%,X7R,TMP_QCH21006JB10    I56 @T6G_MB_LIB.T6G(SCH_1):PAGE184

FM_PWRGD_PVDD33_S5 @T6G_MB_LIB.T6G(SCH_1):FM_PWRGD_PVDD33_S5
  R225    2      B Q_RES_0402LF-33,5%,1/16W,CHIP,CS03302JB10    I33 @T6G_MB_LIB.T6G(SCH_1):PAGE167
   U18  AB6  PB11B LCMXO3LF9400C5BG484C-LCMXO3LF-9400C-5BG484C,SMLF,IA   I216 @T6G_MB_LIB.T6G(SCH_1):PAGE80
 C5002    1      A Q_CAP_0402-1000PF,50V,5%,X7R,TMP_QCH21006JB10    I43 @T6G_MB_LIB.T6G(SCH_1):PAGE167

FM_PWRGD_PVDDCR_CPU0_P1 @T6G_MB_LIB.T6G(SCH_1):FM_PWRGD_PVDDCR_CPU0_P1
  R209    2      B Q_RES_0402LF-0,5%,1/16W,CHIP,CS00002JB13    I61 @T6G_MB_LIB.T6G(SCH_1):PAGE80
   U18   Y5  PB10C LCMXO3LF9400C5BG484C-LCMXO3LF-9400C-5BG484C,SMLF,IA   I216 @T6G_MB_LIB.T6G(SCH_1):PAGE80

FM_PWRGD_PVDDCR_CPU1_P0 @T6G_MB_LIB.T6G(SCH_1):FM_PWRGD_PVDDCR_CPU1_P0
  R233    2      B Q_RES_0402LF-0,5%,1/16W,CHIP,CS00002JB13    I54 @T6G_MB_LIB.T6G(SCH_1):PAGE81
   U18   R7  PL25D LCMXO3LF9400C5BG484C-LCMXO3LF-9400C-5BG484C,SMLF,IA   I143 @T6G_MB_LIB.T6G(SCH_1):PAGE81

FM_PWRGD_PVDDCR_CPU1_P1 @T6G_MB_LIB.T6G(SCH_1):FM_PWRGD_PVDDCR_CPU1_P1
  R286    2      B Q_RES_0402LF-0,5%,1/16W,CHIP,CS00002JB13    I62 @T6G_MB_LIB.T6G(SCH_1):PAGE80
   U18   T8   PB8D LCMXO3LF9400C5BG484C-LCMXO3LF-9400C-5BG484C,SMLF,IA   I216 @T6G_MB_LIB.T6G(SCH_1):PAGE80

FM_PWRGD_PVDDIO_P0 @T6G_MB_LIB.T6G(SCH_1):FM_PWRGD_PVDDIO_P0
  R230    2      B Q_RES_0402LF-0,5%,1/16W,CHIP,CS00002JB13    I67 @T6G_MB_LIB.T6G(SCH_1):PAGE80
   U18   U6   PB5D LCMXO3LF9400C5BG484C-LCMXO3LF-9400C-5BG484C,SMLF,IA   I216 @T6G_MB_LIB.T6G(SCH_1):PAGE80

FM_PWRGD_PVDDIO_P1 @T6G_MB_LIB.T6G(SCH_1):FM_PWRGD_PVDDIO_P1
  R283    2      B Q_RES_0402LF-0,5%,1/16W,CHIP,CS00002JB13    I30 @T6G_MB_LIB.T6G(SCH_1):PAGE80
   U18  AB9  PB19B LCMXO3LF9400C5BG484C-LCMXO3LF-9400C-5BG484C,SMLF,IA   I216 @T6G_MB_LIB.T6G(SCH_1):PAGE80

FM_ROM_LS_EN @T6G_MB_LIB.T6G(SCH_1):FM_ROM_LS_EN
 R1564    1      A Q_RES_0402LF-33,5%,1/16W,CHIP,CS03302JB10   I156 @T6G_MB_LIB.T6G(SCH_1):PAGE80
   U18  Y22  PR28A LCMXO3LF9400C5BG484C-LCMXO3LF-9400C-5BG484C,SMLF,IA   I217 @T6G_MB_LIB.T6G(SCH_1):PAGE80

FM_ROM_SD_LS_OE @T6G_MB_LIB.T6G(SCH_1):FM_ROM_SD_LS_OE
 R1616    1      A Q_RES_0402LF-33,5%,1/16W,CHIP,CS03302JB10   I157 @T6G_MB_LIB.T6G(SCH_1):PAGE80
   U18  W21  PR28B LCMXO3LF9400C5BG484C-LCMXO3LF-9400C-5BG484C,SMLF,IA   I217 @T6G_MB_LIB.T6G(SCH_1):PAGE80

FM_RST_CPU0_RESETL_N @T6G_MB_LIB.T6G(SCH_1):FM_RST_CPU0_RESETL_N
  R241    2      B Q_RES_0402LF-0,5%,1/16W,CHIP,CS00002JB13   I114 @T6G_MB_LIB.T6G(SCH_1):PAGE80
   U18  H22   PR7A LCMXO3LF9400C5BG484C-LCMXO3LF-9400C-5BG484C,SMLF,IA   I217 @T6G_MB_LIB.T6G(SCH_1):PAGE80

FM_RST_CPU1_RESETL_N @T6G_MB_LIB.T6G(SCH_1):FM_RST_CPU1_RESETL_N
   R57    2      B Q_RES_0402LF-0,5%,1/16W,CHIP,CS00002JB13   I113 @T6G_MB_LIB.T6G(SCH_1):PAGE80
   U18  H21   PR7B LCMXO3LF9400C5BG484C-LCMXO3LF-9400C-5BG484C,SMLF,IA   I217 @T6G_MB_LIB.T6G(SCH_1):PAGE80

FM_RST_PERST_SCM_N @T6G_MB_LIB.T6G(SCH_1):FM_RST_PERST_SCM_N
   J41  A51 PERP10 SCONN168_ME1016810202011-SCONN168_ME1016810202011,A   I176 @T6G_MB_LIB.T6G(SCH_1):PAGE348
  R957    2      B Q_RES_0402LF-33,5%,1/16W,CHIP,CS03302JB10   I130 @T6G_MB_LIB.T6G(SCH_1):PAGE80

FM_RST_PERST_SCM_R_N @T6G_MB_LIB.T6G(SCH_1):FM_RST_PERST_SCM_R_N
  R957    1      A Q_RES_0402LF-33,5%,1/16W,CHIP,CS03302JB10   I130 @T6G_MB_LIB.T6G(SCH_1):PAGE80
   U18 AB13  PB30A LCMXO3LF9400C5BG484C-LCMXO3LF-9400C-5BG484C,SMLF,IA   I216 @T6G_MB_LIB.T6G(SCH_1):PAGE80

FM_SCM_PRSNT1_N @T6G_MB_LIB.T6G(SCH_1):FM_SCM_PRSNT1_N
 R1854    2      B Q_RES_0402LF-1K,1%,1/16W,CHIP,CS21002FB06     I2 @T6G_MB_LIB.T6G(SCH_1):PAGE350
 R1856    1      A Q_RES_0402LF-100,1%,1/16W,CHIP,CS11002FB07     I3 @T6G_MB_LIB.T6G(SCH_1):PAGE350
   J41  A57 PERP12 SCONN168_ME1016810202011-SCONN168_ME1016810202011,A   I176 @T6G_MB_LIB.T6G(SCH_1):PAGE348
   U18   M2 PL16B||PCLKC4_0 LCMXO3LF9400C5BG484C-LCMXO3LF-9400C-5BG484C,SMLF,IA   I143 @T6G_MB_LIB.T6G(SCH_1):PAGE81

FM_SCM_PRSNT1_R_N @T6G_MB_LIB.T6G(SCH_1):FM_SCM_PRSNT1_R_N
 R1856    2      B Q_RES_0402LF-100,1%,1/16W,CHIP,CS11002FB07     I3 @T6G_MB_LIB.T6G(SCH_1):PAGE350
   Q39    G      G MOSFET_NCH_GDS_ESD_PROTECTED-2N7002K,SMLF,IC,BAM70A     I9 @T6G_MB_LIB.T6G(SCH_1):PAGE350

FM_SEC_MUX_OE_N @T6G_MB_LIB.T6G(SCH_1):FM_SEC_MUX_OE_N
    U6    6    OE# PI3CSW12ZUAEX-PI3CSW12ZUAEX,SMLF,IC,AL3CSW12000    I67 @T6G_MB_LIB.T6G(SCH_1):PAGE138
 R6183    1      A Q_RES_0402LF-0,5%,1/16W,CHIP,CS00002JB13   I164 @T6G_MB_LIB.T6G(SCH_1):PAGE81
 R6185    1      A Q_RES_0402LF-10K,1%,1/16W,CHIP,CS31002FB08   I143 @T6G_MB_LIB.T6G(SCH_1):PAGE82
 R6186    1      A Q_RES_0402LF-4.7K,5%,1/16W,EMPTY,CS24702JB10   I146 @T6G_MB_LIB.T6G(SCH_1):PAGE82

FM_SEC_MUX_OE_R_N @T6G_MB_LIB.T6G(SCH_1):FM_SEC_MUX_OE_R_N
   U18   K2  PL14A LCMXO3LF9400C5BG484C-LCMXO3LF-9400C-5BG484C,SMLF,IA   I143 @T6G_MB_LIB.T6G(SCH_1):PAGE81
 R6183    2      B Q_RES_0402LF-0,5%,1/16W,CHIP,CS00002JB13   I164 @T6G_MB_LIB.T6G(SCH_1):PAGE81

FM_SEC_MUX_R_SEL @T6G_MB_LIB.T6G(SCH_1):FM_SEC_MUX_R_SEL
   U18   K1  PL14B LCMXO3LF9400C5BG484C-LCMXO3LF-9400C-5BG484C,SMLF,IA   I143 @T6G_MB_LIB.T6G(SCH_1):PAGE81
 R6184    2      B Q_RES_0402LF-0,5%,1/16W,CHIP,CS00002JB13   I165 @T6G_MB_LIB.T6G(SCH_1):PAGE81

FM_SEC_MUX_SEL @T6G_MB_LIB.T6G(SCH_1):FM_SEC_MUX_SEL
    U6    9      S PI3CSW12ZUAEX-PI3CSW12ZUAEX,SMLF,IC,AL3CSW12000    I67 @T6G_MB_LIB.T6G(SCH_1):PAGE138
 R6184    1      A Q_RES_0402LF-0,5%,1/16W,CHIP,CS00002JB13   I165 @T6G_MB_LIB.T6G(SCH_1):PAGE81
 R6187    1      A Q_RES_0402LF-10K,1%,1/16W,EMPTY,CS31002FB08   I151 @T6G_MB_LIB.T6G(SCH_1):PAGE82
 R6188    1      A Q_RES_0402LF-4.7K,5%,1/16W,EMPTY,CS24702JB10   I152 @T6G_MB_LIB.T6G(SCH_1):PAGE82

FM_SMB_1_ALERT_GPU @T6G_MB_LIB.T6G(SCH_1):FM_SMB_1_ALERT_GPU
 R3029    2      B Q_RES_0402LF-4.7K,5%,1/16W,CHIP,CS24702JB10   I144 @T6G_MB_LIB.T6G(SCH_1):PAGE333
   Q75    5     G2 MOSFET_NCH_DUAL-PJT138K,SMLF,IC,BAM138K0003   I151 @T6G_MB_LIB.T6G(SCH_1):PAGE333
   Q75    6     D1 MOSFET_NCH_DUAL-PJT138K,SMLF,IC,BAM138K0003   I152 @T6G_MB_LIB.T6G(SCH_1):PAGE333

FM_SMB_1_ALERT_GPU_ISO_N @T6G_MB_LIB.T6G(SCH_1):FM_SMB_1_ALERT_GPU_ISO_N
 C1802    1      A Q_CAP_0402-0.1UF,25V,10%,X7R,CH4104K1B00   I148 @T6G_MB_LIB.T6G(SCH_1):PAGE333
   Q75    3     D2 MOSFET_NCH_DUAL-PJT138K,SMLF,IC,BAM138K0003   I151 @T6G_MB_LIB.T6G(SCH_1):PAGE333
 R3066    2      B Q_RES_0402LF-33.2,1%,1/16W,CHIP,CS03322FB03   I268 @T6G_MB_LIB.T6G(SCH_1):PAGE80
 R3030    2      B Q_RES_0402LF-100K,1%,1/16W,CHIP,CS41002FB09   I178 @T6G_MB_LIB.T6G(SCH_1):PAGE333

FM_SMB_1_ALERT_GPU_ISO_R_N @T6G_MB_LIB.T6G(SCH_1):FM_SMB_1_ALERT_GPU_ISO_R_N
   U18 AA17  PB40B LCMXO3LF9400C5BG484C-LCMXO3LF-9400C-5BG484C,SMLF,IA   I216 @T6G_MB_LIB.T6G(SCH_1):PAGE80
 R3066    1      A Q_RES_0402LF-33.2,1%,1/16W,CHIP,CS03322FB03   I268 @T6G_MB_LIB.T6G(SCH_1):PAGE80

FM_SMB_1_ALERT_GPU_N @T6G_MB_LIB.T6G(SCH_1):FM_SMB_1_ALERT_GPU_N
 R3028    1      A Q_RES_0402LF-100K,1%,1/16W,EMPTY,CS41002FB09   I139 @T6G_MB_LIB.T6G(SCH_1):PAGE333
   Q75    2     G1 MOSFET_NCH_DUAL-PJT138K,SMLF,IC,BAM138K0003   I152 @T6G_MB_LIB.T6G(SCH_1):PAGE333
 R3510    2      B Q_RES_0402LF-54.9K,1%,1/16W,CHIP,CS35492FB03   I176 @T6G_MB_LIB.T6G(SCH_1):PAGE333
  J110   N4     N4 CONN112_10137002101LF-CONN112_10137002-101LF,THLF,A    I76 @T6G_MB_LIB.T6G(SCH_1):PAGE318

FM_SMB_2_ALERT_GPU @T6G_MB_LIB.T6G(SCH_1):FM_SMB_2_ALERT_GPU
   Q74    6     D1 MOSFET_NCH_DUAL-PJT138K,SMLF,IC,BAM138K0003   I121 @T6G_MB_LIB.T6G(SCH_1):PAGE333
   Q74    5     G2 MOSFET_NCH_DUAL-PJT138K,SMLF,IC,BAM138K0003   I122 @T6G_MB_LIB.T6G(SCH_1):PAGE333
 R3034    2      B Q_RES_0402LF-4.7K,5%,1/16W,CHIP,CS24702JB10   I129 @T6G_MB_LIB.T6G(SCH_1):PAGE333

FM_SMB_2_ALERT_GPU_ISO_N @T6G_MB_LIB.T6G(SCH_1):FM_SMB_2_ALERT_GPU_ISO_N
   Q74    3     D2 MOSFET_NCH_DUAL-PJT138K,SMLF,IC,BAM138K0003   I122 @T6G_MB_LIB.T6G(SCH_1):PAGE333
 C1804    1      A Q_CAP_0402-0.1UF,25V,10%,X7R,CH4104K1B00   I125 @T6G_MB_LIB.T6G(SCH_1):PAGE333
R11667    2      B Q_RES_0402LF-33.2,1%,1/16W,CHIP,CS03322FB03   I274 @T6G_MB_LIB.T6G(SCH_1):PAGE80
 R3035    2      B Q_RES_0402LF-100K,1%,1/16W,CHIP,CS41002FB09   I179 @T6G_MB_LIB.T6G(SCH_1):PAGE333

FM_SMB_2_ALERT_GPU_ISO_R_N @T6G_MB_LIB.T6G(SCH_1):FM_SMB_2_ALERT_GPU_ISO_R_N
   U18  Y18  PB41C LCMXO3LF9400C5BG484C-LCMXO3LF-9400C-5BG484C,SMLF,IA   I216 @T6G_MB_LIB.T6G(SCH_1):PAGE80
R11667    1      A Q_RES_0402LF-33.2,1%,1/16W,CHIP,CS03322FB03   I274 @T6G_MB_LIB.T6G(SCH_1):PAGE80

FM_SMB_2_ALERT_GPU_N @T6G_MB_LIB.T6G(SCH_1):FM_SMB_2_ALERT_GPU_N
   Q74    2     G1 MOSFET_NCH_DUAL-PJT138K,SMLF,IC,BAM138K0003   I121 @T6G_MB_LIB.T6G(SCH_1):PAGE333
 R3032    1      A Q_RES_0402LF-100K,1%,1/16W,EMPTY,CS41002FB09   I134 @T6G_MB_LIB.T6G(SCH_1):PAGE333
 R3514    2      B Q_RES_0402LF-54.9K,1%,1/16W,CHIP,CS35492FB03   I175 @T6G_MB_LIB.T6G(SCH_1):PAGE333
  J110   N6     N6 CONN112_10137002101LF-CONN112_10137002-101LF,THLF,A    I16 @T6G_MB_LIB.T6G(SCH_1):PAGE318

FM_SMB_RST_E1S_0_N @T6G_MB_LIB.T6G(SCH_1):FM_SMB_RST_E1S_0_N
   U18   P2  PL19A LCMXO3LF9400C5BG484C-LCMXO3LF-9400C-5BG484C,SMLF,IA   I143 @T6G_MB_LIB.T6G(SCH_1):PAGE81
 R1303    1      A Q_RES_0402LF-1K,1%,1/16W,CHIP,CS21002FB06     I5 @T6G_MB_LIB.T6G(SCH_1):PAGE84
 R1036    1      A Q_RES_0402LF-0,5%,1/16W,CHIP,CS00002JB13     I6 @T6G_MB_LIB.T6G(SCH_1):PAGE84

FM_SMB_RST_E1S_0_R_N @T6G_MB_LIB.T6G(SCH_1):FM_SMB_RST_E1S_0_R_N
 R3775    1      A Q_RES_0402LF-0,5%,1/16W,CHIP,CS00002JB13     I2 @T6G_MB_LIB.T6G(SCH_1):PAGE297
 R1036    2      B Q_RES_0402LF-0,5%,1/16W,CHIP,CS00002JB13     I6 @T6G_MB_LIB.T6G(SCH_1):PAGE84

FM_SMB_RT_ROM_MUX1_SEL @T6G_MB_LIB.T6G(SCH_1):FM_SMB_RT_ROM_MUX1_SEL
   U45    9      S PI3CSW12ZUAEX-PI3CSW12ZUAEX,SMLF,IC,AL3CSW12000    I22 @T6G_MB_LIB.T6G(SCH_1):PAGE376
 R1201    2      B Q_RES_0201LF-0,5%,1/20W,CHIP,CS00001JE10    I30 @T6G_MB_LIB.T6G(SCH_1):PAGE376

FM_SMB_RT_ROM_MUX2_SEL @T6G_MB_LIB.T6G(SCH_1):FM_SMB_RT_ROM_MUX2_SEL
   U42    9      S PI3CSW12ZUAEX-PI3CSW12ZUAEX,SMLF,IC,AL3CSW12000    I31 @T6G_MB_LIB.T6G(SCH_1):PAGE376
 R1199    2      B Q_RES_0201LF-0,5%,1/20W,CHIP,CS00001JE10    I40 @T6G_MB_LIB.T6G(SCH_1):PAGE376

FM_SMB_RT_ROM_MUX3_SEL @T6G_MB_LIB.T6G(SCH_1):FM_SMB_RT_ROM_MUX3_SEL
   U41    9      S PI3CSW12ZUAEX-PI3CSW12ZUAEX,SMLF,IC,AL3CSW12000    I46 @T6G_MB_LIB.T6G(SCH_1):PAGE376
 R1198    2      B Q_RES_0201LF-0,5%,1/20W,CHIP,CS00001JE10    I53 @T6G_MB_LIB.T6G(SCH_1):PAGE376

FM_SMB_RT_ROM_MUX4_SEL @T6G_MB_LIB.T6G(SCH_1):FM_SMB_RT_ROM_MUX4_SEL
   U43    9      S PI3CSW12ZUAEX-PI3CSW12ZUAEX,SMLF,IC,AL3CSW12000    I61 @T6G_MB_LIB.T6G(SCH_1):PAGE376
 R1200    2      B Q_RES_0201LF-0,5%,1/20W,CHIP,CS00001JE10    I68 @T6G_MB_LIB.T6G(SCH_1):PAGE376

FM_SMB_RT_ROM_MUX5_SEL @T6G_MB_LIB.T6G(SCH_1):FM_SMB_RT_ROM_MUX5_SEL
   U49    9      S PI3CSW12ZUAEX-PI3CSW12ZUAEX,SMLF,IC,AL3CSW12000    I85 @T6G_MB_LIB.T6G(SCH_1):PAGE376
 R1211    2      B Q_RES_0201LF-0,5%,1/20W,CHIP,CS00001JE10    I86 @T6G_MB_LIB.T6G(SCH_1):PAGE376

FM_SMB_RT_ROM_MUX6_SEL @T6G_MB_LIB.T6G(SCH_1):FM_SMB_RT_ROM_MUX6_SEL
   U48    9      S PI3CSW12ZUAEX-PI3CSW12ZUAEX,SMLF,IC,AL3CSW12000    I76 @T6G_MB_LIB.T6G(SCH_1):PAGE376
 R1210    2      B Q_RES_0201LF-0,5%,1/20W,CHIP,CS00001JE10   I109 @T6G_MB_LIB.T6G(SCH_1):PAGE376

FM_SMB_RT_ROM_MUX7_SEL @T6G_MB_LIB.T6G(SCH_1):FM_SMB_RT_ROM_MUX7_SEL
   U46    9      S PI3CSW12ZUAEX-PI3CSW12ZUAEX,SMLF,IC,AL3CSW12000   I108 @T6G_MB_LIB.T6G(SCH_1):PAGE376
 R1206    2      B Q_RES_0201LF-0,5%,1/20W,CHIP,CS00001JE10   I115 @T6G_MB_LIB.T6G(SCH_1):PAGE376

FM_SMB_RT_ROM_MUX8_SEL @T6G_MB_LIB.T6G(SCH_1):FM_SMB_RT_ROM_MUX8_SEL
   U47    9      S PI3CSW12ZUAEX-PI3CSW12ZUAEX,SMLF,IC,AL3CSW12000   I121 @T6G_MB_LIB.T6G(SCH_1):PAGE376
 R1209    2      B Q_RES_0201LF-0,5%,1/20W,CHIP,CS00001JE10   I123 @T6G_MB_LIB.T6G(SCH_1):PAGE376

FM_SMERR_BUF_LED_N @T6G_MB_LIB.T6G(SCH_1):FM_SMERR_BUF_LED_N
  R936    1      A Q_RES_0402LF-0,5%,1/16W,CHIP,CS00002JB13    I22 @T6G_MB_LIB.T6G(SCH_1):PAGE143
   U86    4      Y SN74LVC1G07DBVR_SMLF-SN74LVC1G07DBVR,IC,AL1G0007024    I31 @T6G_MB_LIB.T6G(SCH_1):PAGE143

FM_SMERR_BUF_R_LED_N @T6G_MB_LIB.T6G(SCH_1):FM_SMERR_BUF_R_LED_N
  R945    2      B Q_RES_0402LF-4.7K,5%,1/16W,CHIP,CS24702JB10    I18 @T6G_MB_LIB.T6G(SCH_1):PAGE143
   Q11    2     G1 MOSFET_DUAL_6P-2N7002KDW,SMLF,IC,BAM70020047    I19 @T6G_MB_LIB.T6G(SCH_1):PAGE143
  R936    2      B Q_RES_0402LF-0,5%,1/16W,CHIP,CS00002JB13    I22 @T6G_MB_LIB.T6G(SCH_1):PAGE143

FM_SMERR_LED_N @T6G_MB_LIB.T6G(SCH_1):FM_SMERR_LED_N
   U86    2      A SN74LVC1G07DBVR_SMLF-SN74LVC1G07DBVR,IC,AL1G0007024    I31 @T6G_MB_LIB.T6G(SCH_1):PAGE143
  R933    2      B Q_RES_0402LF-33,5%,1/16W,CHIP,CS03302JB10   I215 @T6G_MB_LIB.T6G(SCH_1):PAGE80

FM_SMERR_LED_R_N @T6G_MB_LIB.T6G(SCH_1):FM_SMERR_LED_R_N
  R933    1      A Q_RES_0402LF-33,5%,1/16W,CHIP,CS03302JB10   I215 @T6G_MB_LIB.T6G(SCH_1):PAGE80
   U18  M22 PR17A||PCLKT1_0 LCMXO3LF9400C5BG484C-LCMXO3LF-9400C-5BG484C,SMLF,IA   I217 @T6G_MB_LIB.T6G(SCH_1):PAGE80

FM_SMM_CRASHDUMP @T6G_MB_LIB.T6G(SCH_1):FM_SMM_CRASHDUMP
  R243    1      A Q_RES_0402LF-0,5%,1/16W,CHIP,CS00002JB13    I63 @T6G_MB_LIB.T6G(SCH_1):PAGE81
 R5026    2      B Q_RES_0402LF-4.7K,5%,1/16W,EMPTY,CS24702JB10    I40 @T6G_MB_LIB.T6G(SCH_1):PAGE28
  R444    1      A Q_RES_0402LF-4.7K,5%,1/16W,CHIP,CS24702JB10    I43 @T6G_MB_LIB.T6G(SCH_1):PAGE28
   U25 DF40 AGPIO5||DEVSLP0||SATA_ZP0_L GENOA_SP5-SOCKET6096_13568-001,SMLF,IO,DGA^6000030   I188 @T6G_MB_LIB.T6G(SCH_1):PAGE28

FM_SMM_CRASHDUMP_R @T6G_MB_LIB.T6G(SCH_1):FM_SMM_CRASHDUMP_R
  R243    2      B Q_RES_0402LF-0,5%,1/16W,CHIP,CS00002JB13    I63 @T6G_MB_LIB.T6G(SCH_1):PAGE81
   U18   D1   PL5A LCMXO3LF9400C5BG484C-LCMXO3LF-9400C-5BG484C,SMLF,IA   I143 @T6G_MB_LIB.T6G(SCH_1):PAGE81

FM_SOL_UART_CH_SEL @T6G_MB_LIB.T6G(SCH_1):FM_SOL_UART_CH_SEL
   U18  B20  PT42B LCMXO3LF9400C5BG484C-LCMXO3LF-9400C-5BG484C,SMLF,IA    I94 @T6G_MB_LIB.T6G(SCH_1):PAGE79
 R3778    2      B Q_RES_0402LF-0,5%,1/16W,CHIP,CS00002JB13   I169 @T6G_MB_LIB.T6G(SCH_1):PAGE348

FM_SOL_UART_CH_SEL_R @T6G_MB_LIB.T6G(SCH_1):FM_SOL_UART_CH_SEL_R
   J41 OB14 RBT_CRS_DV SCONN168_ME1016810202011-SCONN168_ME1016810202011,A   I176 @T6G_MB_LIB.T6G(SCH_1):PAGE348
 R3778    1      A Q_RES_0402LF-0,5%,1/16W,CHIP,CS00002JB13   I169 @T6G_MB_LIB.T6G(SCH_1):PAGE348

FM_SPD_CPU0_SWITCH_CTRL_N @T6G_MB_LIB.T6G(SCH_1):FM_SPD_CPU0_SWITCH_CTRL_N
  R395    2      B Q_RES_0402LF-0,5%,1/16W,CHIP,CS00002JB13   I155 @T6G_MB_LIB.T6G(SCH_1):PAGE80
 R1261    2      B Q_RES_0402LF-10K,5%,1/16W,CHIP,CS31002JB08    I15 @T6G_MB_LIB.T6G(SCH_1):PAGE144
   SW1   11     11 SW20S_DHNF10FQTR-SW20S_DHNF-10F-Q-T/R,SMLF,MECH,DHA    I90 @T6G_MB_LIB.T6G(SCH_1):PAGE144

FM_SPD_CPU0_SWITCH_CTRL_R_N @T6G_MB_LIB.T6G(SCH_1):FM_SPD_CPU0_SWITCH_CTRL_R_N
  R395    1      A Q_RES_0402LF-0,5%,1/16W,CHIP,CS00002JB13   I155 @T6G_MB_LIB.T6G(SCH_1):PAGE80
   U18  U19  PR28C LCMXO3LF9400C5BG484C-LCMXO3LF-9400C-5BG484C,SMLF,IA   I217 @T6G_MB_LIB.T6G(SCH_1):PAGE80

FM_SWB_BIC_READY @T6G_MB_LIB.T6G(SCH_1):FM_SWB_BIC_READY
 R2836    2      B Q_RES_0402LF-4.7K,5%,1/16W,CHIP,CS24702JB10    I19 @T6G_MB_LIB.T6G(SCH_1):PAGE333
   Q70    6     D1 MOSFET_NCH_DUAL-PJT138K,SMLF,IC,BAM138K0003    I35 @T6G_MB_LIB.T6G(SCH_1):PAGE333
   Q70    5     G2 MOSFET_NCH_DUAL-PJT138K,SMLF,IC,BAM138K0003   I120 @T6G_MB_LIB.T6G(SCH_1):PAGE333

FM_SWB_BIC_READY_ISO_N @T6G_MB_LIB.T6G(SCH_1):FM_SWB_BIC_READY_ISO_N
 C1754    1      A Q_CAP_0402-0.1UF,25V,10%,X7R,CH4104K1B00    I92 @T6G_MB_LIB.T6G(SCH_1):PAGE333
   Q70    3     D2 MOSFET_NCH_DUAL-PJT138K,SMLF,IC,BAM138K0003   I120 @T6G_MB_LIB.T6G(SCH_1):PAGE333
 R2844    2      B Q_RES_0402LF-33.2,1%,1/16W,CHIP,CS03322FB03   I263 @T6G_MB_LIB.T6G(SCH_1):PAGE80
 R2933    2      B Q_RES_0402LF-100K,1%,1/16W,CHIP,CS41002FB09   I180 @T6G_MB_LIB.T6G(SCH_1):PAGE333

FM_SWB_BIC_READY_ISO_R_N @T6G_MB_LIB.T6G(SCH_1):FM_SWB_BIC_READY_ISO_R_N
   U18 AB17  PB40A LCMXO3LF9400C5BG484C-LCMXO3LF-9400C-5BG484C,SMLF,IA   I216 @T6G_MB_LIB.T6G(SCH_1):PAGE80
 R2844    1      A Q_RES_0402LF-33.2,1%,1/16W,CHIP,CS03322FB03   I263 @T6G_MB_LIB.T6G(SCH_1):PAGE80

FM_SWB_BIC_READY_N @T6G_MB_LIB.T6G(SCH_1):FM_SWB_BIC_READY_N
   Q70    2     G1 MOSFET_NCH_DUAL-PJT138K,SMLF,IC,BAM138K0003    I35 @T6G_MB_LIB.T6G(SCH_1):PAGE333
 R2833    1      A Q_RES_0402LF-100K,1%,1/16W,EMPTY,CS41002FB09    I60 @T6G_MB_LIB.T6G(SCH_1):PAGE333
 R2832    2      B Q_RES_0402LF-100K,1%,1/16W,CHIP,CS41002FB09    I67 @T6G_MB_LIB.T6G(SCH_1):PAGE333
  J105   N4     N4 CONN112_10137002101LF-CONN112_10137002-101LF,THLF,A    I75 @T6G_MB_LIB.T6G(SCH_1):PAGE326

FM_SWB_PWRGD @T6G_MB_LIB.T6G(SCH_1):FM_SWB_PWRGD
 R2838    1      A Q_RES_0402LF-100K,1%,1/16W,CHIP,CS41002FB09    I62 @T6G_MB_LIB.T6G(SCH_1):PAGE333
 R2837    2      B Q_RES_0402LF-100K,1%,1/16W,EMPTY,CS41002FB09    I80 @T6G_MB_LIB.T6G(SCH_1):PAGE333
   Q71    2     G1 MOSFET_NCH_DUAL-PJT138K,SMLF,IC,BAM138K0003   I118 @T6G_MB_LIB.T6G(SCH_1):PAGE333
  J106   A3     A3 CONN112_10137002101LF-CONN112_10137002-101LF,THLF,A    I74 @T6G_MB_LIB.T6G(SCH_1):PAGE327

FM_SWB_PWRGD_ISO @T6G_MB_LIB.T6G(SCH_1):FM_SWB_PWRGD_ISO
   Q71    3     D2 MOSFET_NCH_DUAL-PJT138K,SMLF,IC,BAM138K0003   I100 @T6G_MB_LIB.T6G(SCH_1):PAGE333
 R2934    2      B Q_RES_0402LF-100K,1%,1/16W,CHIP,CS41002FB09   I101 @T6G_MB_LIB.T6G(SCH_1):PAGE333
 C1774    1      A Q_CAP_0402-0.1UF,25V,10%,X7R,CH4104K1B00   I111 @T6G_MB_LIB.T6G(SCH_1):PAGE333
 R2663    2      B Q_RES_0402LF-33.2,1%,1/16W,CHIP,CS03322FB03   I271 @T6G_MB_LIB.T6G(SCH_1):PAGE80

FM_SWB_PWRGD_ISO_R @T6G_MB_LIB.T6G(SCH_1):FM_SWB_PWRGD_ISO_R
   U18 AB18  PB41A LCMXO3LF9400C5BG484C-LCMXO3LF-9400C-5BG484C,SMLF,IA   I216 @T6G_MB_LIB.T6G(SCH_1):PAGE80
 R2663    1      A Q_RES_0402LF-33.2,1%,1/16W,CHIP,CS03322FB03   I271 @T6G_MB_LIB.T6G(SCH_1):PAGE80

FM_SWB_PWRGD_N @T6G_MB_LIB.T6G(SCH_1):FM_SWB_PWRGD_N
 R2841    2      B Q_RES_0402LF-4.7K,5%,1/16W,CHIP,CS24702JB10    I24 @T6G_MB_LIB.T6G(SCH_1):PAGE333
   Q71    5     G2 MOSFET_NCH_DUAL-PJT138K,SMLF,IC,BAM138K0003   I100 @T6G_MB_LIB.T6G(SCH_1):PAGE333
   Q71    6     D1 MOSFET_NCH_DUAL-PJT138K,SMLF,IC,BAM138K0003   I118 @T6G_MB_LIB.T6G(SCH_1):PAGE333

FM_SWB_PWR_EN @T6G_MB_LIB.T6G(SCH_1):FM_SWB_PWR_EN
   U18  AA2   PB5A LCMXO3LF9400C5BG484C-LCMXO3LF-9400C-5BG484C,SMLF,IA   I216 @T6G_MB_LIB.T6G(SCH_1):PAGE80
 R2261    2      B Q_RES_0402LF-33.2,1%,1/16W,CHIP,CS03322FB03   I284 @T6G_MB_LIB.T6G(SCH_1):PAGE80

FM_SWB_PWR_EN_R @T6G_MB_LIB.T6G(SCH_1):FM_SWB_PWR_EN_R
  U256    3     A1 74LVC2G17GW-74LVC2G17GW,SMLF,IC,AL2G0017005   I173 @T6G_MB_LIB.T6G(SCH_1):PAGE334
 R2910    2      B Q_RES_0402LF-100K,1%,1/16W,EMPTY,CS41002FB09   I187 @T6G_MB_LIB.T6G(SCH_1):PAGE334
 R2918    1      A Q_RES_0402LF-4.7K,5%,1/16W,CHIP,CS24702JB10   I188 @T6G_MB_LIB.T6G(SCH_1):PAGE334
 R2261    1      A Q_RES_0402LF-33.2,1%,1/16W,CHIP,CS03322FB03   I284 @T6G_MB_LIB.T6G(SCH_1):PAGE80

FM_SWB_PWR_EN_R1_BUF @T6G_MB_LIB.T6G(SCH_1):FM_SWB_PWR_EN_R1_BUF
  U256    4     B1 74LVC2G17GW-74LVC2G17GW,SMLF,IC,AL2G0017005   I173 @T6G_MB_LIB.T6G(SCH_1):PAGE334
 R2914    2      B Q_RES_0402LF-4.7K,5%,1/16W,EMPTY,CS24702JB10   I192 @T6G_MB_LIB.T6G(SCH_1):PAGE334
 R3515    1      A Q_RES_0402LF-49.9,1%,1/16W,CHIP,CS04992FB07   I193 @T6G_MB_LIB.T6G(SCH_1):PAGE334
 R2932    1      A Q_RES_0402LF-4.7K,5%,1/16W,CHIP,CS24702JB10   I195 @T6G_MB_LIB.T6G(SCH_1):PAGE334

FM_SWB_PWR_EN_R_BUF @T6G_MB_LIB.T6G(SCH_1):FM_SWB_PWR_EN_R_BUF
 R3515    2      B Q_RES_0402LF-49.9,1%,1/16W,CHIP,CS04992FB07   I193 @T6G_MB_LIB.T6G(SCH_1):PAGE334
  J105   N2     N2 CONN112_10137002101LF-CONN112_10137002-101LF,THLF,A    I75 @T6G_MB_LIB.T6G(SCH_1):PAGE326

FM_SYS_THROTTLE_N @T6G_MB_LIB.T6G(SCH_1):FM_SYS_THROTTLE_N
  R992    2      B Q_RES_0402LF-33,5%,1/16W,CHIP,CS03302JB10    I17 @T6G_MB_LIB.T6G(SCH_1):PAGE79
  R993    1      A Q_RES_0402LF-1K,1%,1/16W,CHIP,CS21002FB06    I53 @T6G_MB_LIB.T6G(SCH_1):PAGE82
  U104    2      A 74LVC1G07GV-74LVC1G07GV,SMLF,IC,AL1G0007001    I38 @T6G_MB_LIB.T6G(SCH_1):PAGE337
  U218    2      A 74LVC1G07GV-74LVC1G07GV,SMLF,IC,AL1G0007001    I22 @T6G_MB_LIB.T6G(SCH_1):PAGE342

FM_SYS_THROTTLE_R_N @T6G_MB_LIB.T6G(SCH_1):FM_SYS_THROTTLE_R_N
  R992    1      A Q_RES_0402LF-33,5%,1/16W,CHIP,CS03302JB10    I17 @T6G_MB_LIB.T6G(SCH_1):PAGE79
   U18  E11  PT24C LCMXO3LF9400C5BG484C-LCMXO3LF-9400C-5BG484C,SMLF,IA    I94 @T6G_MB_LIB.T6G(SCH_1):PAGE79

FM_THERMAL_ALERT_N @T6G_MB_LIB.T6G(SCH_1):FM_THERMAL_ALERT_N
 R4215    1      A Q_RES_0402LF-0,5%,1/16W,CHIP,CS00002JB13    I79 @T6G_MB_LIB.T6G(SCH_1):PAGE359
 R4214    1      A Q_RES_0402LF-0,5%,1/16W,CHIP,CS00002JB13   I108 @T6G_MB_LIB.T6G(SCH_1):PAGE359
 R4213    1      A Q_RES_0402LF-0,5%,1/16W,CHIP,CS00002JB13   I115 @T6G_MB_LIB.T6G(SCH_1):PAGE359
 R4212    1      A Q_RES_0402LF-0,5%,1/16W,CHIP,CS00002JB13   I135 @T6G_MB_LIB.T6G(SCH_1):PAGE359
 R4211    2      B Q_RES_0402LF-200K,1%,1/16W,CHIP,CS42002FB05   I168 @T6G_MB_LIB.T6G(SCH_1):PAGE359
 R4209    2      B Q_RES_0402LF-200K,1%,1/16W,EMPTY,CS42002FB05   I169 @T6G_MB_LIB.T6G(SCH_1):PAGE359
 R4210    2      B Q_RES_0402LF-200K,1%,1/16W,EMPTY,CS42002FB05   I170 @T6G_MB_LIB.T6G(SCH_1):PAGE359
 R4208    2      B Q_RES_0402LF-200K,1%,1/16W,EMPTY,CS42002FB05   I171 @T6G_MB_LIB.T6G(SCH_1):PAGE359
 R6074    1      A Q_RES_0402LF-0,5%,1/16W,CHIP,CS00002JB13    I53 @T6G_MB_LIB.T6G(SCH_1):PAGE84

FM_THERMAL_ALERT_R_N @T6G_MB_LIB.T6G(SCH_1):FM_THERMAL_ALERT_R_N
   U18   L3  PL16C LCMXO3LF9400C5BG484C-LCMXO3LF-9400C-5BG484C,SMLF,IA   I143 @T6G_MB_LIB.T6G(SCH_1):PAGE81
 R6074    2      B Q_RES_0402LF-0,5%,1/16W,CHIP,CS00002JB13    I53 @T6G_MB_LIB.T6G(SCH_1):PAGE84

FM_UARTSW_LSB_N @T6G_MB_LIB.T6G(SCH_1):FM_UARTSW_LSB_N
 R3777    1      A Q_RES_0402LF-0,5%,1/16W,CHIP,CS00002JB13    I25 @T6G_MB_LIB.T6G(SCH_1):PAGE348
   U18  G15  PT42D LCMXO3LF9400C5BG484C-LCMXO3LF-9400C-5BG484C,SMLF,IA    I94 @T6G_MB_LIB.T6G(SCH_1):PAGE79

FM_UARTSW_LSB_R @T6G_MB_LIB.T6G(SCH_1):FM_UARTSW_LSB_R
 R3777    2      B Q_RES_0402LF-0,5%,1/16W,CHIP,CS00002JB13    I25 @T6G_MB_LIB.T6G(SCH_1):PAGE348
   J41  A55 GND_A55 SCONN168_ME1016810202011-SCONN168_ME1016810202011,A   I176 @T6G_MB_LIB.T6G(SCH_1):PAGE348

FM_UARTSW_MSB_N @T6G_MB_LIB.T6G(SCH_1):FM_UARTSW_MSB_N
 R3776    1      A Q_RES_0402LF-0,5%,1/16W,CHIP,CS00002JB13    I27 @T6G_MB_LIB.T6G(SCH_1):PAGE348
   U18  F13  PT28D LCMXO3LF9400C5BG484C-LCMXO3LF-9400C-5BG484C,SMLF,IA    I94 @T6G_MB_LIB.T6G(SCH_1):PAGE79

FM_UARTSW_MSB_R @T6G_MB_LIB.T6G(SCH_1):FM_UARTSW_MSB_R
 R3776    2      B Q_RES_0402LF-0,5%,1/16W,CHIP,CS00002JB13    I27 @T6G_MB_LIB.T6G(SCH_1):PAGE348
   J41  A52 GND_A52 SCONN168_ME1016810202011-SCONN168_ME1016810202011,A   I176 @T6G_MB_LIB.T6G(SCH_1):PAGE348

FM_UART_EN @T6G_MB_LIB.T6G(SCH_1):FM_UART_EN
 R3063    2      B Q_RES_0402LF-0,5%,1/16W,CHIP,CS00002JB13   I171 @T6G_MB_LIB.T6G(SCH_1):PAGE256
  U204    1     OE 74LVC1G126SE7-74LVC1G126SE-7,SMLF,IC,AL1G0126009   I195 @T6G_MB_LIB.T6G(SCH_1):PAGE256

FM_UART_LS_EN @T6G_MB_LIB.T6G(SCH_1):FM_UART_LS_EN
 R1563    2      B Q_RES_0402LF-33,5%,1/16W,CHIP,CS03302JB10    I63 @T6G_MB_LIB.T6G(SCH_1):PAGE80
   U18   U7   PB8C LCMXO3LF9400C5BG484C-LCMXO3LF-9400C-5BG484C,SMLF,IA   I216 @T6G_MB_LIB.T6G(SCH_1):PAGE80

FM_UV_ADR_TRIGGER_N @T6G_MB_LIB.T6G(SCH_1):FM_UV_ADR_TRIGGER_N
 R6096    2      B Q_RES_0402LF-0,5%,1/16W,CHIP,CS00002JB13   I115 @T6G_MB_LIB.T6G(SCH_1):PAGE79
 R2233    2      B Q_RES_0402LF-1K,1%,1/16W,EMPTY,CS21002FB06    I45 @T6G_MB_LIB.T6G(SCH_1):PAGE372
  U206    1   OUTA LT6700CS61TRPBF-LT6700CS6-1#TRPBF,SMLF,EMPTY,AL006A    I49 @T6G_MB_LIB.T6G(SCH_1):PAGE372
 R8118    2      B Q_RES_0402LF-33.2,1%,1/16W,CHIP,CS03322FB03    I67 @T6G_MB_LIB.T6G(SCH_1):PAGE372
 R8119    2      B Q_RES_0402LF-1K,1%,1/16W,CHIP,CS21002FB06    I69 @T6G_MB_LIB.T6G(SCH_1):PAGE372

FM_UV_ADR_TRIGGER_N_R2 @T6G_MB_LIB.T6G(SCH_1):FM_UV_ADR_TRIGGER_N_R2
 R8117    2      B Q_RES_0402LF-1M,1%,1/16W,CHIP,CS51002FB05    I63 @T6G_MB_LIB.T6G(SCH_1):PAGE372
 R8118    1      A Q_RES_0402LF-33.2,1%,1/16W,CHIP,CS03322FB03    I67 @T6G_MB_LIB.T6G(SCH_1):PAGE372
 U8008    4 OUTPUT AP331AWG7-AP331AWG-7,SMLF,IC,AL000331011    I71 @T6G_MB_LIB.T6G(SCH_1):PAGE372

FM_UV_ADR_TRIGGER_R_N @T6G_MB_LIB.T6G(SCH_1):FM_UV_ADR_TRIGGER_R_N
   U18   A7  PT14B LCMXO3LF9400C5BG484C-LCMXO3LF-9400C-5BG484C,SMLF,IA    I94 @T6G_MB_LIB.T6G(SCH_1):PAGE79
 R6096    1      A Q_RES_0402LF-0,5%,1/16W,CHIP,CS00002JB13   I115 @T6G_MB_LIB.T6G(SCH_1):PAGE79

FPGA_DEBUG_LED_CTRL @T6G_MB_LIB.T6G(SCH_1):FPGA_DEBUG_LED_CTRL
  R371    1      A Q_RES_0402LF-33,5%,1/16W,CHIP,CS03302JB10   I107 @T6G_MB_LIB.T6G(SCH_1):PAGE80
 R6041    2      B Q_RES_0402LF-100K,1%,1/16W,CHIP,CS41002FB09    I69 @T6G_MB_LIB.T6G(SCH_1):PAGE144
   SW1   20     20 SW20S_DHNF10FQTR-SW20S_DHNF-10F-Q-T/R,SMLF,MECH,DHA    I90 @T6G_MB_LIB.T6G(SCH_1):PAGE144

FPGA_DEBUG_SW_SPARE @T6G_MB_LIB.T6G(SCH_1):FPGA_DEBUG_SW_SPARE
 R5099    1      A Q_RES_0402LF-0,5%,1/16W,CHIP,CS00002JB13    I35 @T6G_MB_LIB.T6G(SCH_1):PAGE80
 R6043    2      B Q_RES_0402LF-100K,1%,1/16W,CHIP,CS41002FB09    I61 @T6G_MB_LIB.T6G(SCH_1):PAGE144
   SW1   15     15 SW20S_DHNF10FQTR-SW20S_DHNF-10F-Q-T/R,SMLF,MECH,DHA    I90 @T6G_MB_LIB.T6G(SCH_1):PAGE144

FPGA_IO3V3_RSVD_1 @T6G_MB_LIB.T6G(SCH_1):FPGA_IO3V3_RSVD_1
   J41 OB13 GND_OB13 SCONN168_ME1016810202011-SCONN168_ME1016810202011,A   I176 @T6G_MB_LIB.T6G(SCH_1):PAGE348
   U18  D16  PT39D LCMXO3LF9400C5BG484C-LCMXO3LF-9400C-5BG484C,SMLF,IA    I94 @T6G_MB_LIB.T6G(SCH_1):PAGE79

FW_RECOVERY @T6G_MB_LIB.T6G(SCH_1):FW_RECOVERY
 R4087    2      B Q_RES_0402LF-0,5%,1/16W,CHIP,CS00002JB13    I31 @T6G_MB_LIB.T6G(SCH_1):PAGE348
   J41  A43 GND_A43 SCONN168_ME1016810202011-SCONN168_ME1016810202011,A   I176 @T6G_MB_LIB.T6G(SCH_1):PAGE348

FW_RECOVERY_R @T6G_MB_LIB.T6G(SCH_1):FW_RECOVERY_R
   U99    2      A SN74LVC1G07DBVR_SMLF-SN74LVC1G07DBVR,EMPTY,AL1G000A   I340 @T6G_MB_LIB.T6G(SCH_1):PAGE148
 R1342    1      A Q_RES_0402LF-10K,1%,1/16W,CHIP,CS31002FB08   I369 @T6G_MB_LIB.T6G(SCH_1):PAGE148
 R4087    1      A Q_RES_0402LF-0,5%,1/16W,CHIP,CS00002JB13    I31 @T6G_MB_LIB.T6G(SCH_1):PAGE348

GMI_CPU0_G0_CPU1_G2_TX_DN<0> @T6G_MB_LIB.T6G(SCH_1):GMI_CPU0_G0_CPU1_G2_TX_DN(0)
   U25 AF41 G0_TXN0 GENOA_SP5-SOCKET6096_13568-001,SMLF,IO,DGA^6000030   I207 @T6G_MB_LIB.T6G(SCH_1):PAGE22
   U26 AF35 G2_RXN15 GENOA_SP5-SOCKET6096_13568-001,SMLF,IO,DGA^6000030   I143 @T6G_MB_LIB.T6G(SCH_1):PAGE50

GMI_CPU0_G0_CPU1_G2_TX_DN<10> @T6G_MB_LIB.T6G(SCH_1):GMI_CPU0_G0_CPU1_G2_TX_DN(10)
   U25 AG50 G0_TXN10 GENOA_SP5-SOCKET6096_13568-001,SMLF,IO,DGA^6000030   I207 @T6G_MB_LIB.T6G(SCH_1):PAGE22
   U26 AG26 G2_RXN5 GENOA_SP5-SOCKET6096_13568-001,SMLF,IO,DGA^6000030   I143 @T6G_MB_LIB.T6G(SCH_1):PAGE50

GMI_CPU0_G0_CPU1_G2_TX_DN<11> @T6G_MB_LIB.T6G(SCH_1):GMI_CPU0_G0_CPU1_G2_TX_DN(11)
   U25 AC50 G0_TXN11 GENOA_SP5-SOCKET6096_13568-001,SMLF,IO,DGA^6000030   I207 @T6G_MB_LIB.T6G(SCH_1):PAGE22
   U26 AC26 G2_RXN4 GENOA_SP5-SOCKET6096_13568-001,SMLF,IO,DGA^6000030   I143 @T6G_MB_LIB.T6G(SCH_1):PAGE50

GMI_CPU0_G0_CPU1_G2_TX_DN<12> @T6G_MB_LIB.T6G(SCH_1):GMI_CPU0_G0_CPU1_G2_TX_DN(12)
   U25 AE50 G0_TXN12 GENOA_SP5-SOCKET6096_13568-001,SMLF,IO,DGA^6000030   I207 @T6G_MB_LIB.T6G(SCH_1):PAGE22
   U26 AE26 G2_RXN3 GENOA_SP5-SOCKET6096_13568-001,SMLF,IO,DGA^6000030   I143 @T6G_MB_LIB.T6G(SCH_1):PAGE50

GMI_CPU0_G0_CPU1_G2_TX_DN<13> @T6G_MB_LIB.T6G(SCH_1):GMI_CPU0_G0_CPU1_G2_TX_DN(13)
   U25 AG53 G0_TXN13 GENOA_SP5-SOCKET6096_13568-001,SMLF,IO,DGA^6000030   I207 @T6G_MB_LIB.T6G(SCH_1):PAGE22
   U26 AG23 G2_RXN2 GENOA_SP5-SOCKET6096_13568-001,SMLF,IO,DGA^6000030   I143 @T6G_MB_LIB.T6G(SCH_1):PAGE50

GMI_CPU0_G0_CPU1_G2_TX_DN<14> @T6G_MB_LIB.T6G(SCH_1):GMI_CPU0_G0_CPU1_G2_TX_DN(14)
   U25 AC53 G0_TXN14 GENOA_SP5-SOCKET6096_13568-001,SMLF,IO,DGA^6000030   I207 @T6G_MB_LIB.T6G(SCH_1):PAGE22
   U26 AC23 G2_RXN1 GENOA_SP5-SOCKET6096_13568-001,SMLF,IO,DGA^6000030   I143 @T6G_MB_LIB.T6G(SCH_1):PAGE50

GMI_CPU0_G0_CPU1_G2_TX_DN<15> @T6G_MB_LIB.T6G(SCH_1):GMI_CPU0_G0_CPU1_G2_TX_DN(15)
   U25 AE53 G0_TXN15 GENOA_SP5-SOCKET6096_13568-001,SMLF,IO,DGA^6000030   I207 @T6G_MB_LIB.T6G(SCH_1):PAGE22
   U26 AE23 G2_RXN0 GENOA_SP5-SOCKET6096_13568-001,SMLF,IO,DGA^6000030   I143 @T6G_MB_LIB.T6G(SCH_1):PAGE50

GMI_CPU0_G0_CPU1_G2_TX_DN<1> @T6G_MB_LIB.T6G(SCH_1):GMI_CPU0_G0_CPU1_G2_TX_DN(1)
   U25 AD41 G0_TXN1 GENOA_SP5-SOCKET6096_13568-001,SMLF,IO,DGA^6000030   I207 @T6G_MB_LIB.T6G(SCH_1):PAGE22
   U26 AD35 G2_RXN14 GENOA_SP5-SOCKET6096_13568-001,SMLF,IO,DGA^6000030   I143 @T6G_MB_LIB.T6G(SCH_1):PAGE50

GMI_CPU0_G0_CPU1_G2_TX_DN<2> @T6G_MB_LIB.T6G(SCH_1):GMI_CPU0_G0_CPU1_G2_TX_DN(2)
   U25 AB41 G0_TXN2 GENOA_SP5-SOCKET6096_13568-001,SMLF,IO,DGA^6000030   I207 @T6G_MB_LIB.T6G(SCH_1):PAGE22
   U26 AB35 G2_RXN13 GENOA_SP5-SOCKET6096_13568-001,SMLF,IO,DGA^6000030   I143 @T6G_MB_LIB.T6G(SCH_1):PAGE50

GMI_CPU0_G0_CPU1_G2_TX_DN<3> @T6G_MB_LIB.T6G(SCH_1):GMI_CPU0_G0_CPU1_G2_TX_DN(3)
   U25 AG44 G0_TXN3 GENOA_SP5-SOCKET6096_13568-001,SMLF,IO,DGA^6000030   I207 @T6G_MB_LIB.T6G(SCH_1):PAGE22
   U26 AG32 G2_RXN12 GENOA_SP5-SOCKET6096_13568-001,SMLF,IO,DGA^6000030   I143 @T6G_MB_LIB.T6G(SCH_1):PAGE50

GMI_CPU0_G0_CPU1_G2_TX_DN<4> @T6G_MB_LIB.T6G(SCH_1):GMI_CPU0_G0_CPU1_G2_TX_DN(4)
   U25 AA44 G0_TXN4 GENOA_SP5-SOCKET6096_13568-001,SMLF,IO,DGA^6000030   I207 @T6G_MB_LIB.T6G(SCH_1):PAGE22
   U26 AA32 G2_RXN11 GENOA_SP5-SOCKET6096_13568-001,SMLF,IO,DGA^6000030   I143 @T6G_MB_LIB.T6G(SCH_1):PAGE50

GMI_CPU0_G0_CPU1_G2_TX_DN<5> @T6G_MB_LIB.T6G(SCH_1):GMI_CPU0_G0_CPU1_G2_TX_DN(5)
   U25 AC44 G0_TXN5 GENOA_SP5-SOCKET6096_13568-001,SMLF,IO,DGA^6000030   I207 @T6G_MB_LIB.T6G(SCH_1):PAGE22
   U26 AC32 G2_RXN10 GENOA_SP5-SOCKET6096_13568-001,SMLF,IO,DGA^6000030   I143 @T6G_MB_LIB.T6G(SCH_1):PAGE50

GMI_CPU0_G0_CPU1_G2_TX_DN<6> @T6G_MB_LIB.T6G(SCH_1):GMI_CPU0_G0_CPU1_G2_TX_DN(6)
   U25 AE44 G0_TXN6 GENOA_SP5-SOCKET6096_13568-001,SMLF,IO,DGA^6000030   I207 @T6G_MB_LIB.T6G(SCH_1):PAGE22
   U26 AE32 G2_RXN9 GENOA_SP5-SOCKET6096_13568-001,SMLF,IO,DGA^6000030   I143 @T6G_MB_LIB.T6G(SCH_1):PAGE50

GMI_CPU0_G0_CPU1_G2_TX_DN<7> @T6G_MB_LIB.T6G(SCH_1):GMI_CPU0_G0_CPU1_G2_TX_DN(7)
   U25 AG47 G0_TXN7 GENOA_SP5-SOCKET6096_13568-001,SMLF,IO,DGA^6000030   I207 @T6G_MB_LIB.T6G(SCH_1):PAGE22
   U26 AG29 G2_RXN8 GENOA_SP5-SOCKET6096_13568-001,SMLF,IO,DGA^6000030   I143 @T6G_MB_LIB.T6G(SCH_1):PAGE50

GMI_CPU0_G0_CPU1_G2_TX_DN<8> @T6G_MB_LIB.T6G(SCH_1):GMI_CPU0_G0_CPU1_G2_TX_DN(8)
   U25 AC47 G0_TXN8 GENOA_SP5-SOCKET6096_13568-001,SMLF,IO,DGA^6000030   I207 @T6G_MB_LIB.T6G(SCH_1):PAGE22
   U26 AC29 G2_RXN7 GENOA_SP5-SOCKET6096_13568-001,SMLF,IO,DGA^6000030   I143 @T6G_MB_LIB.T6G(SCH_1):PAGE50

GMI_CPU0_G0_CPU1_G2_TX_DN<9> @T6G_MB_LIB.T6G(SCH_1):GMI_CPU0_G0_CPU1_G2_TX_DN(9)
   U25 AE47 G0_TXN9 GENOA_SP5-SOCKET6096_13568-001,SMLF,IO,DGA^6000030   I207 @T6G_MB_LIB.T6G(SCH_1):PAGE22
   U26 AE29 G2_RXN6 GENOA_SP5-SOCKET6096_13568-001,SMLF,IO,DGA^6000030   I143 @T6G_MB_LIB.T6G(SCH_1):PAGE50

GMI_CPU0_G0_CPU1_G2_TX_DP<0> @T6G_MB_LIB.T6G(SCH_1):GMI_CPU0_G0_CPU1_G2_TX_DP(0)
   U25 AF40 G0_TXP0 GENOA_SP5-SOCKET6096_13568-001,SMLF,IO,DGA^6000030   I207 @T6G_MB_LIB.T6G(SCH_1):PAGE22
   U26 AF36 G2_RXP15 GENOA_SP5-SOCKET6096_13568-001,SMLF,IO,DGA^6000030   I143 @T6G_MB_LIB.T6G(SCH_1):PAGE50

GMI_CPU0_G0_CPU1_G2_TX_DP<10> @T6G_MB_LIB.T6G(SCH_1):GMI_CPU0_G0_CPU1_G2_TX_DP(10)
   U25 AG49 G0_TXP10 GENOA_SP5-SOCKET6096_13568-001,SMLF,IO,DGA^6000030   I207 @T6G_MB_LIB.T6G(SCH_1):PAGE22
   U26 AG27 G2_RXP5 GENOA_SP5-SOCKET6096_13568-001,SMLF,IO,DGA^6000030   I143 @T6G_MB_LIB.T6G(SCH_1):PAGE50

GMI_CPU0_G0_CPU1_G2_TX_DP<11> @T6G_MB_LIB.T6G(SCH_1):GMI_CPU0_G0_CPU1_G2_TX_DP(11)
   U25 AC49 G0_TXP11 GENOA_SP5-SOCKET6096_13568-001,SMLF,IO,DGA^6000030   I207 @T6G_MB_LIB.T6G(SCH_1):PAGE22
   U26 AC27 G2_RXP4 GENOA_SP5-SOCKET6096_13568-001,SMLF,IO,DGA^6000030   I143 @T6G_MB_LIB.T6G(SCH_1):PAGE50

GMI_CPU0_G0_CPU1_G2_TX_DP<12> @T6G_MB_LIB.T6G(SCH_1):GMI_CPU0_G0_CPU1_G2_TX_DP(12)
   U25 AE49 G0_TXP12 GENOA_SP5-SOCKET6096_13568-001,SMLF,IO,DGA^6000030   I207 @T6G_MB_LIB.T6G(SCH_1):PAGE22
   U26 AE27 G2_RXP3 GENOA_SP5-SOCKET6096_13568-001,SMLF,IO,DGA^6000030   I143 @T6G_MB_LIB.T6G(SCH_1):PAGE50

GMI_CPU0_G0_CPU1_G2_TX_DP<13> @T6G_MB_LIB.T6G(SCH_1):GMI_CPU0_G0_CPU1_G2_TX_DP(13)
   U25 AG52 G0_TXP13 GENOA_SP5-SOCKET6096_13568-001,SMLF,IO,DGA^6000030   I207 @T6G_MB_LIB.T6G(SCH_1):PAGE22
   U26 AG24 G2_RXP2 GENOA_SP5-SOCKET6096_13568-001,SMLF,IO,DGA^6000030   I143 @T6G_MB_LIB.T6G(SCH_1):PAGE50

GMI_CPU0_G0_CPU1_G2_TX_DP<14> @T6G_MB_LIB.T6G(SCH_1):GMI_CPU0_G0_CPU1_G2_TX_DP(14)
   U25 AC52 G0_TXP14 GENOA_SP5-SOCKET6096_13568-001,SMLF,IO,DGA^6000030   I207 @T6G_MB_LIB.T6G(SCH_1):PAGE22
   U26 AC24 G2_RXP1 GENOA_SP5-SOCKET6096_13568-001,SMLF,IO,DGA^6000030   I143 @T6G_MB_LIB.T6G(SCH_1):PAGE50

GMI_CPU0_G0_CPU1_G2_TX_DP<15> @T6G_MB_LIB.T6G(SCH_1):GMI_CPU0_G0_CPU1_G2_TX_DP(15)
   U25 AE52 G0_TXP15 GENOA_SP5-SOCKET6096_13568-001,SMLF,IO,DGA^6000030   I207 @T6G_MB_LIB.T6G(SCH_1):PAGE22
   U26 AE24 G2_RXP0 GENOA_SP5-SOCKET6096_13568-001,SMLF,IO,DGA^6000030   I143 @T6G_MB_LIB.T6G(SCH_1):PAGE50

GMI_CPU0_G0_CPU1_G2_TX_DP<1> @T6G_MB_LIB.T6G(SCH_1):GMI_CPU0_G0_CPU1_G2_TX_DP(1)
   U25 AD40 G0_TXP1 GENOA_SP5-SOCKET6096_13568-001,SMLF,IO,DGA^6000030   I207 @T6G_MB_LIB.T6G(SCH_1):PAGE22
   U26 AD36 G2_RXP14 GENOA_SP5-SOCKET6096_13568-001,SMLF,IO,DGA^6000030   I143 @T6G_MB_LIB.T6G(SCH_1):PAGE50

GMI_CPU0_G0_CPU1_G2_TX_DP<2> @T6G_MB_LIB.T6G(SCH_1):GMI_CPU0_G0_CPU1_G2_TX_DP(2)
   U25 AB40 G0_TXP2 GENOA_SP5-SOCKET6096_13568-001,SMLF,IO,DGA^6000030   I207 @T6G_MB_LIB.T6G(SCH_1):PAGE22
   U26 AB36 G2_RXP13 GENOA_SP5-SOCKET6096_13568-001,SMLF,IO,DGA^6000030   I143 @T6G_MB_LIB.T6G(SCH_1):PAGE50

GMI_CPU0_G0_CPU1_G2_TX_DP<3> @T6G_MB_LIB.T6G(SCH_1):GMI_CPU0_G0_CPU1_G2_TX_DP(3)
   U25 AG43 G0_TXP3 GENOA_SP5-SOCKET6096_13568-001,SMLF,IO,DGA^6000030   I207 @T6G_MB_LIB.T6G(SCH_1):PAGE22
   U26 AG33 G2_RXP12 GENOA_SP5-SOCKET6096_13568-001,SMLF,IO,DGA^6000030   I143 @T6G_MB_LIB.T6G(SCH_1):PAGE50

GMI_CPU0_G0_CPU1_G2_TX_DP<4> @T6G_MB_LIB.T6G(SCH_1):GMI_CPU0_G0_CPU1_G2_TX_DP(4)
   U25 AA43 G0_TXP4 GENOA_SP5-SOCKET6096_13568-001,SMLF,IO,DGA^6000030   I207 @T6G_MB_LIB.T6G(SCH_1):PAGE22
   U26 AA33 G2_RXP11 GENOA_SP5-SOCKET6096_13568-001,SMLF,IO,DGA^6000030   I143 @T6G_MB_LIB.T6G(SCH_1):PAGE50

GMI_CPU0_G0_CPU1_G2_TX_DP<5> @T6G_MB_LIB.T6G(SCH_1):GMI_CPU0_G0_CPU1_G2_TX_DP(5)
   U25 AC43 G0_TXP5 GENOA_SP5-SOCKET6096_13568-001,SMLF,IO,DGA^6000030   I207 @T6G_MB_LIB.T6G(SCH_1):PAGE22
   U26 AC33 G2_RXP10 GENOA_SP5-SOCKET6096_13568-001,SMLF,IO,DGA^6000030   I143 @T6G_MB_LIB.T6G(SCH_1):PAGE50

GMI_CPU0_G0_CPU1_G2_TX_DP<6> @T6G_MB_LIB.T6G(SCH_1):GMI_CPU0_G0_CPU1_G2_TX_DP(6)
   U25 AE43 G0_TXP6 GENOA_SP5-SOCKET6096_13568-001,SMLF,IO,DGA^6000030   I207 @T6G_MB_LIB.T6G(SCH_1):PAGE22
   U26 AE33 G2_RXP9 GENOA_SP5-SOCKET6096_13568-001,SMLF,IO,DGA^6000030   I143 @T6G_MB_LIB.T6G(SCH_1):PAGE50

GMI_CPU0_G0_CPU1_G2_TX_DP<7> @T6G_MB_LIB.T6G(SCH_1):GMI_CPU0_G0_CPU1_G2_TX_DP(7)
   U25 AG46 G0_TXP7 GENOA_SP5-SOCKET6096_13568-001,SMLF,IO,DGA^6000030   I207 @T6G_MB_LIB.T6G(SCH_1):PAGE22
   U26 AG30 G2_RXP8 GENOA_SP5-SOCKET6096_13568-001,SMLF,IO,DGA^6000030   I143 @T6G_MB_LIB.T6G(SCH_1):PAGE50

GMI_CPU0_G0_CPU1_G2_TX_DP<8> @T6G_MB_LIB.T6G(SCH_1):GMI_CPU0_G0_CPU1_G2_TX_DP(8)
   U25 AC46 G0_TXP8 GENOA_SP5-SOCKET6096_13568-001,SMLF,IO,DGA^6000030   I207 @T6G_MB_LIB.T6G(SCH_1):PAGE22
   U26 AC30 G2_RXP7 GENOA_SP5-SOCKET6096_13568-001,SMLF,IO,DGA^6000030   I143 @T6G_MB_LIB.T6G(SCH_1):PAGE50

GMI_CPU0_G0_CPU1_G2_TX_DP<9> @T6G_MB_LIB.T6G(SCH_1):GMI_CPU0_G0_CPU1_G2_TX_DP(9)
   U25 AE46 G0_TXP9 GENOA_SP5-SOCKET6096_13568-001,SMLF,IO,DGA^6000030   I207 @T6G_MB_LIB.T6G(SCH_1):PAGE22
   U26 AE30 G2_RXP6 GENOA_SP5-SOCKET6096_13568-001,SMLF,IO,DGA^6000030   I143 @T6G_MB_LIB.T6G(SCH_1):PAGE50

GMI_CPU0_G1_CPU1_G3_TX_DN<0> @T6G_MB_LIB.T6G(SCH_1):GMI_CPU0_G1_CPU1_G3_TX_DN(0)
   U25 AP41 G1_TXN0 GENOA_SP5-SOCKET6096_13568-001,SMLF,IO,DGA^6000030   I208 @T6G_MB_LIB.T6G(SCH_1):PAGE22
   U26 AP35 G3_RXN15||SATA37_RXN GENOA_SP5-SOCKET6096_13568-001,SMLF,IO,DGA^6000030   I144 @T6G_MB_LIB.T6G(SCH_1):PAGE50

GMI_CPU0_G1_CPU1_G3_TX_DN<10> @T6G_MB_LIB.T6G(SCH_1):GMI_CPU0_G1_CPU1_G3_TX_DN(10)
   U25 AN50 G1_TXN10 GENOA_SP5-SOCKET6096_13568-001,SMLF,IO,DGA^6000030   I208 @T6G_MB_LIB.T6G(SCH_1):PAGE22
   U26 AN26 G3_RXN5||SATA25_RXN GENOA_SP5-SOCKET6096_13568-001,SMLF,IO,DGA^6000030   I144 @T6G_MB_LIB.T6G(SCH_1):PAGE50

GMI_CPU0_G1_CPU1_G3_TX_DN<11> @T6G_MB_LIB.T6G(SCH_1):GMI_CPU0_G1_CPU1_G3_TX_DN(11)
   U25 AJ50 G1_TXN11 GENOA_SP5-SOCKET6096_13568-001,SMLF,IO,DGA^6000030   I208 @T6G_MB_LIB.T6G(SCH_1):PAGE22
   U26 AJ26 G3_RXN4||SATA24_RXN GENOA_SP5-SOCKET6096_13568-001,SMLF,IO,DGA^6000030   I144 @T6G_MB_LIB.T6G(SCH_1):PAGE50

GMI_CPU0_G1_CPU1_G3_TX_DN<12> @T6G_MB_LIB.T6G(SCH_1):GMI_CPU0_G1_CPU1_G3_TX_DN(12)
   U25 AL50 G1_TXN12 GENOA_SP5-SOCKET6096_13568-001,SMLF,IO,DGA^6000030   I208 @T6G_MB_LIB.T6G(SCH_1):PAGE22
   U26 AL26 G3_RXN3||SATA23_RXN GENOA_SP5-SOCKET6096_13568-001,SMLF,IO,DGA^6000030   I144 @T6G_MB_LIB.T6G(SCH_1):PAGE50

GMI_CPU0_G1_CPU1_G3_TX_DN<13> @T6G_MB_LIB.T6G(SCH_1):GMI_CPU0_G1_CPU1_G3_TX_DN(13)
   U25 AN53 G1_TXN13 GENOA_SP5-SOCKET6096_13568-001,SMLF,IO,DGA^6000030   I208 @T6G_MB_LIB.T6G(SCH_1):PAGE22
   U26 AN23 G3_RXN2||SATA22_RXN GENOA_SP5-SOCKET6096_13568-001,SMLF,IO,DGA^6000030   I144 @T6G_MB_LIB.T6G(SCH_1):PAGE50

GMI_CPU0_G1_CPU1_G3_TX_DN<14> @T6G_MB_LIB.T6G(SCH_1):GMI_CPU0_G1_CPU1_G3_TX_DN(14)
   U25 AJ53 G1_TXN14 GENOA_SP5-SOCKET6096_13568-001,SMLF,IO,DGA^6000030   I208 @T6G_MB_LIB.T6G(SCH_1):PAGE22
   U26 AJ23 G3_RXN1||SATA21_RXN GENOA_SP5-SOCKET6096_13568-001,SMLF,IO,DGA^6000030   I144 @T6G_MB_LIB.T6G(SCH_1):PAGE50

GMI_CPU0_G1_CPU1_G3_TX_DN<15> @T6G_MB_LIB.T6G(SCH_1):GMI_CPU0_G1_CPU1_G3_TX_DN(15)
   U25 AL53 G1_TXN15 GENOA_SP5-SOCKET6096_13568-001,SMLF,IO,DGA^6000030   I208 @T6G_MB_LIB.T6G(SCH_1):PAGE22
   U26 AL23 G3_RXN0||SATA20_RXN GENOA_SP5-SOCKET6096_13568-001,SMLF,IO,DGA^6000030   I144 @T6G_MB_LIB.T6G(SCH_1):PAGE50

GMI_CPU0_G1_CPU1_G3_TX_DN<1> @T6G_MB_LIB.T6G(SCH_1):GMI_CPU0_G1_CPU1_G3_TX_DN(1)
   U25 AM41 G1_TXN1 GENOA_SP5-SOCKET6096_13568-001,SMLF,IO,DGA^6000030   I208 @T6G_MB_LIB.T6G(SCH_1):PAGE22
   U26 AM35 G3_RXN14||SATA36_RXN GENOA_SP5-SOCKET6096_13568-001,SMLF,IO,DGA^6000030   I144 @T6G_MB_LIB.T6G(SCH_1):PAGE50

GMI_CPU0_G1_CPU1_G3_TX_DN<2> @T6G_MB_LIB.T6G(SCH_1):GMI_CPU0_G1_CPU1_G3_TX_DN(2)
   U25 AH41 G1_TXN2 GENOA_SP5-SOCKET6096_13568-001,SMLF,IO,DGA^6000030   I208 @T6G_MB_LIB.T6G(SCH_1):PAGE22
   U26 AH35 G3_RXN13||SATA35_RXN GENOA_SP5-SOCKET6096_13568-001,SMLF,IO,DGA^6000030   I144 @T6G_MB_LIB.T6G(SCH_1):PAGE50

GMI_CPU0_G1_CPU1_G3_TX_DN<3> @T6G_MB_LIB.T6G(SCH_1):GMI_CPU0_G1_CPU1_G3_TX_DN(3)
   U25 AK41 G1_TXN3 GENOA_SP5-SOCKET6096_13568-001,SMLF,IO,DGA^6000030   I208 @T6G_MB_LIB.T6G(SCH_1):PAGE22
   U26 AK35 G3_RXN12||SATA34_RXN GENOA_SP5-SOCKET6096_13568-001,SMLF,IO,DGA^6000030   I144 @T6G_MB_LIB.T6G(SCH_1):PAGE50

GMI_CPU0_G1_CPU1_G3_TX_DN<4> @T6G_MB_LIB.T6G(SCH_1):GMI_CPU0_G1_CPU1_G3_TX_DN(4)
   U25 AN44 G1_TXN4 GENOA_SP5-SOCKET6096_13568-001,SMLF,IO,DGA^6000030   I208 @T6G_MB_LIB.T6G(SCH_1):PAGE22
   U26 AN32 G3_RXN11||SATA33_RXN GENOA_SP5-SOCKET6096_13568-001,SMLF,IO,DGA^6000030   I144 @T6G_MB_LIB.T6G(SCH_1):PAGE50

GMI_CPU0_G1_CPU1_G3_TX_DN<5> @T6G_MB_LIB.T6G(SCH_1):GMI_CPU0_G1_CPU1_G3_TX_DN(5)
   U25 AJ44 G1_TXN5 GENOA_SP5-SOCKET6096_13568-001,SMLF,IO,DGA^6000030   I208 @T6G_MB_LIB.T6G(SCH_1):PAGE22
   U26 AJ32 G3_RXN10||SATA32_RXN GENOA_SP5-SOCKET6096_13568-001,SMLF,IO,DGA^6000030   I144 @T6G_MB_LIB.T6G(SCH_1):PAGE50

GMI_CPU0_G1_CPU1_G3_TX_DN<6> @T6G_MB_LIB.T6G(SCH_1):GMI_CPU0_G1_CPU1_G3_TX_DN(6)
   U25 AL44 G1_TXN6 GENOA_SP5-SOCKET6096_13568-001,SMLF,IO,DGA^6000030   I208 @T6G_MB_LIB.T6G(SCH_1):PAGE22
   U26 AL32 G3_RXN9||SATA31_RXN GENOA_SP5-SOCKET6096_13568-001,SMLF,IO,DGA^6000030   I144 @T6G_MB_LIB.T6G(SCH_1):PAGE50

GMI_CPU0_G1_CPU1_G3_TX_DN<7> @T6G_MB_LIB.T6G(SCH_1):GMI_CPU0_G1_CPU1_G3_TX_DN(7)
   U25 AN47 G1_TXN7 GENOA_SP5-SOCKET6096_13568-001,SMLF,IO,DGA^6000030   I208 @T6G_MB_LIB.T6G(SCH_1):PAGE22
   U26 AN29 G3_RXN8||SATA30_RXN GENOA_SP5-SOCKET6096_13568-001,SMLF,IO,DGA^6000030   I144 @T6G_MB_LIB.T6G(SCH_1):PAGE50

GMI_CPU0_G1_CPU1_G3_TX_DN<8> @T6G_MB_LIB.T6G(SCH_1):GMI_CPU0_G1_CPU1_G3_TX_DN(8)
   U25 AJ47 G1_TXN8 GENOA_SP5-SOCKET6096_13568-001,SMLF,IO,DGA^6000030   I208 @T6G_MB_LIB.T6G(SCH_1):PAGE22
   U26 AJ29 G3_RXN7||SATA27_RXN GENOA_SP5-SOCKET6096_13568-001,SMLF,IO,DGA^6000030   I144 @T6G_MB_LIB.T6G(SCH_1):PAGE50

GMI_CPU0_G1_CPU1_G3_TX_DN<9> @T6G_MB_LIB.T6G(SCH_1):GMI_CPU0_G1_CPU1_G3_TX_DN(9)
   U25 AL47 G1_TXN9 GENOA_SP5-SOCKET6096_13568-001,SMLF,IO,DGA^6000030   I208 @T6G_MB_LIB.T6G(SCH_1):PAGE22
   U26 AL29 G3_RXN6||SATA26_RXN GENOA_SP5-SOCKET6096_13568-001,SMLF,IO,DGA^6000030   I144 @T6G_MB_LIB.T6G(SCH_1):PAGE50

GMI_CPU0_G1_CPU1_G3_TX_DP<0> @T6G_MB_LIB.T6G(SCH_1):GMI_CPU0_G1_CPU1_G3_TX_DP(0)
   U25 AP40 G1_TXP0 GENOA_SP5-SOCKET6096_13568-001,SMLF,IO,DGA^6000030   I208 @T6G_MB_LIB.T6G(SCH_1):PAGE22
   U26 AP36 G3_RXP15||SATA37_RXP GENOA_SP5-SOCKET6096_13568-001,SMLF,IO,DGA^6000030   I144 @T6G_MB_LIB.T6G(SCH_1):PAGE50

GMI_CPU0_G1_CPU1_G3_TX_DP<10> @T6G_MB_LIB.T6G(SCH_1):GMI_CPU0_G1_CPU1_G3_TX_DP(10)
   U25 AN49 G1_TXP10 GENOA_SP5-SOCKET6096_13568-001,SMLF,IO,DGA^6000030   I208 @T6G_MB_LIB.T6G(SCH_1):PAGE22
   U26 AN27 G3_RXP5||SATA25_RXP GENOA_SP5-SOCKET6096_13568-001,SMLF,IO,DGA^6000030   I144 @T6G_MB_LIB.T6G(SCH_1):PAGE50

GMI_CPU0_G1_CPU1_G3_TX_DP<11> @T6G_MB_LIB.T6G(SCH_1):GMI_CPU0_G1_CPU1_G3_TX_DP(11)
   U25 AJ49 G1_TXP11 GENOA_SP5-SOCKET6096_13568-001,SMLF,IO,DGA^6000030   I208 @T6G_MB_LIB.T6G(SCH_1):PAGE22
   U26 AJ27 G3_RXP4||SATA24_RXP GENOA_SP5-SOCKET6096_13568-001,SMLF,IO,DGA^6000030   I144 @T6G_MB_LIB.T6G(SCH_1):PAGE50

GMI_CPU0_G1_CPU1_G3_TX_DP<12> @T6G_MB_LIB.T6G(SCH_1):GMI_CPU0_G1_CPU1_G3_TX_DP(12)
   U25 AL49 G1_TXP12 GENOA_SP5-SOCKET6096_13568-001,SMLF,IO,DGA^6000030   I208 @T6G_MB_LIB.T6G(SCH_1):PAGE22
   U26 AL27 G3_RXP3||SATA23_RXP GENOA_SP5-SOCKET6096_13568-001,SMLF,IO,DGA^6000030   I144 @T6G_MB_LIB.T6G(SCH_1):PAGE50

GMI_CPU0_G1_CPU1_G3_TX_DP<13> @T6G_MB_LIB.T6G(SCH_1):GMI_CPU0_G1_CPU1_G3_TX_DP(13)
   U25 AN52 G1_TXP13 GENOA_SP5-SOCKET6096_13568-001,SMLF,IO,DGA^6000030   I208 @T6G_MB_LIB.T6G(SCH_1):PAGE22
   U26 AN24 G3_RXP2||SATA22_RXP GENOA_SP5-SOCKET6096_13568-001,SMLF,IO,DGA^6000030   I144 @T6G_MB_LIB.T6G(SCH_1):PAGE50

GMI_CPU0_G1_CPU1_G3_TX_DP<14> @T6G_MB_LIB.T6G(SCH_1):GMI_CPU0_G1_CPU1_G3_TX_DP(14)
   U25 AJ52 G1_TXP14 GENOA_SP5-SOCKET6096_13568-001,SMLF,IO,DGA^6000030   I208 @T6G_MB_LIB.T6G(SCH_1):PAGE22
   U26 AJ24 G3_RXP1||SATA21_RXP GENOA_SP5-SOCKET6096_13568-001,SMLF,IO,DGA^6000030   I144 @T6G_MB_LIB.T6G(SCH_1):PAGE50

GMI_CPU0_G1_CPU1_G3_TX_DP<15> @T6G_MB_LIB.T6G(SCH_1):GMI_CPU0_G1_CPU1_G3_TX_DP(15)
   U25 AL52 G1_TXP15 GENOA_SP5-SOCKET6096_13568-001,SMLF,IO,DGA^6000030   I208 @T6G_MB_LIB.T6G(SCH_1):PAGE22
   U26 AL24 G3_RXP0||SATA20_RXP GENOA_SP5-SOCKET6096_13568-001,SMLF,IO,DGA^6000030   I144 @T6G_MB_LIB.T6G(SCH_1):PAGE50

GMI_CPU0_G1_CPU1_G3_TX_DP<1> @T6G_MB_LIB.T6G(SCH_1):GMI_CPU0_G1_CPU1_G3_TX_DP(1)
   U25 AM40 G1_TXP1 GENOA_SP5-SOCKET6096_13568-001,SMLF,IO,DGA^6000030   I208 @T6G_MB_LIB.T6G(SCH_1):PAGE22
   U26 AM36 G3_RXP14||SATA36_RXP GENOA_SP5-SOCKET6096_13568-001,SMLF,IO,DGA^6000030   I144 @T6G_MB_LIB.T6G(SCH_1):PAGE50

GMI_CPU0_G1_CPU1_G3_TX_DP<2> @T6G_MB_LIB.T6G(SCH_1):GMI_CPU0_G1_CPU1_G3_TX_DP(2)
   U25 AH40 G1_TXP2 GENOA_SP5-SOCKET6096_13568-001,SMLF,IO,DGA^6000030   I208 @T6G_MB_LIB.T6G(SCH_1):PAGE22
   U26 AH36 G3_RXP13||SATA35_RXP GENOA_SP5-SOCKET6096_13568-001,SMLF,IO,DGA^6000030   I144 @T6G_MB_LIB.T6G(SCH_1):PAGE50

GMI_CPU0_G1_CPU1_G3_TX_DP<3> @T6G_MB_LIB.T6G(SCH_1):GMI_CPU0_G1_CPU1_G3_TX_DP(3)
   U25 AK40 G1_TXP3 GENOA_SP5-SOCKET6096_13568-001,SMLF,IO,DGA^6000030   I208 @T6G_MB_LIB.T6G(SCH_1):PAGE22
   U26 AK36 G3_RXP12||SATA34_RXP GENOA_SP5-SOCKET6096_13568-001,SMLF,IO,DGA^6000030   I144 @T6G_MB_LIB.T6G(SCH_1):PAGE50

GMI_CPU0_G1_CPU1_G3_TX_DP<4> @T6G_MB_LIB.T6G(SCH_1):GMI_CPU0_G1_CPU1_G3_TX_DP(4)
   U25 AN43 G1_TXP4 GENOA_SP5-SOCKET6096_13568-001,SMLF,IO,DGA^6000030   I208 @T6G_MB_LIB.T6G(SCH_1):PAGE22
   U26 AN33 G3_RXP11||SATA33_RXP GENOA_SP5-SOCKET6096_13568-001,SMLF,IO,DGA^6000030   I144 @T6G_MB_LIB.T6G(SCH_1):PAGE50

GMI_CPU0_G1_CPU1_G3_TX_DP<5> @T6G_MB_LIB.T6G(SCH_1):GMI_CPU0_G1_CPU1_G3_TX_DP(5)
   U25 AJ43 G1_TXP5 GENOA_SP5-SOCKET6096_13568-001,SMLF,IO,DGA^6000030   I208 @T6G_MB_LIB.T6G(SCH_1):PAGE22
   U26 AJ33 G3_RXP10||SATA32_RXP GENOA_SP5-SOCKET6096_13568-001,SMLF,IO,DGA^6000030   I144 @T6G_MB_LIB.T6G(SCH_1):PAGE50

GMI_CPU0_G1_CPU1_G3_TX_DP<6> @T6G_MB_LIB.T6G(SCH_1):GMI_CPU0_G1_CPU1_G3_TX_DP(6)
   U25 AL43 G1_TXP6 GENOA_SP5-SOCKET6096_13568-001,SMLF,IO,DGA^6000030   I208 @T6G_MB_LIB.T6G(SCH_1):PAGE22
   U26 AL33 G3_RXP9||SATA31_RXP GENOA_SP5-SOCKET6096_13568-001,SMLF,IO,DGA^6000030   I144 @T6G_MB_LIB.T6G(SCH_1):PAGE50

GMI_CPU0_G1_CPU1_G3_TX_DP<7> @T6G_MB_LIB.T6G(SCH_1):GMI_CPU0_G1_CPU1_G3_TX_DP(7)
   U25 AN46 G1_TXP7 GENOA_SP5-SOCKET6096_13568-001,SMLF,IO,DGA^6000030   I208 @T6G_MB_LIB.T6G(SCH_1):PAGE22
   U26 AN30 G3_RXP8||SATA30_RXP GENOA_SP5-SOCKET6096_13568-001,SMLF,IO,DGA^6000030   I144 @T6G_MB_LIB.T6G(SCH_1):PAGE50

GMI_CPU0_G1_CPU1_G3_TX_DP<8> @T6G_MB_LIB.T6G(SCH_1):GMI_CPU0_G1_CPU1_G3_TX_DP(8)
   U25 AJ46 G1_TXP8 GENOA_SP5-SOCKET6096_13568-001,SMLF,IO,DGA^6000030   I208 @T6G_MB_LIB.T6G(SCH_1):PAGE22
   U26 AJ30 G3_RXP7||SATA27_RXP GENOA_SP5-SOCKET6096_13568-001,SMLF,IO,DGA^6000030   I144 @T6G_MB_LIB.T6G(SCH_1):PAGE50

GMI_CPU0_G1_CPU1_G3_TX_DP<9> @T6G_MB_LIB.T6G(SCH_1):GMI_CPU0_G1_CPU1_G3_TX_DP(9)
   U25 AL46 G1_TXP9 GENOA_SP5-SOCKET6096_13568-001,SMLF,IO,DGA^6000030   I208 @T6G_MB_LIB.T6G(SCH_1):PAGE22
   U26 AL30 G3_RXP6||SATA26_RXP GENOA_SP5-SOCKET6096_13568-001,SMLF,IO,DGA^6000030   I144 @T6G_MB_LIB.T6G(SCH_1):PAGE50

GMI_CPU0_G2_CPU1_G0_TX_DN<0> @T6G_MB_LIB.T6G(SCH_1):GMI_CPU0_G2_CPU1_G0_TX_DN(0)
   U25  N24 G2_TXN0 GENOA_SP5-SOCKET6096_13568-001,SMLF,IO,DGA^6000030   I215 @T6G_MB_LIB.T6G(SCH_1):PAGE23
   U26  N52 G0_RXN15 GENOA_SP5-SOCKET6096_13568-001,SMLF,IO,DGA^6000030   I213 @T6G_MB_LIB.T6G(SCH_1):PAGE49

GMI_CPU0_G2_CPU1_G0_TX_DN<10> @T6G_MB_LIB.T6G(SCH_1):GMI_CPU0_G2_CPU1_G0_TX_DN(10)
   U25  J33 G2_TXN10 GENOA_SP5-SOCKET6096_13568-001,SMLF,IO,DGA^6000030   I215 @T6G_MB_LIB.T6G(SCH_1):PAGE23
   U26  J43 G0_RXN5 GENOA_SP5-SOCKET6096_13568-001,SMLF,IO,DGA^6000030   I213 @T6G_MB_LIB.T6G(SCH_1):PAGE49

GMI_CPU0_G2_CPU1_G0_TX_DN<11> @T6G_MB_LIB.T6G(SCH_1):GMI_CPU0_G2_CPU1_G0_TX_DN(11)
   U25  G33 G2_TXN11 GENOA_SP5-SOCKET6096_13568-001,SMLF,IO,DGA^6000030   I215 @T6G_MB_LIB.T6G(SCH_1):PAGE23
   U26  G43 G0_RXN4 GENOA_SP5-SOCKET6096_13568-001,SMLF,IO,DGA^6000030   I213 @T6G_MB_LIB.T6G(SCH_1):PAGE49

GMI_CPU0_G2_CPU1_G0_TX_DN<12> @T6G_MB_LIB.T6G(SCH_1):GMI_CPU0_G2_CPU1_G0_TX_DN(12)
   U25  L33 G2_TXN12 GENOA_SP5-SOCKET6096_13568-001,SMLF,IO,DGA^6000030   I215 @T6G_MB_LIB.T6G(SCH_1):PAGE23
   U26  L43 G0_RXN3 GENOA_SP5-SOCKET6096_13568-001,SMLF,IO,DGA^6000030   I213 @T6G_MB_LIB.T6G(SCH_1):PAGE49

GMI_CPU0_G2_CPU1_G0_TX_DN<13> @T6G_MB_LIB.T6G(SCH_1):GMI_CPU0_G2_CPU1_G0_TX_DN(13)
   U25  H36 G2_TXN13 GENOA_SP5-SOCKET6096_13568-001,SMLF,IO,DGA^6000030   I215 @T6G_MB_LIB.T6G(SCH_1):PAGE23
   U26  H40 G0_RXN2 GENOA_SP5-SOCKET6096_13568-001,SMLF,IO,DGA^6000030   I213 @T6G_MB_LIB.T6G(SCH_1):PAGE49

GMI_CPU0_G2_CPU1_G0_TX_DN<14> @T6G_MB_LIB.T6G(SCH_1):GMI_CPU0_G2_CPU1_G0_TX_DN(14)
   U25  K36 G2_TXN14 GENOA_SP5-SOCKET6096_13568-001,SMLF,IO,DGA^6000030   I215 @T6G_MB_LIB.T6G(SCH_1):PAGE23
   U26  K40 G0_RXN1 GENOA_SP5-SOCKET6096_13568-001,SMLF,IO,DGA^6000030   I213 @T6G_MB_LIB.T6G(SCH_1):PAGE49

GMI_CPU0_G2_CPU1_G0_TX_DN<15> @T6G_MB_LIB.T6G(SCH_1):GMI_CPU0_G2_CPU1_G0_TX_DN(15)
   U25  M36 G2_TXN15 GENOA_SP5-SOCKET6096_13568-001,SMLF,IO,DGA^6000030   I215 @T6G_MB_LIB.T6G(SCH_1):PAGE23
   U26  M40 G0_RXN0 GENOA_SP5-SOCKET6096_13568-001,SMLF,IO,DGA^6000030   I213 @T6G_MB_LIB.T6G(SCH_1):PAGE49

GMI_CPU0_G2_CPU1_G0_TX_DN<1> @T6G_MB_LIB.T6G(SCH_1):GMI_CPU0_G2_CPU1_G0_TX_DN(1)
   U25  J24 G2_TXN1 GENOA_SP5-SOCKET6096_13568-001,SMLF,IO,DGA^6000030   I215 @T6G_MB_LIB.T6G(SCH_1):PAGE23
   U26  J52 G0_RXN14 GENOA_SP5-SOCKET6096_13568-001,SMLF,IO,DGA^6000030   I213 @T6G_MB_LIB.T6G(SCH_1):PAGE49

GMI_CPU0_G2_CPU1_G0_TX_DN<2> @T6G_MB_LIB.T6G(SCH_1):GMI_CPU0_G2_CPU1_G0_TX_DN(2)
   U25  G24 G2_TXN2 GENOA_SP5-SOCKET6096_13568-001,SMLF,IO,DGA^6000030   I215 @T6G_MB_LIB.T6G(SCH_1):PAGE23
   U26  G52 G0_RXN13 GENOA_SP5-SOCKET6096_13568-001,SMLF,IO,DGA^6000030   I213 @T6G_MB_LIB.T6G(SCH_1):PAGE49

GMI_CPU0_G2_CPU1_G0_TX_DN<3> @T6G_MB_LIB.T6G(SCH_1):GMI_CPU0_G2_CPU1_G0_TX_DN(3)
   U25  L24 G2_TXN3 GENOA_SP5-SOCKET6096_13568-001,SMLF,IO,DGA^6000030   I215 @T6G_MB_LIB.T6G(SCH_1):PAGE23
   U26  L52 G0_RXN12 GENOA_SP5-SOCKET6096_13568-001,SMLF,IO,DGA^6000030   I213 @T6G_MB_LIB.T6G(SCH_1):PAGE49

GMI_CPU0_G2_CPU1_G0_TX_DN<4> @T6G_MB_LIB.T6G(SCH_1):GMI_CPU0_G2_CPU1_G0_TX_DN(4)
   U25  J27 G2_TXN4 GENOA_SP5-SOCKET6096_13568-001,SMLF,IO,DGA^6000030   I215 @T6G_MB_LIB.T6G(SCH_1):PAGE23
   U26  J49 G0_RXN11 GENOA_SP5-SOCKET6096_13568-001,SMLF,IO,DGA^6000030   I213 @T6G_MB_LIB.T6G(SCH_1):PAGE49

GMI_CPU0_G2_CPU1_G0_TX_DN<5> @T6G_MB_LIB.T6G(SCH_1):GMI_CPU0_G2_CPU1_G0_TX_DN(5)
   U25  G27 G2_TXN5 GENOA_SP5-SOCKET6096_13568-001,SMLF,IO,DGA^6000030   I215 @T6G_MB_LIB.T6G(SCH_1):PAGE23
   U26  G49 G0_RXN10 GENOA_SP5-SOCKET6096_13568-001,SMLF,IO,DGA^6000030   I213 @T6G_MB_LIB.T6G(SCH_1):PAGE49

GMI_CPU0_G2_CPU1_G0_TX_DN<6> @T6G_MB_LIB.T6G(SCH_1):GMI_CPU0_G2_CPU1_G0_TX_DN(6)
   U25  L27 G2_TXN6 GENOA_SP5-SOCKET6096_13568-001,SMLF,IO,DGA^6000030   I215 @T6G_MB_LIB.T6G(SCH_1):PAGE23
   U26  L49 G0_RXN9 GENOA_SP5-SOCKET6096_13568-001,SMLF,IO,DGA^6000030   I213 @T6G_MB_LIB.T6G(SCH_1):PAGE49

GMI_CPU0_G2_CPU1_G0_TX_DN<7> @T6G_MB_LIB.T6G(SCH_1):GMI_CPU0_G2_CPU1_G0_TX_DN(7)
   U25  J30 G2_TXN7 GENOA_SP5-SOCKET6096_13568-001,SMLF,IO,DGA^6000030   I215 @T6G_MB_LIB.T6G(SCH_1):PAGE23
   U26  J46 G0_RXN8 GENOA_SP5-SOCKET6096_13568-001,SMLF,IO,DGA^6000030   I213 @T6G_MB_LIB.T6G(SCH_1):PAGE49

GMI_CPU0_G2_CPU1_G0_TX_DN<8> @T6G_MB_LIB.T6G(SCH_1):GMI_CPU0_G2_CPU1_G0_TX_DN(8)
   U25  G30 G2_TXN8 GENOA_SP5-SOCKET6096_13568-001,SMLF,IO,DGA^6000030   I215 @T6G_MB_LIB.T6G(SCH_1):PAGE23
   U26  G46 G0_RXN7 GENOA_SP5-SOCKET6096_13568-001,SMLF,IO,DGA^6000030   I213 @T6G_MB_LIB.T6G(SCH_1):PAGE49

GMI_CPU0_G2_CPU1_G0_TX_DN<9> @T6G_MB_LIB.T6G(SCH_1):GMI_CPU0_G2_CPU1_G0_TX_DN(9)
   U25  L30 G2_TXN9 GENOA_SP5-SOCKET6096_13568-001,SMLF,IO,DGA^6000030   I215 @T6G_MB_LIB.T6G(SCH_1):PAGE23
   U26  L46 G0_RXN6 GENOA_SP5-SOCKET6096_13568-001,SMLF,IO,DGA^6000030   I213 @T6G_MB_LIB.T6G(SCH_1):PAGE49

GMI_CPU0_G2_CPU1_G0_TX_DP<0> @T6G_MB_LIB.T6G(SCH_1):GMI_CPU0_G2_CPU1_G0_TX_DP(0)
   U25  N23 G2_TXP0 GENOA_SP5-SOCKET6096_13568-001,SMLF,IO,DGA^6000030   I215 @T6G_MB_LIB.T6G(SCH_1):PAGE23
   U26  N53 G0_RXP15 GENOA_SP5-SOCKET6096_13568-001,SMLF,IO,DGA^6000030   I213 @T6G_MB_LIB.T6G(SCH_1):PAGE49

GMI_CPU0_G2_CPU1_G0_TX_DP<10> @T6G_MB_LIB.T6G(SCH_1):GMI_CPU0_G2_CPU1_G0_TX_DP(10)
   U25  J32 G2_TXP10 GENOA_SP5-SOCKET6096_13568-001,SMLF,IO,DGA^6000030   I215 @T6G_MB_LIB.T6G(SCH_1):PAGE23
   U26  J44 G0_RXP5 GENOA_SP5-SOCKET6096_13568-001,SMLF,IO,DGA^6000030   I213 @T6G_MB_LIB.T6G(SCH_1):PAGE49

GMI_CPU0_G2_CPU1_G0_TX_DP<11> @T6G_MB_LIB.T6G(SCH_1):GMI_CPU0_G2_CPU1_G0_TX_DP(11)
   U25  G32 G2_TXP11 GENOA_SP5-SOCKET6096_13568-001,SMLF,IO,DGA^6000030   I215 @T6G_MB_LIB.T6G(SCH_1):PAGE23
   U26  G44 G0_RXP4 GENOA_SP5-SOCKET6096_13568-001,SMLF,IO,DGA^6000030   I213 @T6G_MB_LIB.T6G(SCH_1):PAGE49

GMI_CPU0_G2_CPU1_G0_TX_DP<12> @T6G_MB_LIB.T6G(SCH_1):GMI_CPU0_G2_CPU1_G0_TX_DP(12)
   U25  L32 G2_TXP12 GENOA_SP5-SOCKET6096_13568-001,SMLF,IO,DGA^6000030   I215 @T6G_MB_LIB.T6G(SCH_1):PAGE23
   U26  L44 G0_RXP3 GENOA_SP5-SOCKET6096_13568-001,SMLF,IO,DGA^6000030   I213 @T6G_MB_LIB.T6G(SCH_1):PAGE49

GMI_CPU0_G2_CPU1_G0_TX_DP<13> @T6G_MB_LIB.T6G(SCH_1):GMI_CPU0_G2_CPU1_G0_TX_DP(13)
   U25  H35 G2_TXP13 GENOA_SP5-SOCKET6096_13568-001,SMLF,IO,DGA^6000030   I215 @T6G_MB_LIB.T6G(SCH_1):PAGE23
   U26  H41 G0_RXP2 GENOA_SP5-SOCKET6096_13568-001,SMLF,IO,DGA^6000030   I213 @T6G_MB_LIB.T6G(SCH_1):PAGE49

GMI_CPU0_G2_CPU1_G0_TX_DP<14> @T6G_MB_LIB.T6G(SCH_1):GMI_CPU0_G2_CPU1_G0_TX_DP(14)
   U25  K35 G2_TXP14 GENOA_SP5-SOCKET6096_13568-001,SMLF,IO,DGA^6000030   I215 @T6G_MB_LIB.T6G(SCH_1):PAGE23
   U26  K41 G0_RXP1 GENOA_SP5-SOCKET6096_13568-001,SMLF,IO,DGA^6000030   I213 @T6G_MB_LIB.T6G(SCH_1):PAGE49

GMI_CPU0_G2_CPU1_G0_TX_DP<15> @T6G_MB_LIB.T6G(SCH_1):GMI_CPU0_G2_CPU1_G0_TX_DP(15)
   U25  M35 G2_TXP15 GENOA_SP5-SOCKET6096_13568-001,SMLF,IO,DGA^6000030   I215 @T6G_MB_LIB.T6G(SCH_1):PAGE23
   U26  M41 G0_RXP0 GENOA_SP5-SOCKET6096_13568-001,SMLF,IO,DGA^6000030   I213 @T6G_MB_LIB.T6G(SCH_1):PAGE49

GMI_CPU0_G2_CPU1_G0_TX_DP<1> @T6G_MB_LIB.T6G(SCH_1):GMI_CPU0_G2_CPU1_G0_TX_DP(1)
   U25  J23 G2_TXP1 GENOA_SP5-SOCKET6096_13568-001,SMLF,IO,DGA^6000030   I215 @T6G_MB_LIB.T6G(SCH_1):PAGE23
   U26  J53 G0_RXP14 GENOA_SP5-SOCKET6096_13568-001,SMLF,IO,DGA^6000030   I213 @T6G_MB_LIB.T6G(SCH_1):PAGE49

GMI_CPU0_G2_CPU1_G0_TX_DP<2> @T6G_MB_LIB.T6G(SCH_1):GMI_CPU0_G2_CPU1_G0_TX_DP(2)
   U25  G23 G2_TXP2 GENOA_SP5-SOCKET6096_13568-001,SMLF,IO,DGA^6000030   I215 @T6G_MB_LIB.T6G(SCH_1):PAGE23
   U26  G53 G0_RXP13 GENOA_SP5-SOCKET6096_13568-001,SMLF,IO,DGA^6000030   I213 @T6G_MB_LIB.T6G(SCH_1):PAGE49

GMI_CPU0_G2_CPU1_G0_TX_DP<3> @T6G_MB_LIB.T6G(SCH_1):GMI_CPU0_G2_CPU1_G0_TX_DP(3)
   U25  L23 G2_TXP3 GENOA_SP5-SOCKET6096_13568-001,SMLF,IO,DGA^6000030   I215 @T6G_MB_LIB.T6G(SCH_1):PAGE23
   U26  L53 G0_RXP12 GENOA_SP5-SOCKET6096_13568-001,SMLF,IO,DGA^6000030   I213 @T6G_MB_LIB.T6G(SCH_1):PAGE49

GMI_CPU0_G2_CPU1_G0_TX_DP<4> @T6G_MB_LIB.T6G(SCH_1):GMI_CPU0_G2_CPU1_G0_TX_DP(4)
   U25  J26 G2_TXP4 GENOA_SP5-SOCKET6096_13568-001,SMLF,IO,DGA^6000030   I215 @T6G_MB_LIB.T6G(SCH_1):PAGE23
   U26  J50 G0_RXP11 GENOA_SP5-SOCKET6096_13568-001,SMLF,IO,DGA^6000030   I213 @T6G_MB_LIB.T6G(SCH_1):PAGE49

GMI_CPU0_G2_CPU1_G0_TX_DP<5> @T6G_MB_LIB.T6G(SCH_1):GMI_CPU0_G2_CPU1_G0_TX_DP(5)
   U25  G26 G2_TXP5 GENOA_SP5-SOCKET6096_13568-001,SMLF,IO,DGA^6000030   I215 @T6G_MB_LIB.T6G(SCH_1):PAGE23
   U26  G50 G0_RXP10 GENOA_SP5-SOCKET6096_13568-001,SMLF,IO,DGA^6000030   I213 @T6G_MB_LIB.T6G(SCH_1):PAGE49

GMI_CPU0_G2_CPU1_G0_TX_DP<6> @T6G_MB_LIB.T6G(SCH_1):GMI_CPU0_G2_CPU1_G0_TX_DP(6)
   U25  L26 G2_TXP6 GENOA_SP5-SOCKET6096_13568-001,SMLF,IO,DGA^6000030   I215 @T6G_MB_LIB.T6G(SCH_1):PAGE23
   U26  L50 G0_RXP9 GENOA_SP5-SOCKET6096_13568-001,SMLF,IO,DGA^6000030   I213 @T6G_MB_LIB.T6G(SCH_1):PAGE49

GMI_CPU0_G2_CPU1_G0_TX_DP<7> @T6G_MB_LIB.T6G(SCH_1):GMI_CPU0_G2_CPU1_G0_TX_DP(7)
   U25  J29 G2_TXP7 GENOA_SP5-SOCKET6096_13568-001,SMLF,IO,DGA^6000030   I215 @T6G_MB_LIB.T6G(SCH_1):PAGE23
   U26  J47 G0_RXP8 GENOA_SP5-SOCKET6096_13568-001,SMLF,IO,DGA^6000030   I213 @T6G_MB_LIB.T6G(SCH_1):PAGE49

GMI_CPU0_G2_CPU1_G0_TX_DP<8> @T6G_MB_LIB.T6G(SCH_1):GMI_CPU0_G2_CPU1_G0_TX_DP(8)
   U25  G29 G2_TXP8 GENOA_SP5-SOCKET6096_13568-001,SMLF,IO,DGA^6000030   I215 @T6G_MB_LIB.T6G(SCH_1):PAGE23
   U26  G47 G0_RXP7 GENOA_SP5-SOCKET6096_13568-001,SMLF,IO,DGA^6000030   I213 @T6G_MB_LIB.T6G(SCH_1):PAGE49

GMI_CPU0_G2_CPU1_G0_TX_DP<9> @T6G_MB_LIB.T6G(SCH_1):GMI_CPU0_G2_CPU1_G0_TX_DP(9)
   U25  L29 G2_TXP9 GENOA_SP5-SOCKET6096_13568-001,SMLF,IO,DGA^6000030   I215 @T6G_MB_LIB.T6G(SCH_1):PAGE23
   U26  L47 G0_RXP6 GENOA_SP5-SOCKET6096_13568-001,SMLF,IO,DGA^6000030   I213 @T6G_MB_LIB.T6G(SCH_1):PAGE49

GMI_CPU1_G0_CPU0_G2_TX_DN<0> @T6G_MB_LIB.T6G(SCH_1):GMI_CPU1_G0_CPU0_G2_TX_DN(0)
   U25 AE23 G2_RXN0 GENOA_SP5-SOCKET6096_13568-001,SMLF,IO,DGA^6000030   I215 @T6G_MB_LIB.T6G(SCH_1):PAGE23
   U26 AE53 G0_TXN15 GENOA_SP5-SOCKET6096_13568-001,SMLF,IO,DGA^6000030   I213 @T6G_MB_LIB.T6G(SCH_1):PAGE49

GMI_CPU1_G0_CPU0_G2_TX_DN<10> @T6G_MB_LIB.T6G(SCH_1):GMI_CPU1_G0_CPU0_G2_TX_DN(10)
   U25 AC32 G2_RXN10 GENOA_SP5-SOCKET6096_13568-001,SMLF,IO,DGA^6000030   I215 @T6G_MB_LIB.T6G(SCH_1):PAGE23
   U26 AC44 G0_TXN5 GENOA_SP5-SOCKET6096_13568-001,SMLF,IO,DGA^6000030   I213 @T6G_MB_LIB.T6G(SCH_1):PAGE49

GMI_CPU1_G0_CPU0_G2_TX_DN<11> @T6G_MB_LIB.T6G(SCH_1):GMI_CPU1_G0_CPU0_G2_TX_DN(11)
   U25 AA32 G2_RXN11 GENOA_SP5-SOCKET6096_13568-001,SMLF,IO,DGA^6000030   I215 @T6G_MB_LIB.T6G(SCH_1):PAGE23
   U26 AA44 G0_TXN4 GENOA_SP5-SOCKET6096_13568-001,SMLF,IO,DGA^6000030   I213 @T6G_MB_LIB.T6G(SCH_1):PAGE49

GMI_CPU1_G0_CPU0_G2_TX_DN<12> @T6G_MB_LIB.T6G(SCH_1):GMI_CPU1_G0_CPU0_G2_TX_DN(12)
   U25 AG32 G2_RXN12 GENOA_SP5-SOCKET6096_13568-001,SMLF,IO,DGA^6000030   I215 @T6G_MB_LIB.T6G(SCH_1):PAGE23
   U26 AG44 G0_TXN3 GENOA_SP5-SOCKET6096_13568-001,SMLF,IO,DGA^6000030   I213 @T6G_MB_LIB.T6G(SCH_1):PAGE49

GMI_CPU1_G0_CPU0_G2_TX_DN<13> @T6G_MB_LIB.T6G(SCH_1):GMI_CPU1_G0_CPU0_G2_TX_DN(13)
   U25 AB35 G2_RXN13 GENOA_SP5-SOCKET6096_13568-001,SMLF,IO,DGA^6000030   I215 @T6G_MB_LIB.T6G(SCH_1):PAGE23
   U26 AB41 G0_TXN2 GENOA_SP5-SOCKET6096_13568-001,SMLF,IO,DGA^6000030   I213 @T6G_MB_LIB.T6G(SCH_1):PAGE49

GMI_CPU1_G0_CPU0_G2_TX_DN<14> @T6G_MB_LIB.T6G(SCH_1):GMI_CPU1_G0_CPU0_G2_TX_DN(14)
   U25 AD35 G2_RXN14 GENOA_SP5-SOCKET6096_13568-001,SMLF,IO,DGA^6000030   I215 @T6G_MB_LIB.T6G(SCH_1):PAGE23
   U26 AD41 G0_TXN1 GENOA_SP5-SOCKET6096_13568-001,SMLF,IO,DGA^6000030   I213 @T6G_MB_LIB.T6G(SCH_1):PAGE49

GMI_CPU1_G0_CPU0_G2_TX_DN<15> @T6G_MB_LIB.T6G(SCH_1):GMI_CPU1_G0_CPU0_G2_TX_DN(15)
   U25 AF35 G2_RXN15 GENOA_SP5-SOCKET6096_13568-001,SMLF,IO,DGA^6000030   I215 @T6G_MB_LIB.T6G(SCH_1):PAGE23
   U26 AF41 G0_TXN0 GENOA_SP5-SOCKET6096_13568-001,SMLF,IO,DGA^6000030   I213 @T6G_MB_LIB.T6G(SCH_1):PAGE49

GMI_CPU1_G0_CPU0_G2_TX_DN<1> @T6G_MB_LIB.T6G(SCH_1):GMI_CPU1_G0_CPU0_G2_TX_DN(1)
   U25 AC23 G2_RXN1 GENOA_SP5-SOCKET6096_13568-001,SMLF,IO,DGA^6000030   I215 @T6G_MB_LIB.T6G(SCH_1):PAGE23
   U26 AC53 G0_TXN14 GENOA_SP5-SOCKET6096_13568-001,SMLF,IO,DGA^6000030   I213 @T6G_MB_LIB.T6G(SCH_1):PAGE49

GMI_CPU1_G0_CPU0_G2_TX_DN<2> @T6G_MB_LIB.T6G(SCH_1):GMI_CPU1_G0_CPU0_G2_TX_DN(2)
   U25 AG23 G2_RXN2 GENOA_SP5-SOCKET6096_13568-001,SMLF,IO,DGA^6000030   I215 @T6G_MB_LIB.T6G(SCH_1):PAGE23
   U26 AG53 G0_TXN13 GENOA_SP5-SOCKET6096_13568-001,SMLF,IO,DGA^6000030   I213 @T6G_MB_LIB.T6G(SCH_1):PAGE49

GMI_CPU1_G0_CPU0_G2_TX_DN<3> @T6G_MB_LIB.T6G(SCH_1):GMI_CPU1_G0_CPU0_G2_TX_DN(3)
   U25 AE26 G2_RXN3 GENOA_SP5-SOCKET6096_13568-001,SMLF,IO,DGA^6000030   I215 @T6G_MB_LIB.T6G(SCH_1):PAGE23
   U26 AE50 G0_TXN12 GENOA_SP5-SOCKET6096_13568-001,SMLF,IO,DGA^6000030   I213 @T6G_MB_LIB.T6G(SCH_1):PAGE49

GMI_CPU1_G0_CPU0_G2_TX_DN<4> @T6G_MB_LIB.T6G(SCH_1):GMI_CPU1_G0_CPU0_G2_TX_DN(4)
   U25 AC26 G2_RXN4 GENOA_SP5-SOCKET6096_13568-001,SMLF,IO,DGA^6000030   I215 @T6G_MB_LIB.T6G(SCH_1):PAGE23
   U26 AC50 G0_TXN11 GENOA_SP5-SOCKET6096_13568-001,SMLF,IO,DGA^6000030   I213 @T6G_MB_LIB.T6G(SCH_1):PAGE49

GMI_CPU1_G0_CPU0_G2_TX_DN<5> @T6G_MB_LIB.T6G(SCH_1):GMI_CPU1_G0_CPU0_G2_TX_DN(5)
   U25 AG26 G2_RXN5 GENOA_SP5-SOCKET6096_13568-001,SMLF,IO,DGA^6000030   I215 @T6G_MB_LIB.T6G(SCH_1):PAGE23
   U26 AG50 G0_TXN10 GENOA_SP5-SOCKET6096_13568-001,SMLF,IO,DGA^6000030   I213 @T6G_MB_LIB.T6G(SCH_1):PAGE49

GMI_CPU1_G0_CPU0_G2_TX_DN<6> @T6G_MB_LIB.T6G(SCH_1):GMI_CPU1_G0_CPU0_G2_TX_DN(6)
   U25 AE29 G2_RXN6 GENOA_SP5-SOCKET6096_13568-001,SMLF,IO,DGA^6000030   I215 @T6G_MB_LIB.T6G(SCH_1):PAGE23
   U26 AE47 G0_TXN9 GENOA_SP5-SOCKET6096_13568-001,SMLF,IO,DGA^6000030   I213 @T6G_MB_LIB.T6G(SCH_1):PAGE49

GMI_CPU1_G0_CPU0_G2_TX_DN<7> @T6G_MB_LIB.T6G(SCH_1):GMI_CPU1_G0_CPU0_G2_TX_DN(7)
   U25 AC29 G2_RXN7 GENOA_SP5-SOCKET6096_13568-001,SMLF,IO,DGA^6000030   I215 @T6G_MB_LIB.T6G(SCH_1):PAGE23
   U26 AC47 G0_TXN8 GENOA_SP5-SOCKET6096_13568-001,SMLF,IO,DGA^6000030   I213 @T6G_MB_LIB.T6G(SCH_1):PAGE49

GMI_CPU1_G0_CPU0_G2_TX_DN<8> @T6G_MB_LIB.T6G(SCH_1):GMI_CPU1_G0_CPU0_G2_TX_DN(8)
   U25 AG29 G2_RXN8 GENOA_SP5-SOCKET6096_13568-001,SMLF,IO,DGA^6000030   I215 @T6G_MB_LIB.T6G(SCH_1):PAGE23
   U26 AG47 G0_TXN7 GENOA_SP5-SOCKET6096_13568-001,SMLF,IO,DGA^6000030   I213 @T6G_MB_LIB.T6G(SCH_1):PAGE49

GMI_CPU1_G0_CPU0_G2_TX_DN<9> @T6G_MB_LIB.T6G(SCH_1):GMI_CPU1_G0_CPU0_G2_TX_DN(9)
   U25 AE32 G2_RXN9 GENOA_SP5-SOCKET6096_13568-001,SMLF,IO,DGA^6000030   I215 @T6G_MB_LIB.T6G(SCH_1):PAGE23
   U26 AE44 G0_TXN6 GENOA_SP5-SOCKET6096_13568-001,SMLF,IO,DGA^6000030   I213 @T6G_MB_LIB.T6G(SCH_1):PAGE49

GMI_CPU1_G0_CPU0_G2_TX_DP<0> @T6G_MB_LIB.T6G(SCH_1):GMI_CPU1_G0_CPU0_G2_TX_DP(0)
   U25 AE24 G2_RXP0 GENOA_SP5-SOCKET6096_13568-001,SMLF,IO,DGA^6000030   I215 @T6G_MB_LIB.T6G(SCH_1):PAGE23
   U26 AE52 G0_TXP15 GENOA_SP5-SOCKET6096_13568-001,SMLF,IO,DGA^6000030   I213 @T6G_MB_LIB.T6G(SCH_1):PAGE49

GMI_CPU1_G0_CPU0_G2_TX_DP<10> @T6G_MB_LIB.T6G(SCH_1):GMI_CPU1_G0_CPU0_G2_TX_DP(10)
   U25 AC33 G2_RXP10 GENOA_SP5-SOCKET6096_13568-001,SMLF,IO,DGA^6000030   I215 @T6G_MB_LIB.T6G(SCH_1):PAGE23
   U26 AC43 G0_TXP5 GENOA_SP5-SOCKET6096_13568-001,SMLF,IO,DGA^6000030   I213 @T6G_MB_LIB.T6G(SCH_1):PAGE49

GMI_CPU1_G0_CPU0_G2_TX_DP<11> @T6G_MB_LIB.T6G(SCH_1):GMI_CPU1_G0_CPU0_G2_TX_DP(11)
   U25 AA33 G2_RXP11 GENOA_SP5-SOCKET6096_13568-001,SMLF,IO,DGA^6000030   I215 @T6G_MB_LIB.T6G(SCH_1):PAGE23
   U26 AA43 G0_TXP4 GENOA_SP5-SOCKET6096_13568-001,SMLF,IO,DGA^6000030   I213 @T6G_MB_LIB.T6G(SCH_1):PAGE49

GMI_CPU1_G0_CPU0_G2_TX_DP<12> @T6G_MB_LIB.T6G(SCH_1):GMI_CPU1_G0_CPU0_G2_TX_DP(12)
   U25 AG33 G2_RXP12 GENOA_SP5-SOCKET6096_13568-001,SMLF,IO,DGA^6000030   I215 @T6G_MB_LIB.T6G(SCH_1):PAGE23
   U26 AG43 G0_TXP3 GENOA_SP5-SOCKET6096_13568-001,SMLF,IO,DGA^6000030   I213 @T6G_MB_LIB.T6G(SCH_1):PAGE49

GMI_CPU1_G0_CPU0_G2_TX_DP<13> @T6G_MB_LIB.T6G(SCH_1):GMI_CPU1_G0_CPU0_G2_TX_DP(13)
   U25 AB36 G2_RXP13 GENOA_SP5-SOCKET6096_13568-001,SMLF,IO,DGA^6000030   I215 @T6G_MB_LIB.T6G(SCH_1):PAGE23
   U26 AB40 G0_TXP2 GENOA_SP5-SOCKET6096_13568-001,SMLF,IO,DGA^6000030   I213 @T6G_MB_LIB.T6G(SCH_1):PAGE49

GMI_CPU1_G0_CPU0_G2_TX_DP<14> @T6G_MB_LIB.T6G(SCH_1):GMI_CPU1_G0_CPU0_G2_TX_DP(14)
   U25 AD36 G2_RXP14 GENOA_SP5-SOCKET6096_13568-001,SMLF,IO,DGA^6000030   I215 @T6G_MB_LIB.T6G(SCH_1):PAGE23
   U26 AD40 G0_TXP1 GENOA_SP5-SOCKET6096_13568-001,SMLF,IO,DGA^6000030   I213 @T6G_MB_LIB.T6G(SCH_1):PAGE49

GMI_CPU1_G0_CPU0_G2_TX_DP<15> @T6G_MB_LIB.T6G(SCH_1):GMI_CPU1_G0_CPU0_G2_TX_DP(15)
   U25 AF36 G2_RXP15 GENOA_SP5-SOCKET6096_13568-001,SMLF,IO,DGA^6000030   I215 @T6G_MB_LIB.T6G(SCH_1):PAGE23
   U26 AF40 G0_TXP0 GENOA_SP5-SOCKET6096_13568-001,SMLF,IO,DGA^6000030   I213 @T6G_MB_LIB.T6G(SCH_1):PAGE49

GMI_CPU1_G0_CPU0_G2_TX_DP<1> @T6G_MB_LIB.T6G(SCH_1):GMI_CPU1_G0_CPU0_G2_TX_DP(1)
   U25 AC24 G2_RXP1 GENOA_SP5-SOCKET6096_13568-001,SMLF,IO,DGA^6000030   I215 @T6G_MB_LIB.T6G(SCH_1):PAGE23
   U26 AC52 G0_TXP14 GENOA_SP5-SOCKET6096_13568-001,SMLF,IO,DGA^6000030   I213 @T6G_MB_LIB.T6G(SCH_1):PAGE49

GMI_CPU1_G0_CPU0_G2_TX_DP<2> @T6G_MB_LIB.T6G(SCH_1):GMI_CPU1_G0_CPU0_G2_TX_DP(2)
   U25 AG24 G2_RXP2 GENOA_SP5-SOCKET6096_13568-001,SMLF,IO,DGA^6000030   I215 @T6G_MB_LIB.T6G(SCH_1):PAGE23
   U26 AG52 G0_TXP13 GENOA_SP5-SOCKET6096_13568-001,SMLF,IO,DGA^6000030   I213 @T6G_MB_LIB.T6G(SCH_1):PAGE49

GMI_CPU1_G0_CPU0_G2_TX_DP<3> @T6G_MB_LIB.T6G(SCH_1):GMI_CPU1_G0_CPU0_G2_TX_DP(3)
   U25 AE27 G2_RXP3 GENOA_SP5-SOCKET6096_13568-001,SMLF,IO,DGA^6000030   I215 @T6G_MB_LIB.T6G(SCH_1):PAGE23
   U26 AE49 G0_TXP12 GENOA_SP5-SOCKET6096_13568-001,SMLF,IO,DGA^6000030   I213 @T6G_MB_LIB.T6G(SCH_1):PAGE49

GMI_CPU1_G0_CPU0_G2_TX_DP<4> @T6G_MB_LIB.T6G(SCH_1):GMI_CPU1_G0_CPU0_G2_TX_DP(4)
   U25 AC27 G2_RXP4 GENOA_SP5-SOCKET6096_13568-001,SMLF,IO,DGA^6000030   I215 @T6G_MB_LIB.T6G(SCH_1):PAGE23
   U26 AC49 G0_TXP11 GENOA_SP5-SOCKET6096_13568-001,SMLF,IO,DGA^6000030   I213 @T6G_MB_LIB.T6G(SCH_1):PAGE49

GMI_CPU1_G0_CPU0_G2_TX_DP<5> @T6G_MB_LIB.T6G(SCH_1):GMI_CPU1_G0_CPU0_G2_TX_DP(5)
   U25 AG27 G2_RXP5 GENOA_SP5-SOCKET6096_13568-001,SMLF,IO,DGA^6000030   I215 @T6G_MB_LIB.T6G(SCH_1):PAGE23
   U26 AG49 G0_TXP10 GENOA_SP5-SOCKET6096_13568-001,SMLF,IO,DGA^6000030   I213 @T6G_MB_LIB.T6G(SCH_1):PAGE49

GMI_CPU1_G0_CPU0_G2_TX_DP<6> @T6G_MB_LIB.T6G(SCH_1):GMI_CPU1_G0_CPU0_G2_TX_DP(6)
   U25 AE30 G2_RXP6 GENOA_SP5-SOCKET6096_13568-001,SMLF,IO,DGA^6000030   I215 @T6G_MB_LIB.T6G(SCH_1):PAGE23
   U26 AE46 G0_TXP9 GENOA_SP5-SOCKET6096_13568-001,SMLF,IO,DGA^6000030   I213 @T6G_MB_LIB.T6G(SCH_1):PAGE49

GMI_CPU1_G0_CPU0_G2_TX_DP<7> @T6G_MB_LIB.T6G(SCH_1):GMI_CPU1_G0_CPU0_G2_TX_DP(7)
   U25 AC30 G2_RXP7 GENOA_SP5-SOCKET6096_13568-001,SMLF,IO,DGA^6000030   I215 @T6G_MB_LIB.T6G(SCH_1):PAGE23
   U26 AC46 G0_TXP8 GENOA_SP5-SOCKET6096_13568-001,SMLF,IO,DGA^6000030   I213 @T6G_MB_LIB.T6G(SCH_1):PAGE49

GMI_CPU1_G0_CPU0_G2_TX_DP<8> @T6G_MB_LIB.T6G(SCH_1):GMI_CPU1_G0_CPU0_G2_TX_DP(8)
   U25 AG30 G2_RXP8 GENOA_SP5-SOCKET6096_13568-001,SMLF,IO,DGA^6000030   I215 @T6G_MB_LIB.T6G(SCH_1):PAGE23
   U26 AG46 G0_TXP7 GENOA_SP5-SOCKET6096_13568-001,SMLF,IO,DGA^6000030   I213 @T6G_MB_LIB.T6G(SCH_1):PAGE49

GMI_CPU1_G0_CPU0_G2_TX_DP<9> @T6G_MB_LIB.T6G(SCH_1):GMI_CPU1_G0_CPU0_G2_TX_DP(9)
   U25 AE33 G2_RXP9 GENOA_SP5-SOCKET6096_13568-001,SMLF,IO,DGA^6000030   I215 @T6G_MB_LIB.T6G(SCH_1):PAGE23
   U26 AE43 G0_TXP6 GENOA_SP5-SOCKET6096_13568-001,SMLF,IO,DGA^6000030   I213 @T6G_MB_LIB.T6G(SCH_1):PAGE49

GMI_CPU1_G2_CPU0_G0_TX_DN<0> @T6G_MB_LIB.T6G(SCH_1):GMI_CPU1_G2_CPU0_G0_TX_DN(0)
   U25  M40 G0_RXN0 GENOA_SP5-SOCKET6096_13568-001,SMLF,IO,DGA^6000030   I207 @T6G_MB_LIB.T6G(SCH_1):PAGE22
   U26  M36 G2_TXN15 GENOA_SP5-SOCKET6096_13568-001,SMLF,IO,DGA^6000030   I143 @T6G_MB_LIB.T6G(SCH_1):PAGE50

GMI_CPU1_G2_CPU0_G0_TX_DN<10> @T6G_MB_LIB.T6G(SCH_1):GMI_CPU1_G2_CPU0_G0_TX_DN(10)
   U25  G49 G0_RXN10 GENOA_SP5-SOCKET6096_13568-001,SMLF,IO,DGA^6000030   I207 @T6G_MB_LIB.T6G(SCH_1):PAGE22
   U26  G27 G2_TXN5 GENOA_SP5-SOCKET6096_13568-001,SMLF,IO,DGA^6000030   I143 @T6G_MB_LIB.T6G(SCH_1):PAGE50

GMI_CPU1_G2_CPU0_G0_TX_DN<11> @T6G_MB_LIB.T6G(SCH_1):GMI_CPU1_G2_CPU0_G0_TX_DN(11)
   U25  J49 G0_RXN11 GENOA_SP5-SOCKET6096_13568-001,SMLF,IO,DGA^6000030   I207 @T6G_MB_LIB.T6G(SCH_1):PAGE22
   U26  J27 G2_TXN4 GENOA_SP5-SOCKET6096_13568-001,SMLF,IO,DGA^6000030   I143 @T6G_MB_LIB.T6G(SCH_1):PAGE50

GMI_CPU1_G2_CPU0_G0_TX_DN<12> @T6G_MB_LIB.T6G(SCH_1):GMI_CPU1_G2_CPU0_G0_TX_DN(12)
   U25  L52 G0_RXN12 GENOA_SP5-SOCKET6096_13568-001,SMLF,IO,DGA^6000030   I207 @T6G_MB_LIB.T6G(SCH_1):PAGE22
   U26  L24 G2_TXN3 GENOA_SP5-SOCKET6096_13568-001,SMLF,IO,DGA^6000030   I143 @T6G_MB_LIB.T6G(SCH_1):PAGE50

GMI_CPU1_G2_CPU0_G0_TX_DN<13> @T6G_MB_LIB.T6G(SCH_1):GMI_CPU1_G2_CPU0_G0_TX_DN(13)
   U25  G52 G0_RXN13 GENOA_SP5-SOCKET6096_13568-001,SMLF,IO,DGA^6000030   I207 @T6G_MB_LIB.T6G(SCH_1):PAGE22
   U26  G24 G2_TXN2 GENOA_SP5-SOCKET6096_13568-001,SMLF,IO,DGA^6000030   I143 @T6G_MB_LIB.T6G(SCH_1):PAGE50

GMI_CPU1_G2_CPU0_G0_TX_DN<14> @T6G_MB_LIB.T6G(SCH_1):GMI_CPU1_G2_CPU0_G0_TX_DN(14)
   U25  J52 G0_RXN14 GENOA_SP5-SOCKET6096_13568-001,SMLF,IO,DGA^6000030   I207 @T6G_MB_LIB.T6G(SCH_1):PAGE22
   U26  J24 G2_TXN1 GENOA_SP5-SOCKET6096_13568-001,SMLF,IO,DGA^6000030   I143 @T6G_MB_LIB.T6G(SCH_1):PAGE50

GMI_CPU1_G2_CPU0_G0_TX_DN<15> @T6G_MB_LIB.T6G(SCH_1):GMI_CPU1_G2_CPU0_G0_TX_DN(15)
   U25  N52 G0_RXN15 GENOA_SP5-SOCKET6096_13568-001,SMLF,IO,DGA^6000030   I207 @T6G_MB_LIB.T6G(SCH_1):PAGE22
   U26  N24 G2_TXN0 GENOA_SP5-SOCKET6096_13568-001,SMLF,IO,DGA^6000030   I143 @T6G_MB_LIB.T6G(SCH_1):PAGE50

GMI_CPU1_G2_CPU0_G0_TX_DN<1> @T6G_MB_LIB.T6G(SCH_1):GMI_CPU1_G2_CPU0_G0_TX_DN(1)
   U25  K40 G0_RXN1 GENOA_SP5-SOCKET6096_13568-001,SMLF,IO,DGA^6000030   I207 @T6G_MB_LIB.T6G(SCH_1):PAGE22
   U26  K36 G2_TXN14 GENOA_SP5-SOCKET6096_13568-001,SMLF,IO,DGA^6000030   I143 @T6G_MB_LIB.T6G(SCH_1):PAGE50

GMI_CPU1_G2_CPU0_G0_TX_DN<2> @T6G_MB_LIB.T6G(SCH_1):GMI_CPU1_G2_CPU0_G0_TX_DN(2)
   U25  H40 G0_RXN2 GENOA_SP5-SOCKET6096_13568-001,SMLF,IO,DGA^6000030   I207 @T6G_MB_LIB.T6G(SCH_1):PAGE22
   U26  H36 G2_TXN13 GENOA_SP5-SOCKET6096_13568-001,SMLF,IO,DGA^6000030   I143 @T6G_MB_LIB.T6G(SCH_1):PAGE50

GMI_CPU1_G2_CPU0_G0_TX_DN<3> @T6G_MB_LIB.T6G(SCH_1):GMI_CPU1_G2_CPU0_G0_TX_DN(3)
   U25  L43 G0_RXN3 GENOA_SP5-SOCKET6096_13568-001,SMLF,IO,DGA^6000030   I207 @T6G_MB_LIB.T6G(SCH_1):PAGE22
   U26  L33 G2_TXN12 GENOA_SP5-SOCKET6096_13568-001,SMLF,IO,DGA^6000030   I143 @T6G_MB_LIB.T6G(SCH_1):PAGE50

GMI_CPU1_G2_CPU0_G0_TX_DN<4> @T6G_MB_LIB.T6G(SCH_1):GMI_CPU1_G2_CPU0_G0_TX_DN(4)
   U25  G43 G0_RXN4 GENOA_SP5-SOCKET6096_13568-001,SMLF,IO,DGA^6000030   I207 @T6G_MB_LIB.T6G(SCH_1):PAGE22
   U26  G33 G2_TXN11 GENOA_SP5-SOCKET6096_13568-001,SMLF,IO,DGA^6000030   I143 @T6G_MB_LIB.T6G(SCH_1):PAGE50

GMI_CPU1_G2_CPU0_G0_TX_DN<5> @T6G_MB_LIB.T6G(SCH_1):GMI_CPU1_G2_CPU0_G0_TX_DN(5)
   U25  J43 G0_RXN5 GENOA_SP5-SOCKET6096_13568-001,SMLF,IO,DGA^6000030   I207 @T6G_MB_LIB.T6G(SCH_1):PAGE22
   U26  J33 G2_TXN10 GENOA_SP5-SOCKET6096_13568-001,SMLF,IO,DGA^6000030   I143 @T6G_MB_LIB.T6G(SCH_1):PAGE50

GMI_CPU1_G2_CPU0_G0_TX_DN<6> @T6G_MB_LIB.T6G(SCH_1):GMI_CPU1_G2_CPU0_G0_TX_DN(6)
   U25  L46 G0_RXN6 GENOA_SP5-SOCKET6096_13568-001,SMLF,IO,DGA^6000030   I207 @T6G_MB_LIB.T6G(SCH_1):PAGE22
   U26  L30 G2_TXN9 GENOA_SP5-SOCKET6096_13568-001,SMLF,IO,DGA^6000030   I143 @T6G_MB_LIB.T6G(SCH_1):PAGE50

GMI_CPU1_G2_CPU0_G0_TX_DN<7> @T6G_MB_LIB.T6G(SCH_1):GMI_CPU1_G2_CPU0_G0_TX_DN(7)
   U25  G46 G0_RXN7 GENOA_SP5-SOCKET6096_13568-001,SMLF,IO,DGA^6000030   I207 @T6G_MB_LIB.T6G(SCH_1):PAGE22
   U26  G30 G2_TXN8 GENOA_SP5-SOCKET6096_13568-001,SMLF,IO,DGA^6000030   I143 @T6G_MB_LIB.T6G(SCH_1):PAGE50

GMI_CPU1_G2_CPU0_G0_TX_DN<8> @T6G_MB_LIB.T6G(SCH_1):GMI_CPU1_G2_CPU0_G0_TX_DN(8)
   U25  J46 G0_RXN8 GENOA_SP5-SOCKET6096_13568-001,SMLF,IO,DGA^6000030   I207 @T6G_MB_LIB.T6G(SCH_1):PAGE22
   U26  J30 G2_TXN7 GENOA_SP5-SOCKET6096_13568-001,SMLF,IO,DGA^6000030   I143 @T6G_MB_LIB.T6G(SCH_1):PAGE50

GMI_CPU1_G2_CPU0_G0_TX_DN<9> @T6G_MB_LIB.T6G(SCH_1):GMI_CPU1_G2_CPU0_G0_TX_DN(9)
   U25  L49 G0_RXN9 GENOA_SP5-SOCKET6096_13568-001,SMLF,IO,DGA^6000030   I207 @T6G_MB_LIB.T6G(SCH_1):PAGE22
   U26  L27 G2_TXN6 GENOA_SP5-SOCKET6096_13568-001,SMLF,IO,DGA^6000030   I143 @T6G_MB_LIB.T6G(SCH_1):PAGE50

GMI_CPU1_G2_CPU0_G0_TX_DP<0> @T6G_MB_LIB.T6G(SCH_1):GMI_CPU1_G2_CPU0_G0_TX_DP(0)
   U25  M41 G0_RXP0 GENOA_SP5-SOCKET6096_13568-001,SMLF,IO,DGA^6000030   I207 @T6G_MB_LIB.T6G(SCH_1):PAGE22
   U26  M35 G2_TXP15 GENOA_SP5-SOCKET6096_13568-001,SMLF,IO,DGA^6000030   I143 @T6G_MB_LIB.T6G(SCH_1):PAGE50

GMI_CPU1_G2_CPU0_G0_TX_DP<10> @T6G_MB_LIB.T6G(SCH_1):GMI_CPU1_G2_CPU0_G0_TX_DP(10)
   U25  G50 G0_RXP10 GENOA_SP5-SOCKET6096_13568-001,SMLF,IO,DGA^6000030   I207 @T6G_MB_LIB.T6G(SCH_1):PAGE22
   U26  G26 G2_TXP5 GENOA_SP5-SOCKET6096_13568-001,SMLF,IO,DGA^6000030   I143 @T6G_MB_LIB.T6G(SCH_1):PAGE50

GMI_CPU1_G2_CPU0_G0_TX_DP<11> @T6G_MB_LIB.T6G(SCH_1):GMI_CPU1_G2_CPU0_G0_TX_DP(11)
   U25  J50 G0_RXP11 GENOA_SP5-SOCKET6096_13568-001,SMLF,IO,DGA^6000030   I207 @T6G_MB_LIB.T6G(SCH_1):PAGE22
   U26  J26 G2_TXP4 GENOA_SP5-SOCKET6096_13568-001,SMLF,IO,DGA^6000030   I143 @T6G_MB_LIB.T6G(SCH_1):PAGE50

GMI_CPU1_G2_CPU0_G0_TX_DP<12> @T6G_MB_LIB.T6G(SCH_1):GMI_CPU1_G2_CPU0_G0_TX_DP(12)
   U25  L53 G0_RXP12 GENOA_SP5-SOCKET6096_13568-001,SMLF,IO,DGA^6000030   I207 @T6G_MB_LIB.T6G(SCH_1):PAGE22
   U26  L23 G2_TXP3 GENOA_SP5-SOCKET6096_13568-001,SMLF,IO,DGA^6000030   I143 @T6G_MB_LIB.T6G(SCH_1):PAGE50

GMI_CPU1_G2_CPU0_G0_TX_DP<13> @T6G_MB_LIB.T6G(SCH_1):GMI_CPU1_G2_CPU0_G0_TX_DP(13)
   U25  G53 G0_RXP13 GENOA_SP5-SOCKET6096_13568-001,SMLF,IO,DGA^6000030   I207 @T6G_MB_LIB.T6G(SCH_1):PAGE22
   U26  G23 G2_TXP2 GENOA_SP5-SOCKET6096_13568-001,SMLF,IO,DGA^6000030   I143 @T6G_MB_LIB.T6G(SCH_1):PAGE50

GMI_CPU1_G2_CPU0_G0_TX_DP<14> @T6G_MB_LIB.T6G(SCH_1):GMI_CPU1_G2_CPU0_G0_TX_DP(14)
   U25  J53 G0_RXP14 GENOA_SP5-SOCKET6096_13568-001,SMLF,IO,DGA^6000030   I207 @T6G_MB_LIB.T6G(SCH_1):PAGE22
   U26  J23 G2_TXP1 GENOA_SP5-SOCKET6096_13568-001,SMLF,IO,DGA^6000030   I143 @T6G_MB_LIB.T6G(SCH_1):PAGE50

GMI_CPU1_G2_CPU0_G0_TX_DP<15> @T6G_MB_LIB.T6G(SCH_1):GMI_CPU1_G2_CPU0_G0_TX_DP(15)
   U25  N53 G0_RXP15 GENOA_SP5-SOCKET6096_13568-001,SMLF,IO,DGA^6000030   I207 @T6G_MB_LIB.T6G(SCH_1):PAGE22
   U26  N23 G2_TXP0 GENOA_SP5-SOCKET6096_13568-001,SMLF,IO,DGA^6000030   I143 @T6G_MB_LIB.T6G(SCH_1):PAGE50

GMI_CPU1_G2_CPU0_G0_TX_DP<1> @T6G_MB_LIB.T6G(SCH_1):GMI_CPU1_G2_CPU0_G0_TX_DP(1)
   U25  K41 G0_RXP1 GENOA_SP5-SOCKET6096_13568-001,SMLF,IO,DGA^6000030   I207 @T6G_MB_LIB.T6G(SCH_1):PAGE22
   U26  K35 G2_TXP14 GENOA_SP5-SOCKET6096_13568-001,SMLF,IO,DGA^6000030   I143 @T6G_MB_LIB.T6G(SCH_1):PAGE50

GMI_CPU1_G2_CPU0_G0_TX_DP<2> @T6G_MB_LIB.T6G(SCH_1):GMI_CPU1_G2_CPU0_G0_TX_DP(2)
   U25  H41 G0_RXP2 GENOA_SP5-SOCKET6096_13568-001,SMLF,IO,DGA^6000030   I207 @T6G_MB_LIB.T6G(SCH_1):PAGE22
   U26  H35 G2_TXP13 GENOA_SP5-SOCKET6096_13568-001,SMLF,IO,DGA^6000030   I143 @T6G_MB_LIB.T6G(SCH_1):PAGE50

GMI_CPU1_G2_CPU0_G0_TX_DP<3> @T6G_MB_LIB.T6G(SCH_1):GMI_CPU1_G2_CPU0_G0_TX_DP(3)
   U25  L44 G0_RXP3 GENOA_SP5-SOCKET6096_13568-001,SMLF,IO,DGA^6000030   I207 @T6G_MB_LIB.T6G(SCH_1):PAGE22
   U26  L32 G2_TXP12 GENOA_SP5-SOCKET6096_13568-001,SMLF,IO,DGA^6000030   I143 @T6G_MB_LIB.T6G(SCH_1):PAGE50

GMI_CPU1_G2_CPU0_G0_TX_DP<4> @T6G_MB_LIB.T6G(SCH_1):GMI_CPU1_G2_CPU0_G0_TX_DP(4)
   U25  G44 G0_RXP4 GENOA_SP5-SOCKET6096_13568-001,SMLF,IO,DGA^6000030   I207 @T6G_MB_LIB.T6G(SCH_1):PAGE22
   U26  G32 G2_TXP11 GENOA_SP5-SOCKET6096_13568-001,SMLF,IO,DGA^6000030   I143 @T6G_MB_LIB.T6G(SCH_1):PAGE50

GMI_CPU1_G2_CPU0_G0_TX_DP<5> @T6G_MB_LIB.T6G(SCH_1):GMI_CPU1_G2_CPU0_G0_TX_DP(5)
   U25  J44 G0_RXP5 GENOA_SP5-SOCKET6096_13568-001,SMLF,IO,DGA^6000030   I207 @T6G_MB_LIB.T6G(SCH_1):PAGE22
   U26  J32 G2_TXP10 GENOA_SP5-SOCKET6096_13568-001,SMLF,IO,DGA^6000030   I143 @T6G_MB_LIB.T6G(SCH_1):PAGE50

GMI_CPU1_G2_CPU0_G0_TX_DP<6> @T6G_MB_LIB.T6G(SCH_1):GMI_CPU1_G2_CPU0_G0_TX_DP(6)
   U25  L47 G0_RXP6 GENOA_SP5-SOCKET6096_13568-001,SMLF,IO,DGA^6000030   I207 @T6G_MB_LIB.T6G(SCH_1):PAGE22
   U26  L29 G2_TXP9 GENOA_SP5-SOCKET6096_13568-001,SMLF,IO,DGA^6000030   I143 @T6G_MB_LIB.T6G(SCH_1):PAGE50

GMI_CPU1_G2_CPU0_G0_TX_DP<7> @T6G_MB_LIB.T6G(SCH_1):GMI_CPU1_G2_CPU0_G0_TX_DP(7)
   U25  G47 G0_RXP7 GENOA_SP5-SOCKET6096_13568-001,SMLF,IO,DGA^6000030   I207 @T6G_MB_LIB.T6G(SCH_1):PAGE22
   U26  G29 G2_TXP8 GENOA_SP5-SOCKET6096_13568-001,SMLF,IO,DGA^6000030   I143 @T6G_MB_LIB.T6G(SCH_1):PAGE50

GMI_CPU1_G2_CPU0_G0_TX_DP<8> @T6G_MB_LIB.T6G(SCH_1):GMI_CPU1_G2_CPU0_G0_TX_DP(8)
   U25  J47 G0_RXP8 GENOA_SP5-SOCKET6096_13568-001,SMLF,IO,DGA^6000030   I207 @T6G_MB_LIB.T6G(SCH_1):PAGE22
   U26  J29 G2_TXP7 GENOA_SP5-SOCKET6096_13568-001,SMLF,IO,DGA^6000030   I143 @T6G_MB_LIB.T6G(SCH_1):PAGE50

GMI_CPU1_G2_CPU0_G0_TX_DP<9> @T6G_MB_LIB.T6G(SCH_1):GMI_CPU1_G2_CPU0_G0_TX_DP(9)
   U25  L50 G0_RXP9 GENOA_SP5-SOCKET6096_13568-001,SMLF,IO,DGA^6000030   I207 @T6G_MB_LIB.T6G(SCH_1):PAGE22
   U26  L26 G2_TXP6 GENOA_SP5-SOCKET6096_13568-001,SMLF,IO,DGA^6000030   I143 @T6G_MB_LIB.T6G(SCH_1):PAGE50

GMI_CPU1_G3_CPU0_G1_TX_DN<0> @T6G_MB_LIB.T6G(SCH_1):GMI_CPU1_G3_CPU0_G1_TX_DN(0)
   U25  V40 G1_RXN0 GENOA_SP5-SOCKET6096_13568-001,SMLF,IO,DGA^6000030   I208 @T6G_MB_LIB.T6G(SCH_1):PAGE22
   U26  V36 G3_TXN15||SATA37_TXN GENOA_SP5-SOCKET6096_13568-001,SMLF,IO,DGA^6000030   I144 @T6G_MB_LIB.T6G(SCH_1):PAGE50

GMI_CPU1_G3_CPU0_G1_TX_DN<10> @T6G_MB_LIB.T6G(SCH_1):GMI_CPU1_G3_CPU0_G1_TX_DN(10)
   U25  N49 G1_RXN10 GENOA_SP5-SOCKET6096_13568-001,SMLF,IO,DGA^6000030   I208 @T6G_MB_LIB.T6G(SCH_1):PAGE22
   U26  N27 G3_TXN5||SATA25_TXN GENOA_SP5-SOCKET6096_13568-001,SMLF,IO,DGA^6000030   I144 @T6G_MB_LIB.T6G(SCH_1):PAGE50

GMI_CPU1_G3_CPU0_G1_TX_DN<11> @T6G_MB_LIB.T6G(SCH_1):GMI_CPU1_G3_CPU0_G1_TX_DN(11)
   U25  R49 G1_RXN11 GENOA_SP5-SOCKET6096_13568-001,SMLF,IO,DGA^6000030   I208 @T6G_MB_LIB.T6G(SCH_1):PAGE22
   U26  R27 G3_TXN4||SATA24_TXN GENOA_SP5-SOCKET6096_13568-001,SMLF,IO,DGA^6000030   I144 @T6G_MB_LIB.T6G(SCH_1):PAGE50

GMI_CPU1_G3_CPU0_G1_TX_DN<12> @T6G_MB_LIB.T6G(SCH_1):GMI_CPU1_G3_CPU0_G1_TX_DN(12)
   U25  U49 G1_RXN12 GENOA_SP5-SOCKET6096_13568-001,SMLF,IO,DGA^6000030   I208 @T6G_MB_LIB.T6G(SCH_1):PAGE22
   U26  U27 G3_TXN3||SATA23_TXN GENOA_SP5-SOCKET6096_13568-001,SMLF,IO,DGA^6000030   I144 @T6G_MB_LIB.T6G(SCH_1):PAGE50

GMI_CPU1_G3_CPU0_G1_TX_DN<13> @T6G_MB_LIB.T6G(SCH_1):GMI_CPU1_G3_CPU0_G1_TX_DN(13)
   U25  W52 G1_RXN13 GENOA_SP5-SOCKET6096_13568-001,SMLF,IO,DGA^6000030   I208 @T6G_MB_LIB.T6G(SCH_1):PAGE22
   U26  W24 G3_TXN2||SATA22_TXN GENOA_SP5-SOCKET6096_13568-001,SMLF,IO,DGA^6000030   I144 @T6G_MB_LIB.T6G(SCH_1):PAGE50

GMI_CPU1_G3_CPU0_G1_TX_DN<14> @T6G_MB_LIB.T6G(SCH_1):GMI_CPU1_G3_CPU0_G1_TX_DN(14)
   U25  R52 G1_RXN14 GENOA_SP5-SOCKET6096_13568-001,SMLF,IO,DGA^6000030   I208 @T6G_MB_LIB.T6G(SCH_1):PAGE22
   U26  R24 G3_TXN1||SATA21_TXN GENOA_SP5-SOCKET6096_13568-001,SMLF,IO,DGA^6000030   I144 @T6G_MB_LIB.T6G(SCH_1):PAGE50

GMI_CPU1_G3_CPU0_G1_TX_DN<15> @T6G_MB_LIB.T6G(SCH_1):GMI_CPU1_G3_CPU0_G1_TX_DN(15)
   U25  U52 G1_RXN15 GENOA_SP5-SOCKET6096_13568-001,SMLF,IO,DGA^6000030   I208 @T6G_MB_LIB.T6G(SCH_1):PAGE22
   U26  U24 G3_TXN0||SATA20_TXN GENOA_SP5-SOCKET6096_13568-001,SMLF,IO,DGA^6000030   I144 @T6G_MB_LIB.T6G(SCH_1):PAGE50

GMI_CPU1_G3_CPU0_G1_TX_DN<1> @T6G_MB_LIB.T6G(SCH_1):GMI_CPU1_G3_CPU0_G1_TX_DN(1)
   U25  T40 G1_RXN1 GENOA_SP5-SOCKET6096_13568-001,SMLF,IO,DGA^6000030   I208 @T6G_MB_LIB.T6G(SCH_1):PAGE22
   U26  T36 G3_TXN14||SATA36_TXN GENOA_SP5-SOCKET6096_13568-001,SMLF,IO,DGA^6000030   I144 @T6G_MB_LIB.T6G(SCH_1):PAGE50

GMI_CPU1_G3_CPU0_G1_TX_DN<2> @T6G_MB_LIB.T6G(SCH_1):GMI_CPU1_G3_CPU0_G1_TX_DN(2)
   U25  P40 G1_RXN2 GENOA_SP5-SOCKET6096_13568-001,SMLF,IO,DGA^6000030   I208 @T6G_MB_LIB.T6G(SCH_1):PAGE22
   U26  P36 G3_TXN13||SATA35_TXN GENOA_SP5-SOCKET6096_13568-001,SMLF,IO,DGA^6000030   I144 @T6G_MB_LIB.T6G(SCH_1):PAGE50

GMI_CPU1_G3_CPU0_G1_TX_DN<3> @T6G_MB_LIB.T6G(SCH_1):GMI_CPU1_G3_CPU0_G1_TX_DN(3)
   U25  U43 G1_RXN3 GENOA_SP5-SOCKET6096_13568-001,SMLF,IO,DGA^6000030   I208 @T6G_MB_LIB.T6G(SCH_1):PAGE22
   U26  U33 G3_TXN12||SATA34_TXN GENOA_SP5-SOCKET6096_13568-001,SMLF,IO,DGA^6000030   I144 @T6G_MB_LIB.T6G(SCH_1):PAGE50

GMI_CPU1_G3_CPU0_G1_TX_DN<4> @T6G_MB_LIB.T6G(SCH_1):GMI_CPU1_G3_CPU0_G1_TX_DN(4)
   U25  N43 G1_RXN4 GENOA_SP5-SOCKET6096_13568-001,SMLF,IO,DGA^6000030   I208 @T6G_MB_LIB.T6G(SCH_1):PAGE22
   U26  N33 G3_TXN11||SATA33_TXN GENOA_SP5-SOCKET6096_13568-001,SMLF,IO,DGA^6000030   I144 @T6G_MB_LIB.T6G(SCH_1):PAGE50

GMI_CPU1_G3_CPU0_G1_TX_DN<5> @T6G_MB_LIB.T6G(SCH_1):GMI_CPU1_G3_CPU0_G1_TX_DN(5)
   U25  R43 G1_RXN5 GENOA_SP5-SOCKET6096_13568-001,SMLF,IO,DGA^6000030   I208 @T6G_MB_LIB.T6G(SCH_1):PAGE22
   U26  R33 G3_TXN10||SATA32_TXN GENOA_SP5-SOCKET6096_13568-001,SMLF,IO,DGA^6000030   I144 @T6G_MB_LIB.T6G(SCH_1):PAGE50

GMI_CPU1_G3_CPU0_G1_TX_DN<6> @T6G_MB_LIB.T6G(SCH_1):GMI_CPU1_G3_CPU0_G1_TX_DN(6)
   U25  U46 G1_RXN6 GENOA_SP5-SOCKET6096_13568-001,SMLF,IO,DGA^6000030   I208 @T6G_MB_LIB.T6G(SCH_1):PAGE22
   U26  U30 G3_TXN9||SATA31_TXN GENOA_SP5-SOCKET6096_13568-001,SMLF,IO,DGA^6000030   I144 @T6G_MB_LIB.T6G(SCH_1):PAGE50

GMI_CPU1_G3_CPU0_G1_TX_DN<7> @T6G_MB_LIB.T6G(SCH_1):GMI_CPU1_G3_CPU0_G1_TX_DN(7)
   U25  N46 G1_RXN7 GENOA_SP5-SOCKET6096_13568-001,SMLF,IO,DGA^6000030   I208 @T6G_MB_LIB.T6G(SCH_1):PAGE22
   U26  N30 G3_TXN8||SATA30_TXN GENOA_SP5-SOCKET6096_13568-001,SMLF,IO,DGA^6000030   I144 @T6G_MB_LIB.T6G(SCH_1):PAGE50

GMI_CPU1_G3_CPU0_G1_TX_DN<8> @T6G_MB_LIB.T6G(SCH_1):GMI_CPU1_G3_CPU0_G1_TX_DN(8)
   U25  R46 G1_RXN8 GENOA_SP5-SOCKET6096_13568-001,SMLF,IO,DGA^6000030   I208 @T6G_MB_LIB.T6G(SCH_1):PAGE22
   U26  R30 G3_TXN7||SATA27_TXN GENOA_SP5-SOCKET6096_13568-001,SMLF,IO,DGA^6000030   I144 @T6G_MB_LIB.T6G(SCH_1):PAGE50

GMI_CPU1_G3_CPU0_G1_TX_DN<9> @T6G_MB_LIB.T6G(SCH_1):GMI_CPU1_G3_CPU0_G1_TX_DN(9)
   U25  W49 G1_RXN9 GENOA_SP5-SOCKET6096_13568-001,SMLF,IO,DGA^6000030   I208 @T6G_MB_LIB.T6G(SCH_1):PAGE22
   U26  W27 G3_TXN6||SATA26_TXN GENOA_SP5-SOCKET6096_13568-001,SMLF,IO,DGA^6000030   I144 @T6G_MB_LIB.T6G(SCH_1):PAGE50

GMI_CPU1_G3_CPU0_G1_TX_DP<0> @T6G_MB_LIB.T6G(SCH_1):GMI_CPU1_G3_CPU0_G1_TX_DP(0)
   U25  V41 G1_RXP0 GENOA_SP5-SOCKET6096_13568-001,SMLF,IO,DGA^6000030   I208 @T6G_MB_LIB.T6G(SCH_1):PAGE22
   U26  V35 G3_TXP15||SATA37_TXP GENOA_SP5-SOCKET6096_13568-001,SMLF,IO,DGA^6000030   I144 @T6G_MB_LIB.T6G(SCH_1):PAGE50

GMI_CPU1_G3_CPU0_G1_TX_DP<10> @T6G_MB_LIB.T6G(SCH_1):GMI_CPU1_G3_CPU0_G1_TX_DP(10)
   U25  N50 G1_RXP10 GENOA_SP5-SOCKET6096_13568-001,SMLF,IO,DGA^6000030   I208 @T6G_MB_LIB.T6G(SCH_1):PAGE22
   U26  N26 G3_TXP5||SATA25_TXP GENOA_SP5-SOCKET6096_13568-001,SMLF,IO,DGA^6000030   I144 @T6G_MB_LIB.T6G(SCH_1):PAGE50

GMI_CPU1_G3_CPU0_G1_TX_DP<11> @T6G_MB_LIB.T6G(SCH_1):GMI_CPU1_G3_CPU0_G1_TX_DP(11)
   U25  R50 G1_RXP11 GENOA_SP5-SOCKET6096_13568-001,SMLF,IO,DGA^6000030   I208 @T6G_MB_LIB.T6G(SCH_1):PAGE22
   U26  R26 G3_TXP4||SATA24_TXP GENOA_SP5-SOCKET6096_13568-001,SMLF,IO,DGA^6000030   I144 @T6G_MB_LIB.T6G(SCH_1):PAGE50

GMI_CPU1_G3_CPU0_G1_TX_DP<12> @T6G_MB_LIB.T6G(SCH_1):GMI_CPU1_G3_CPU0_G1_TX_DP(12)
   U25  U50 G1_RXP12 GENOA_SP5-SOCKET6096_13568-001,SMLF,IO,DGA^6000030   I208 @T6G_MB_LIB.T6G(SCH_1):PAGE22
   U26  U26 G3_TXP3||SATA23_TXP GENOA_SP5-SOCKET6096_13568-001,SMLF,IO,DGA^6000030   I144 @T6G_MB_LIB.T6G(SCH_1):PAGE50

GMI_CPU1_G3_CPU0_G1_TX_DP<13> @T6G_MB_LIB.T6G(SCH_1):GMI_CPU1_G3_CPU0_G1_TX_DP(13)
   U25  W53 G1_RXP13 GENOA_SP5-SOCKET6096_13568-001,SMLF,IO,DGA^6000030   I208 @T6G_MB_LIB.T6G(SCH_1):PAGE22
   U26  W23 G3_TXP2||SATA22_TXP GENOA_SP5-SOCKET6096_13568-001,SMLF,IO,DGA^6000030   I144 @T6G_MB_LIB.T6G(SCH_1):PAGE50

GMI_CPU1_G3_CPU0_G1_TX_DP<14> @T6G_MB_LIB.T6G(SCH_1):GMI_CPU1_G3_CPU0_G1_TX_DP(14)
   U25  R53 G1_RXP14 GENOA_SP5-SOCKET6096_13568-001,SMLF,IO,DGA^6000030   I208 @T6G_MB_LIB.T6G(SCH_1):PAGE22
   U26  R23 G3_TXP1||SATA21_TXP GENOA_SP5-SOCKET6096_13568-001,SMLF,IO,DGA^6000030   I144 @T6G_MB_LIB.T6G(SCH_1):PAGE50

GMI_CPU1_G3_CPU0_G1_TX_DP<15> @T6G_MB_LIB.T6G(SCH_1):GMI_CPU1_G3_CPU0_G1_TX_DP(15)
   U25  U53 G1_RXP15 GENOA_SP5-SOCKET6096_13568-001,SMLF,IO,DGA^6000030   I208 @T6G_MB_LIB.T6G(SCH_1):PAGE22
   U26  U23 G3_TXP0||SATA20_TXP GENOA_SP5-SOCKET6096_13568-001,SMLF,IO,DGA^6000030   I144 @T6G_MB_LIB.T6G(SCH_1):PAGE50

GMI_CPU1_G3_CPU0_G1_TX_DP<1> @T6G_MB_LIB.T6G(SCH_1):GMI_CPU1_G3_CPU0_G1_TX_DP(1)
   U25  T41 G1_RXP1 GENOA_SP5-SOCKET6096_13568-001,SMLF,IO,DGA^6000030   I208 @T6G_MB_LIB.T6G(SCH_1):PAGE22
   U26  T35 G3_TXP14||SATA36_TXP GENOA_SP5-SOCKET6096_13568-001,SMLF,IO,DGA^6000030   I144 @T6G_MB_LIB.T6G(SCH_1):PAGE50

GMI_CPU1_G3_CPU0_G1_TX_DP<2> @T6G_MB_LIB.T6G(SCH_1):GMI_CPU1_G3_CPU0_G1_TX_DP(2)
   U25  P41 G1_RXP2 GENOA_SP5-SOCKET6096_13568-001,SMLF,IO,DGA^6000030   I208 @T6G_MB_LIB.T6G(SCH_1):PAGE22
   U26  P35 G3_TXP13||SATA35_TXP GENOA_SP5-SOCKET6096_13568-001,SMLF,IO,DGA^6000030   I144 @T6G_MB_LIB.T6G(SCH_1):PAGE50

GMI_CPU1_G3_CPU0_G1_TX_DP<3> @T6G_MB_LIB.T6G(SCH_1):GMI_CPU1_G3_CPU0_G1_TX_DP(3)
   U25  U44 G1_RXP3 GENOA_SP5-SOCKET6096_13568-001,SMLF,IO,DGA^6000030   I208 @T6G_MB_LIB.T6G(SCH_1):PAGE22
   U26  U32 G3_TXP12||SATA34_TXP GENOA_SP5-SOCKET6096_13568-001,SMLF,IO,DGA^6000030   I144 @T6G_MB_LIB.T6G(SCH_1):PAGE50

GMI_CPU1_G3_CPU0_G1_TX_DP<4> @T6G_MB_LIB.T6G(SCH_1):GMI_CPU1_G3_CPU0_G1_TX_DP(4)
   U25  N44 G1_RXP4 GENOA_SP5-SOCKET6096_13568-001,SMLF,IO,DGA^6000030   I208 @T6G_MB_LIB.T6G(SCH_1):PAGE22
   U26  N32 G3_TXP11||SATA33_TXP GENOA_SP5-SOCKET6096_13568-001,SMLF,IO,DGA^6000030   I144 @T6G_MB_LIB.T6G(SCH_1):PAGE50

GMI_CPU1_G3_CPU0_G1_TX_DP<5> @T6G_MB_LIB.T6G(SCH_1):GMI_CPU1_G3_CPU0_G1_TX_DP(5)
   U25  R44 G1_RXP5 GENOA_SP5-SOCKET6096_13568-001,SMLF,IO,DGA^6000030   I208 @T6G_MB_LIB.T6G(SCH_1):PAGE22
   U26  R32 G3_TXP10||SATA32_TXP GENOA_SP5-SOCKET6096_13568-001,SMLF,IO,DGA^6000030   I144 @T6G_MB_LIB.T6G(SCH_1):PAGE50

GMI_CPU1_G3_CPU0_G1_TX_DP<6> @T6G_MB_LIB.T6G(SCH_1):GMI_CPU1_G3_CPU0_G1_TX_DP(6)
   U25  U47 G1_RXP6 GENOA_SP5-SOCKET6096_13568-001,SMLF,IO,DGA^6000030   I208 @T6G_MB_LIB.T6G(SCH_1):PAGE22
   U26  U29 G3_TXP9||SATA31_TXP GENOA_SP5-SOCKET6096_13568-001,SMLF,IO,DGA^6000030   I144 @T6G_MB_LIB.T6G(SCH_1):PAGE50

GMI_CPU1_G3_CPU0_G1_TX_DP<7> @T6G_MB_LIB.T6G(SCH_1):GMI_CPU1_G3_CPU0_G1_TX_DP(7)
   U25  N47 G1_RXP7 GENOA_SP5-SOCKET6096_13568-001,SMLF,IO,DGA^6000030   I208 @T6G_MB_LIB.T6G(SCH_1):PAGE22
   U26  N29 G3_TXP8||SATA30_TXP GENOA_SP5-SOCKET6096_13568-001,SMLF,IO,DGA^6000030   I144 @T6G_MB_LIB.T6G(SCH_1):PAGE50

GMI_CPU1_G3_CPU0_G1_TX_DP<8> @T6G_MB_LIB.T6G(SCH_1):GMI_CPU1_G3_CPU0_G1_TX_DP(8)
   U25  R47 G1_RXP8 GENOA_SP5-SOCKET6096_13568-001,SMLF,IO,DGA^6000030   I208 @T6G_MB_LIB.T6G(SCH_1):PAGE22
   U26  R29 G3_TXP7||SATA27_TXP GENOA_SP5-SOCKET6096_13568-001,SMLF,IO,DGA^6000030   I144 @T6G_MB_LIB.T6G(SCH_1):PAGE50

GMI_CPU1_G3_CPU0_G1_TX_DP<9> @T6G_MB_LIB.T6G(SCH_1):GMI_CPU1_G3_CPU0_G1_TX_DP(9)
   U25  W50 G1_RXP9 GENOA_SP5-SOCKET6096_13568-001,SMLF,IO,DGA^6000030   I208 @T6G_MB_LIB.T6G(SCH_1):PAGE22
   U26  W26 G3_TXP6||SATA26_TXP GENOA_SP5-SOCKET6096_13568-001,SMLF,IO,DGA^6000030   I144 @T6G_MB_LIB.T6G(SCH_1):PAGE50

GND @T6G_MB_LIB.T6G(SCH_1):GND
  C212    2      B Q_CAP_C0402-0.001UF,50V,10%,EMPTY,CH30106KB19   I295 @T6G_MB_LIB.T6G(SCH_1):PAGE27
  C211    2      B Q_CAP_C0402-0.001UF,50V,10%,EMPTY,CH30106KB19   I297 @T6G_MB_LIB.T6G(SCH_1):PAGE27
  C210    2      B Q_CAP_C0402-0.001UF,50V,10%,EMPTY,CH30106KB19   I302 @T6G_MB_LIB.T6G(SCH_1):PAGE27
  C209    2      B Q_CAP_C0402-0.001UF,50V,10%,EMPTY,CH30106KB19   I303 @T6G_MB_LIB.T6G(SCH_1):PAGE27
  C208    2      B Q_CAP_C0402-0.001UF,50V,10%,EMPTY,CH30106KB19   I306 @T6G_MB_LIB.T6G(SCH_1):PAGE27
  C207    2      B Q_CAP_C0402-0.001UF,50V,10%,EMPTY,CH30106KB19   I307 @T6G_MB_LIB.T6G(SCH_1):PAGE27
  R393    2      B Q_RES_0402LF-2.2K,5%,1/16W,CHIP,CS22202JB07   I396 @T6G_MB_LIB.T6G(SCH_1):PAGE27
  R394    2      B Q_RES_0402LF-2.2K,5%,1/16W,CHIP,CS22202JB07   I397 @T6G_MB_LIB.T6G(SCH_1):PAGE27
    U3    3    GND SN74LVC1G07DBVR_SMLF-SN74LVC1G07DBVR,IC,AL1G0007024   I373 @T6G_MB_LIB.T6G(SCH_1):PAGE29
   C30    2      B Q_CAP_0402-0.1UF,25V,10%,X7R,CH4104K1B00   I379 @T6G_MB_LIB.T6G(SCH_1):PAGE29
   U25   A3 VSS_A3 GENOA_SP5-SOCKET6096_13568-001,SMLF,IO,DGA^6000030    I19 @T6G_MB_LIB.T6G(SCH_1):PAGE31
   U25   A9 VSS_A9 GENOA_SP5-SOCKET6096_13568-001,SMLF,IO,DGA^6000030    I19 @T6G_MB_LIB.T6G(SCH_1):PAGE31
   U25  A15 VSS_A15 GENOA_SP5-SOCKET6096_13568-001,SMLF,IO,DGA^6000030    I19 @T6G_MB_LIB.T6G(SCH_1):PAGE31
   U25  A21 VSS_A21 GENOA_SP5-SOCKET6096_13568-001,SMLF,IO,DGA^6000030    I19 @T6G_MB_LIB.T6G(SCH_1):PAGE31
   U25  A27 VSS_A27 GENOA_SP5-SOCKET6096_13568-001,SMLF,IO,DGA^6000030    I19 @T6G_MB_LIB.T6G(SCH_1):PAGE31
   U25  A43 VSS_A43 GENOA_SP5-SOCKET6096_13568-001,SMLF,IO,DGA^6000030    I19 @T6G_MB_LIB.T6G(SCH_1):PAGE31
   U25  A44 VSS_A44 GENOA_SP5-SOCKET6096_13568-001,SMLF,IO,DGA^6000030    I19 @T6G_MB_LIB.T6G(SCH_1):PAGE31
   U25  A47 VSS_A47 GENOA_SP5-SOCKET6096_13568-001,SMLF,IO,DGA^6000030    I19 @T6G_MB_LIB.T6G(SCH_1):PAGE31
   U25  A49 VSS_A49 GENOA_SP5-SOCKET6096_13568-001,SMLF,IO,DGA^6000030    I19 @T6G_MB_LIB.T6G(SCH_1):PAGE31
   U25  A53 VSS_A53 GENOA_SP5-SOCKET6096_13568-001,SMLF,IO,DGA^6000030    I19 @T6G_MB_LIB.T6G(SCH_1):PAGE31
   U25  A61 VSS_A61 GENOA_SP5-SOCKET6096_13568-001,SMLF,IO,DGA^6000030    I19 @T6G_MB_LIB.T6G(SCH_1):PAGE31
   U25  A67 VSS_A67 GENOA_SP5-SOCKET6096_13568-001,SMLF,IO,DGA^6000030    I19 @T6G_MB_LIB.T6G(SCH_1):PAGE31
   U25  A72 VSS_A72 GENOA_SP5-SOCKET6096_13568-001,SMLF,IO,DGA^6000030    I19 @T6G_MB_LIB.T6G(SCH_1):PAGE31
   U25  A73 VSS_A73 GENOA_SP5-SOCKET6096_13568-001,SMLF,IO,DGA^6000030    I19 @T6G_MB_LIB.T6G(SCH_1):PAGE31
   U25   B7 VSS_B7 GENOA_SP5-SOCKET6096_13568-001,SMLF,IO,DGA^6000030    I19 @T6G_MB_LIB.T6G(SCH_1):PAGE31
   U25   B8 VSS_B8 GENOA_SP5-SOCKET6096_13568-001,SMLF,IO,DGA^6000030    I19 @T6G_MB_LIB.T6G(SCH_1):PAGE31
   U25  B10 VSS_B10 GENOA_SP5-SOCKET6096_13568-001,SMLF,IO,DGA^6000030    I19 @T6G_MB_LIB.T6G(SCH_1):PAGE31
   U25  B11 VSS_B11 GENOA_SP5-SOCKET6096_13568-001,SMLF,IO,DGA^6000030    I19 @T6G_MB_LIB.T6G(SCH_1):PAGE31
   U25  B13 VSS_B13 GENOA_SP5-SOCKET6096_13568-001,SMLF,IO,DGA^6000030    I19 @T6G_MB_LIB.T6G(SCH_1):PAGE31
   U25  B18 VSS_B18 GENOA_SP5-SOCKET6096_13568-001,SMLF,IO,DGA^6000030    I19 @T6G_MB_LIB.T6G(SCH_1):PAGE31
   U25  B24 VSS_B24 GENOA_SP5-SOCKET6096_13568-001,SMLF,IO,DGA^6000030    I19 @T6G_MB_LIB.T6G(SCH_1):PAGE31
   U25  B27 VSS_B27 GENOA_SP5-SOCKET6096_13568-001,SMLF,IO,DGA^6000030    I19 @T6G_MB_LIB.T6G(SCH_1):PAGE31
   U25  B30 VSS_B30 GENOA_SP5-SOCKET6096_13568-001,SMLF,IO,DGA^6000030    I19 @T6G_MB_LIB.T6G(SCH_1):PAGE31
   U25  B33 VSS_B33 GENOA_SP5-SOCKET6096_13568-001,SMLF,IO,DGA^6000030    I19 @T6G_MB_LIB.T6G(SCH_1):PAGE31
   U25  B37 VSS_B37 GENOA_SP5-SOCKET6096_13568-001,SMLF,IO,DGA^6000030    I19 @T6G_MB_LIB.T6G(SCH_1):PAGE31
   U25  B39 VSS_B39 GENOA_SP5-SOCKET6096_13568-001,SMLF,IO,DGA^6000030    I19 @T6G_MB_LIB.T6G(SCH_1):PAGE31
   U25  B43 VSS_B43 GENOA_SP5-SOCKET6096_13568-001,SMLF,IO,DGA^6000030    I19 @T6G_MB_LIB.T6G(SCH_1):PAGE31
   U25  B46 VSS_B46 GENOA_SP5-SOCKET6096_13568-001,SMLF,IO,DGA^6000030    I19 @T6G_MB_LIB.T6G(SCH_1):PAGE31
   U25  B49 VSS_B49 GENOA_SP5-SOCKET6096_13568-001,SMLF,IO,DGA^6000030    I19 @T6G_MB_LIB.T6G(SCH_1):PAGE31
   U25  B52 VSS_B52 GENOA_SP5-SOCKET6096_13568-001,SMLF,IO,DGA^6000030    I19 @T6G_MB_LIB.T6G(SCH_1):PAGE31
   U25  B55 VSS_B55 GENOA_SP5-SOCKET6096_13568-001,SMLF,IO,DGA^6000030    I19 @T6G_MB_LIB.T6G(SCH_1):PAGE31
   U25  B59 VSS_B59 GENOA_SP5-SOCKET6096_13568-001,SMLF,IO,DGA^6000030    I19 @T6G_MB_LIB.T6G(SCH_1):PAGE31
   U25  B62 VSS_B62 GENOA_SP5-SOCKET6096_13568-001,SMLF,IO,DGA^6000030    I19 @T6G_MB_LIB.T6G(SCH_1):PAGE31
   U25  B65 VSS_B65 GENOA_SP5-SOCKET6096_13568-001,SMLF,IO,DGA^6000030    I19 @T6G_MB_LIB.T6G(SCH_1):PAGE31
   U25  B68 VSS_B68 GENOA_SP5-SOCKET6096_13568-001,SMLF,IO,DGA^6000030    I19 @T6G_MB_LIB.T6G(SCH_1):PAGE31
   U25  B70 VSS_B70 GENOA_SP5-SOCKET6096_13568-001,SMLF,IO,DGA^6000030    I19 @T6G_MB_LIB.T6G(SCH_1):PAGE31
   U25   C1 VSS_C1 GENOA_SP5-SOCKET6096_13568-001,SMLF,IO,DGA^6000030    I19 @T6G_MB_LIB.T6G(SCH_1):PAGE31
   U25   C5 VSS_C5 GENOA_SP5-SOCKET6096_13568-001,SMLF,IO,DGA^6000030    I19 @T6G_MB_LIB.T6G(SCH_1):PAGE31
   U25   C8 VSS_C8 GENOA_SP5-SOCKET6096_13568-001,SMLF,IO,DGA^6000030    I19 @T6G_MB_LIB.T6G(SCH_1):PAGE31
   U25  C10 VSS_C10 GENOA_SP5-SOCKET6096_13568-001,SMLF,IO,DGA^6000030    I19 @T6G_MB_LIB.T6G(SCH_1):PAGE31
   U25  C11 VSS_C11 GENOA_SP5-SOCKET6096_13568-001,SMLF,IO,DGA^6000030    I19 @T6G_MB_LIB.T6G(SCH_1):PAGE31
   U25  C13 VSS_C13 GENOA_SP5-SOCKET6096_13568-001,SMLF,IO,DGA^6000030    I19 @T6G_MB_LIB.T6G(SCH_1):PAGE31
   U25  C15 VSS_C15 GENOA_SP5-SOCKET6096_13568-001,SMLF,IO,DGA^6000030    I19 @T6G_MB_LIB.T6G(SCH_1):PAGE31
   U25  C21 VSS_C21 GENOA_SP5-SOCKET6096_13568-001,SMLF,IO,DGA^6000030    I19 @T6G_MB_LIB.T6G(SCH_1):PAGE31
   U25  C24 VSS_C24 GENOA_SP5-SOCKET6096_13568-001,SMLF,IO,DGA^6000030    I19 @T6G_MB_LIB.T6G(SCH_1):PAGE31
   U25  C27 VSS_C27 GENOA_SP5-SOCKET6096_13568-001,SMLF,IO,DGA^6000030    I19 @T6G_MB_LIB.T6G(SCH_1):PAGE31
   U25  C30 VSS_C30 GENOA_SP5-SOCKET6096_13568-001,SMLF,IO,DGA^6000030    I19 @T6G_MB_LIB.T6G(SCH_1):PAGE31
   U25  C36 VSS_C36 GENOA_SP5-SOCKET6096_13568-001,SMLF,IO,DGA^6000030    I19 @T6G_MB_LIB.T6G(SCH_1):PAGE31
   U25  C40 VSS_C40 GENOA_SP5-SOCKET6096_13568-001,SMLF,IO,DGA^6000030    I19 @T6G_MB_LIB.T6G(SCH_1):PAGE31
   U25  C43 VSS_C43 GENOA_SP5-SOCKET6096_13568-001,SMLF,IO,DGA^6000030    I19 @T6G_MB_LIB.T6G(SCH_1):PAGE31
   U25  C46 VSS_C46 GENOA_SP5-SOCKET6096_13568-001,SMLF,IO,DGA^6000030    I19 @T6G_MB_LIB.T6G(SCH_1):PAGE31
   U25  C49 VSS_C49 GENOA_SP5-SOCKET6096_13568-001,SMLF,IO,DGA^6000030    I19 @T6G_MB_LIB.T6G(SCH_1):PAGE31
   U25  C52 VSS_C52 GENOA_SP5-SOCKET6096_13568-001,SMLF,IO,DGA^6000030    I19 @T6G_MB_LIB.T6G(SCH_1):PAGE31
   U25  C55 VSS_C55 GENOA_SP5-SOCKET6096_13568-001,SMLF,IO,DGA^6000030    I19 @T6G_MB_LIB.T6G(SCH_1):PAGE31
   U25  C56 VSS_C56 GENOA_SP5-SOCKET6096_13568-001,SMLF,IO,DGA^6000030    I19 @T6G_MB_LIB.T6G(SCH_1):PAGE31
   U25  C57 VSS_C57 GENOA_SP5-SOCKET6096_13568-001,SMLF,IO,DGA^6000030    I19 @T6G_MB_LIB.T6G(SCH_1):PAGE31
   U25  C61 VSS_C61 GENOA_SP5-SOCKET6096_13568-001,SMLF,IO,DGA^6000030    I19 @T6G_MB_LIB.T6G(SCH_1):PAGE31
   U25  C64 VSS_C64 GENOA_SP5-SOCKET6096_13568-001,SMLF,IO,DGA^6000030    I19 @T6G_MB_LIB.T6G(SCH_1):PAGE31
   U25  C67 VSS_C67 GENOA_SP5-SOCKET6096_13568-001,SMLF,IO,DGA^6000030    I19 @T6G_MB_LIB.T6G(SCH_1):PAGE31
   U25  C69 VSS_C69 GENOA_SP5-SOCKET6096_13568-001,SMLF,IO,DGA^6000030    I19 @T6G_MB_LIB.T6G(SCH_1):PAGE31
   U25  C71 VSS_C71 GENOA_SP5-SOCKET6096_13568-001,SMLF,IO,DGA^6000030    I19 @T6G_MB_LIB.T6G(SCH_1):PAGE31
   U25  C73 VSS_C73 GENOA_SP5-SOCKET6096_13568-001,SMLF,IO,DGA^6000030    I19 @T6G_MB_LIB.T6G(SCH_1):PAGE31
   U25  C75 VSS_C75 GENOA_SP5-SOCKET6096_13568-001,SMLF,IO,DGA^6000030    I19 @T6G_MB_LIB.T6G(SCH_1):PAGE31
   U25   D2 VSS_D2 GENOA_SP5-SOCKET6096_13568-001,SMLF,IO,DGA^6000030    I19 @T6G_MB_LIB.T6G(SCH_1):PAGE31
   U25   D3 VSS_D3 GENOA_SP5-SOCKET6096_13568-001,SMLF,IO,DGA^6000030    I19 @T6G_MB_LIB.T6G(SCH_1):PAGE31
   U25   D5 VSS_D5 GENOA_SP5-SOCKET6096_13568-001,SMLF,IO,DGA^6000030    I19 @T6G_MB_LIB.T6G(SCH_1):PAGE31
   U25   D6 VSS_D6 GENOA_SP5-SOCKET6096_13568-001,SMLF,IO,DGA^6000030    I19 @T6G_MB_LIB.T6G(SCH_1):PAGE31
   U25   D9 VSS_D9 GENOA_SP5-SOCKET6096_13568-001,SMLF,IO,DGA^6000030    I19 @T6G_MB_LIB.T6G(SCH_1):PAGE31
   U25  D10 VSS_D10 GENOA_SP5-SOCKET6096_13568-001,SMLF,IO,DGA^6000030    I19 @T6G_MB_LIB.T6G(SCH_1):PAGE31
   U25  D12 VSS_D12 GENOA_SP5-SOCKET6096_13568-001,SMLF,IO,DGA^6000030    I19 @T6G_MB_LIB.T6G(SCH_1):PAGE31
   U25  D13 VSS_D13 GENOA_SP5-SOCKET6096_13568-001,SMLF,IO,DGA^6000030    I19 @T6G_MB_LIB.T6G(SCH_1):PAGE31
   U25  D16 VSS_D16 GENOA_SP5-SOCKET6096_13568-001,SMLF,IO,DGA^6000030    I19 @T6G_MB_LIB.T6G(SCH_1):PAGE31
   U25  D17 VSS_D17 GENOA_SP5-SOCKET6096_13568-001,SMLF,IO,DGA^6000030    I19 @T6G_MB_LIB.T6G(SCH_1):PAGE31
   U25  D19 VSS_D19 GENOA_SP5-SOCKET6096_13568-001,SMLF,IO,DGA^6000030    I19 @T6G_MB_LIB.T6G(SCH_1):PAGE31
   U25  D20 VSS_D20 GENOA_SP5-SOCKET6096_13568-001,SMLF,IO,DGA^6000030    I19 @T6G_MB_LIB.T6G(SCH_1):PAGE31
   U25  D21 VSS_D21 GENOA_SP5-SOCKET6096_13568-001,SMLF,IO,DGA^6000030    I19 @T6G_MB_LIB.T6G(SCH_1):PAGE31
   U25  D24 VSS_D24 GENOA_SP5-SOCKET6096_13568-001,SMLF,IO,DGA^6000030    I19 @T6G_MB_LIB.T6G(SCH_1):PAGE31
   U25  D25 VSS_D25 GENOA_SP5-SOCKET6096_13568-001,SMLF,IO,DGA^6000030    I19 @T6G_MB_LIB.T6G(SCH_1):PAGE31
   U25  D26 VSS_D26 GENOA_SP5-SOCKET6096_13568-001,SMLF,IO,DGA^6000030    I19 @T6G_MB_LIB.T6G(SCH_1):PAGE31
   U25  D27 VSS_D27 GENOA_SP5-SOCKET6096_13568-001,SMLF,IO,DGA^6000030    I19 @T6G_MB_LIB.T6G(SCH_1):PAGE31
   U25  D28 VSS_D28 GENOA_SP5-SOCKET6096_13568-001,SMLF,IO,DGA^6000030    I19 @T6G_MB_LIB.T6G(SCH_1):PAGE31
   U25  D29 VSS_D29 GENOA_SP5-SOCKET6096_13568-001,SMLF,IO,DGA^6000030    I19 @T6G_MB_LIB.T6G(SCH_1):PAGE31
   U25  D30 VSS_D30 GENOA_SP5-SOCKET6096_13568-001,SMLF,IO,DGA^6000030    I19 @T6G_MB_LIB.T6G(SCH_1):PAGE31
   U25  D31 VSS_D31 GENOA_SP5-SOCKET6096_13568-001,SMLF,IO,DGA^6000030    I19 @T6G_MB_LIB.T6G(SCH_1):PAGE31
   U25  D35 VSS_D35 GENOA_SP5-SOCKET6096_13568-001,SMLF,IO,DGA^6000030    I19 @T6G_MB_LIB.T6G(SCH_1):PAGE31
   U25  D37 VSS_D37 GENOA_SP5-SOCKET6096_13568-001,SMLF,IO,DGA^6000030    I19 @T6G_MB_LIB.T6G(SCH_1):PAGE31
   U25  D39 VSS_D39 GENOA_SP5-SOCKET6096_13568-001,SMLF,IO,DGA^6000030    I19 @T6G_MB_LIB.T6G(SCH_1):PAGE31
   U25  D40 VSS_D40 GENOA_SP5-SOCKET6096_13568-001,SMLF,IO,DGA^6000030    I19 @T6G_MB_LIB.T6G(SCH_1):PAGE31
   U25  D41 VSS_D41 GENOA_SP5-SOCKET6096_13568-001,SMLF,IO,DGA^6000030    I19 @T6G_MB_LIB.T6G(SCH_1):PAGE31
   U25  D42 VSS_D42 GENOA_SP5-SOCKET6096_13568-001,SMLF,IO,DGA^6000030    I19 @T6G_MB_LIB.T6G(SCH_1):PAGE31
   U25  D43 VSS_D43 GENOA_SP5-SOCKET6096_13568-001,SMLF,IO,DGA^6000030    I19 @T6G_MB_LIB.T6G(SCH_1):PAGE31
   U25  D44 VSS_D44 GENOA_SP5-SOCKET6096_13568-001,SMLF,IO,DGA^6000030    I19 @T6G_MB_LIB.T6G(SCH_1):PAGE31
   U25  D45 VSS_D45 GENOA_SP5-SOCKET6096_13568-001,SMLF,IO,DGA^6000030    I19 @T6G_MB_LIB.T6G(SCH_1):PAGE31
   U25  D46 VSS_D46 GENOA_SP5-SOCKET6096_13568-001,SMLF,IO,DGA^6000030    I19 @T6G_MB_LIB.T6G(SCH_1):PAGE31
   U25  D47 VSS_D47 GENOA_SP5-SOCKET6096_13568-001,SMLF,IO,DGA^6000030    I19 @T6G_MB_LIB.T6G(SCH_1):PAGE31
   U25  D48 VSS_D48 GENOA_SP5-SOCKET6096_13568-001,SMLF,IO,DGA^6000030    I19 @T6G_MB_LIB.T6G(SCH_1):PAGE31
   U25  D49 VSS_D49 GENOA_SP5-SOCKET6096_13568-001,SMLF,IO,DGA^6000030    I19 @T6G_MB_LIB.T6G(SCH_1):PAGE31
   U25  D50 VSS_D50 GENOA_SP5-SOCKET6096_13568-001,SMLF,IO,DGA^6000030    I19 @T6G_MB_LIB.T6G(SCH_1):PAGE31
   U25  D51 VSS_D51 GENOA_SP5-SOCKET6096_13568-001,SMLF,IO,DGA^6000030    I19 @T6G_MB_LIB.T6G(SCH_1):PAGE31
   U25  D52 VSS_D52 GENOA_SP5-SOCKET6096_13568-001,SMLF,IO,DGA^6000030    I19 @T6G_MB_LIB.T6G(SCH_1):PAGE31
   U25  D53 VSS_D53 GENOA_SP5-SOCKET6096_13568-001,SMLF,IO,DGA^6000030    I19 @T6G_MB_LIB.T6G(SCH_1):PAGE31
   U25  D54 VSS_D54 GENOA_SP5-SOCKET6096_13568-001,SMLF,IO,DGA^6000030    I19 @T6G_MB_LIB.T6G(SCH_1):PAGE31
   U25  D57 VSS_D57 GENOA_SP5-SOCKET6096_13568-001,SMLF,IO,DGA^6000030    I19 @T6G_MB_LIB.T6G(SCH_1):PAGE31
   U25  D59 VSS_D59 GENOA_SP5-SOCKET6096_13568-001,SMLF,IO,DGA^6000030    I19 @T6G_MB_LIB.T6G(SCH_1):PAGE31
   U25  D60 VSS_D60 GENOA_SP5-SOCKET6096_13568-001,SMLF,IO,DGA^6000030    I19 @T6G_MB_LIB.T6G(SCH_1):PAGE31
   U25  D61 VSS_D61 GENOA_SP5-SOCKET6096_13568-001,SMLF,IO,DGA^6000030    I19 @T6G_MB_LIB.T6G(SCH_1):PAGE31
   U25  D63 VSS_D63 GENOA_SP5-SOCKET6096_13568-001,SMLF,IO,DGA^6000030    I19 @T6G_MB_LIB.T6G(SCH_1):PAGE31
   U25  D64 VSS_D64 GENOA_SP5-SOCKET6096_13568-001,SMLF,IO,DGA^6000030    I19 @T6G_MB_LIB.T6G(SCH_1):PAGE31
   U25  D66 VSS_D66 GENOA_SP5-SOCKET6096_13568-001,SMLF,IO,DGA^6000030    I19 @T6G_MB_LIB.T6G(SCH_1):PAGE31
   U25  D67 VSS_D67 GENOA_SP5-SOCKET6096_13568-001,SMLF,IO,DGA^6000030    I19 @T6G_MB_LIB.T6G(SCH_1):PAGE31
   U25  D70 VSS_D70 GENOA_SP5-SOCKET6096_13568-001,SMLF,IO,DGA^6000030    I19 @T6G_MB_LIB.T6G(SCH_1):PAGE31
   U25  D71 VSS_D71 GENOA_SP5-SOCKET6096_13568-001,SMLF,IO,DGA^6000030    I19 @T6G_MB_LIB.T6G(SCH_1):PAGE31
   U25  D73 VSS_D73 GENOA_SP5-SOCKET6096_13568-001,SMLF,IO,DGA^6000030    I19 @T6G_MB_LIB.T6G(SCH_1):PAGE31
   U25  D74 VSS_D74 GENOA_SP5-SOCKET6096_13568-001,SMLF,IO,DGA^6000030    I19 @T6G_MB_LIB.T6G(SCH_1):PAGE31
   U25   E1 VSS_E1 GENOA_SP5-SOCKET6096_13568-001,SMLF,IO,DGA^6000030    I19 @T6G_MB_LIB.T6G(SCH_1):PAGE31
   U25   E3 VSS_E3 GENOA_SP5-SOCKET6096_13568-001,SMLF,IO,DGA^6000030    I19 @T6G_MB_LIB.T6G(SCH_1):PAGE31
   U25   E6 VSS_E6 GENOA_SP5-SOCKET6096_13568-001,SMLF,IO,DGA^6000030    I19 @T6G_MB_LIB.T6G(SCH_1):PAGE31
   U25   E7 VSS_E7 GENOA_SP5-SOCKET6096_13568-001,SMLF,IO,DGA^6000030    I19 @T6G_MB_LIB.T6G(SCH_1):PAGE31
   U25   E8 VSS_E8 GENOA_SP5-SOCKET6096_13568-001,SMLF,IO,DGA^6000030    I19 @T6G_MB_LIB.T6G(SCH_1):PAGE31
   U25  E10 VSS_E10 GENOA_SP5-SOCKET6096_13568-001,SMLF,IO,DGA^6000030    I19 @T6G_MB_LIB.T6G(SCH_1):PAGE31
   U25  E13 VSS_E13 GENOA_SP5-SOCKET6096_13568-001,SMLF,IO,DGA^6000030    I19 @T6G_MB_LIB.T6G(SCH_1):PAGE31
   U25  E14 VSS_E14 GENOA_SP5-SOCKET6096_13568-001,SMLF,IO,DGA^6000030    I19 @T6G_MB_LIB.T6G(SCH_1):PAGE31
   U25  E15 VSS_E15 GENOA_SP5-SOCKET6096_13568-001,SMLF,IO,DGA^6000030    I19 @T6G_MB_LIB.T6G(SCH_1):PAGE31
   U25  E17 VSS_E17 GENOA_SP5-SOCKET6096_13568-001,SMLF,IO,DGA^6000030    I19 @T6G_MB_LIB.T6G(SCH_1):PAGE31
   U25  E18 VSS_E18 GENOA_SP5-SOCKET6096_13568-001,SMLF,IO,DGA^6000030    I19 @T6G_MB_LIB.T6G(SCH_1):PAGE31
   U25  E20 VSS_E20 GENOA_SP5-SOCKET6096_13568-001,SMLF,IO,DGA^6000030    I19 @T6G_MB_LIB.T6G(SCH_1):PAGE31
   U25  E21 VSS_E21 GENOA_SP5-SOCKET6096_13568-001,SMLF,IO,DGA^6000030    I19 @T6G_MB_LIB.T6G(SCH_1):PAGE31
   U25  E52 VSS_E52 GENOA_SP5-SOCKET6096_13568-001,SMLF,IO,DGA^6000030    I19 @T6G_MB_LIB.T6G(SCH_1):PAGE31
   U25  E53 VSS_E53 GENOA_SP5-SOCKET6096_13568-001,SMLF,IO,DGA^6000030    I19 @T6G_MB_LIB.T6G(SCH_1):PAGE31
   U25  E55 VSS_E55 GENOA_SP5-SOCKET6096_13568-001,SMLF,IO,DGA^6000030    I19 @T6G_MB_LIB.T6G(SCH_1):PAGE31
   U25  E56 VSS_E56 GENOA_SP5-SOCKET6096_13568-001,SMLF,IO,DGA^6000030    I19 @T6G_MB_LIB.T6G(SCH_1):PAGE31
   U25  E58 VSS_E58 GENOA_SP5-SOCKET6096_13568-001,SMLF,IO,DGA^6000030    I19 @T6G_MB_LIB.T6G(SCH_1):PAGE31
   U25  E59 VSS_E59 GENOA_SP5-SOCKET6096_13568-001,SMLF,IO,DGA^6000030    I19 @T6G_MB_LIB.T6G(SCH_1):PAGE31
   U25  E61 VSS_E61 GENOA_SP5-SOCKET6096_13568-001,SMLF,IO,DGA^6000030    I19 @T6G_MB_LIB.T6G(SCH_1):PAGE31
   U25  E62 VSS_E62 GENOA_SP5-SOCKET6096_13568-001,SMLF,IO,DGA^6000030    I19 @T6G_MB_LIB.T6G(SCH_1):PAGE31
   U25  E63 VSS_E63 GENOA_SP5-SOCKET6096_13568-001,SMLF,IO,DGA^6000030    I19 @T6G_MB_LIB.T6G(SCH_1):PAGE31
   U25  E65 VSS_E65 GENOA_SP5-SOCKET6096_13568-001,SMLF,IO,DGA^6000030    I19 @T6G_MB_LIB.T6G(SCH_1):PAGE31
   U25  E66 VSS_E66 GENOA_SP5-SOCKET6096_13568-001,SMLF,IO,DGA^6000030    I19 @T6G_MB_LIB.T6G(SCH_1):PAGE31
   U25  E68 VSS_E68 GENOA_SP5-SOCKET6096_13568-001,SMLF,IO,DGA^6000030    I19 @T6G_MB_LIB.T6G(SCH_1):PAGE31
   U25  E69 VSS_E69 GENOA_SP5-SOCKET6096_13568-001,SMLF,IO,DGA^6000030    I19 @T6G_MB_LIB.T6G(SCH_1):PAGE31
   U25  E70 VSS_E70 GENOA_SP5-SOCKET6096_13568-001,SMLF,IO,DGA^6000030    I19 @T6G_MB_LIB.T6G(SCH_1):PAGE31
   U25  E72 VSS_E72 GENOA_SP5-SOCKET6096_13568-001,SMLF,IO,DGA^6000030    I19 @T6G_MB_LIB.T6G(SCH_1):PAGE31
   U25  E73 VSS_E73 GENOA_SP5-SOCKET6096_13568-001,SMLF,IO,DGA^6000030    I19 @T6G_MB_LIB.T6G(SCH_1):PAGE31
   U25  E75 VSS_E75 GENOA_SP5-SOCKET6096_13568-001,SMLF,IO,DGA^6000030    I19 @T6G_MB_LIB.T6G(SCH_1):PAGE31
   U25   F3 VSS_F3 GENOA_SP5-SOCKET6096_13568-001,SMLF,IO,DGA^6000030    I19 @T6G_MB_LIB.T6G(SCH_1):PAGE31
   U25   F5 VSS_F5 GENOA_SP5-SOCKET6096_13568-001,SMLF,IO,DGA^6000030    I19 @T6G_MB_LIB.T6G(SCH_1):PAGE31
   U25   F8 VSS_F8 GENOA_SP5-SOCKET6096_13568-001,SMLF,IO,DGA^6000030    I19 @T6G_MB_LIB.T6G(SCH_1):PAGE31
   U25  F10 VSS_F10 GENOA_SP5-SOCKET6096_13568-001,SMLF,IO,DGA^6000030    I19 @T6G_MB_LIB.T6G(SCH_1):PAGE31
   U25  F12 VSS_F12 GENOA_SP5-SOCKET6096_13568-001,SMLF,IO,DGA^6000030    I19 @T6G_MB_LIB.T6G(SCH_1):PAGE31
   U25  F15 VSS_F15 GENOA_SP5-SOCKET6096_13568-001,SMLF,IO,DGA^6000030    I19 @T6G_MB_LIB.T6G(SCH_1):PAGE31
   U25  F17 VSS_F17 GENOA_SP5-SOCKET6096_13568-001,SMLF,IO,DGA^6000030    I19 @T6G_MB_LIB.T6G(SCH_1):PAGE31
   U25  F19 VSS_F19 GENOA_SP5-SOCKET6096_13568-001,SMLF,IO,DGA^6000030    I19 @T6G_MB_LIB.T6G(SCH_1):PAGE31
   U25  F23 VSS_F23 GENOA_SP5-SOCKET6096_13568-001,SMLF,IO,DGA^6000030    I19 @T6G_MB_LIB.T6G(SCH_1):PAGE31
   U25  F24 VSS_F24 GENOA_SP5-SOCKET6096_13568-001,SMLF,IO,DGA^6000030    I19 @T6G_MB_LIB.T6G(SCH_1):PAGE31
   U25  F26 VSS_F26 GENOA_SP5-SOCKET6096_13568-001,SMLF,IO,DGA^6000030    I19 @T6G_MB_LIB.T6G(SCH_1):PAGE31
   U25  F27 VSS_F27 GENOA_SP5-SOCKET6096_13568-001,SMLF,IO,DGA^6000030    I19 @T6G_MB_LIB.T6G(SCH_1):PAGE31
   U25  F29 VSS_F29 GENOA_SP5-SOCKET6096_13568-001,SMLF,IO,DGA^6000030    I19 @T6G_MB_LIB.T6G(SCH_1):PAGE31
   U25  F30 VSS_F30 GENOA_SP5-SOCKET6096_13568-001,SMLF,IO,DGA^6000030    I19 @T6G_MB_LIB.T6G(SCH_1):PAGE31
   U25  F32 VSS_F32 GENOA_SP5-SOCKET6096_13568-001,SMLF,IO,DGA^6000030    I19 @T6G_MB_LIB.T6G(SCH_1):PAGE31
   U25  F33 VSS_F33 GENOA_SP5-SOCKET6096_13568-001,SMLF,IO,DGA^6000030    I19 @T6G_MB_LIB.T6G(SCH_1):PAGE31
   U25  F35 VSS_F35 GENOA_SP5-SOCKET6096_13568-001,SMLF,IO,DGA^6000030    I19 @T6G_MB_LIB.T6G(SCH_1):PAGE31
   U25  F36 VSS_F36 GENOA_SP5-SOCKET6096_13568-001,SMLF,IO,DGA^6000030    I19 @T6G_MB_LIB.T6G(SCH_1):PAGE31
   U25  F37 VSS_F37 GENOA_SP5-SOCKET6096_13568-001,SMLF,IO,DGA^6000030    I19 @T6G_MB_LIB.T6G(SCH_1):PAGE31
   U25  F39 VSS_F39 GENOA_SP5-SOCKET6096_13568-001,SMLF,IO,DGA^6000030    I19 @T6G_MB_LIB.T6G(SCH_1):PAGE31
   U25  F40 VSS_F40 GENOA_SP5-SOCKET6096_13568-001,SMLF,IO,DGA^6000030    I19 @T6G_MB_LIB.T6G(SCH_1):PAGE31
   U25  F41 VSS_F41 GENOA_SP5-SOCKET6096_13568-001,SMLF,IO,DGA^6000030    I19 @T6G_MB_LIB.T6G(SCH_1):PAGE31
   U25  F43 VSS_F43 GENOA_SP5-SOCKET6096_13568-001,SMLF,IO,DGA^6000030    I19 @T6G_MB_LIB.T6G(SCH_1):PAGE31
   U25  F44 VSS_F44 GENOA_SP5-SOCKET6096_13568-001,SMLF,IO,DGA^6000030    I19 @T6G_MB_LIB.T6G(SCH_1):PAGE31
   U25  F46 VSS_F46 GENOA_SP5-SOCKET6096_13568-001,SMLF,IO,DGA^6000030    I19 @T6G_MB_LIB.T6G(SCH_1):PAGE31
   U25  F47 VSS_F47 GENOA_SP5-SOCKET6096_13568-001,SMLF,IO,DGA^6000030    I19 @T6G_MB_LIB.T6G(SCH_1):PAGE31
   U25  F49 VSS_F49 GENOA_SP5-SOCKET6096_13568-001,SMLF,IO,DGA^6000030    I19 @T6G_MB_LIB.T6G(SCH_1):PAGE31
   U25  F50 VSS_F50 GENOA_SP5-SOCKET6096_13568-001,SMLF,IO,DGA^6000030    I19 @T6G_MB_LIB.T6G(SCH_1):PAGE31
   U25  F52 VSS_F52 GENOA_SP5-SOCKET6096_13568-001,SMLF,IO,DGA^6000030    I19 @T6G_MB_LIB.T6G(SCH_1):PAGE31
   U25  F53 VSS_F53 GENOA_SP5-SOCKET6096_13568-001,SMLF,IO,DGA^6000030    I19 @T6G_MB_LIB.T6G(SCH_1):PAGE31
   U25  F57 VSS_F57 GENOA_SP5-SOCKET6096_13568-001,SMLF,IO,DGA^6000030    I19 @T6G_MB_LIB.T6G(SCH_1):PAGE31
   U25  F59 VSS_F59 GENOA_SP5-SOCKET6096_13568-001,SMLF,IO,DGA^6000030    I19 @T6G_MB_LIB.T6G(SCH_1):PAGE31
   U25  F61 VSS_F61 GENOA_SP5-SOCKET6096_13568-001,SMLF,IO,DGA^6000030    I19 @T6G_MB_LIB.T6G(SCH_1):PAGE31
   U25  F64 VSS_F64 GENOA_SP5-SOCKET6096_13568-001,SMLF,IO,DGA^6000030    I19 @T6G_MB_LIB.T6G(SCH_1):PAGE31
   U25  F66 VSS_F66 GENOA_SP5-SOCKET6096_13568-001,SMLF,IO,DGA^6000030    I19 @T6G_MB_LIB.T6G(SCH_1):PAGE31
   U25  F68 VSS_F68 GENOA_SP5-SOCKET6096_13568-001,SMLF,IO,DGA^6000030    I19 @T6G_MB_LIB.T6G(SCH_1):PAGE31
   U25  F71 VSS_F71 GENOA_SP5-SOCKET6096_13568-001,SMLF,IO,DGA^6000030    I19 @T6G_MB_LIB.T6G(SCH_1):PAGE31
   U25  F73 VSS_F73 GENOA_SP5-SOCKET6096_13568-001,SMLF,IO,DGA^6000030    I19 @T6G_MB_LIB.T6G(SCH_1):PAGE31
   U25   G1 VSS_G1 GENOA_SP5-SOCKET6096_13568-001,SMLF,IO,DGA^6000030    I19 @T6G_MB_LIB.T6G(SCH_1):PAGE31
   U25   G4 VSS_G4 GENOA_SP5-SOCKET6096_13568-001,SMLF,IO,DGA^6000030    I19 @T6G_MB_LIB.T6G(SCH_1):PAGE31
   U25   G6 VSS_G6 GENOA_SP5-SOCKET6096_13568-001,SMLF,IO,DGA^6000030    I19 @T6G_MB_LIB.T6G(SCH_1):PAGE31
   U25   G8 VSS_G8 GENOA_SP5-SOCKET6096_13568-001,SMLF,IO,DGA^6000030    I19 @T6G_MB_LIB.T6G(SCH_1):PAGE31
   U25  G11 VSS_G11 GENOA_SP5-SOCKET6096_13568-001,SMLF,IO,DGA^6000030    I19 @T6G_MB_LIB.T6G(SCH_1):PAGE31
   U25  G13 VSS_G13 GENOA_SP5-SOCKET6096_13568-001,SMLF,IO,DGA^6000030    I19 @T6G_MB_LIB.T6G(SCH_1):PAGE31
   U25  G15 VSS_G15 GENOA_SP5-SOCKET6096_13568-001,SMLF,IO,DGA^6000030    I19 @T6G_MB_LIB.T6G(SCH_1):PAGE31
   U25  G18 VSS_G18 GENOA_SP5-SOCKET6096_13568-001,SMLF,IO,DGA^6000030    I19 @T6G_MB_LIB.T6G(SCH_1):PAGE31
   U25  G20 VSS_G20 GENOA_SP5-SOCKET6096_13568-001,SMLF,IO,DGA^6000030    I19 @T6G_MB_LIB.T6G(SCH_1):PAGE31
   U25  G22 VSS_G22 GENOA_SP5-SOCKET6096_13568-001,SMLF,IO,DGA^6000030    I19 @T6G_MB_LIB.T6G(SCH_1):PAGE31
   U25  G25 VSS_G25 GENOA_SP5-SOCKET6096_13568-001,SMLF,IO,DGA^6000030    I19 @T6G_MB_LIB.T6G(SCH_1):PAGE31
   U25  G28 VSS_G28 GENOA_SP5-SOCKET6096_13568-001,SMLF,IO,DGA^6000030    I19 @T6G_MB_LIB.T6G(SCH_1):PAGE31
   U25  G31 VSS_G31 GENOA_SP5-SOCKET6096_13568-001,SMLF,IO,DGA^6000030    I19 @T6G_MB_LIB.T6G(SCH_1):PAGE31
   U25  G34 VSS_G34 GENOA_SP5-SOCKET6096_13568-001,SMLF,IO,DGA^6000030    I19 @T6G_MB_LIB.T6G(SCH_1):PAGE31
   U25  G42 VSS_G42 GENOA_SP5-SOCKET6096_13568-001,SMLF,IO,DGA^6000030    I19 @T6G_MB_LIB.T6G(SCH_1):PAGE31
   U25  G45 VSS_G45 GENOA_SP5-SOCKET6096_13568-001,SMLF,IO,DGA^6000030    I19 @T6G_MB_LIB.T6G(SCH_1):PAGE31
   U25  G48 VSS_G48 GENOA_SP5-SOCKET6096_13568-001,SMLF,IO,DGA^6000030    I19 @T6G_MB_LIB.T6G(SCH_1):PAGE31
   U25  G51 VSS_G51 GENOA_SP5-SOCKET6096_13568-001,SMLF,IO,DGA^6000030    I19 @T6G_MB_LIB.T6G(SCH_1):PAGE31
   U25  G54 VSS_G54 GENOA_SP5-SOCKET6096_13568-001,SMLF,IO,DGA^6000030    I19 @T6G_MB_LIB.T6G(SCH_1):PAGE31
   U25  G56 VSS_G56 GENOA_SP5-SOCKET6096_13568-001,SMLF,IO,DGA^6000030    I19 @T6G_MB_LIB.T6G(SCH_1):PAGE31
   U25  G58 VSS_G58 GENOA_SP5-SOCKET6096_13568-001,SMLF,IO,DGA^6000030    I19 @T6G_MB_LIB.T6G(SCH_1):PAGE31
   U25  G61 VSS_G61 GENOA_SP5-SOCKET6096_13568-001,SMLF,IO,DGA^6000030    I19 @T6G_MB_LIB.T6G(SCH_1):PAGE31
   U25  G63 VSS_G63 GENOA_SP5-SOCKET6096_13568-001,SMLF,IO,DGA^6000030    I19 @T6G_MB_LIB.T6G(SCH_1):PAGE31
   U25  G65 VSS_G65 GENOA_SP5-SOCKET6096_13568-001,SMLF,IO,DGA^6000030    I19 @T6G_MB_LIB.T6G(SCH_1):PAGE31
   U25  G68 VSS_G68 GENOA_SP5-SOCKET6096_13568-001,SMLF,IO,DGA^6000030    I19 @T6G_MB_LIB.T6G(SCH_1):PAGE31
   U25  G70 VSS_G70 GENOA_SP5-SOCKET6096_13568-001,SMLF,IO,DGA^6000030    I19 @T6G_MB_LIB.T6G(SCH_1):PAGE31
   U25  G72 VSS_G72 GENOA_SP5-SOCKET6096_13568-001,SMLF,IO,DGA^6000030    I19 @T6G_MB_LIB.T6G(SCH_1):PAGE31
   U25  G75 VSS_G75 GENOA_SP5-SOCKET6096_13568-001,SMLF,IO,DGA^6000030    I19 @T6G_MB_LIB.T6G(SCH_1):PAGE31
   U25   H3 VSS_H3 GENOA_SP5-SOCKET6096_13568-001,SMLF,IO,DGA^6000030    I19 @T6G_MB_LIB.T6G(SCH_1):PAGE31
   U25   H8 VSS_H8 GENOA_SP5-SOCKET6096_13568-001,SMLF,IO,DGA^6000030    I19 @T6G_MB_LIB.T6G(SCH_1):PAGE31
   U25  H10 VSS_H10 GENOA_SP5-SOCKET6096_13568-001,SMLF,IO,DGA^6000030    I19 @T6G_MB_LIB.T6G(SCH_1):PAGE31
   U25  H15 VSS_H15 GENOA_SP5-SOCKET6096_13568-001,SMLF,IO,DGA^6000030    I19 @T6G_MB_LIB.T6G(SCH_1):PAGE31
   U25  H17 VSS_H17 GENOA_SP5-SOCKET6096_13568-001,SMLF,IO,DGA^6000030    I19 @T6G_MB_LIB.T6G(SCH_1):PAGE31
   U25  H22 VSS_H22 GENOA_SP5-SOCKET6096_13568-001,SMLF,IO,DGA^6000030    I19 @T6G_MB_LIB.T6G(SCH_1):PAGE31
   U25  H25 VSS_H25 GENOA_SP5-SOCKET6096_13568-001,SMLF,IO,DGA^6000030    I19 @T6G_MB_LIB.T6G(SCH_1):PAGE31
   U25  H28 VSS_H28 GENOA_SP5-SOCKET6096_13568-001,SMLF,IO,DGA^6000030    I19 @T6G_MB_LIB.T6G(SCH_1):PAGE31
   U25  H31 VSS_H31 GENOA_SP5-SOCKET6096_13568-001,SMLF,IO,DGA^6000030    I19 @T6G_MB_LIB.T6G(SCH_1):PAGE31
   U25  H34 VSS_H34 GENOA_SP5-SOCKET6096_13568-001,SMLF,IO,DGA^6000030    I19 @T6G_MB_LIB.T6G(SCH_1):PAGE31
   U25  H37 VSS_H37 GENOA_SP5-SOCKET6096_13568-001,SMLF,IO,DGA^6000030    I19 @T6G_MB_LIB.T6G(SCH_1):PAGE31
   U25  H39 VSS_H39 GENOA_SP5-SOCKET6096_13568-001,SMLF,IO,DGA^6000030    I19 @T6G_MB_LIB.T6G(SCH_1):PAGE31
   U25  H42 VSS_H42 GENOA_SP5-SOCKET6096_13568-001,SMLF,IO,DGA^6000030    I19 @T6G_MB_LIB.T6G(SCH_1):PAGE31
   U25  H45 VSS_H45 GENOA_SP5-SOCKET6096_13568-001,SMLF,IO,DGA^6000030    I19 @T6G_MB_LIB.T6G(SCH_1):PAGE31
   U25  H48 VSS_H48 GENOA_SP5-SOCKET6096_13568-001,SMLF,IO,DGA^6000030    I19 @T6G_MB_LIB.T6G(SCH_1):PAGE31
   U25  H51 VSS_H51 GENOA_SP5-SOCKET6096_13568-001,SMLF,IO,DGA^6000030    I19 @T6G_MB_LIB.T6G(SCH_1):PAGE31
   U25  H54 VSS_H54 GENOA_SP5-SOCKET6096_13568-001,SMLF,IO,DGA^6000030    I19 @T6G_MB_LIB.T6G(SCH_1):PAGE31
   U25  H59 VSS_H59 GENOA_SP5-SOCKET6096_13568-001,SMLF,IO,DGA^6000030    I19 @T6G_MB_LIB.T6G(SCH_1):PAGE31
   U25  H61 VSS_H61 GENOA_SP5-SOCKET6096_13568-001,SMLF,IO,DGA^6000030    I19 @T6G_MB_LIB.T6G(SCH_1):PAGE31
   U25  H66 VSS_H66 GENOA_SP5-SOCKET6096_13568-001,SMLF,IO,DGA^6000030    I19 @T6G_MB_LIB.T6G(SCH_1):PAGE31
   U25  H68 VSS_H68 GENOA_SP5-SOCKET6096_13568-001,SMLF,IO,DGA^6000030    I19 @T6G_MB_LIB.T6G(SCH_1):PAGE31
   U25  H73 VSS_H73 GENOA_SP5-SOCKET6096_13568-001,SMLF,IO,DGA^6000030    I19 @T6G_MB_LIB.T6G(SCH_1):PAGE31
   U25   J1 VSS_J1 GENOA_SP5-SOCKET6096_13568-001,SMLF,IO,DGA^6000030    I19 @T6G_MB_LIB.T6G(SCH_1):PAGE31
   U25   J4 VSS_J4 GENOA_SP5-SOCKET6096_13568-001,SMLF,IO,DGA^6000030    I19 @T6G_MB_LIB.T6G(SCH_1):PAGE31
   U25   J6 VSS_J6 GENOA_SP5-SOCKET6096_13568-001,SMLF,IO,DGA^6000030    I19 @T6G_MB_LIB.T6G(SCH_1):PAGE31
   U25   J8 VSS_J8 GENOA_SP5-SOCKET6096_13568-001,SMLF,IO,DGA^6000030    I19 @T6G_MB_LIB.T6G(SCH_1):PAGE31
   U25  J11 VSS_J11 GENOA_SP5-SOCKET6096_13568-001,SMLF,IO,DGA^6000030    I19 @T6G_MB_LIB.T6G(SCH_1):PAGE31
   U25  J13 VSS_J13 GENOA_SP5-SOCKET6096_13568-001,SMLF,IO,DGA^6000030    I19 @T6G_MB_LIB.T6G(SCH_1):PAGE31
   U25  J15 VSS_J15 GENOA_SP5-SOCKET6096_13568-001,SMLF,IO,DGA^6000030    I20 @T6G_MB_LIB.T6G(SCH_1):PAGE31
   U25  J18 VSS_J18 GENOA_SP5-SOCKET6096_13568-001,SMLF,IO,DGA^6000030    I20 @T6G_MB_LIB.T6G(SCH_1):PAGE31
   U25  J20 VSS_J20 GENOA_SP5-SOCKET6096_13568-001,SMLF,IO,DGA^6000030    I20 @T6G_MB_LIB.T6G(SCH_1):PAGE31
   U25  J22 VSS_J22 GENOA_SP5-SOCKET6096_13568-001,SMLF,IO,DGA^6000030    I20 @T6G_MB_LIB.T6G(SCH_1):PAGE31
   U25  J25 VSS_J25 GENOA_SP5-SOCKET6096_13568-001,SMLF,IO,DGA^6000030    I20 @T6G_MB_LIB.T6G(SCH_1):PAGE31
   U25  J28 VSS_J28 GENOA_SP5-SOCKET6096_13568-001,SMLF,IO,DGA^6000030    I20 @T6G_MB_LIB.T6G(SCH_1):PAGE31
   U25  J31 VSS_J31 GENOA_SP5-SOCKET6096_13568-001,SMLF,IO,DGA^6000030    I20 @T6G_MB_LIB.T6G(SCH_1):PAGE31
   U25  J34 VSS_J34 GENOA_SP5-SOCKET6096_13568-001,SMLF,IO,DGA^6000030    I20 @T6G_MB_LIB.T6G(SCH_1):PAGE31
   U25  J42 VSS_J42 GENOA_SP5-SOCKET6096_13568-001,SMLF,IO,DGA^6000030    I20 @T6G_MB_LIB.T6G(SCH_1):PAGE31
   U25  J45 VSS_J45 GENOA_SP5-SOCKET6096_13568-001,SMLF,IO,DGA^6000030    I20 @T6G_MB_LIB.T6G(SCH_1):PAGE31
   U25  J48 VSS_J48 GENOA_SP5-SOCKET6096_13568-001,SMLF,IO,DGA^6000030    I20 @T6G_MB_LIB.T6G(SCH_1):PAGE31
   U25  J51 VSS_J51 GENOA_SP5-SOCKET6096_13568-001,SMLF,IO,DGA^6000030    I20 @T6G_MB_LIB.T6G(SCH_1):PAGE31
   U25  J54 VSS_J54 GENOA_SP5-SOCKET6096_13568-001,SMLF,IO,DGA^6000030    I20 @T6G_MB_LIB.T6G(SCH_1):PAGE31
   U25  J56 VSS_J56 GENOA_SP5-SOCKET6096_13568-001,SMLF,IO,DGA^6000030    I20 @T6G_MB_LIB.T6G(SCH_1):PAGE31
   U25  J58 VSS_J58 GENOA_SP5-SOCKET6096_13568-001,SMLF,IO,DGA^6000030    I20 @T6G_MB_LIB.T6G(SCH_1):PAGE31
   U25  J61 VSS_J61 GENOA_SP5-SOCKET6096_13568-001,SMLF,IO,DGA^6000030    I20 @T6G_MB_LIB.T6G(SCH_1):PAGE31
   U25  J63 VSS_J63 GENOA_SP5-SOCKET6096_13568-001,SMLF,IO,DGA^6000030    I20 @T6G_MB_LIB.T6G(SCH_1):PAGE31
   U25  J65 VSS_J65 GENOA_SP5-SOCKET6096_13568-001,SMLF,IO,DGA^6000030    I20 @T6G_MB_LIB.T6G(SCH_1):PAGE31
   U25  J68 VSS_J68 GENOA_SP5-SOCKET6096_13568-001,SMLF,IO,DGA^6000030    I20 @T6G_MB_LIB.T6G(SCH_1):PAGE31
   U25  J70 VSS_J70 GENOA_SP5-SOCKET6096_13568-001,SMLF,IO,DGA^6000030    I20 @T6G_MB_LIB.T6G(SCH_1):PAGE31
   U25  J72 VSS_J72 GENOA_SP5-SOCKET6096_13568-001,SMLF,IO,DGA^6000030    I20 @T6G_MB_LIB.T6G(SCH_1):PAGE31
   U25  J75 VSS_J75 GENOA_SP5-SOCKET6096_13568-001,SMLF,IO,DGA^6000030    I20 @T6G_MB_LIB.T6G(SCH_1):PAGE31
   U25   K3 VSS_K3 GENOA_SP5-SOCKET6096_13568-001,SMLF,IO,DGA^6000030    I20 @T6G_MB_LIB.T6G(SCH_1):PAGE31
   U25   K5 VSS_K5 GENOA_SP5-SOCKET6096_13568-001,SMLF,IO,DGA^6000030    I20 @T6G_MB_LIB.T6G(SCH_1):PAGE31
   U25   K8 VSS_K8 GENOA_SP5-SOCKET6096_13568-001,SMLF,IO,DGA^6000030    I20 @T6G_MB_LIB.T6G(SCH_1):PAGE31
   U25  K10 VSS_K10 GENOA_SP5-SOCKET6096_13568-001,SMLF,IO,DGA^6000030    I20 @T6G_MB_LIB.T6G(SCH_1):PAGE31
   U25  K12 VSS_K12 GENOA_SP5-SOCKET6096_13568-001,SMLF,IO,DGA^6000030    I20 @T6G_MB_LIB.T6G(SCH_1):PAGE31
   U25  K15 VSS_K15 GENOA_SP5-SOCKET6096_13568-001,SMLF,IO,DGA^6000030    I20 @T6G_MB_LIB.T6G(SCH_1):PAGE31
   U25  K17 VSS_K17 GENOA_SP5-SOCKET6096_13568-001,SMLF,IO,DGA^6000030    I20 @T6G_MB_LIB.T6G(SCH_1):PAGE31
   U25  K19 VSS_K19 GENOA_SP5-SOCKET6096_13568-001,SMLF,IO,DGA^6000030    I20 @T6G_MB_LIB.T6G(SCH_1):PAGE31
   U25  K24 VSS_K24 GENOA_SP5-SOCKET6096_13568-001,SMLF,IO,DGA^6000030    I20 @T6G_MB_LIB.T6G(SCH_1):PAGE31
   U25  K25 VSS_K25 GENOA_SP5-SOCKET6096_13568-001,SMLF,IO,DGA^6000030    I20 @T6G_MB_LIB.T6G(SCH_1):PAGE31
   U25  K26 VSS_K26 GENOA_SP5-SOCKET6096_13568-001,SMLF,IO,DGA^6000030    I20 @T6G_MB_LIB.T6G(SCH_1):PAGE31
   U25  K27 VSS_K27 GENOA_SP5-SOCKET6096_13568-001,SMLF,IO,DGA^6000030    I20 @T6G_MB_LIB.T6G(SCH_1):PAGE31
   U25  K28 VSS_K28 GENOA_SP5-SOCKET6096_13568-001,SMLF,IO,DGA^6000030    I20 @T6G_MB_LIB.T6G(SCH_1):PAGE31
   U25  K29 VSS_K29 GENOA_SP5-SOCKET6096_13568-001,SMLF,IO,DGA^6000030    I20 @T6G_MB_LIB.T6G(SCH_1):PAGE31
   U25  K30 VSS_K30 GENOA_SP5-SOCKET6096_13568-001,SMLF,IO,DGA^6000030    I20 @T6G_MB_LIB.T6G(SCH_1):PAGE31
   U25  K31 VSS_K31 GENOA_SP5-SOCKET6096_13568-001,SMLF,IO,DGA^6000030    I20 @T6G_MB_LIB.T6G(SCH_1):PAGE31
   U25  K32 VSS_K32 GENOA_SP5-SOCKET6096_13568-001,SMLF,IO,DGA^6000030    I20 @T6G_MB_LIB.T6G(SCH_1):PAGE31
   U25  K33 VSS_K33 GENOA_SP5-SOCKET6096_13568-001,SMLF,IO,DGA^6000030    I20 @T6G_MB_LIB.T6G(SCH_1):PAGE31
   U25  K34 VSS_K34 GENOA_SP5-SOCKET6096_13568-001,SMLF,IO,DGA^6000030    I20 @T6G_MB_LIB.T6G(SCH_1):PAGE31
   U25  K37 VSS_K37 GENOA_SP5-SOCKET6096_13568-001,SMLF,IO,DGA^6000030    I20 @T6G_MB_LIB.T6G(SCH_1):PAGE31
   U25  K39 VSS_K39 GENOA_SP5-SOCKET6096_13568-001,SMLF,IO,DGA^6000030    I20 @T6G_MB_LIB.T6G(SCH_1):PAGE31
   U25  K42 VSS_K42 GENOA_SP5-SOCKET6096_13568-001,SMLF,IO,DGA^6000030    I20 @T6G_MB_LIB.T6G(SCH_1):PAGE31
   U25  K43 VSS_K43 GENOA_SP5-SOCKET6096_13568-001,SMLF,IO,DGA^6000030    I20 @T6G_MB_LIB.T6G(SCH_1):PAGE31
   U25  K44 VSS_K44 GENOA_SP5-SOCKET6096_13568-001,SMLF,IO,DGA^6000030    I20 @T6G_MB_LIB.T6G(SCH_1):PAGE31
   U25  K45 VSS_K45 GENOA_SP5-SOCKET6096_13568-001,SMLF,IO,DGA^6000030    I20 @T6G_MB_LIB.T6G(SCH_1):PAGE31
   U25  K46 VSS_K46 GENOA_SP5-SOCKET6096_13568-001,SMLF,IO,DGA^6000030    I20 @T6G_MB_LIB.T6G(SCH_1):PAGE31
   U25  K47 VSS_K47 GENOA_SP5-SOCKET6096_13568-001,SMLF,IO,DGA^6000030    I20 @T6G_MB_LIB.T6G(SCH_1):PAGE31
   U25  K48 VSS_K48 GENOA_SP5-SOCKET6096_13568-001,SMLF,IO,DGA^6000030    I20 @T6G_MB_LIB.T6G(SCH_1):PAGE31
   U25  K49 VSS_K49 GENOA_SP5-SOCKET6096_13568-001,SMLF,IO,DGA^6000030    I20 @T6G_MB_LIB.T6G(SCH_1):PAGE31
   U25  K50 VSS_K50 GENOA_SP5-SOCKET6096_13568-001,SMLF,IO,DGA^6000030    I20 @T6G_MB_LIB.T6G(SCH_1):PAGE31
   U25  K51 VSS_K51 GENOA_SP5-SOCKET6096_13568-001,SMLF,IO,DGA^6000030    I20 @T6G_MB_LIB.T6G(SCH_1):PAGE31
   U25  K52 VSS_K52 GENOA_SP5-SOCKET6096_13568-001,SMLF,IO,DGA^6000030    I20 @T6G_MB_LIB.T6G(SCH_1):PAGE31
   U25  K53 VSS_K53 GENOA_SP5-SOCKET6096_13568-001,SMLF,IO,DGA^6000030    I20 @T6G_MB_LIB.T6G(SCH_1):PAGE31
   U25  K57 VSS_K57 GENOA_SP5-SOCKET6096_13568-001,SMLF,IO,DGA^6000030    I20 @T6G_MB_LIB.T6G(SCH_1):PAGE31
   U25  K61 VSS_K61 GENOA_SP5-SOCKET6096_13568-001,SMLF,IO,DGA^6000030    I20 @T6G_MB_LIB.T6G(SCH_1):PAGE31
   U25  K64 VSS_K64 GENOA_SP5-SOCKET6096_13568-001,SMLF,IO,DGA^6000030    I20 @T6G_MB_LIB.T6G(SCH_1):PAGE31
   U25  K66 VSS_K66 GENOA_SP5-SOCKET6096_13568-001,SMLF,IO,DGA^6000030    I20 @T6G_MB_LIB.T6G(SCH_1):PAGE31
   U25  K68 VSS_K68 GENOA_SP5-SOCKET6096_13568-001,SMLF,IO,DGA^6000030    I20 @T6G_MB_LIB.T6G(SCH_1):PAGE31
   U25  K71 VSS_K71 GENOA_SP5-SOCKET6096_13568-001,SMLF,IO,DGA^6000030    I20 @T6G_MB_LIB.T6G(SCH_1):PAGE31
   U25  K73 VSS_K73 GENOA_SP5-SOCKET6096_13568-001,SMLF,IO,DGA^6000030    I20 @T6G_MB_LIB.T6G(SCH_1):PAGE31
   U25   L1 VSS_L1 GENOA_SP5-SOCKET6096_13568-001,SMLF,IO,DGA^6000030    I20 @T6G_MB_LIB.T6G(SCH_1):PAGE31
   U25   L6 VSS_L6 GENOA_SP5-SOCKET6096_13568-001,SMLF,IO,DGA^6000030    I20 @T6G_MB_LIB.T6G(SCH_1):PAGE31
   U25   L8 VSS_L8 GENOA_SP5-SOCKET6096_13568-001,SMLF,IO,DGA^6000030    I20 @T6G_MB_LIB.T6G(SCH_1):PAGE31
   U25  L13 VSS_L13 GENOA_SP5-SOCKET6096_13568-001,SMLF,IO,DGA^6000030    I20 @T6G_MB_LIB.T6G(SCH_1):PAGE31
   U25  L15 VSS_L15 GENOA_SP5-SOCKET6096_13568-001,SMLF,IO,DGA^6000030    I20 @T6G_MB_LIB.T6G(SCH_1):PAGE31
   U25  L20 VSS_L20 GENOA_SP5-SOCKET6096_13568-001,SMLF,IO,DGA^6000030    I20 @T6G_MB_LIB.T6G(SCH_1):PAGE31
   U25  L22 VSS_L22 GENOA_SP5-SOCKET6096_13568-001,SMLF,IO,DGA^6000030    I20 @T6G_MB_LIB.T6G(SCH_1):PAGE31
   U25  L25 VSS_L25 GENOA_SP5-SOCKET6096_13568-001,SMLF,IO,DGA^6000030    I20 @T6G_MB_LIB.T6G(SCH_1):PAGE31
   U25  L28 VSS_L28 GENOA_SP5-SOCKET6096_13568-001,SMLF,IO,DGA^6000030    I20 @T6G_MB_LIB.T6G(SCH_1):PAGE31
   U25  L31 VSS_L31 GENOA_SP5-SOCKET6096_13568-001,SMLF,IO,DGA^6000030    I20 @T6G_MB_LIB.T6G(SCH_1):PAGE31
   U25  L34 VSS_L34 GENOA_SP5-SOCKET6096_13568-001,SMLF,IO,DGA^6000030    I20 @T6G_MB_LIB.T6G(SCH_1):PAGE31
   U25  L35 VSS_L35 GENOA_SP5-SOCKET6096_13568-001,SMLF,IO,DGA^6000030    I20 @T6G_MB_LIB.T6G(SCH_1):PAGE31
   U25  L36 VSS_L36 GENOA_SP5-SOCKET6096_13568-001,SMLF,IO,DGA^6000030    I20 @T6G_MB_LIB.T6G(SCH_1):PAGE31
   U25  L40 VSS_L40 GENOA_SP5-SOCKET6096_13568-001,SMLF,IO,DGA^6000030    I20 @T6G_MB_LIB.T6G(SCH_1):PAGE31
   U25  L41 VSS_L41 GENOA_SP5-SOCKET6096_13568-001,SMLF,IO,DGA^6000030    I20 @T6G_MB_LIB.T6G(SCH_1):PAGE31
   U25  L42 VSS_L42 GENOA_SP5-SOCKET6096_13568-001,SMLF,IO,DGA^6000030    I20 @T6G_MB_LIB.T6G(SCH_1):PAGE31
   U25  L45 VSS_L45 GENOA_SP5-SOCKET6096_13568-001,SMLF,IO,DGA^6000030    I20 @T6G_MB_LIB.T6G(SCH_1):PAGE31
   U25  L48 VSS_L48 GENOA_SP5-SOCKET6096_13568-001,SMLF,IO,DGA^6000030    I20 @T6G_MB_LIB.T6G(SCH_1):PAGE31
   U25  L51 VSS_L51 GENOA_SP5-SOCKET6096_13568-001,SMLF,IO,DGA^6000030    I20 @T6G_MB_LIB.T6G(SCH_1):PAGE31
   U25  L54 VSS_L54 GENOA_SP5-SOCKET6096_13568-001,SMLF,IO,DGA^6000030    I20 @T6G_MB_LIB.T6G(SCH_1):PAGE31
   U25  L56 VSS_L56 GENOA_SP5-SOCKET6096_13568-001,SMLF,IO,DGA^6000030    I20 @T6G_MB_LIB.T6G(SCH_1):PAGE31
   U25  L61 VSS_L61 GENOA_SP5-SOCKET6096_13568-001,SMLF,IO,DGA^6000030    I20 @T6G_MB_LIB.T6G(SCH_1):PAGE31
   U25  L63 VSS_L63 GENOA_SP5-SOCKET6096_13568-001,SMLF,IO,DGA^6000030    I20 @T6G_MB_LIB.T6G(SCH_1):PAGE31
   U25  L68 VSS_L68 GENOA_SP5-SOCKET6096_13568-001,SMLF,IO,DGA^6000030    I20 @T6G_MB_LIB.T6G(SCH_1):PAGE31
   U25  L70 VSS_L70 GENOA_SP5-SOCKET6096_13568-001,SMLF,IO,DGA^6000030    I20 @T6G_MB_LIB.T6G(SCH_1):PAGE31
   U25  L75 VSS_L75 GENOA_SP5-SOCKET6096_13568-001,SMLF,IO,DGA^6000030    I20 @T6G_MB_LIB.T6G(SCH_1):PAGE31
   U25   M3 VSS_M3 GENOA_SP5-SOCKET6096_13568-001,SMLF,IO,DGA^6000030    I20 @T6G_MB_LIB.T6G(SCH_1):PAGE31
   U25   M5 VSS_M5 GENOA_SP5-SOCKET6096_13568-001,SMLF,IO,DGA^6000030    I20 @T6G_MB_LIB.T6G(SCH_1):PAGE31
   U25   M8 VSS_M8 GENOA_SP5-SOCKET6096_13568-001,SMLF,IO,DGA^6000030    I20 @T6G_MB_LIB.T6G(SCH_1):PAGE31
   U25  M10 VSS_M10 GENOA_SP5-SOCKET6096_13568-001,SMLF,IO,DGA^6000030    I20 @T6G_MB_LIB.T6G(SCH_1):PAGE31
   U25  M12 VSS_M12 GENOA_SP5-SOCKET6096_13568-001,SMLF,IO,DGA^6000030    I20 @T6G_MB_LIB.T6G(SCH_1):PAGE31
   U25  M15 VSS_M15 GENOA_SP5-SOCKET6096_13568-001,SMLF,IO,DGA^6000030    I20 @T6G_MB_LIB.T6G(SCH_1):PAGE31
   U25  M17 VSS_M17 GENOA_SP5-SOCKET6096_13568-001,SMLF,IO,DGA^6000030    I20 @T6G_MB_LIB.T6G(SCH_1):PAGE31
   U25  M19 VSS_M19 GENOA_SP5-SOCKET6096_13568-001,SMLF,IO,DGA^6000030    I20 @T6G_MB_LIB.T6G(SCH_1):PAGE31
   U25  M22 VSS_M22 GENOA_SP5-SOCKET6096_13568-001,SMLF,IO,DGA^6000030    I20 @T6G_MB_LIB.T6G(SCH_1):PAGE31
   U25  M25 VSS_M25 GENOA_SP5-SOCKET6096_13568-001,SMLF,IO,DGA^6000030    I20 @T6G_MB_LIB.T6G(SCH_1):PAGE31
   U25  M28 VSS_M28 GENOA_SP5-SOCKET6096_13568-001,SMLF,IO,DGA^6000030    I20 @T6G_MB_LIB.T6G(SCH_1):PAGE31
   U25  M31 VSS_M31 GENOA_SP5-SOCKET6096_13568-001,SMLF,IO,DGA^6000030    I20 @T6G_MB_LIB.T6G(SCH_1):PAGE31
   U25  M34 VSS_M34 GENOA_SP5-SOCKET6096_13568-001,SMLF,IO,DGA^6000030    I20 @T6G_MB_LIB.T6G(SCH_1):PAGE31
   U25  M37 VSS_M37 GENOA_SP5-SOCKET6096_13568-001,SMLF,IO,DGA^6000030    I20 @T6G_MB_LIB.T6G(SCH_1):PAGE31
   U25  M39 VSS_M39 GENOA_SP5-SOCKET6096_13568-001,SMLF,IO,DGA^6000030    I20 @T6G_MB_LIB.T6G(SCH_1):PAGE31
   U25  M42 VSS_M42 GENOA_SP5-SOCKET6096_13568-001,SMLF,IO,DGA^6000030    I20 @T6G_MB_LIB.T6G(SCH_1):PAGE31
   U25  M45 VSS_M45 GENOA_SP5-SOCKET6096_13568-001,SMLF,IO,DGA^6000030    I20 @T6G_MB_LIB.T6G(SCH_1):PAGE31
   U25  M48 VSS_M48 GENOA_SP5-SOCKET6096_13568-001,SMLF,IO,DGA^6000030    I20 @T6G_MB_LIB.T6G(SCH_1):PAGE31
   U25  M51 VSS_M51 GENOA_SP5-SOCKET6096_13568-001,SMLF,IO,DGA^6000030    I20 @T6G_MB_LIB.T6G(SCH_1):PAGE31
   U25  M54 VSS_M54 GENOA_SP5-SOCKET6096_13568-001,SMLF,IO,DGA^6000030    I20 @T6G_MB_LIB.T6G(SCH_1):PAGE31
   U25  M57 VSS_M57 GENOA_SP5-SOCKET6096_13568-001,SMLF,IO,DGA^6000030    I20 @T6G_MB_LIB.T6G(SCH_1):PAGE31
   U25  M59 VSS_M59 GENOA_SP5-SOCKET6096_13568-001,SMLF,IO,DGA^6000030    I20 @T6G_MB_LIB.T6G(SCH_1):PAGE31
   U25  M61 VSS_M61 GENOA_SP5-SOCKET6096_13568-001,SMLF,IO,DGA^6000030    I20 @T6G_MB_LIB.T6G(SCH_1):PAGE31
   U25  M64 VSS_M64 GENOA_SP5-SOCKET6096_13568-001,SMLF,IO,DGA^6000030    I20 @T6G_MB_LIB.T6G(SCH_1):PAGE31
   U25  M66 VSS_M66 GENOA_SP5-SOCKET6096_13568-001,SMLF,IO,DGA^6000030    I20 @T6G_MB_LIB.T6G(SCH_1):PAGE31
   U25  M68 VSS_M68 GENOA_SP5-SOCKET6096_13568-001,SMLF,IO,DGA^6000030    I20 @T6G_MB_LIB.T6G(SCH_1):PAGE31
   U25  M71 VSS_M71 GENOA_SP5-SOCKET6096_13568-001,SMLF,IO,DGA^6000030    I20 @T6G_MB_LIB.T6G(SCH_1):PAGE31
   U25  M73 VSS_M73 GENOA_SP5-SOCKET6096_13568-001,SMLF,IO,DGA^6000030    I20 @T6G_MB_LIB.T6G(SCH_1):PAGE31
   U25   N1 VSS_N1 GENOA_SP5-SOCKET6096_13568-001,SMLF,IO,DGA^6000030    I20 @T6G_MB_LIB.T6G(SCH_1):PAGE31
   U25   N4 VSS_N4 GENOA_SP5-SOCKET6096_13568-001,SMLF,IO,DGA^6000030    I20 @T6G_MB_LIB.T6G(SCH_1):PAGE31
   U25   N6 VSS_N6 GENOA_SP5-SOCKET6096_13568-001,SMLF,IO,DGA^6000030    I20 @T6G_MB_LIB.T6G(SCH_1):PAGE31
   U25   N8 VSS_N8 GENOA_SP5-SOCKET6096_13568-001,SMLF,IO,DGA^6000030    I20 @T6G_MB_LIB.T6G(SCH_1):PAGE31
   U25  N11 VSS_N11 GENOA_SP5-SOCKET6096_13568-001,SMLF,IO,DGA^6000030    I20 @T6G_MB_LIB.T6G(SCH_1):PAGE31
   U25  N13 VSS_N13 GENOA_SP5-SOCKET6096_13568-001,SMLF,IO,DGA^6000030    I20 @T6G_MB_LIB.T6G(SCH_1):PAGE31
   U25  N15 VSS_N15 GENOA_SP5-SOCKET6096_13568-001,SMLF,IO,DGA^6000030    I20 @T6G_MB_LIB.T6G(SCH_1):PAGE31
   U25  N18 VSS_N18 GENOA_SP5-SOCKET6096_13568-001,SMLF,IO,DGA^6000030    I20 @T6G_MB_LIB.T6G(SCH_1):PAGE31
   U25  N20 VSS_N20 GENOA_SP5-SOCKET6096_13568-001,SMLF,IO,DGA^6000030    I20 @T6G_MB_LIB.T6G(SCH_1):PAGE31
   U25  N22 VSS_N22 GENOA_SP5-SOCKET6096_13568-001,SMLF,IO,DGA^6000030    I20 @T6G_MB_LIB.T6G(SCH_1):PAGE31
   U25  N25 VSS_N25 GENOA_SP5-SOCKET6096_13568-001,SMLF,IO,DGA^6000030    I20 @T6G_MB_LIB.T6G(SCH_1):PAGE31
   U25  N28 VSS_N28 GENOA_SP5-SOCKET6096_13568-001,SMLF,IO,DGA^6000030    I20 @T6G_MB_LIB.T6G(SCH_1):PAGE31
   U25  N31 VSS_N31 GENOA_SP5-SOCKET6096_13568-001,SMLF,IO,DGA^6000030    I20 @T6G_MB_LIB.T6G(SCH_1):PAGE31
   U25  N34 VSS_N34 GENOA_SP5-SOCKET6096_13568-001,SMLF,IO,DGA^6000030    I20 @T6G_MB_LIB.T6G(SCH_1):PAGE31
   U25  N42 VSS_N42 GENOA_SP5-SOCKET6096_13568-001,SMLF,IO,DGA^6000030    I20 @T6G_MB_LIB.T6G(SCH_1):PAGE31
   U25  N45 VSS_N45 GENOA_SP5-SOCKET6096_13568-001,SMLF,IO,DGA^6000030    I20 @T6G_MB_LIB.T6G(SCH_1):PAGE31
   U25  N48 VSS_N48 GENOA_SP5-SOCKET6096_13568-001,SMLF,IO,DGA^6000030    I20 @T6G_MB_LIB.T6G(SCH_1):PAGE31
   U25  N51 VSS_N51 GENOA_SP5-SOCKET6096_13568-001,SMLF,IO,DGA^6000030    I20 @T6G_MB_LIB.T6G(SCH_1):PAGE31
   U25  N54 VSS_N54 GENOA_SP5-SOCKET6096_13568-001,SMLF,IO,DGA^6000030    I20 @T6G_MB_LIB.T6G(SCH_1):PAGE31
   U25  N56 VSS_N56 GENOA_SP5-SOCKET6096_13568-001,SMLF,IO,DGA^6000030    I20 @T6G_MB_LIB.T6G(SCH_1):PAGE31
   U25  N58 VSS_N58 GENOA_SP5-SOCKET6096_13568-001,SMLF,IO,DGA^6000030    I20 @T6G_MB_LIB.T6G(SCH_1):PAGE31
   U25  N61 VSS_N61 GENOA_SP5-SOCKET6096_13568-001,SMLF,IO,DGA^6000030    I20 @T6G_MB_LIB.T6G(SCH_1):PAGE31
   U25  N63 VSS_N63 GENOA_SP5-SOCKET6096_13568-001,SMLF,IO,DGA^6000030    I20 @T6G_MB_LIB.T6G(SCH_1):PAGE31
   U25  N65 VSS_N65 GENOA_SP5-SOCKET6096_13568-001,SMLF,IO,DGA^6000030    I20 @T6G_MB_LIB.T6G(SCH_1):PAGE31
   U25  N68 VSS_N68 GENOA_SP5-SOCKET6096_13568-001,SMLF,IO,DGA^6000030    I20 @T6G_MB_LIB.T6G(SCH_1):PAGE31
   U25  N70 VSS_N70 GENOA_SP5-SOCKET6096_13568-001,SMLF,IO,DGA^6000030    I20 @T6G_MB_LIB.T6G(SCH_1):PAGE31
   U25  N72 VSS_N72 GENOA_SP5-SOCKET6096_13568-001,SMLF,IO,DGA^6000030    I20 @T6G_MB_LIB.T6G(SCH_1):PAGE31
   U25  N75 VSS_N75 GENOA_SP5-SOCKET6096_13568-001,SMLF,IO,DGA^6000030    I20 @T6G_MB_LIB.T6G(SCH_1):PAGE31
   U25   P3 VSS_P3 GENOA_SP5-SOCKET6096_13568-001,SMLF,IO,DGA^6000030    I20 @T6G_MB_LIB.T6G(SCH_1):PAGE31
   U25   P8 VSS_P8 GENOA_SP5-SOCKET6096_13568-001,SMLF,IO,DGA^6000030    I20 @T6G_MB_LIB.T6G(SCH_1):PAGE31
   U25  P10 VSS_P10 GENOA_SP5-SOCKET6096_13568-001,SMLF,IO,DGA^6000030    I20 @T6G_MB_LIB.T6G(SCH_1):PAGE31
   U25  P15 VSS_P15 GENOA_SP5-SOCKET6096_13568-001,SMLF,IO,DGA^6000030    I20 @T6G_MB_LIB.T6G(SCH_1):PAGE31
   U25  P17 VSS_P17 GENOA_SP5-SOCKET6096_13568-001,SMLF,IO,DGA^6000030    I20 @T6G_MB_LIB.T6G(SCH_1):PAGE31
   U25  P23 VSS_P23 GENOA_SP5-SOCKET6096_13568-001,SMLF,IO,DGA^6000030    I20 @T6G_MB_LIB.T6G(SCH_1):PAGE31
   U25  P24 VSS_P24 GENOA_SP5-SOCKET6096_13568-001,SMLF,IO,DGA^6000030    I20 @T6G_MB_LIB.T6G(SCH_1):PAGE31
   U25  P26 VSS_P26 GENOA_SP5-SOCKET6096_13568-001,SMLF,IO,DGA^6000030    I20 @T6G_MB_LIB.T6G(SCH_1):PAGE31
   U25  P27 VSS_P27 GENOA_SP5-SOCKET6096_13568-001,SMLF,IO,DGA^6000030    I20 @T6G_MB_LIB.T6G(SCH_1):PAGE31
   U25  P28 VSS_P28 GENOA_SP5-SOCKET6096_13568-001,SMLF,IO,DGA^6000030    I20 @T6G_MB_LIB.T6G(SCH_1):PAGE31
   U25  P29 VSS_P29 GENOA_SP5-SOCKET6096_13568-001,SMLF,IO,DGA^6000030    I20 @T6G_MB_LIB.T6G(SCH_1):PAGE31
   U25  P30 VSS_P30 GENOA_SP5-SOCKET6096_13568-001,SMLF,IO,DGA^6000030    I20 @T6G_MB_LIB.T6G(SCH_1):PAGE31
   U25  P31 VSS_P31 GENOA_SP5-SOCKET6096_13568-001,SMLF,IO,DGA^6000030    I20 @T6G_MB_LIB.T6G(SCH_1):PAGE31
   U25  P32 VSS_P32 GENOA_SP5-SOCKET6096_13568-001,SMLF,IO,DGA^6000030    I20 @T6G_MB_LIB.T6G(SCH_1):PAGE31
   U25  P33 VSS_P33 GENOA_SP5-SOCKET6096_13568-001,SMLF,IO,DGA^6000030    I20 @T6G_MB_LIB.T6G(SCH_1):PAGE31
   U25  P34 VSS_P34 GENOA_SP5-SOCKET6096_13568-001,SMLF,IO,DGA^6000030    I20 @T6G_MB_LIB.T6G(SCH_1):PAGE31
   U25  P37 VSS_P37 GENOA_SP5-SOCKET6096_13568-001,SMLF,IO,DGA^6000030    I20 @T6G_MB_LIB.T6G(SCH_1):PAGE31
   U25  P39 VSS_P39 GENOA_SP5-SOCKET6096_13568-001,SMLF,IO,DGA^6000030    I20 @T6G_MB_LIB.T6G(SCH_1):PAGE31
   U25  P42 VSS_P42 GENOA_SP5-SOCKET6096_13568-001,SMLF,IO,DGA^6000030    I20 @T6G_MB_LIB.T6G(SCH_1):PAGE31
   U25  P43 VSS_P43 GENOA_SP5-SOCKET6096_13568-001,SMLF,IO,DGA^6000030    I20 @T6G_MB_LIB.T6G(SCH_1):PAGE31
   U25  P44 VSS_P44 GENOA_SP5-SOCKET6096_13568-001,SMLF,IO,DGA^6000030    I20 @T6G_MB_LIB.T6G(SCH_1):PAGE31
   U25  P45 VSS_P45 GENOA_SP5-SOCKET6096_13568-001,SMLF,IO,DGA^6000030    I20 @T6G_MB_LIB.T6G(SCH_1):PAGE31
   U25  P46 VSS_P46 GENOA_SP5-SOCKET6096_13568-001,SMLF,IO,DGA^6000030    I20 @T6G_MB_LIB.T6G(SCH_1):PAGE31
   U25  P47 VSS_P47 GENOA_SP5-SOCKET6096_13568-001,SMLF,IO,DGA^6000030    I20 @T6G_MB_LIB.T6G(SCH_1):PAGE31
   U25  P48 VSS_P48 GENOA_SP5-SOCKET6096_13568-001,SMLF,IO,DGA^6000030    I20 @T6G_MB_LIB.T6G(SCH_1):PAGE31
   U25  P49 VSS_P49 GENOA_SP5-SOCKET6096_13568-001,SMLF,IO,DGA^6000030    I20 @T6G_MB_LIB.T6G(SCH_1):PAGE31
   U25  P50 VSS_P50 GENOA_SP5-SOCKET6096_13568-001,SMLF,IO,DGA^6000030    I20 @T6G_MB_LIB.T6G(SCH_1):PAGE31
   U25  P51 VSS_P51 GENOA_SP5-SOCKET6096_13568-001,SMLF,IO,DGA^6000030    I20 @T6G_MB_LIB.T6G(SCH_1):PAGE31
   U25  P52 VSS_P52 GENOA_SP5-SOCKET6096_13568-001,SMLF,IO,DGA^6000030    I20 @T6G_MB_LIB.T6G(SCH_1):PAGE31
   U25  P53 VSS_P53 GENOA_SP5-SOCKET6096_13568-001,SMLF,IO,DGA^6000030    I20 @T6G_MB_LIB.T6G(SCH_1):PAGE31
   U25  P59 VSS_P59 GENOA_SP5-SOCKET6096_13568-001,SMLF,IO,DGA^6000030    I20 @T6G_MB_LIB.T6G(SCH_1):PAGE31
   U25  P61 VSS_P61 GENOA_SP5-SOCKET6096_13568-001,SMLF,IO,DGA^6000030    I20 @T6G_MB_LIB.T6G(SCH_1):PAGE31
   U25  P66 VSS_P66 GENOA_SP5-SOCKET6096_13568-001,SMLF,IO,DGA^6000030    I20 @T6G_MB_LIB.T6G(SCH_1):PAGE31
   U25  P73 VSS_P73 GENOA_SP5-SOCKET6096_13568-001,SMLF,IO,DGA^6000030    I20 @T6G_MB_LIB.T6G(SCH_1):PAGE31
   U25   R1 VSS_R1 GENOA_SP5-SOCKET6096_13568-001,SMLF,IO,DGA^6000030    I20 @T6G_MB_LIB.T6G(SCH_1):PAGE31
   U25   R4 VSS_R4 GENOA_SP5-SOCKET6096_13568-001,SMLF,IO,DGA^6000030    I20 @T6G_MB_LIB.T6G(SCH_1):PAGE31
   U25   R6 VSS_R6 GENOA_SP5-SOCKET6096_13568-001,SMLF,IO,DGA^6000030    I20 @T6G_MB_LIB.T6G(SCH_1):PAGE31
   U25   R8 VSS_R8 GENOA_SP5-SOCKET6096_13568-001,SMLF,IO,DGA^6000030    I20 @T6G_MB_LIB.T6G(SCH_1):PAGE31
   U25  R11 VSS_R11 GENOA_SP5-SOCKET6096_13568-001,SMLF,IO,DGA^6000030    I20 @T6G_MB_LIB.T6G(SCH_1):PAGE31
   U25  R13 VSS_R13 GENOA_SP5-SOCKET6096_13568-001,SMLF,IO,DGA^6000030    I20 @T6G_MB_LIB.T6G(SCH_1):PAGE31
   U25  R15 VSS_R15 GENOA_SP5-SOCKET6096_13568-001,SMLF,IO,DGA^6000030    I20 @T6G_MB_LIB.T6G(SCH_1):PAGE31
   U25  R18 VSS_R18 GENOA_SP5-SOCKET6096_13568-001,SMLF,IO,DGA^6000030    I20 @T6G_MB_LIB.T6G(SCH_1):PAGE31
   U25  R20 VSS_R20 GENOA_SP5-SOCKET6096_13568-001,SMLF,IO,DGA^6000030    I20 @T6G_MB_LIB.T6G(SCH_1):PAGE31
   U25  R22 VSS_R22 GENOA_SP5-SOCKET6096_13568-001,SMLF,IO,DGA^6000030    I20 @T6G_MB_LIB.T6G(SCH_1):PAGE31
   U25  R25 VSS_R25 GENOA_SP5-SOCKET6096_13568-001,SMLF,IO,DGA^6000030    I20 @T6G_MB_LIB.T6G(SCH_1):PAGE31
   U25  R28 VSS_R28 GENOA_SP5-SOCKET6096_13568-001,SMLF,IO,DGA^6000030    I20 @T6G_MB_LIB.T6G(SCH_1):PAGE31
   U25  R31 VSS_R31 GENOA_SP5-SOCKET6096_13568-001,SMLF,IO,DGA^6000030    I20 @T6G_MB_LIB.T6G(SCH_1):PAGE31
   U25  R34 VSS_R34 GENOA_SP5-SOCKET6096_13568-001,SMLF,IO,DGA^6000030    I20 @T6G_MB_LIB.T6G(SCH_1):PAGE31
   U25  R35 VSS_R35 GENOA_SP5-SOCKET6096_13568-001,SMLF,IO,DGA^6000030    I20 @T6G_MB_LIB.T6G(SCH_1):PAGE31
   U25  R36 VSS_R36 GENOA_SP5-SOCKET6096_13568-001,SMLF,IO,DGA^6000030    I20 @T6G_MB_LIB.T6G(SCH_1):PAGE31
   U25  R40 VSS_R40 GENOA_SP5-SOCKET6096_13568-001,SMLF,IO,DGA^6000030    I20 @T6G_MB_LIB.T6G(SCH_1):PAGE31
   U25  R41 VSS_R41 GENOA_SP5-SOCKET6096_13568-001,SMLF,IO,DGA^6000030    I20 @T6G_MB_LIB.T6G(SCH_1):PAGE31
   U25  R42 VSS_R42 GENOA_SP5-SOCKET6096_13568-001,SMLF,IO,DGA^6000030    I20 @T6G_MB_LIB.T6G(SCH_1):PAGE31
   U25  R45 VSS_R45 GENOA_SP5-SOCKET6096_13568-001,SMLF,IO,DGA^6000030    I20 @T6G_MB_LIB.T6G(SCH_1):PAGE31
   U25  R48 VSS_R48 GENOA_SP5-SOCKET6096_13568-001,SMLF,IO,DGA^6000030    I20 @T6G_MB_LIB.T6G(SCH_1):PAGE31
   U25  R51 VSS_R51 GENOA_SP5-SOCKET6096_13568-001,SMLF,IO,DGA^6000030    I20 @T6G_MB_LIB.T6G(SCH_1):PAGE31
   U25  R54 VSS_R54 GENOA_SP5-SOCKET6096_13568-001,SMLF,IO,DGA^6000030    I20 @T6G_MB_LIB.T6G(SCH_1):PAGE31
   U25  R56 VSS_R56 GENOA_SP5-SOCKET6096_13568-001,SMLF,IO,DGA^6000030    I20 @T6G_MB_LIB.T6G(SCH_1):PAGE31
   U25  R58 VSS_R58 GENOA_SP5-SOCKET6096_13568-001,SMLF,IO,DGA^6000030    I20 @T6G_MB_LIB.T6G(SCH_1):PAGE31
   U25  R61 VSS_R61 GENOA_SP5-SOCKET6096_13568-001,SMLF,IO,DGA^6000030    I20 @T6G_MB_LIB.T6G(SCH_1):PAGE31
   U25  R63 VSS_R63 GENOA_SP5-SOCKET6096_13568-001,SMLF,IO,DGA^6000030    I20 @T6G_MB_LIB.T6G(SCH_1):PAGE31
   U25  R65 VSS_R65 GENOA_SP5-SOCKET6096_13568-001,SMLF,IO,DGA^6000030    I20 @T6G_MB_LIB.T6G(SCH_1):PAGE31
   U25  R68 VSS_R68 GENOA_SP5-SOCKET6096_13568-001,SMLF,IO,DGA^6000030    I20 @T6G_MB_LIB.T6G(SCH_1):PAGE31
   U25  R70 VSS_R70 GENOA_SP5-SOCKET6096_13568-001,SMLF,IO,DGA^6000030    I20 @T6G_MB_LIB.T6G(SCH_1):PAGE31
   U25  R72 VSS_R72 GENOA_SP5-SOCKET6096_13568-001,SMLF,IO,DGA^6000030    I20 @T6G_MB_LIB.T6G(SCH_1):PAGE31
   U25  R75 VSS_R75 GENOA_SP5-SOCKET6096_13568-001,SMLF,IO,DGA^6000030    I20 @T6G_MB_LIB.T6G(SCH_1):PAGE31
   U25   T3 VSS_T3 GENOA_SP5-SOCKET6096_13568-001,SMLF,IO,DGA^6000030    I20 @T6G_MB_LIB.T6G(SCH_1):PAGE31
   U25   T5 VSS_T5 GENOA_SP5-SOCKET6096_13568-001,SMLF,IO,DGA^6000030    I20 @T6G_MB_LIB.T6G(SCH_1):PAGE31
   U25   T8 VSS_T8 GENOA_SP5-SOCKET6096_13568-001,SMLF,IO,DGA^6000030    I20 @T6G_MB_LIB.T6G(SCH_1):PAGE31
   U25  T10 VSS_T10 GENOA_SP5-SOCKET6096_13568-001,SMLF,IO,DGA^6000030    I20 @T6G_MB_LIB.T6G(SCH_1):PAGE31
   U25  T12 VSS_T12 GENOA_SP5-SOCKET6096_13568-001,SMLF,IO,DGA^6000030    I20 @T6G_MB_LIB.T6G(SCH_1):PAGE31
   U25  T15 VSS_T15 GENOA_SP5-SOCKET6096_13568-001,SMLF,IO,DGA^6000030    I20 @T6G_MB_LIB.T6G(SCH_1):PAGE31
   U25  T17 VSS_T17 GENOA_SP5-SOCKET6096_13568-001,SMLF,IO,DGA^6000030    I20 @T6G_MB_LIB.T6G(SCH_1):PAGE31
   U25  T19 VSS_T19 GENOA_SP5-SOCKET6096_13568-001,SMLF,IO,DGA^6000030    I20 @T6G_MB_LIB.T6G(SCH_1):PAGE31
   U25  T22 VSS_T22 GENOA_SP5-SOCKET6096_13568-001,SMLF,IO,DGA^6000030    I20 @T6G_MB_LIB.T6G(SCH_1):PAGE31
   U25  T25 VSS_T25 GENOA_SP5-SOCKET6096_13568-001,SMLF,IO,DGA^6000030    I20 @T6G_MB_LIB.T6G(SCH_1):PAGE31
   U25  T28 VSS_T28 GENOA_SP5-SOCKET6096_13568-001,SMLF,IO,DGA^6000030    I20 @T6G_MB_LIB.T6G(SCH_1):PAGE31
   U25  T31 VSS_T31 GENOA_SP5-SOCKET6096_13568-001,SMLF,IO,DGA^6000030    I20 @T6G_MB_LIB.T6G(SCH_1):PAGE31
   U25  T34 VSS_T34 GENOA_SP5-SOCKET6096_13568-001,SMLF,IO,DGA^6000030    I20 @T6G_MB_LIB.T6G(SCH_1):PAGE31
   U25  T37 VSS_T37 GENOA_SP5-SOCKET6096_13568-001,SMLF,IO,DGA^6000030    I20 @T6G_MB_LIB.T6G(SCH_1):PAGE31
   U25  T39 VSS_T39 GENOA_SP5-SOCKET6096_13568-001,SMLF,IO,DGA^6000030    I20 @T6G_MB_LIB.T6G(SCH_1):PAGE31
   U25  T42 VSS_T42 GENOA_SP5-SOCKET6096_13568-001,SMLF,IO,DGA^6000030    I20 @T6G_MB_LIB.T6G(SCH_1):PAGE31
   U25  T45 VSS_T45 GENOA_SP5-SOCKET6096_13568-001,SMLF,IO,DGA^6000030    I20 @T6G_MB_LIB.T6G(SCH_1):PAGE31
   U25  T48 VSS_T48 GENOA_SP5-SOCKET6096_13568-001,SMLF,IO,DGA^6000030    I20 @T6G_MB_LIB.T6G(SCH_1):PAGE31
   U25  T51 VSS_T51 GENOA_SP5-SOCKET6096_13568-001,SMLF,IO,DGA^6000030    I20 @T6G_MB_LIB.T6G(SCH_1):PAGE31
   U25  T54 VSS_T54 GENOA_SP5-SOCKET6096_13568-001,SMLF,IO,DGA^6000030    I20 @T6G_MB_LIB.T6G(SCH_1):PAGE31
   U25  T57 VSS_T57 GENOA_SP5-SOCKET6096_13568-001,SMLF,IO,DGA^6000030    I20 @T6G_MB_LIB.T6G(SCH_1):PAGE31
   U25  T59 VSS_T59 GENOA_SP5-SOCKET6096_13568-001,SMLF,IO,DGA^6000030    I20 @T6G_MB_LIB.T6G(SCH_1):PAGE31
   U25  T61 VSS_T61 GENOA_SP5-SOCKET6096_13568-001,SMLF,IO,DGA^6000030    I20 @T6G_MB_LIB.T6G(SCH_1):PAGE31
   U25  T64 VSS_T64 GENOA_SP5-SOCKET6096_13568-001,SMLF,IO,DGA^6000030    I20 @T6G_MB_LIB.T6G(SCH_1):PAGE31
   U25  AA1 VSS_AA1 GENOA_SP5-SOCKET6096_13568-001,SMLF,IO,DGA^6000030    I21 @T6G_MB_LIB.T6G(SCH_1):PAGE31
   U25  AA4 VSS_AA4 GENOA_SP5-SOCKET6096_13568-001,SMLF,IO,DGA^6000030    I21 @T6G_MB_LIB.T6G(SCH_1):PAGE31
   U25  AA6 VSS_AA6 GENOA_SP5-SOCKET6096_13568-001,SMLF,IO,DGA^6000030    I21 @T6G_MB_LIB.T6G(SCH_1):PAGE31
   U25  AA8 VSS_AA8 GENOA_SP5-SOCKET6096_13568-001,SMLF,IO,DGA^6000030    I21 @T6G_MB_LIB.T6G(SCH_1):PAGE31
   U25 AA11 VSS_AA11 GENOA_SP5-SOCKET6096_13568-001,SMLF,IO,DGA^6000030    I21 @T6G_MB_LIB.T6G(SCH_1):PAGE31
   U25 AA13 VSS_AA13 GENOA_SP5-SOCKET6096_13568-001,SMLF,IO,DGA^6000030    I21 @T6G_MB_LIB.T6G(SCH_1):PAGE31
   U25 AA15 VSS_AA15 GENOA_SP5-SOCKET6096_13568-001,SMLF,IO,DGA^6000030    I21 @T6G_MB_LIB.T6G(SCH_1):PAGE31
   U25 AA18 VSS_AA18 GENOA_SP5-SOCKET6096_13568-001,SMLF,IO,DGA^6000030    I21 @T6G_MB_LIB.T6G(SCH_1):PAGE31
   U25 AA20 VSS_AA20 GENOA_SP5-SOCKET6096_13568-001,SMLF,IO,DGA^6000030    I21 @T6G_MB_LIB.T6G(SCH_1):PAGE31
   U25 AA31 VSS_AA31 GENOA_SP5-SOCKET6096_13568-001,SMLF,IO,DGA^6000030    I21 @T6G_MB_LIB.T6G(SCH_1):PAGE31
   U25 AA34 VSS_AA34 GENOA_SP5-SOCKET6096_13568-001,SMLF,IO,DGA^6000030    I21 @T6G_MB_LIB.T6G(SCH_1):PAGE31
   U25 AA35 VSS_AA35 GENOA_SP5-SOCKET6096_13568-001,SMLF,IO,DGA^6000030    I21 @T6G_MB_LIB.T6G(SCH_1):PAGE31
   U25 AA36 VSS_AA36 GENOA_SP5-SOCKET6096_13568-001,SMLF,IO,DGA^6000030    I21 @T6G_MB_LIB.T6G(SCH_1):PAGE31
   U25 AA40 VSS_AA40 GENOA_SP5-SOCKET6096_13568-001,SMLF,IO,DGA^6000030    I21 @T6G_MB_LIB.T6G(SCH_1):PAGE31
   U25 AA41 VSS_AA41 GENOA_SP5-SOCKET6096_13568-001,SMLF,IO,DGA^6000030    I21 @T6G_MB_LIB.T6G(SCH_1):PAGE31
   U25 AA45 VSS_AA45 GENOA_SP5-SOCKET6096_13568-001,SMLF,IO,DGA^6000030    I21 @T6G_MB_LIB.T6G(SCH_1):PAGE31
   U25 AA56 VSS_AA56 GENOA_SP5-SOCKET6096_13568-001,SMLF,IO,DGA^6000030    I21 @T6G_MB_LIB.T6G(SCH_1):PAGE31
   U25 AA58 VSS_AA58 GENOA_SP5-SOCKET6096_13568-001,SMLF,IO,DGA^6000030    I21 @T6G_MB_LIB.T6G(SCH_1):PAGE31
   U25 AA61 VSS_AA61 GENOA_SP5-SOCKET6096_13568-001,SMLF,IO,DGA^6000030    I21 @T6G_MB_LIB.T6G(SCH_1):PAGE31
   U25 AA63 VSS_AA63 GENOA_SP5-SOCKET6096_13568-001,SMLF,IO,DGA^6000030    I21 @T6G_MB_LIB.T6G(SCH_1):PAGE31
   U25 AA65 VSS_AA65 GENOA_SP5-SOCKET6096_13568-001,SMLF,IO,DGA^6000030    I21 @T6G_MB_LIB.T6G(SCH_1):PAGE31
   U25 AA68 VSS_AA68 GENOA_SP5-SOCKET6096_13568-001,SMLF,IO,DGA^6000030    I21 @T6G_MB_LIB.T6G(SCH_1):PAGE31
   U25 AA70 VSS_AA70 GENOA_SP5-SOCKET6096_13568-001,SMLF,IO,DGA^6000030    I21 @T6G_MB_LIB.T6G(SCH_1):PAGE31
   U25 AA75 VSS_AA75 GENOA_SP5-SOCKET6096_13568-001,SMLF,IO,DGA^6000030    I21 @T6G_MB_LIB.T6G(SCH_1):PAGE31
   U25  AB3 VSS_AB3 GENOA_SP5-SOCKET6096_13568-001,SMLF,IO,DGA^6000030    I21 @T6G_MB_LIB.T6G(SCH_1):PAGE31
   U25  AB5 VSS_AB5 GENOA_SP5-SOCKET6096_13568-001,SMLF,IO,DGA^6000030    I21 @T6G_MB_LIB.T6G(SCH_1):PAGE31
   U25  AB8 VSS_AB8 GENOA_SP5-SOCKET6096_13568-001,SMLF,IO,DGA^6000030    I21 @T6G_MB_LIB.T6G(SCH_1):PAGE31
   U25 AB10 VSS_AB10 GENOA_SP5-SOCKET6096_13568-001,SMLF,IO,DGA^6000030    I21 @T6G_MB_LIB.T6G(SCH_1):PAGE31
   U25 AB12 VSS_AB12 GENOA_SP5-SOCKET6096_13568-001,SMLF,IO,DGA^6000030    I21 @T6G_MB_LIB.T6G(SCH_1):PAGE31
   U25 AB15 VSS_AB15 GENOA_SP5-SOCKET6096_13568-001,SMLF,IO,DGA^6000030    I21 @T6G_MB_LIB.T6G(SCH_1):PAGE31
   U25 AB17 VSS_AB17 GENOA_SP5-SOCKET6096_13568-001,SMLF,IO,DGA^6000030    I21 @T6G_MB_LIB.T6G(SCH_1):PAGE31
   U25 AB19 VSS_AB19 GENOA_SP5-SOCKET6096_13568-001,SMLF,IO,DGA^6000030    I21 @T6G_MB_LIB.T6G(SCH_1):PAGE31
   U25 AB22 VSS_AB22 GENOA_SP5-SOCKET6096_13568-001,SMLF,IO,DGA^6000030    I21 @T6G_MB_LIB.T6G(SCH_1):PAGE31
   U25 AB25 VSS_AB25 GENOA_SP5-SOCKET6096_13568-001,SMLF,IO,DGA^6000030    I21 @T6G_MB_LIB.T6G(SCH_1):PAGE31
   U25 AB28 VSS_AB28 GENOA_SP5-SOCKET6096_13568-001,SMLF,IO,DGA^6000030    I21 @T6G_MB_LIB.T6G(SCH_1):PAGE31
   U25 AB31 VSS_AB31 GENOA_SP5-SOCKET6096_13568-001,SMLF,IO,DGA^6000030    I21 @T6G_MB_LIB.T6G(SCH_1):PAGE31
   U25 AB34 VSS_AB34 GENOA_SP5-SOCKET6096_13568-001,SMLF,IO,DGA^6000030    I21 @T6G_MB_LIB.T6G(SCH_1):PAGE31
   U25 AB37 VSS_AB37 GENOA_SP5-SOCKET6096_13568-001,SMLF,IO,DGA^6000030    I21 @T6G_MB_LIB.T6G(SCH_1):PAGE31
   U25 AB39 VSS_AB39 GENOA_SP5-SOCKET6096_13568-001,SMLF,IO,DGA^6000030    I21 @T6G_MB_LIB.T6G(SCH_1):PAGE31
   U25 AB42 VSS_AB42 GENOA_SP5-SOCKET6096_13568-001,SMLF,IO,DGA^6000030    I21 @T6G_MB_LIB.T6G(SCH_1):PAGE31
   U25 AB45 VSS_AB45 GENOA_SP5-SOCKET6096_13568-001,SMLF,IO,DGA^6000030    I21 @T6G_MB_LIB.T6G(SCH_1):PAGE31
   U25 AB48 VSS_AB48 GENOA_SP5-SOCKET6096_13568-001,SMLF,IO,DGA^6000030    I21 @T6G_MB_LIB.T6G(SCH_1):PAGE31
   U25 AB51 VSS_AB51 GENOA_SP5-SOCKET6096_13568-001,SMLF,IO,DGA^6000030    I21 @T6G_MB_LIB.T6G(SCH_1):PAGE31
   U25 AB54 VSS_AB54 GENOA_SP5-SOCKET6096_13568-001,SMLF,IO,DGA^6000030    I21 @T6G_MB_LIB.T6G(SCH_1):PAGE31
   U25 AB57 VSS_AB57 GENOA_SP5-SOCKET6096_13568-001,SMLF,IO,DGA^6000030    I21 @T6G_MB_LIB.T6G(SCH_1):PAGE31
   U25 AB59 VSS_AB59 GENOA_SP5-SOCKET6096_13568-001,SMLF,IO,DGA^6000030    I21 @T6G_MB_LIB.T6G(SCH_1):PAGE31
   U25 AB61 VSS_AB61 GENOA_SP5-SOCKET6096_13568-001,SMLF,IO,DGA^6000030    I21 @T6G_MB_LIB.T6G(SCH_1):PAGE31
   U25 AB64 VSS_AB64 GENOA_SP5-SOCKET6096_13568-001,SMLF,IO,DGA^6000030    I21 @T6G_MB_LIB.T6G(SCH_1):PAGE31
   U25 AB66 VSS_AB66 GENOA_SP5-SOCKET6096_13568-001,SMLF,IO,DGA^6000030    I21 @T6G_MB_LIB.T6G(SCH_1):PAGE31
   U25 AB68 VSS_AB68 GENOA_SP5-SOCKET6096_13568-001,SMLF,IO,DGA^6000030    I21 @T6G_MB_LIB.T6G(SCH_1):PAGE31
   U25 AB71 VSS_AB71 GENOA_SP5-SOCKET6096_13568-001,SMLF,IO,DGA^6000030    I21 @T6G_MB_LIB.T6G(SCH_1):PAGE31
   U25 AB73 VSS_AB73 GENOA_SP5-SOCKET6096_13568-001,SMLF,IO,DGA^6000030    I21 @T6G_MB_LIB.T6G(SCH_1):PAGE31
   U25  AC1 VSS_AC1 GENOA_SP5-SOCKET6096_13568-001,SMLF,IO,DGA^6000030    I21 @T6G_MB_LIB.T6G(SCH_1):PAGE31
   U25  AC6 VSS_AC6 GENOA_SP5-SOCKET6096_13568-001,SMLF,IO,DGA^6000030    I21 @T6G_MB_LIB.T6G(SCH_1):PAGE31
   U25  AC8 VSS_AC8 GENOA_SP5-SOCKET6096_13568-001,SMLF,IO,DGA^6000030    I21 @T6G_MB_LIB.T6G(SCH_1):PAGE31
   U25 AC13 VSS_AC13 GENOA_SP5-SOCKET6096_13568-001,SMLF,IO,DGA^6000030    I21 @T6G_MB_LIB.T6G(SCH_1):PAGE31
   U25 AC15 VSS_AC15 GENOA_SP5-SOCKET6096_13568-001,SMLF,IO,DGA^6000030    I21 @T6G_MB_LIB.T6G(SCH_1):PAGE31
   U25 AC20 VSS_AC20 GENOA_SP5-SOCKET6096_13568-001,SMLF,IO,DGA^6000030    I21 @T6G_MB_LIB.T6G(SCH_1):PAGE31
   U25 AC22 VSS_AC22 GENOA_SP5-SOCKET6096_13568-001,SMLF,IO,DGA^6000030    I21 @T6G_MB_LIB.T6G(SCH_1):PAGE31
   U25 AC25 VSS_AC25 GENOA_SP5-SOCKET6096_13568-001,SMLF,IO,DGA^6000030    I21 @T6G_MB_LIB.T6G(SCH_1):PAGE31
   U25 AC28 VSS_AC28 GENOA_SP5-SOCKET6096_13568-001,SMLF,IO,DGA^6000030    I21 @T6G_MB_LIB.T6G(SCH_1):PAGE31
   U25 AC31 VSS_AC31 GENOA_SP5-SOCKET6096_13568-001,SMLF,IO,DGA^6000030    I21 @T6G_MB_LIB.T6G(SCH_1):PAGE31
   U25 AC34 VSS_AC34 GENOA_SP5-SOCKET6096_13568-001,SMLF,IO,DGA^6000030    I21 @T6G_MB_LIB.T6G(SCH_1):PAGE31
   U25 AC42 VSS_AC42 GENOA_SP5-SOCKET6096_13568-001,SMLF,IO,DGA^6000030    I21 @T6G_MB_LIB.T6G(SCH_1):PAGE31
   U25 AC45 VSS_AC45 GENOA_SP5-SOCKET6096_13568-001,SMLF,IO,DGA^6000030    I21 @T6G_MB_LIB.T6G(SCH_1):PAGE31
   U25 AC48 VSS_AC48 GENOA_SP5-SOCKET6096_13568-001,SMLF,IO,DGA^6000030    I21 @T6G_MB_LIB.T6G(SCH_1):PAGE31
   U25 AC51 VSS_AC51 GENOA_SP5-SOCKET6096_13568-001,SMLF,IO,DGA^6000030    I21 @T6G_MB_LIB.T6G(SCH_1):PAGE31
   U25 AC54 VSS_AC54 GENOA_SP5-SOCKET6096_13568-001,SMLF,IO,DGA^6000030    I21 @T6G_MB_LIB.T6G(SCH_1):PAGE31
   U25 AC56 VSS_AC56 GENOA_SP5-SOCKET6096_13568-001,SMLF,IO,DGA^6000030    I21 @T6G_MB_LIB.T6G(SCH_1):PAGE31
   U25 AC61 VSS_AC61 GENOA_SP5-SOCKET6096_13568-001,SMLF,IO,DGA^6000030    I21 @T6G_MB_LIB.T6G(SCH_1):PAGE31
   U25 AC63 VSS_AC63 GENOA_SP5-SOCKET6096_13568-001,SMLF,IO,DGA^6000030    I21 @T6G_MB_LIB.T6G(SCH_1):PAGE31
   U25 AC68 VSS_AC68 GENOA_SP5-SOCKET6096_13568-001,SMLF,IO,DGA^6000030    I21 @T6G_MB_LIB.T6G(SCH_1):PAGE31
   U25 AC70 VSS_AC70 GENOA_SP5-SOCKET6096_13568-001,SMLF,IO,DGA^6000030    I21 @T6G_MB_LIB.T6G(SCH_1):PAGE31
   U25 AC75 VSS_AC75 GENOA_SP5-SOCKET6096_13568-001,SMLF,IO,DGA^6000030    I21 @T6G_MB_LIB.T6G(SCH_1):PAGE31
   U25  AD3 VSS_AD3 GENOA_SP5-SOCKET6096_13568-001,SMLF,IO,DGA^6000030    I21 @T6G_MB_LIB.T6G(SCH_1):PAGE31
   U25  AD5 VSS_AD5 GENOA_SP5-SOCKET6096_13568-001,SMLF,IO,DGA^6000030    I21 @T6G_MB_LIB.T6G(SCH_1):PAGE31
   U25  AD8 VSS_AD8 GENOA_SP5-SOCKET6096_13568-001,SMLF,IO,DGA^6000030    I21 @T6G_MB_LIB.T6G(SCH_1):PAGE31
   U25 AD10 VSS_AD10 GENOA_SP5-SOCKET6096_13568-001,SMLF,IO,DGA^6000030    I21 @T6G_MB_LIB.T6G(SCH_1):PAGE31
   U25 AD12 VSS_AD12 GENOA_SP5-SOCKET6096_13568-001,SMLF,IO,DGA^6000030    I21 @T6G_MB_LIB.T6G(SCH_1):PAGE31
   U25 AD15 VSS_AD15 GENOA_SP5-SOCKET6096_13568-001,SMLF,IO,DGA^6000030    I21 @T6G_MB_LIB.T6G(SCH_1):PAGE31
   U25 AD17 VSS_AD17 GENOA_SP5-SOCKET6096_13568-001,SMLF,IO,DGA^6000030    I21 @T6G_MB_LIB.T6G(SCH_1):PAGE31
   U25 AD19 VSS_AD19 GENOA_SP5-SOCKET6096_13568-001,SMLF,IO,DGA^6000030    I21 @T6G_MB_LIB.T6G(SCH_1):PAGE31
   U25 AD23 VSS_AD23 GENOA_SP5-SOCKET6096_13568-001,SMLF,IO,DGA^6000030    I21 @T6G_MB_LIB.T6G(SCH_1):PAGE31
   U25 AD24 VSS_AD24 GENOA_SP5-SOCKET6096_13568-001,SMLF,IO,DGA^6000030    I21 @T6G_MB_LIB.T6G(SCH_1):PAGE31
   U25 AD25 VSS_AD25 GENOA_SP5-SOCKET6096_13568-001,SMLF,IO,DGA^6000030    I21 @T6G_MB_LIB.T6G(SCH_1):PAGE31
   U25 AD26 VSS_AD26 GENOA_SP5-SOCKET6096_13568-001,SMLF,IO,DGA^6000030    I21 @T6G_MB_LIB.T6G(SCH_1):PAGE31
   U25 AD27 VSS_AD27 GENOA_SP5-SOCKET6096_13568-001,SMLF,IO,DGA^6000030    I21 @T6G_MB_LIB.T6G(SCH_1):PAGE31
   U25 AD28 VSS_AD28 GENOA_SP5-SOCKET6096_13568-001,SMLF,IO,DGA^6000030    I21 @T6G_MB_LIB.T6G(SCH_1):PAGE31
   U25 AD29 VSS_AD29 GENOA_SP5-SOCKET6096_13568-001,SMLF,IO,DGA^6000030    I21 @T6G_MB_LIB.T6G(SCH_1):PAGE31
   U25 AD30 VSS_AD30 GENOA_SP5-SOCKET6096_13568-001,SMLF,IO,DGA^6000030    I21 @T6G_MB_LIB.T6G(SCH_1):PAGE31
   U25 AD32 VSS_AD32 GENOA_SP5-SOCKET6096_13568-001,SMLF,IO,DGA^6000030    I21 @T6G_MB_LIB.T6G(SCH_1):PAGE31
   U25 AD33 VSS_AD33 GENOA_SP5-SOCKET6096_13568-001,SMLF,IO,DGA^6000030    I21 @T6G_MB_LIB.T6G(SCH_1):PAGE31
   U25 AD34 VSS_AD34 GENOA_SP5-SOCKET6096_13568-001,SMLF,IO,DGA^6000030    I21 @T6G_MB_LIB.T6G(SCH_1):PAGE31
   U25 AD37 VSS_AD37 GENOA_SP5-SOCKET6096_13568-001,SMLF,IO,DGA^6000030    I21 @T6G_MB_LIB.T6G(SCH_1):PAGE31
   U25 AD39 VSS_AD39 GENOA_SP5-SOCKET6096_13568-001,SMLF,IO,DGA^6000030    I21 @T6G_MB_LIB.T6G(SCH_1):PAGE31
   U25 AD42 VSS_AD42 GENOA_SP5-SOCKET6096_13568-001,SMLF,IO,DGA^6000030    I21 @T6G_MB_LIB.T6G(SCH_1):PAGE31
   U25 AD43 VSS_AD43 GENOA_SP5-SOCKET6096_13568-001,SMLF,IO,DGA^6000030    I21 @T6G_MB_LIB.T6G(SCH_1):PAGE31
   U25 AD44 VSS_AD44 GENOA_SP5-SOCKET6096_13568-001,SMLF,IO,DGA^6000030    I21 @T6G_MB_LIB.T6G(SCH_1):PAGE31
   U25 AD45 VSS_AD45 GENOA_SP5-SOCKET6096_13568-001,SMLF,IO,DGA^6000030    I21 @T6G_MB_LIB.T6G(SCH_1):PAGE31
   U25 AD46 VSS_AD46 GENOA_SP5-SOCKET6096_13568-001,SMLF,IO,DGA^6000030    I21 @T6G_MB_LIB.T6G(SCH_1):PAGE31
   U25 AD47 VSS_AD47 GENOA_SP5-SOCKET6096_13568-001,SMLF,IO,DGA^6000030    I21 @T6G_MB_LIB.T6G(SCH_1):PAGE31
   U25 AD48 VSS_AD48 GENOA_SP5-SOCKET6096_13568-001,SMLF,IO,DGA^6000030    I21 @T6G_MB_LIB.T6G(SCH_1):PAGE31
   U25  T66 VSS_T66 GENOA_SP5-SOCKET6096_13568-001,SMLF,IO,DGA^6000030    I21 @T6G_MB_LIB.T6G(SCH_1):PAGE31
   U25  T68 VSS_T68 GENOA_SP5-SOCKET6096_13568-001,SMLF,IO,DGA^6000030    I21 @T6G_MB_LIB.T6G(SCH_1):PAGE31
   U25  T71 VSS_T71 GENOA_SP5-SOCKET6096_13568-001,SMLF,IO,DGA^6000030    I21 @T6G_MB_LIB.T6G(SCH_1):PAGE31
   U25  T73 VSS_T73 GENOA_SP5-SOCKET6096_13568-001,SMLF,IO,DGA^6000030    I21 @T6G_MB_LIB.T6G(SCH_1):PAGE31
   U25   U1 VSS_U1 GENOA_SP5-SOCKET6096_13568-001,SMLF,IO,DGA^6000030    I21 @T6G_MB_LIB.T6G(SCH_1):PAGE31
   U25   U6 VSS_U6 GENOA_SP5-SOCKET6096_13568-001,SMLF,IO,DGA^6000030    I21 @T6G_MB_LIB.T6G(SCH_1):PAGE31
   U25   U8 VSS_U8 GENOA_SP5-SOCKET6096_13568-001,SMLF,IO,DGA^6000030    I21 @T6G_MB_LIB.T6G(SCH_1):PAGE31
   U25  U13 VSS_U13 GENOA_SP5-SOCKET6096_13568-001,SMLF,IO,DGA^6000030    I21 @T6G_MB_LIB.T6G(SCH_1):PAGE31
   U25  U15 VSS_U15 GENOA_SP5-SOCKET6096_13568-001,SMLF,IO,DGA^6000030    I21 @T6G_MB_LIB.T6G(SCH_1):PAGE31
   U25  U20 VSS_U20 GENOA_SP5-SOCKET6096_13568-001,SMLF,IO,DGA^6000030    I21 @T6G_MB_LIB.T6G(SCH_1):PAGE31
   U25  U22 VSS_U22 GENOA_SP5-SOCKET6096_13568-001,SMLF,IO,DGA^6000030    I21 @T6G_MB_LIB.T6G(SCH_1):PAGE31
   U25  U25 VSS_U25 GENOA_SP5-SOCKET6096_13568-001,SMLF,IO,DGA^6000030    I21 @T6G_MB_LIB.T6G(SCH_1):PAGE31
   U25  U28 VSS_U28 GENOA_SP5-SOCKET6096_13568-001,SMLF,IO,DGA^6000030    I21 @T6G_MB_LIB.T6G(SCH_1):PAGE31
   U25  U31 VSS_U31 GENOA_SP5-SOCKET6096_13568-001,SMLF,IO,DGA^6000030    I21 @T6G_MB_LIB.T6G(SCH_1):PAGE31
   U25  U34 VSS_U34 GENOA_SP5-SOCKET6096_13568-001,SMLF,IO,DGA^6000030    I21 @T6G_MB_LIB.T6G(SCH_1):PAGE31
   U25  U42 VSS_U42 GENOA_SP5-SOCKET6096_13568-001,SMLF,IO,DGA^6000030    I21 @T6G_MB_LIB.T6G(SCH_1):PAGE31
   U25  U45 VSS_U45 GENOA_SP5-SOCKET6096_13568-001,SMLF,IO,DGA^6000030    I21 @T6G_MB_LIB.T6G(SCH_1):PAGE31
   U25  U48 VSS_U48 GENOA_SP5-SOCKET6096_13568-001,SMLF,IO,DGA^6000030    I21 @T6G_MB_LIB.T6G(SCH_1):PAGE31
   U25  U51 VSS_U51 GENOA_SP5-SOCKET6096_13568-001,SMLF,IO,DGA^6000030    I21 @T6G_MB_LIB.T6G(SCH_1):PAGE31
   U25  U54 VSS_U54 GENOA_SP5-SOCKET6096_13568-001,SMLF,IO,DGA^6000030    I21 @T6G_MB_LIB.T6G(SCH_1):PAGE31
   U25  U56 VSS_U56 GENOA_SP5-SOCKET6096_13568-001,SMLF,IO,DGA^6000030    I21 @T6G_MB_LIB.T6G(SCH_1):PAGE31
   U25  U61 VSS_U61 GENOA_SP5-SOCKET6096_13568-001,SMLF,IO,DGA^6000030    I21 @T6G_MB_LIB.T6G(SCH_1):PAGE31
   U25  U63 VSS_U63 GENOA_SP5-SOCKET6096_13568-001,SMLF,IO,DGA^6000030    I21 @T6G_MB_LIB.T6G(SCH_1):PAGE31
   U25  U68 VSS_U68 GENOA_SP5-SOCKET6096_13568-001,SMLF,IO,DGA^6000030    I21 @T6G_MB_LIB.T6G(SCH_1):PAGE31
   U25  U70 VSS_U70 GENOA_SP5-SOCKET6096_13568-001,SMLF,IO,DGA^6000030    I21 @T6G_MB_LIB.T6G(SCH_1):PAGE31
   U25  U75 VSS_U75 GENOA_SP5-SOCKET6096_13568-001,SMLF,IO,DGA^6000030    I21 @T6G_MB_LIB.T6G(SCH_1):PAGE31
   U25   V3 VSS_V3 GENOA_SP5-SOCKET6096_13568-001,SMLF,IO,DGA^6000030    I21 @T6G_MB_LIB.T6G(SCH_1):PAGE31
   U25   V5 VSS_V5 GENOA_SP5-SOCKET6096_13568-001,SMLF,IO,DGA^6000030    I21 @T6G_MB_LIB.T6G(SCH_1):PAGE31
   U25   V8 VSS_V8 GENOA_SP5-SOCKET6096_13568-001,SMLF,IO,DGA^6000030    I21 @T6G_MB_LIB.T6G(SCH_1):PAGE31
   U25  V10 VSS_V10 GENOA_SP5-SOCKET6096_13568-001,SMLF,IO,DGA^6000030    I21 @T6G_MB_LIB.T6G(SCH_1):PAGE31
   U25  V12 VSS_V12 GENOA_SP5-SOCKET6096_13568-001,SMLF,IO,DGA^6000030    I21 @T6G_MB_LIB.T6G(SCH_1):PAGE31
   U25  V15 VSS_V15 GENOA_SP5-SOCKET6096_13568-001,SMLF,IO,DGA^6000030    I21 @T6G_MB_LIB.T6G(SCH_1):PAGE31
   U25  V17 VSS_V17 GENOA_SP5-SOCKET6096_13568-001,SMLF,IO,DGA^6000030    I21 @T6G_MB_LIB.T6G(SCH_1):PAGE31
   U25  V19 VSS_V19 GENOA_SP5-SOCKET6096_13568-001,SMLF,IO,DGA^6000030    I21 @T6G_MB_LIB.T6G(SCH_1):PAGE31
   U25  V23 VSS_V23 GENOA_SP5-SOCKET6096_13568-001,SMLF,IO,DGA^6000030    I21 @T6G_MB_LIB.T6G(SCH_1):PAGE31
   U25  V24 VSS_V24 GENOA_SP5-SOCKET6096_13568-001,SMLF,IO,DGA^6000030    I21 @T6G_MB_LIB.T6G(SCH_1):PAGE31
   U25  V25 VSS_V25 GENOA_SP5-SOCKET6096_13568-001,SMLF,IO,DGA^6000030    I21 @T6G_MB_LIB.T6G(SCH_1):PAGE31
   U25  V26 VSS_V26 GENOA_SP5-SOCKET6096_13568-001,SMLF,IO,DGA^6000030    I21 @T6G_MB_LIB.T6G(SCH_1):PAGE31
   U25  V28 VSS_V28 GENOA_SP5-SOCKET6096_13568-001,SMLF,IO,DGA^6000030    I21 @T6G_MB_LIB.T6G(SCH_1):PAGE31
   U25  V29 VSS_V29 GENOA_SP5-SOCKET6096_13568-001,SMLF,IO,DGA^6000030    I21 @T6G_MB_LIB.T6G(SCH_1):PAGE31
   U25  V30 VSS_V30 GENOA_SP5-SOCKET6096_13568-001,SMLF,IO,DGA^6000030    I21 @T6G_MB_LIB.T6G(SCH_1):PAGE31
   U25  V31 VSS_V31 GENOA_SP5-SOCKET6096_13568-001,SMLF,IO,DGA^6000030    I21 @T6G_MB_LIB.T6G(SCH_1):PAGE31
   U25  V32 VSS_V32 GENOA_SP5-SOCKET6096_13568-001,SMLF,IO,DGA^6000030    I21 @T6G_MB_LIB.T6G(SCH_1):PAGE31
   U25  V33 VSS_V33 GENOA_SP5-SOCKET6096_13568-001,SMLF,IO,DGA^6000030    I21 @T6G_MB_LIB.T6G(SCH_1):PAGE31
   U25  V34 VSS_V34 GENOA_SP5-SOCKET6096_13568-001,SMLF,IO,DGA^6000030    I21 @T6G_MB_LIB.T6G(SCH_1):PAGE31
   U25  V37 VSS_V37 GENOA_SP5-SOCKET6096_13568-001,SMLF,IO,DGA^6000030    I21 @T6G_MB_LIB.T6G(SCH_1):PAGE31
   U25  V39 VSS_V39 GENOA_SP5-SOCKET6096_13568-001,SMLF,IO,DGA^6000030    I21 @T6G_MB_LIB.T6G(SCH_1):PAGE31
   U25  V42 VSS_V42 GENOA_SP5-SOCKET6096_13568-001,SMLF,IO,DGA^6000030    I21 @T6G_MB_LIB.T6G(SCH_1):PAGE31
   U25  V43 VSS_V43 GENOA_SP5-SOCKET6096_13568-001,SMLF,IO,DGA^6000030    I21 @T6G_MB_LIB.T6G(SCH_1):PAGE31
   U25  V44 VSS_V44 GENOA_SP5-SOCKET6096_13568-001,SMLF,IO,DGA^6000030    I21 @T6G_MB_LIB.T6G(SCH_1):PAGE31
   U25  V45 VSS_V45 GENOA_SP5-SOCKET6096_13568-001,SMLF,IO,DGA^6000030    I21 @T6G_MB_LIB.T6G(SCH_1):PAGE31
   U25  V46 VSS_V46 GENOA_SP5-SOCKET6096_13568-001,SMLF,IO,DGA^6000030    I21 @T6G_MB_LIB.T6G(SCH_1):PAGE31
   U25  V47 VSS_V47 GENOA_SP5-SOCKET6096_13568-001,SMLF,IO,DGA^6000030    I21 @T6G_MB_LIB.T6G(SCH_1):PAGE31
   U25  V48 VSS_V48 GENOA_SP5-SOCKET6096_13568-001,SMLF,IO,DGA^6000030    I21 @T6G_MB_LIB.T6G(SCH_1):PAGE31
   U25  V49 VSS_V49 GENOA_SP5-SOCKET6096_13568-001,SMLF,IO,DGA^6000030    I21 @T6G_MB_LIB.T6G(SCH_1):PAGE31
   U25  V50 VSS_V50 GENOA_SP5-SOCKET6096_13568-001,SMLF,IO,DGA^6000030    I21 @T6G_MB_LIB.T6G(SCH_1):PAGE31
   U25  V51 VSS_V51 GENOA_SP5-SOCKET6096_13568-001,SMLF,IO,DGA^6000030    I21 @T6G_MB_LIB.T6G(SCH_1):PAGE31
   U25  V52 VSS_V52 GENOA_SP5-SOCKET6096_13568-001,SMLF,IO,DGA^6000030    I21 @T6G_MB_LIB.T6G(SCH_1):PAGE31
   U25  V53 VSS_V53 GENOA_SP5-SOCKET6096_13568-001,SMLF,IO,DGA^6000030    I21 @T6G_MB_LIB.T6G(SCH_1):PAGE31
   U25  V57 VSS_V57 GENOA_SP5-SOCKET6096_13568-001,SMLF,IO,DGA^6000030    I21 @T6G_MB_LIB.T6G(SCH_1):PAGE31
   U25  V59 VSS_V59 GENOA_SP5-SOCKET6096_13568-001,SMLF,IO,DGA^6000030    I21 @T6G_MB_LIB.T6G(SCH_1):PAGE31
   U25  V61 VSS_V61 GENOA_SP5-SOCKET6096_13568-001,SMLF,IO,DGA^6000030    I21 @T6G_MB_LIB.T6G(SCH_1):PAGE31
   U25  V64 VSS_V64 GENOA_SP5-SOCKET6096_13568-001,SMLF,IO,DGA^6000030    I21 @T6G_MB_LIB.T6G(SCH_1):PAGE31
   U25  V66 VSS_V66 GENOA_SP5-SOCKET6096_13568-001,SMLF,IO,DGA^6000030    I21 @T6G_MB_LIB.T6G(SCH_1):PAGE31
   U25  V71 VSS_V71 GENOA_SP5-SOCKET6096_13568-001,SMLF,IO,DGA^6000030    I21 @T6G_MB_LIB.T6G(SCH_1):PAGE31
   U25  V73 VSS_V73 GENOA_SP5-SOCKET6096_13568-001,SMLF,IO,DGA^6000030    I21 @T6G_MB_LIB.T6G(SCH_1):PAGE31
   U25   W1 VSS_W1 GENOA_SP5-SOCKET6096_13568-001,SMLF,IO,DGA^6000030    I21 @T6G_MB_LIB.T6G(SCH_1):PAGE31
   U25   W4 VSS_W4 GENOA_SP5-SOCKET6096_13568-001,SMLF,IO,DGA^6000030    I21 @T6G_MB_LIB.T6G(SCH_1):PAGE31
   U25   W6 VSS_W6 GENOA_SP5-SOCKET6096_13568-001,SMLF,IO,DGA^6000030    I21 @T6G_MB_LIB.T6G(SCH_1):PAGE31
   U25   W8 VSS_W8 GENOA_SP5-SOCKET6096_13568-001,SMLF,IO,DGA^6000030    I21 @T6G_MB_LIB.T6G(SCH_1):PAGE31
   U25  W11 VSS_W11 GENOA_SP5-SOCKET6096_13568-001,SMLF,IO,DGA^6000030    I21 @T6G_MB_LIB.T6G(SCH_1):PAGE31
   U25  W13 VSS_W13 GENOA_SP5-SOCKET6096_13568-001,SMLF,IO,DGA^6000030    I21 @T6G_MB_LIB.T6G(SCH_1):PAGE31
   U25  W15 VSS_W15 GENOA_SP5-SOCKET6096_13568-001,SMLF,IO,DGA^6000030    I21 @T6G_MB_LIB.T6G(SCH_1):PAGE31
   U25  W18 VSS_W18 GENOA_SP5-SOCKET6096_13568-001,SMLF,IO,DGA^6000030    I21 @T6G_MB_LIB.T6G(SCH_1):PAGE31
   U25  W20 VSS_W20 GENOA_SP5-SOCKET6096_13568-001,SMLF,IO,DGA^6000030    I21 @T6G_MB_LIB.T6G(SCH_1):PAGE31
   U25  W22 VSS_W22 GENOA_SP5-SOCKET6096_13568-001,SMLF,IO,DGA^6000030    I21 @T6G_MB_LIB.T6G(SCH_1):PAGE31
   U25  W25 VSS_W25 GENOA_SP5-SOCKET6096_13568-001,SMLF,IO,DGA^6000030    I21 @T6G_MB_LIB.T6G(SCH_1):PAGE31
   U25  W28 VSS_W28 GENOA_SP5-SOCKET6096_13568-001,SMLF,IO,DGA^6000030    I21 @T6G_MB_LIB.T6G(SCH_1):PAGE31
   U25  W34 VSS_W34 GENOA_SP5-SOCKET6096_13568-001,SMLF,IO,DGA^6000030    I21 @T6G_MB_LIB.T6G(SCH_1):PAGE31
   U25  W35 VSS_W35 GENOA_SP5-SOCKET6096_13568-001,SMLF,IO,DGA^6000030    I21 @T6G_MB_LIB.T6G(SCH_1):PAGE31
   U25  W36 VSS_W36 GENOA_SP5-SOCKET6096_13568-001,SMLF,IO,DGA^6000030    I21 @T6G_MB_LIB.T6G(SCH_1):PAGE31
   U25  W40 VSS_W40 GENOA_SP5-SOCKET6096_13568-001,SMLF,IO,DGA^6000030    I21 @T6G_MB_LIB.T6G(SCH_1):PAGE31
   U25  W41 VSS_W41 GENOA_SP5-SOCKET6096_13568-001,SMLF,IO,DGA^6000030    I21 @T6G_MB_LIB.T6G(SCH_1):PAGE31
   U25  W42 VSS_W42 GENOA_SP5-SOCKET6096_13568-001,SMLF,IO,DGA^6000030    I21 @T6G_MB_LIB.T6G(SCH_1):PAGE31
   U25  W45 VSS_W45 GENOA_SP5-SOCKET6096_13568-001,SMLF,IO,DGA^6000030    I21 @T6G_MB_LIB.T6G(SCH_1):PAGE31
   U25  W48 VSS_W48 GENOA_SP5-SOCKET6096_13568-001,SMLF,IO,DGA^6000030    I21 @T6G_MB_LIB.T6G(SCH_1):PAGE31
   U25  W51 VSS_W51 GENOA_SP5-SOCKET6096_13568-001,SMLF,IO,DGA^6000030    I21 @T6G_MB_LIB.T6G(SCH_1):PAGE31
   U25  W54 VSS_W54 GENOA_SP5-SOCKET6096_13568-001,SMLF,IO,DGA^6000030    I21 @T6G_MB_LIB.T6G(SCH_1):PAGE31
   U25  W56 VSS_W56 GENOA_SP5-SOCKET6096_13568-001,SMLF,IO,DGA^6000030    I21 @T6G_MB_LIB.T6G(SCH_1):PAGE31
   U25  W58 VSS_W58 GENOA_SP5-SOCKET6096_13568-001,SMLF,IO,DGA^6000030    I21 @T6G_MB_LIB.T6G(SCH_1):PAGE31
   U25  W61 VSS_W61 GENOA_SP5-SOCKET6096_13568-001,SMLF,IO,DGA^6000030    I21 @T6G_MB_LIB.T6G(SCH_1):PAGE31
   U25  W63 VSS_W63 GENOA_SP5-SOCKET6096_13568-001,SMLF,IO,DGA^6000030    I21 @T6G_MB_LIB.T6G(SCH_1):PAGE31
   U25  W65 VSS_W65 GENOA_SP5-SOCKET6096_13568-001,SMLF,IO,DGA^6000030    I21 @T6G_MB_LIB.T6G(SCH_1):PAGE31
   U25  W68 VSS_W68 GENOA_SP5-SOCKET6096_13568-001,SMLF,IO,DGA^6000030    I21 @T6G_MB_LIB.T6G(SCH_1):PAGE31
   U25  W70 VSS_W70 GENOA_SP5-SOCKET6096_13568-001,SMLF,IO,DGA^6000030    I21 @T6G_MB_LIB.T6G(SCH_1):PAGE31
   U25  W72 VSS_W72 GENOA_SP5-SOCKET6096_13568-001,SMLF,IO,DGA^6000030    I21 @T6G_MB_LIB.T6G(SCH_1):PAGE31
   U25  W75 VSS_W75 GENOA_SP5-SOCKET6096_13568-001,SMLF,IO,DGA^6000030    I21 @T6G_MB_LIB.T6G(SCH_1):PAGE31
   U25   Y3 VSS_Y3 GENOA_SP5-SOCKET6096_13568-001,SMLF,IO,DGA^6000030    I21 @T6G_MB_LIB.T6G(SCH_1):PAGE31
   U25   Y8 VSS_Y8 GENOA_SP5-SOCKET6096_13568-001,SMLF,IO,DGA^6000030    I21 @T6G_MB_LIB.T6G(SCH_1):PAGE31
   U25  Y10 VSS_Y10 GENOA_SP5-SOCKET6096_13568-001,SMLF,IO,DGA^6000030    I21 @T6G_MB_LIB.T6G(SCH_1):PAGE31
   U25  Y15 VSS_Y15 GENOA_SP5-SOCKET6096_13568-001,SMLF,IO,DGA^6000030    I21 @T6G_MB_LIB.T6G(SCH_1):PAGE31
   U25  Y17 VSS_Y17 GENOA_SP5-SOCKET6096_13568-001,SMLF,IO,DGA^6000030    I21 @T6G_MB_LIB.T6G(SCH_1):PAGE31
   U25  Y22 VSS_Y22 GENOA_SP5-SOCKET6096_13568-001,SMLF,IO,DGA^6000030    I21 @T6G_MB_LIB.T6G(SCH_1):PAGE31
   U25  Y23 VSS_Y23 GENOA_SP5-SOCKET6096_13568-001,SMLF,IO,DGA^6000030    I21 @T6G_MB_LIB.T6G(SCH_1):PAGE31
   U25  Y24 VSS_Y24 GENOA_SP5-SOCKET6096_13568-001,SMLF,IO,DGA^6000030    I21 @T6G_MB_LIB.T6G(SCH_1):PAGE31
   U25  Y25 VSS_Y25 GENOA_SP5-SOCKET6096_13568-001,SMLF,IO,DGA^6000030    I21 @T6G_MB_LIB.T6G(SCH_1):PAGE31
   U25  Y26 VSS_Y26 GENOA_SP5-SOCKET6096_13568-001,SMLF,IO,DGA^6000030    I21 @T6G_MB_LIB.T6G(SCH_1):PAGE31
   U25  Y27 VSS_Y27 GENOA_SP5-SOCKET6096_13568-001,SMLF,IO,DGA^6000030    I21 @T6G_MB_LIB.T6G(SCH_1):PAGE31
   U25  Y28 VSS_Y28 GENOA_SP5-SOCKET6096_13568-001,SMLF,IO,DGA^6000030    I21 @T6G_MB_LIB.T6G(SCH_1):PAGE31
   U25  Y31 VSS_Y31 GENOA_SP5-SOCKET6096_13568-001,SMLF,IO,DGA^6000030    I21 @T6G_MB_LIB.T6G(SCH_1):PAGE31
   U25  Y32 VSS_Y32 GENOA_SP5-SOCKET6096_13568-001,SMLF,IO,DGA^6000030    I21 @T6G_MB_LIB.T6G(SCH_1):PAGE31
   U25  Y33 VSS_Y33 GENOA_SP5-SOCKET6096_13568-001,SMLF,IO,DGA^6000030    I21 @T6G_MB_LIB.T6G(SCH_1):PAGE31
   U25  Y34 VSS_Y34 GENOA_SP5-SOCKET6096_13568-001,SMLF,IO,DGA^6000030    I21 @T6G_MB_LIB.T6G(SCH_1):PAGE31
   U25  Y37 VSS_Y37 GENOA_SP5-SOCKET6096_13568-001,SMLF,IO,DGA^6000030    I21 @T6G_MB_LIB.T6G(SCH_1):PAGE31
   U25  Y39 VSS_Y39 GENOA_SP5-SOCKET6096_13568-001,SMLF,IO,DGA^6000030    I21 @T6G_MB_LIB.T6G(SCH_1):PAGE31
   U25  Y42 VSS_Y42 GENOA_SP5-SOCKET6096_13568-001,SMLF,IO,DGA^6000030    I21 @T6G_MB_LIB.T6G(SCH_1):PAGE31
   U25  Y43 VSS_Y43 GENOA_SP5-SOCKET6096_13568-001,SMLF,IO,DGA^6000030    I21 @T6G_MB_LIB.T6G(SCH_1):PAGE31
   U25  Y44 VSS_Y44 GENOA_SP5-SOCKET6096_13568-001,SMLF,IO,DGA^6000030    I21 @T6G_MB_LIB.T6G(SCH_1):PAGE31
   U25  Y45 VSS_Y45 GENOA_SP5-SOCKET6096_13568-001,SMLF,IO,DGA^6000030    I21 @T6G_MB_LIB.T6G(SCH_1):PAGE31
   U25  Y48 VSS_Y48 GENOA_SP5-SOCKET6096_13568-001,SMLF,IO,DGA^6000030    I21 @T6G_MB_LIB.T6G(SCH_1):PAGE31
   U25  Y49 VSS_Y49 GENOA_SP5-SOCKET6096_13568-001,SMLF,IO,DGA^6000030    I21 @T6G_MB_LIB.T6G(SCH_1):PAGE31
   U25  Y50 VSS_Y50 GENOA_SP5-SOCKET6096_13568-001,SMLF,IO,DGA^6000030    I21 @T6G_MB_LIB.T6G(SCH_1):PAGE31
   U25  Y51 VSS_Y51 GENOA_SP5-SOCKET6096_13568-001,SMLF,IO,DGA^6000030    I21 @T6G_MB_LIB.T6G(SCH_1):PAGE31
   U25  Y52 VSS_Y52 GENOA_SP5-SOCKET6096_13568-001,SMLF,IO,DGA^6000030    I21 @T6G_MB_LIB.T6G(SCH_1):PAGE31
   U25  Y53 VSS_Y53 GENOA_SP5-SOCKET6096_13568-001,SMLF,IO,DGA^6000030    I21 @T6G_MB_LIB.T6G(SCH_1):PAGE31
   U25  Y54 VSS_Y54 GENOA_SP5-SOCKET6096_13568-001,SMLF,IO,DGA^6000030    I21 @T6G_MB_LIB.T6G(SCH_1):PAGE31
   U25  Y59 VSS_Y59 GENOA_SP5-SOCKET6096_13568-001,SMLF,IO,DGA^6000030    I21 @T6G_MB_LIB.T6G(SCH_1):PAGE31
   U25  Y61 VSS_Y61 GENOA_SP5-SOCKET6096_13568-001,SMLF,IO,DGA^6000030    I21 @T6G_MB_LIB.T6G(SCH_1):PAGE31
   U25  Y66 VSS_Y66 GENOA_SP5-SOCKET6096_13568-001,SMLF,IO,DGA^6000030    I21 @T6G_MB_LIB.T6G(SCH_1):PAGE31
   U25  Y68 VSS_Y68 GENOA_SP5-SOCKET6096_13568-001,SMLF,IO,DGA^6000030    I21 @T6G_MB_LIB.T6G(SCH_1):PAGE31
   U25  Y73 VSS_Y73 GENOA_SP5-SOCKET6096_13568-001,SMLF,IO,DGA^6000030    I21 @T6G_MB_LIB.T6G(SCH_1):PAGE31
   U25 AD49 VSS_AD49 GENOA_SP5-SOCKET6096_13568-001,SMLF,IO,DGA^6000030    I22 @T6G_MB_LIB.T6G(SCH_1):PAGE31
   U25 AD50 VSS_AD50 GENOA_SP5-SOCKET6096_13568-001,SMLF,IO,DGA^6000030    I22 @T6G_MB_LIB.T6G(SCH_1):PAGE31
   U25 AD51 VSS_AD51 GENOA_SP5-SOCKET6096_13568-001,SMLF,IO,DGA^6000030    I22 @T6G_MB_LIB.T6G(SCH_1):PAGE31
   U25 AD52 VSS_AD52 GENOA_SP5-SOCKET6096_13568-001,SMLF,IO,DGA^6000030    I22 @T6G_MB_LIB.T6G(SCH_1):PAGE31
   U25 AD53 VSS_AD53 GENOA_SP5-SOCKET6096_13568-001,SMLF,IO,DGA^6000030    I22 @T6G_MB_LIB.T6G(SCH_1):PAGE31
   U25 AD57 VSS_AD57 GENOA_SP5-SOCKET6096_13568-001,SMLF,IO,DGA^6000030    I22 @T6G_MB_LIB.T6G(SCH_1):PAGE31
   U25 AD59 VSS_AD59 GENOA_SP5-SOCKET6096_13568-001,SMLF,IO,DGA^6000030    I22 @T6G_MB_LIB.T6G(SCH_1):PAGE31
   U25 AD61 VSS_AD61 GENOA_SP5-SOCKET6096_13568-001,SMLF,IO,DGA^6000030    I22 @T6G_MB_LIB.T6G(SCH_1):PAGE31
   U25 AD64 VSS_AD64 GENOA_SP5-SOCKET6096_13568-001,SMLF,IO,DGA^6000030    I22 @T6G_MB_LIB.T6G(SCH_1):PAGE31
   U25 AD66 VSS_AD66 GENOA_SP5-SOCKET6096_13568-001,SMLF,IO,DGA^6000030    I22 @T6G_MB_LIB.T6G(SCH_1):PAGE31
   U25 AD68 VSS_AD68 GENOA_SP5-SOCKET6096_13568-001,SMLF,IO,DGA^6000030    I22 @T6G_MB_LIB.T6G(SCH_1):PAGE31
   U25 AD71 VSS_AD71 GENOA_SP5-SOCKET6096_13568-001,SMLF,IO,DGA^6000030    I22 @T6G_MB_LIB.T6G(SCH_1):PAGE31
   U25 AD73 VSS_AD73 GENOA_SP5-SOCKET6096_13568-001,SMLF,IO,DGA^6000030    I22 @T6G_MB_LIB.T6G(SCH_1):PAGE31
   U25  AE1 VSS_AE1 GENOA_SP5-SOCKET6096_13568-001,SMLF,IO,DGA^6000030    I22 @T6G_MB_LIB.T6G(SCH_1):PAGE31
   U25  AE6 VSS_AE6 GENOA_SP5-SOCKET6096_13568-001,SMLF,IO,DGA^6000030    I22 @T6G_MB_LIB.T6G(SCH_1):PAGE31
   U25  AE8 VSS_AE8 GENOA_SP5-SOCKET6096_13568-001,SMLF,IO,DGA^6000030    I22 @T6G_MB_LIB.T6G(SCH_1):PAGE31
   U25 AE11 VSS_AE11 GENOA_SP5-SOCKET6096_13568-001,SMLF,IO,DGA^6000030    I22 @T6G_MB_LIB.T6G(SCH_1):PAGE31
   U25 AE13 VSS_AE13 GENOA_SP5-SOCKET6096_13568-001,SMLF,IO,DGA^6000030    I22 @T6G_MB_LIB.T6G(SCH_1):PAGE31
   U25 AE15 VSS_AE15 GENOA_SP5-SOCKET6096_13568-001,SMLF,IO,DGA^6000030    I22 @T6G_MB_LIB.T6G(SCH_1):PAGE31
   U25 AE18 VSS_AE18 GENOA_SP5-SOCKET6096_13568-001,SMLF,IO,DGA^6000030    I22 @T6G_MB_LIB.T6G(SCH_1):PAGE31
   U25 AE20 VSS_AE20 GENOA_SP5-SOCKET6096_13568-001,SMLF,IO,DGA^6000030    I22 @T6G_MB_LIB.T6G(SCH_1):PAGE31
   U25 AE22 VSS_AE22 GENOA_SP5-SOCKET6096_13568-001,SMLF,IO,DGA^6000030    I22 @T6G_MB_LIB.T6G(SCH_1):PAGE31
   U25 AE25 VSS_AE25 GENOA_SP5-SOCKET6096_13568-001,SMLF,IO,DGA^6000030    I22 @T6G_MB_LIB.T6G(SCH_1):PAGE31
   U25 AE28 VSS_AE28 GENOA_SP5-SOCKET6096_13568-001,SMLF,IO,DGA^6000030    I22 @T6G_MB_LIB.T6G(SCH_1):PAGE31
   U25 AE31 VSS_AE31 GENOA_SP5-SOCKET6096_13568-001,SMLF,IO,DGA^6000030    I22 @T6G_MB_LIB.T6G(SCH_1):PAGE31
   U25 AE34 VSS_AE34 GENOA_SP5-SOCKET6096_13568-001,SMLF,IO,DGA^6000030    I22 @T6G_MB_LIB.T6G(SCH_1):PAGE31
   U25 AE35 VSS_AE35 GENOA_SP5-SOCKET6096_13568-001,SMLF,IO,DGA^6000030    I22 @T6G_MB_LIB.T6G(SCH_1):PAGE31
   U25 AE36 VSS_AE36 GENOA_SP5-SOCKET6096_13568-001,SMLF,IO,DGA^6000030    I22 @T6G_MB_LIB.T6G(SCH_1):PAGE31
   U25 AE40 VSS_AE40 GENOA_SP5-SOCKET6096_13568-001,SMLF,IO,DGA^6000030    I22 @T6G_MB_LIB.T6G(SCH_1):PAGE31
   U25 AE41 VSS_AE41 GENOA_SP5-SOCKET6096_13568-001,SMLF,IO,DGA^6000030    I22 @T6G_MB_LIB.T6G(SCH_1):PAGE31
   U25 AE42 VSS_AE42 GENOA_SP5-SOCKET6096_13568-001,SMLF,IO,DGA^6000030    I22 @T6G_MB_LIB.T6G(SCH_1):PAGE31
   U25 AE45 VSS_AE45 GENOA_SP5-SOCKET6096_13568-001,SMLF,IO,DGA^6000030    I22 @T6G_MB_LIB.T6G(SCH_1):PAGE31
   U25 AE48 VSS_AE48 GENOA_SP5-SOCKET6096_13568-001,SMLF,IO,DGA^6000030    I22 @T6G_MB_LIB.T6G(SCH_1):PAGE31
   U25 AE51 VSS_AE51 GENOA_SP5-SOCKET6096_13568-001,SMLF,IO,DGA^6000030    I22 @T6G_MB_LIB.T6G(SCH_1):PAGE31
   U25 AE54 VSS_AE54 GENOA_SP5-SOCKET6096_13568-001,SMLF,IO,DGA^6000030    I22 @T6G_MB_LIB.T6G(SCH_1):PAGE31
   U25 AE56 VSS_AE56 GENOA_SP5-SOCKET6096_13568-001,SMLF,IO,DGA^6000030    I22 @T6G_MB_LIB.T6G(SCH_1):PAGE31
   U25 AE58 VSS_AE58 GENOA_SP5-SOCKET6096_13568-001,SMLF,IO,DGA^6000030    I22 @T6G_MB_LIB.T6G(SCH_1):PAGE31
   U25 AE61 VSS_AE61 GENOA_SP5-SOCKET6096_13568-001,SMLF,IO,DGA^6000030    I22 @T6G_MB_LIB.T6G(SCH_1):PAGE31
   U25 AE63 VSS_AE63 GENOA_SP5-SOCKET6096_13568-001,SMLF,IO,DGA^6000030    I22 @T6G_MB_LIB.T6G(SCH_1):PAGE31
   U25 AE65 VSS_AE65 GENOA_SP5-SOCKET6096_13568-001,SMLF,IO,DGA^6000030    I22 @T6G_MB_LIB.T6G(SCH_1):PAGE31
   U25 AE68 VSS_AE68 GENOA_SP5-SOCKET6096_13568-001,SMLF,IO,DGA^6000030    I22 @T6G_MB_LIB.T6G(SCH_1):PAGE31
   U25 AE70 VSS_AE70 GENOA_SP5-SOCKET6096_13568-001,SMLF,IO,DGA^6000030    I22 @T6G_MB_LIB.T6G(SCH_1):PAGE31
   U25 AE72 VSS_AE72 GENOA_SP5-SOCKET6096_13568-001,SMLF,IO,DGA^6000030    I22 @T6G_MB_LIB.T6G(SCH_1):PAGE31
   U25 AE75 VSS_AE75 GENOA_SP5-SOCKET6096_13568-001,SMLF,IO,DGA^6000030    I22 @T6G_MB_LIB.T6G(SCH_1):PAGE31
   U25  AF3 VSS_AF3 GENOA_SP5-SOCKET6096_13568-001,SMLF,IO,DGA^6000030    I22 @T6G_MB_LIB.T6G(SCH_1):PAGE31
   U25  AF8 VSS_AF8 GENOA_SP5-SOCKET6096_13568-001,SMLF,IO,DGA^6000030    I22 @T6G_MB_LIB.T6G(SCH_1):PAGE31
   U25 AF10 VSS_AF10 GENOA_SP5-SOCKET6096_13568-001,SMLF,IO,DGA^6000030    I22 @T6G_MB_LIB.T6G(SCH_1):PAGE31
   U25 AF15 VSS_AF15 GENOA_SP5-SOCKET6096_13568-001,SMLF,IO,DGA^6000030    I22 @T6G_MB_LIB.T6G(SCH_1):PAGE31
   U25 AF17 VSS_AF17 GENOA_SP5-SOCKET6096_13568-001,SMLF,IO,DGA^6000030    I22 @T6G_MB_LIB.T6G(SCH_1):PAGE31
   U25 AF22 VSS_AF22 GENOA_SP5-SOCKET6096_13568-001,SMLF,IO,DGA^6000030    I22 @T6G_MB_LIB.T6G(SCH_1):PAGE31
   U25 AF25 VSS_AF25 GENOA_SP5-SOCKET6096_13568-001,SMLF,IO,DGA^6000030    I22 @T6G_MB_LIB.T6G(SCH_1):PAGE31
   U25 AF28 VSS_AF28 GENOA_SP5-SOCKET6096_13568-001,SMLF,IO,DGA^6000030    I22 @T6G_MB_LIB.T6G(SCH_1):PAGE31
   U25 AF31 VSS_AF31 GENOA_SP5-SOCKET6096_13568-001,SMLF,IO,DGA^6000030    I22 @T6G_MB_LIB.T6G(SCH_1):PAGE31
   U25 AF34 VSS_AF34 GENOA_SP5-SOCKET6096_13568-001,SMLF,IO,DGA^6000030    I22 @T6G_MB_LIB.T6G(SCH_1):PAGE31
   U25 AF37 VSS_AF37 GENOA_SP5-SOCKET6096_13568-001,SMLF,IO,DGA^6000030    I22 @T6G_MB_LIB.T6G(SCH_1):PAGE31
   U25 AF39 VSS_AF39 GENOA_SP5-SOCKET6096_13568-001,SMLF,IO,DGA^6000030    I22 @T6G_MB_LIB.T6G(SCH_1):PAGE31
   U25 AF42 VSS_AF42 GENOA_SP5-SOCKET6096_13568-001,SMLF,IO,DGA^6000030    I22 @T6G_MB_LIB.T6G(SCH_1):PAGE31
   U25 AF45 VSS_AF45 GENOA_SP5-SOCKET6096_13568-001,SMLF,IO,DGA^6000030    I22 @T6G_MB_LIB.T6G(SCH_1):PAGE31
   U25 AF48 VSS_AF48 GENOA_SP5-SOCKET6096_13568-001,SMLF,IO,DGA^6000030    I22 @T6G_MB_LIB.T6G(SCH_1):PAGE31
   U25 AF51 VSS_AF51 GENOA_SP5-SOCKET6096_13568-001,SMLF,IO,DGA^6000030    I22 @T6G_MB_LIB.T6G(SCH_1):PAGE31
   U25 AF54 VSS_AF54 GENOA_SP5-SOCKET6096_13568-001,SMLF,IO,DGA^6000030    I22 @T6G_MB_LIB.T6G(SCH_1):PAGE31
   U25 AF59 VSS_AF59 GENOA_SP5-SOCKET6096_13568-001,SMLF,IO,DGA^6000030    I22 @T6G_MB_LIB.T6G(SCH_1):PAGE31
   U25 AF61 VSS_AF61 GENOA_SP5-SOCKET6096_13568-001,SMLF,IO,DGA^6000030    I22 @T6G_MB_LIB.T6G(SCH_1):PAGE31
   U25 AF66 VSS_AF66 GENOA_SP5-SOCKET6096_13568-001,SMLF,IO,DGA^6000030    I22 @T6G_MB_LIB.T6G(SCH_1):PAGE31
   U25 AF68 VSS_AF68 GENOA_SP5-SOCKET6096_13568-001,SMLF,IO,DGA^6000030    I22 @T6G_MB_LIB.T6G(SCH_1):PAGE31
   U25 AF73 VSS_AF73 GENOA_SP5-SOCKET6096_13568-001,SMLF,IO,DGA^6000030    I22 @T6G_MB_LIB.T6G(SCH_1):PAGE31
   U25  AG1 VSS_AG1 GENOA_SP5-SOCKET6096_13568-001,SMLF,IO,DGA^6000030    I22 @T6G_MB_LIB.T6G(SCH_1):PAGE31
   U25  AG4 VSS_AG4 GENOA_SP5-SOCKET6096_13568-001,SMLF,IO,DGA^6000030    I22 @T6G_MB_LIB.T6G(SCH_1):PAGE31
   U25  AG6 VSS_AG6 GENOA_SP5-SOCKET6096_13568-001,SMLF,IO,DGA^6000030    I22 @T6G_MB_LIB.T6G(SCH_1):PAGE31
   U25  AG8 VSS_AG8 GENOA_SP5-SOCKET6096_13568-001,SMLF,IO,DGA^6000030    I22 @T6G_MB_LIB.T6G(SCH_1):PAGE31
   U25 AG11 VSS_AG11 GENOA_SP5-SOCKET6096_13568-001,SMLF,IO,DGA^6000030    I22 @T6G_MB_LIB.T6G(SCH_1):PAGE31
   U25 AG13 VSS_AG13 GENOA_SP5-SOCKET6096_13568-001,SMLF,IO,DGA^6000030    I22 @T6G_MB_LIB.T6G(SCH_1):PAGE31
   U25 AG15 VSS_AG15 GENOA_SP5-SOCKET6096_13568-001,SMLF,IO,DGA^6000030    I22 @T6G_MB_LIB.T6G(SCH_1):PAGE31
   U25 AG18 VSS_AG18 GENOA_SP5-SOCKET6096_13568-001,SMLF,IO,DGA^6000030    I22 @T6G_MB_LIB.T6G(SCH_1):PAGE31
   U25 AG20 VSS_AG20 GENOA_SP5-SOCKET6096_13568-001,SMLF,IO,DGA^6000030    I22 @T6G_MB_LIB.T6G(SCH_1):PAGE31
   U25 AG22 VSS_AG22 GENOA_SP5-SOCKET6096_13568-001,SMLF,IO,DGA^6000030    I22 @T6G_MB_LIB.T6G(SCH_1):PAGE31
   U25 AG25 VSS_AG25 GENOA_SP5-SOCKET6096_13568-001,SMLF,IO,DGA^6000030    I22 @T6G_MB_LIB.T6G(SCH_1):PAGE31
   U25 AG28 VSS_AG28 GENOA_SP5-SOCKET6096_13568-001,SMLF,IO,DGA^6000030    I22 @T6G_MB_LIB.T6G(SCH_1):PAGE31
   U25 AG31 VSS_AG31 GENOA_SP5-SOCKET6096_13568-001,SMLF,IO,DGA^6000030    I22 @T6G_MB_LIB.T6G(SCH_1):PAGE31
   U25 AG34 VSS_AG34 GENOA_SP5-SOCKET6096_13568-001,SMLF,IO,DGA^6000030    I22 @T6G_MB_LIB.T6G(SCH_1):PAGE31
   U25 AG42 VSS_AG42 GENOA_SP5-SOCKET6096_13568-001,SMLF,IO,DGA^6000030    I22 @T6G_MB_LIB.T6G(SCH_1):PAGE31
   U25 AG45 VSS_AG45 GENOA_SP5-SOCKET6096_13568-001,SMLF,IO,DGA^6000030    I22 @T6G_MB_LIB.T6G(SCH_1):PAGE31
   U25 AG48 VSS_AG48 GENOA_SP5-SOCKET6096_13568-001,SMLF,IO,DGA^6000030    I22 @T6G_MB_LIB.T6G(SCH_1):PAGE31
   U25 AG51 VSS_AG51 GENOA_SP5-SOCKET6096_13568-001,SMLF,IO,DGA^6000030    I22 @T6G_MB_LIB.T6G(SCH_1):PAGE31
   U25 AG54 VSS_AG54 GENOA_SP5-SOCKET6096_13568-001,SMLF,IO,DGA^6000030    I22 @T6G_MB_LIB.T6G(SCH_1):PAGE31
   U25 AG56 VSS_AG56 GENOA_SP5-SOCKET6096_13568-001,SMLF,IO,DGA^6000030    I22 @T6G_MB_LIB.T6G(SCH_1):PAGE31
   U25 AG58 VSS_AG58 GENOA_SP5-SOCKET6096_13568-001,SMLF,IO,DGA^6000030    I22 @T6G_MB_LIB.T6G(SCH_1):PAGE31
   U25 AG61 VSS_AG61 GENOA_SP5-SOCKET6096_13568-001,SMLF,IO,DGA^6000030    I22 @T6G_MB_LIB.T6G(SCH_1):PAGE31
   U25 AG63 VSS_AG63 GENOA_SP5-SOCKET6096_13568-001,SMLF,IO,DGA^6000030    I22 @T6G_MB_LIB.T6G(SCH_1):PAGE31
   U25 AG65 VSS_AG65 GENOA_SP5-SOCKET6096_13568-001,SMLF,IO,DGA^6000030    I22 @T6G_MB_LIB.T6G(SCH_1):PAGE31
   U25 AG68 VSS_AG68 GENOA_SP5-SOCKET6096_13568-001,SMLF,IO,DGA^6000030    I22 @T6G_MB_LIB.T6G(SCH_1):PAGE31
   U25 AG70 VSS_AG70 GENOA_SP5-SOCKET6096_13568-001,SMLF,IO,DGA^6000030    I22 @T6G_MB_LIB.T6G(SCH_1):PAGE31
   U25 AG72 VSS_AG72 GENOA_SP5-SOCKET6096_13568-001,SMLF,IO,DGA^6000030    I22 @T6G_MB_LIB.T6G(SCH_1):PAGE31
   U25 AG75 VSS_AG75 GENOA_SP5-SOCKET6096_13568-001,SMLF,IO,DGA^6000030    I22 @T6G_MB_LIB.T6G(SCH_1):PAGE31
   U25  AH3 VSS_AH3 GENOA_SP5-SOCKET6096_13568-001,SMLF,IO,DGA^6000030    I22 @T6G_MB_LIB.T6G(SCH_1):PAGE31
   U25  AH5 VSS_AH5 GENOA_SP5-SOCKET6096_13568-001,SMLF,IO,DGA^6000030    I22 @T6G_MB_LIB.T6G(SCH_1):PAGE31
   U25  AH8 VSS_AH8 GENOA_SP5-SOCKET6096_13568-001,SMLF,IO,DGA^6000030    I22 @T6G_MB_LIB.T6G(SCH_1):PAGE31
   U25 AH10 VSS_AH10 GENOA_SP5-SOCKET6096_13568-001,SMLF,IO,DGA^6000030    I22 @T6G_MB_LIB.T6G(SCH_1):PAGE31
   U25 AH12 VSS_AH12 GENOA_SP5-SOCKET6096_13568-001,SMLF,IO,DGA^6000030    I22 @T6G_MB_LIB.T6G(SCH_1):PAGE31
   U25 AH15 VSS_AH15 GENOA_SP5-SOCKET6096_13568-001,SMLF,IO,DGA^6000030    I22 @T6G_MB_LIB.T6G(SCH_1):PAGE31
   U25 AH17 VSS_AH17 GENOA_SP5-SOCKET6096_13568-001,SMLF,IO,DGA^6000030    I22 @T6G_MB_LIB.T6G(SCH_1):PAGE31
   U25 AH19 VSS_AH19 GENOA_SP5-SOCKET6096_13568-001,SMLF,IO,DGA^6000030    I22 @T6G_MB_LIB.T6G(SCH_1):PAGE31
   U25 AH23 VSS_AH23 GENOA_SP5-SOCKET6096_13568-001,SMLF,IO,DGA^6000030    I22 @T6G_MB_LIB.T6G(SCH_1):PAGE31
   U25 AH24 VSS_AH24 GENOA_SP5-SOCKET6096_13568-001,SMLF,IO,DGA^6000030    I22 @T6G_MB_LIB.T6G(SCH_1):PAGE31
   U25 AH25 VSS_AH25 GENOA_SP5-SOCKET6096_13568-001,SMLF,IO,DGA^6000030    I22 @T6G_MB_LIB.T6G(SCH_1):PAGE31
   U25 AH26 VSS_AH26 GENOA_SP5-SOCKET6096_13568-001,SMLF,IO,DGA^6000030    I22 @T6G_MB_LIB.T6G(SCH_1):PAGE31
   U25 AH27 VSS_AH27 GENOA_SP5-SOCKET6096_13568-001,SMLF,IO,DGA^6000030    I22 @T6G_MB_LIB.T6G(SCH_1):PAGE31
   U25 AH28 VSS_AH28 GENOA_SP5-SOCKET6096_13568-001,SMLF,IO,DGA^6000030    I22 @T6G_MB_LIB.T6G(SCH_1):PAGE31
   U25 AH29 VSS_AH29 GENOA_SP5-SOCKET6096_13568-001,SMLF,IO,DGA^6000030    I22 @T6G_MB_LIB.T6G(SCH_1):PAGE31
   U25 AH30 VSS_AH30 GENOA_SP5-SOCKET6096_13568-001,SMLF,IO,DGA^6000030    I22 @T6G_MB_LIB.T6G(SCH_1):PAGE31
   U25 AH31 VSS_AH31 GENOA_SP5-SOCKET6096_13568-001,SMLF,IO,DGA^6000030    I22 @T6G_MB_LIB.T6G(SCH_1):PAGE31
   U25 AH32 VSS_AH32 GENOA_SP5-SOCKET6096_13568-001,SMLF,IO,DGA^6000030    I22 @T6G_MB_LIB.T6G(SCH_1):PAGE31
   U25 AH34 VSS_AH34 GENOA_SP5-SOCKET6096_13568-001,SMLF,IO,DGA^6000030    I22 @T6G_MB_LIB.T6G(SCH_1):PAGE31
   U25 AH37 VSS_AH37 GENOA_SP5-SOCKET6096_13568-001,SMLF,IO,DGA^6000030    I22 @T6G_MB_LIB.T6G(SCH_1):PAGE31
   U25 AH39 VSS_AH39 GENOA_SP5-SOCKET6096_13568-001,SMLF,IO,DGA^6000030    I22 @T6G_MB_LIB.T6G(SCH_1):PAGE31
   U25 AH42 VSS_AH42 GENOA_SP5-SOCKET6096_13568-001,SMLF,IO,DGA^6000030    I22 @T6G_MB_LIB.T6G(SCH_1):PAGE31
   U25 AH43 VSS_AH43 GENOA_SP5-SOCKET6096_13568-001,SMLF,IO,DGA^6000030    I22 @T6G_MB_LIB.T6G(SCH_1):PAGE31
   U25 AH44 VSS_AH44 GENOA_SP5-SOCKET6096_13568-001,SMLF,IO,DGA^6000030    I22 @T6G_MB_LIB.T6G(SCH_1):PAGE31
   U25 AH45 VSS_AH45 GENOA_SP5-SOCKET6096_13568-001,SMLF,IO,DGA^6000030    I22 @T6G_MB_LIB.T6G(SCH_1):PAGE31
   U25 AH46 VSS_AH46 GENOA_SP5-SOCKET6096_13568-001,SMLF,IO,DGA^6000030    I22 @T6G_MB_LIB.T6G(SCH_1):PAGE31
   U25 AH47 VSS_AH47 GENOA_SP5-SOCKET6096_13568-001,SMLF,IO,DGA^6000030    I22 @T6G_MB_LIB.T6G(SCH_1):PAGE31
   U25 AH48 VSS_AH48 GENOA_SP5-SOCKET6096_13568-001,SMLF,IO,DGA^6000030    I22 @T6G_MB_LIB.T6G(SCH_1):PAGE31
   U25 AH49 VSS_AH49 GENOA_SP5-SOCKET6096_13568-001,SMLF,IO,DGA^6000030    I22 @T6G_MB_LIB.T6G(SCH_1):PAGE31
   U25 AH50 VSS_AH50 GENOA_SP5-SOCKET6096_13568-001,SMLF,IO,DGA^6000030    I22 @T6G_MB_LIB.T6G(SCH_1):PAGE31
   U25 AH51 VSS_AH51 GENOA_SP5-SOCKET6096_13568-001,SMLF,IO,DGA^6000030    I22 @T6G_MB_LIB.T6G(SCH_1):PAGE31
   U25 AH52 VSS_AH52 GENOA_SP5-SOCKET6096_13568-001,SMLF,IO,DGA^6000030    I22 @T6G_MB_LIB.T6G(SCH_1):PAGE31
   U25 AH53 VSS_AH53 GENOA_SP5-SOCKET6096_13568-001,SMLF,IO,DGA^6000030    I22 @T6G_MB_LIB.T6G(SCH_1):PAGE31
   U25 AH57 VSS_AH57 GENOA_SP5-SOCKET6096_13568-001,SMLF,IO,DGA^6000030    I22 @T6G_MB_LIB.T6G(SCH_1):PAGE31
   U25 AH59 VSS_AH59 GENOA_SP5-SOCKET6096_13568-001,SMLF,IO,DGA^6000030    I22 @T6G_MB_LIB.T6G(SCH_1):PAGE31
   U25 AH61 VSS_AH61 GENOA_SP5-SOCKET6096_13568-001,SMLF,IO,DGA^6000030    I22 @T6G_MB_LIB.T6G(SCH_1):PAGE31
   U25 AH64 VSS_AH64 GENOA_SP5-SOCKET6096_13568-001,SMLF,IO,DGA^6000030    I22 @T6G_MB_LIB.T6G(SCH_1):PAGE31
   U25 AH66 VSS_AH66 GENOA_SP5-SOCKET6096_13568-001,SMLF,IO,DGA^6000030    I22 @T6G_MB_LIB.T6G(SCH_1):PAGE31
   U25 AH68 VSS_AH68 GENOA_SP5-SOCKET6096_13568-001,SMLF,IO,DGA^6000030    I22 @T6G_MB_LIB.T6G(SCH_1):PAGE31
   U25 AH71 VSS_AH71 GENOA_SP5-SOCKET6096_13568-001,SMLF,IO,DGA^6000030    I22 @T6G_MB_LIB.T6G(SCH_1):PAGE31
   U25 AH73 VSS_AH73 GENOA_SP5-SOCKET6096_13568-001,SMLF,IO,DGA^6000030    I22 @T6G_MB_LIB.T6G(SCH_1):PAGE31
   U25  AJ1 VSS_AJ1 GENOA_SP5-SOCKET6096_13568-001,SMLF,IO,DGA^6000030    I22 @T6G_MB_LIB.T6G(SCH_1):PAGE31
   U25  AJ6 VSS_AJ6 GENOA_SP5-SOCKET6096_13568-001,SMLF,IO,DGA^6000030    I22 @T6G_MB_LIB.T6G(SCH_1):PAGE31
   U25  AJ8 VSS_AJ8 GENOA_SP5-SOCKET6096_13568-001,SMLF,IO,DGA^6000030    I22 @T6G_MB_LIB.T6G(SCH_1):PAGE31
   U25 AJ15 VSS_AJ15 GENOA_SP5-SOCKET6096_13568-001,SMLF,IO,DGA^6000030    I22 @T6G_MB_LIB.T6G(SCH_1):PAGE31
   U25 AJ20 VSS_AJ20 GENOA_SP5-SOCKET6096_13568-001,SMLF,IO,DGA^6000030    I22 @T6G_MB_LIB.T6G(SCH_1):PAGE31
   U25 AJ22 VSS_AJ22 GENOA_SP5-SOCKET6096_13568-001,SMLF,IO,DGA^6000030    I22 @T6G_MB_LIB.T6G(SCH_1):PAGE31
   U25 AJ25 VSS_AJ25 GENOA_SP5-SOCKET6096_13568-001,SMLF,IO,DGA^6000030    I22 @T6G_MB_LIB.T6G(SCH_1):PAGE31
   U25 AJ28 VSS_AJ28 GENOA_SP5-SOCKET6096_13568-001,SMLF,IO,DGA^6000030    I22 @T6G_MB_LIB.T6G(SCH_1):PAGE31
   U25 AJ31 VSS_AJ31 GENOA_SP5-SOCKET6096_13568-001,SMLF,IO,DGA^6000030    I22 @T6G_MB_LIB.T6G(SCH_1):PAGE31
   U25 AJ34 VSS_AJ34 GENOA_SP5-SOCKET6096_13568-001,SMLF,IO,DGA^6000030    I22 @T6G_MB_LIB.T6G(SCH_1):PAGE31
   U25 AJ35 VSS_AJ35 GENOA_SP5-SOCKET6096_13568-001,SMLF,IO,DGA^6000030    I22 @T6G_MB_LIB.T6G(SCH_1):PAGE31
   U25 AJ36 VSS_AJ36 GENOA_SP5-SOCKET6096_13568-001,SMLF,IO,DGA^6000030    I22 @T6G_MB_LIB.T6G(SCH_1):PAGE31
   U25 AJ40 VSS_AJ40 GENOA_SP5-SOCKET6096_13568-001,SMLF,IO,DGA^6000030    I22 @T6G_MB_LIB.T6G(SCH_1):PAGE31
   U25 AJ41 VSS_AJ41 GENOA_SP5-SOCKET6096_13568-001,SMLF,IO,DGA^6000030    I22 @T6G_MB_LIB.T6G(SCH_1):PAGE31
   U25 AJ42 VSS_AJ42 GENOA_SP5-SOCKET6096_13568-001,SMLF,IO,DGA^6000030    I22 @T6G_MB_LIB.T6G(SCH_1):PAGE31
   U25 AJ45 VSS_AJ45 GENOA_SP5-SOCKET6096_13568-001,SMLF,IO,DGA^6000030    I22 @T6G_MB_LIB.T6G(SCH_1):PAGE31
   U25 AJ48 VSS_AJ48 GENOA_SP5-SOCKET6096_13568-001,SMLF,IO,DGA^6000030    I22 @T6G_MB_LIB.T6G(SCH_1):PAGE31
   U25 AJ51 VSS_AJ51 GENOA_SP5-SOCKET6096_13568-001,SMLF,IO,DGA^6000030    I22 @T6G_MB_LIB.T6G(SCH_1):PAGE31
   U25 AJ54 VSS_AJ54 GENOA_SP5-SOCKET6096_13568-001,SMLF,IO,DGA^6000030    I22 @T6G_MB_LIB.T6G(SCH_1):PAGE31
   U25 AJ56 VSS_AJ56 GENOA_SP5-SOCKET6096_13568-001,SMLF,IO,DGA^6000030    I22 @T6G_MB_LIB.T6G(SCH_1):PAGE31
   U25 AJ61 VSS_AJ61 GENOA_SP5-SOCKET6096_13568-001,SMLF,IO,DGA^6000030    I22 @T6G_MB_LIB.T6G(SCH_1):PAGE31
   U25 AJ63 VSS_AJ63 GENOA_SP5-SOCKET6096_13568-001,SMLF,IO,DGA^6000030    I22 @T6G_MB_LIB.T6G(SCH_1):PAGE31
   U25 AJ68 VSS_AJ68 GENOA_SP5-SOCKET6096_13568-001,SMLF,IO,DGA^6000030    I22 @T6G_MB_LIB.T6G(SCH_1):PAGE31
   U25 AJ70 VSS_AJ70 GENOA_SP5-SOCKET6096_13568-001,SMLF,IO,DGA^6000030    I22 @T6G_MB_LIB.T6G(SCH_1):PAGE31
   U25 AJ75 VSS_AJ75 GENOA_SP5-SOCKET6096_13568-001,SMLF,IO,DGA^6000030    I22 @T6G_MB_LIB.T6G(SCH_1):PAGE31
   U25  AK3 VSS_AK3 GENOA_SP5-SOCKET6096_13568-001,SMLF,IO,DGA^6000030    I22 @T6G_MB_LIB.T6G(SCH_1):PAGE31
   U25  AK5 VSS_AK5 GENOA_SP5-SOCKET6096_13568-001,SMLF,IO,DGA^6000030    I22 @T6G_MB_LIB.T6G(SCH_1):PAGE31
   U25  AK8 VSS_AK8 GENOA_SP5-SOCKET6096_13568-001,SMLF,IO,DGA^6000030    I22 @T6G_MB_LIB.T6G(SCH_1):PAGE31
   U25 AK10 VSS_AK10 GENOA_SP5-SOCKET6096_13568-001,SMLF,IO,DGA^6000030    I22 @T6G_MB_LIB.T6G(SCH_1):PAGE31
   U25 AK12 VSS_AK12 GENOA_SP5-SOCKET6096_13568-001,SMLF,IO,DGA^6000030    I22 @T6G_MB_LIB.T6G(SCH_1):PAGE31
   U25 AK15 VSS_AK15 GENOA_SP5-SOCKET6096_13568-001,SMLF,IO,DGA^6000030    I22 @T6G_MB_LIB.T6G(SCH_1):PAGE31
   U25 AK17 VSS_AK17 GENOA_SP5-SOCKET6096_13568-001,SMLF,IO,DGA^6000030    I22 @T6G_MB_LIB.T6G(SCH_1):PAGE31
   U25 AK19 VSS_AK19 GENOA_SP5-SOCKET6096_13568-001,SMLF,IO,DGA^6000030    I22 @T6G_MB_LIB.T6G(SCH_1):PAGE31
   U25 AK22 VSS_AK22 GENOA_SP5-SOCKET6096_13568-001,SMLF,IO,DGA^6000030    I22 @T6G_MB_LIB.T6G(SCH_1):PAGE31
   U25 AK25 VSS_AK25 GENOA_SP5-SOCKET6096_13568-001,SMLF,IO,DGA^6000030    I22 @T6G_MB_LIB.T6G(SCH_1):PAGE31
   U25 AK28 VSS_AK28 GENOA_SP5-SOCKET6096_13568-001,SMLF,IO,DGA^6000030    I22 @T6G_MB_LIB.T6G(SCH_1):PAGE31
   U25 AK31 VSS_AK31 GENOA_SP5-SOCKET6096_13568-001,SMLF,IO,DGA^6000030    I22 @T6G_MB_LIB.T6G(SCH_1):PAGE31
   U25 AK34 VSS_AK34 GENOA_SP5-SOCKET6096_13568-001,SMLF,IO,DGA^6000030    I22 @T6G_MB_LIB.T6G(SCH_1):PAGE31
   U25 AK37 VSS_AK37 GENOA_SP5-SOCKET6096_13568-001,SMLF,IO,DGA^6000030    I22 @T6G_MB_LIB.T6G(SCH_1):PAGE31
   U25 AK39 VSS_AK39 GENOA_SP5-SOCKET6096_13568-001,SMLF,IO,DGA^6000030    I22 @T6G_MB_LIB.T6G(SCH_1):PAGE31
   U25 AK42 VSS_AK42 GENOA_SP5-SOCKET6096_13568-001,SMLF,IO,DGA^6000030    I22 @T6G_MB_LIB.T6G(SCH_1):PAGE31
   U25 AK45 VSS_AK45 GENOA_SP5-SOCKET6096_13568-001,SMLF,IO,DGA^6000030    I22 @T6G_MB_LIB.T6G(SCH_1):PAGE31
   U25 AK48 VSS_AK48 GENOA_SP5-SOCKET6096_13568-001,SMLF,IO,DGA^6000030    I22 @T6G_MB_LIB.T6G(SCH_1):PAGE31
   U25 AK51 VSS_AK51 GENOA_SP5-SOCKET6096_13568-001,SMLF,IO,DGA^6000030    I22 @T6G_MB_LIB.T6G(SCH_1):PAGE31
   U25 AK54 VSS_AK54 GENOA_SP5-SOCKET6096_13568-001,SMLF,IO,DGA^6000030    I22 @T6G_MB_LIB.T6G(SCH_1):PAGE31
   U25 AK57 VSS_AK57 GENOA_SP5-SOCKET6096_13568-001,SMLF,IO,DGA^6000030    I22 @T6G_MB_LIB.T6G(SCH_1):PAGE31
   U25 AK59 VSS_AK59 GENOA_SP5-SOCKET6096_13568-001,SMLF,IO,DGA^6000030    I22 @T6G_MB_LIB.T6G(SCH_1):PAGE31
   U25 AK61 VSS_AK61 GENOA_SP5-SOCKET6096_13568-001,SMLF,IO,DGA^6000030    I22 @T6G_MB_LIB.T6G(SCH_1):PAGE31
   U25 AK64 VSS_AK64 GENOA_SP5-SOCKET6096_13568-001,SMLF,IO,DGA^6000030    I22 @T6G_MB_LIB.T6G(SCH_1):PAGE31
   U25 AK66 VSS_AK66 GENOA_SP5-SOCKET6096_13568-001,SMLF,IO,DGA^6000030    I22 @T6G_MB_LIB.T6G(SCH_1):PAGE31
   U25 AK68 VSS_AK68 GENOA_SP5-SOCKET6096_13568-001,SMLF,IO,DGA^6000030    I22 @T6G_MB_LIB.T6G(SCH_1):PAGE31
   U25 AK71 VSS_AK71 GENOA_SP5-SOCKET6096_13568-001,SMLF,IO,DGA^6000030    I22 @T6G_MB_LIB.T6G(SCH_1):PAGE31
   U25 AK73 VSS_AK73 GENOA_SP5-SOCKET6096_13568-001,SMLF,IO,DGA^6000030    I22 @T6G_MB_LIB.T6G(SCH_1):PAGE31
   U25  AL1 VSS_AL1 GENOA_SP5-SOCKET6096_13568-001,SMLF,IO,DGA^6000030    I22 @T6G_MB_LIB.T6G(SCH_1):PAGE31
   U25  AL4 VSS_AL4 GENOA_SP5-SOCKET6096_13568-001,SMLF,IO,DGA^6000030    I22 @T6G_MB_LIB.T6G(SCH_1):PAGE31
   U25  AL6 VSS_AL6 GENOA_SP5-SOCKET6096_13568-001,SMLF,IO,DGA^6000030    I22 @T6G_MB_LIB.T6G(SCH_1):PAGE31
   U25  AL8 VSS_AL8 GENOA_SP5-SOCKET6096_13568-001,SMLF,IO,DGA^6000030    I22 @T6G_MB_LIB.T6G(SCH_1):PAGE31
   U25 AL11 VSS_AL11 GENOA_SP5-SOCKET6096_13568-001,SMLF,IO,DGA^6000030    I22 @T6G_MB_LIB.T6G(SCH_1):PAGE31
   U25 AL13 VSS_AL13 GENOA_SP5-SOCKET6096_13568-001,SMLF,IO,DGA^6000030    I22 @T6G_MB_LIB.T6G(SCH_1):PAGE31
   U25 AL15 VSS_AL15 GENOA_SP5-SOCKET6096_13568-001,SMLF,IO,DGA^6000030    I22 @T6G_MB_LIB.T6G(SCH_1):PAGE31
   U25 AL18 VSS_AL18 GENOA_SP5-SOCKET6096_13568-001,SMLF,IO,DGA^6000030    I22 @T6G_MB_LIB.T6G(SCH_1):PAGE31
   U25 AL20 VSS_AL20 GENOA_SP5-SOCKET6096_13568-001,SMLF,IO,DGA^6000030    I22 @T6G_MB_LIB.T6G(SCH_1):PAGE31
   U25 AL22 VSS_AL22 GENOA_SP5-SOCKET6096_13568-001,SMLF,IO,DGA^6000030    I22 @T6G_MB_LIB.T6G(SCH_1):PAGE31
   U25 AL25 VSS_AL25 GENOA_SP5-SOCKET6096_13568-001,SMLF,IO,DGA^6000030    I22 @T6G_MB_LIB.T6G(SCH_1):PAGE31
   U25 AL28 VSS_AL28 GENOA_SP5-SOCKET6096_13568-001,SMLF,IO,DGA^6000030    I22 @T6G_MB_LIB.T6G(SCH_1):PAGE31
   U25 AL31 VSS_AL31 GENOA_SP5-SOCKET6096_13568-001,SMLF,IO,DGA^6000030    I22 @T6G_MB_LIB.T6G(SCH_1):PAGE31
   U25 AL34 VSS_AL34 GENOA_SP5-SOCKET6096_13568-001,SMLF,IO,DGA^6000030    I22 @T6G_MB_LIB.T6G(SCH_1):PAGE31
   U25 AL42 VSS_AL42 GENOA_SP5-SOCKET6096_13568-001,SMLF,IO,DGA^6000030    I22 @T6G_MB_LIB.T6G(SCH_1):PAGE31
   U25 AL45 VSS_AL45 GENOA_SP5-SOCKET6096_13568-001,SMLF,IO,DGA^6000030    I22 @T6G_MB_LIB.T6G(SCH_1):PAGE31
   U25 AL48 VSS_AL48 GENOA_SP5-SOCKET6096_13568-001,SMLF,IO,DGA^6000030    I22 @T6G_MB_LIB.T6G(SCH_1):PAGE31
   U25 AL51 VSS_AL51 GENOA_SP5-SOCKET6096_13568-001,SMLF,IO,DGA^6000030    I22 @T6G_MB_LIB.T6G(SCH_1):PAGE31
   U25 AL54 VSS_AL54 GENOA_SP5-SOCKET6096_13568-001,SMLF,IO,DGA^6000030    I22 @T6G_MB_LIB.T6G(SCH_1):PAGE31
   U25 AL56 VSS_AL56 GENOA_SP5-SOCKET6096_13568-001,SMLF,IO,DGA^6000030    I22 @T6G_MB_LIB.T6G(SCH_1):PAGE31
   U25 AL58 VSS_AL58 GENOA_SP5-SOCKET6096_13568-001,SMLF,IO,DGA^6000030    I22 @T6G_MB_LIB.T6G(SCH_1):PAGE31
   U25 AL61 VSS_AL61 GENOA_SP5-SOCKET6096_13568-001,SMLF,IO,DGA^6000030    I22 @T6G_MB_LIB.T6G(SCH_1):PAGE31
   U25 AL63 VSS_AL63 GENOA_SP5-SOCKET6096_13568-001,SMLF,IO,DGA^6000030    I22 @T6G_MB_LIB.T6G(SCH_1):PAGE31
   U25 AL65 VSS_AL65 GENOA_SP5-SOCKET6096_13568-001,SMLF,IO,DGA^6000030    I22 @T6G_MB_LIB.T6G(SCH_1):PAGE31
   U25 AL68 VSS_AL68 GENOA_SP5-SOCKET6096_13568-001,SMLF,IO,DGA^6000030    I22 @T6G_MB_LIB.T6G(SCH_1):PAGE31
   U25 AL70 VSS_AL70 GENOA_SP5-SOCKET6096_13568-001,SMLF,IO,DGA^6000030    I22 @T6G_MB_LIB.T6G(SCH_1):PAGE31
   U25 AL72 VSS_AL72 GENOA_SP5-SOCKET6096_13568-001,SMLF,IO,DGA^6000030    I22 @T6G_MB_LIB.T6G(SCH_1):PAGE31
   U25 AL75 VSS_AL75 GENOA_SP5-SOCKET6096_13568-001,SMLF,IO,DGA^6000030    I22 @T6G_MB_LIB.T6G(SCH_1):PAGE31
   U25  AM3 VSS_AM3 GENOA_SP5-SOCKET6096_13568-001,SMLF,IO,DGA^6000030    I22 @T6G_MB_LIB.T6G(SCH_1):PAGE31
   U25  AM8 VSS_AM8 GENOA_SP5-SOCKET6096_13568-001,SMLF,IO,DGA^6000030    I22 @T6G_MB_LIB.T6G(SCH_1):PAGE31
   U25 AM10 VSS_AM10 GENOA_SP5-SOCKET6096_13568-001,SMLF,IO,DGA^6000030    I22 @T6G_MB_LIB.T6G(SCH_1):PAGE31
   U25 AM15 VSS_AM15 GENOA_SP5-SOCKET6096_13568-001,SMLF,IO,DGA^6000030    I22 @T6G_MB_LIB.T6G(SCH_1):PAGE31
   U25 AM17 VSS_AM17 GENOA_SP5-SOCKET6096_13568-001,SMLF,IO,DGA^6000030    I22 @T6G_MB_LIB.T6G(SCH_1):PAGE31
   U25 AM23 VSS_AM23 GENOA_SP5-SOCKET6096_13568-001,SMLF,IO,DGA^6000030    I22 @T6G_MB_LIB.T6G(SCH_1):PAGE31
   U25 AM24 VSS_AM24 GENOA_SP5-SOCKET6096_13568-001,SMLF,IO,DGA^6000030    I22 @T6G_MB_LIB.T6G(SCH_1):PAGE31
   U25 AM25 VSS_AM25 GENOA_SP5-SOCKET6096_13568-001,SMLF,IO,DGA^6000030    I22 @T6G_MB_LIB.T6G(SCH_1):PAGE31
   U25 AM26 VSS_AM26 GENOA_SP5-SOCKET6096_13568-001,SMLF,IO,DGA^6000030    I22 @T6G_MB_LIB.T6G(SCH_1):PAGE31
   U25 AM27 VSS_AM27 GENOA_SP5-SOCKET6096_13568-001,SMLF,IO,DGA^6000030    I22 @T6G_MB_LIB.T6G(SCH_1):PAGE31
   U25 AM28 VSS_AM28 GENOA_SP5-SOCKET6096_13568-001,SMLF,IO,DGA^6000030    I22 @T6G_MB_LIB.T6G(SCH_1):PAGE31
   U25 AM29 VSS_AM29 GENOA_SP5-SOCKET6096_13568-001,SMLF,IO,DGA^6000030    I22 @T6G_MB_LIB.T6G(SCH_1):PAGE31
   U25 AM30 VSS_AM30 GENOA_SP5-SOCKET6096_13568-001,SMLF,IO,DGA^6000030    I22 @T6G_MB_LIB.T6G(SCH_1):PAGE31
   U25 AM31 VSS_AM31 GENOA_SP5-SOCKET6096_13568-001,SMLF,IO,DGA^6000030    I22 @T6G_MB_LIB.T6G(SCH_1):PAGE31
   U25 AM32 VSS_AM32 GENOA_SP5-SOCKET6096_13568-001,SMLF,IO,DGA^6000030    I22 @T6G_MB_LIB.T6G(SCH_1):PAGE31
   U25 AM33 VSS_AM33 GENOA_SP5-SOCKET6096_13568-001,SMLF,IO,DGA^6000030    I22 @T6G_MB_LIB.T6G(SCH_1):PAGE31
   U25 AM34 VSS_AM34 GENOA_SP5-SOCKET6096_13568-001,SMLF,IO,DGA^6000030    I22 @T6G_MB_LIB.T6G(SCH_1):PAGE31
   U25 AM39 VSS_AM39 GENOA_SP5-SOCKET6096_13568-001,SMLF,IO,DGA^6000030    I22 @T6G_MB_LIB.T6G(SCH_1):PAGE31
   U25 AM42 VSS_AM42 GENOA_SP5-SOCKET6096_13568-001,SMLF,IO,DGA^6000030    I23 @T6G_MB_LIB.T6G(SCH_1):PAGE31
   U25 AM43 VSS_AM43 GENOA_SP5-SOCKET6096_13568-001,SMLF,IO,DGA^6000030    I23 @T6G_MB_LIB.T6G(SCH_1):PAGE31
   U25 AM44 VSS_AM44 GENOA_SP5-SOCKET6096_13568-001,SMLF,IO,DGA^6000030    I23 @T6G_MB_LIB.T6G(SCH_1):PAGE31
   U25 AM45 VSS_AM45 GENOA_SP5-SOCKET6096_13568-001,SMLF,IO,DGA^6000030    I23 @T6G_MB_LIB.T6G(SCH_1):PAGE31
   U25 AM46 VSS_AM46 GENOA_SP5-SOCKET6096_13568-001,SMLF,IO,DGA^6000030    I23 @T6G_MB_LIB.T6G(SCH_1):PAGE31
   U25 AM47 VSS_AM47 GENOA_SP5-SOCKET6096_13568-001,SMLF,IO,DGA^6000030    I23 @T6G_MB_LIB.T6G(SCH_1):PAGE31
   U25 AM48 VSS_AM48 GENOA_SP5-SOCKET6096_13568-001,SMLF,IO,DGA^6000030    I23 @T6G_MB_LIB.T6G(SCH_1):PAGE31
   U25 AM49 VSS_AM49 GENOA_SP5-SOCKET6096_13568-001,SMLF,IO,DGA^6000030    I23 @T6G_MB_LIB.T6G(SCH_1):PAGE31
   U25 AM50 VSS_AM50 GENOA_SP5-SOCKET6096_13568-001,SMLF,IO,DGA^6000030    I23 @T6G_MB_LIB.T6G(SCH_1):PAGE31
   U25 AM51 VSS_AM51 GENOA_SP5-SOCKET6096_13568-001,SMLF,IO,DGA^6000030    I23 @T6G_MB_LIB.T6G(SCH_1):PAGE31
   U25 AM52 VSS_AM52 GENOA_SP5-SOCKET6096_13568-001,SMLF,IO,DGA^6000030    I23 @T6G_MB_LIB.T6G(SCH_1):PAGE31
   U25 AM53 VSS_AM53 GENOA_SP5-SOCKET6096_13568-001,SMLF,IO,DGA^6000030    I23 @T6G_MB_LIB.T6G(SCH_1):PAGE31
   U25 AM59 VSS_AM59 GENOA_SP5-SOCKET6096_13568-001,SMLF,IO,DGA^6000030    I23 @T6G_MB_LIB.T6G(SCH_1):PAGE31
   U25 AM61 VSS_AM61 GENOA_SP5-SOCKET6096_13568-001,SMLF,IO,DGA^6000030    I23 @T6G_MB_LIB.T6G(SCH_1):PAGE31
   U25 AM66 VSS_AM66 GENOA_SP5-SOCKET6096_13568-001,SMLF,IO,DGA^6000030    I23 @T6G_MB_LIB.T6G(SCH_1):PAGE31
   U25 AM68 VSS_AM68 GENOA_SP5-SOCKET6096_13568-001,SMLF,IO,DGA^6000030    I23 @T6G_MB_LIB.T6G(SCH_1):PAGE31
   U25 AM73 VSS_AM73 GENOA_SP5-SOCKET6096_13568-001,SMLF,IO,DGA^6000030    I23 @T6G_MB_LIB.T6G(SCH_1):PAGE31
   U25  AN1 VSS_AN1 GENOA_SP5-SOCKET6096_13568-001,SMLF,IO,DGA^6000030    I23 @T6G_MB_LIB.T6G(SCH_1):PAGE31
   U25  AN4 VSS_AN4 GENOA_SP5-SOCKET6096_13568-001,SMLF,IO,DGA^6000030    I23 @T6G_MB_LIB.T6G(SCH_1):PAGE31
   U25  AN6 VSS_AN6 GENOA_SP5-SOCKET6096_13568-001,SMLF,IO,DGA^6000030    I23 @T6G_MB_LIB.T6G(SCH_1):PAGE31
   U25  AN8 VSS_AN8 GENOA_SP5-SOCKET6096_13568-001,SMLF,IO,DGA^6000030    I23 @T6G_MB_LIB.T6G(SCH_1):PAGE31
   U25 AN11 VSS_AN11 GENOA_SP5-SOCKET6096_13568-001,SMLF,IO,DGA^6000030    I23 @T6G_MB_LIB.T6G(SCH_1):PAGE31
   U25 AN13 VSS_AN13 GENOA_SP5-SOCKET6096_13568-001,SMLF,IO,DGA^6000030    I23 @T6G_MB_LIB.T6G(SCH_1):PAGE31
   U25 AN15 VSS_AN15 GENOA_SP5-SOCKET6096_13568-001,SMLF,IO,DGA^6000030    I23 @T6G_MB_LIB.T6G(SCH_1):PAGE31
   U25 AN18 VSS_AN18 GENOA_SP5-SOCKET6096_13568-001,SMLF,IO,DGA^6000030    I23 @T6G_MB_LIB.T6G(SCH_1):PAGE31
   U25 AN22 VSS_AN22 GENOA_SP5-SOCKET6096_13568-001,SMLF,IO,DGA^6000030    I23 @T6G_MB_LIB.T6G(SCH_1):PAGE31
   U25 AN25 VSS_AN25 GENOA_SP5-SOCKET6096_13568-001,SMLF,IO,DGA^6000030    I23 @T6G_MB_LIB.T6G(SCH_1):PAGE31
   U25 AN28 VSS_AN28 GENOA_SP5-SOCKET6096_13568-001,SMLF,IO,DGA^6000030    I23 @T6G_MB_LIB.T6G(SCH_1):PAGE31
   U25 AN31 VSS_AN31 GENOA_SP5-SOCKET6096_13568-001,SMLF,IO,DGA^6000030    I23 @T6G_MB_LIB.T6G(SCH_1):PAGE31
   U25 AN34 VSS_AN34 GENOA_SP5-SOCKET6096_13568-001,SMLF,IO,DGA^6000030    I23 @T6G_MB_LIB.T6G(SCH_1):PAGE31
   U25 AN35 VSS_AN35 GENOA_SP5-SOCKET6096_13568-001,SMLF,IO,DGA^6000030    I23 @T6G_MB_LIB.T6G(SCH_1):PAGE31
   U25 AN36 VSS_AN36 GENOA_SP5-SOCKET6096_13568-001,SMLF,IO,DGA^6000030    I23 @T6G_MB_LIB.T6G(SCH_1):PAGE31
   U25 AN40 VSS_AN40 GENOA_SP5-SOCKET6096_13568-001,SMLF,IO,DGA^6000030    I23 @T6G_MB_LIB.T6G(SCH_1):PAGE31
   U25 AN41 VSS_AN41 GENOA_SP5-SOCKET6096_13568-001,SMLF,IO,DGA^6000030    I23 @T6G_MB_LIB.T6G(SCH_1):PAGE31
   U25 AN42 VSS_AN42 GENOA_SP5-SOCKET6096_13568-001,SMLF,IO,DGA^6000030    I23 @T6G_MB_LIB.T6G(SCH_1):PAGE31
   U25 AN45 VSS_AN45 GENOA_SP5-SOCKET6096_13568-001,SMLF,IO,DGA^6000030    I23 @T6G_MB_LIB.T6G(SCH_1):PAGE31
   U25 AN48 VSS_AN48 GENOA_SP5-SOCKET6096_13568-001,SMLF,IO,DGA^6000030    I23 @T6G_MB_LIB.T6G(SCH_1):PAGE31
   U25 AN51 VSS_AN51 GENOA_SP5-SOCKET6096_13568-001,SMLF,IO,DGA^6000030    I23 @T6G_MB_LIB.T6G(SCH_1):PAGE31
   U25 AN54 VSS_AN54 GENOA_SP5-SOCKET6096_13568-001,SMLF,IO,DGA^6000030    I23 @T6G_MB_LIB.T6G(SCH_1):PAGE31
   U25 AN56 VSS_AN56 GENOA_SP5-SOCKET6096_13568-001,SMLF,IO,DGA^6000030    I23 @T6G_MB_LIB.T6G(SCH_1):PAGE31
   U25 AN58 VSS_AN58 GENOA_SP5-SOCKET6096_13568-001,SMLF,IO,DGA^6000030    I23 @T6G_MB_LIB.T6G(SCH_1):PAGE31
   U25 AN61 VSS_AN61 GENOA_SP5-SOCKET6096_13568-001,SMLF,IO,DGA^6000030    I23 @T6G_MB_LIB.T6G(SCH_1):PAGE31
   U25 AN63 VSS_AN63 GENOA_SP5-SOCKET6096_13568-001,SMLF,IO,DGA^6000030    I23 @T6G_MB_LIB.T6G(SCH_1):PAGE31
   U25 AN65 VSS_AN65 GENOA_SP5-SOCKET6096_13568-001,SMLF,IO,DGA^6000030    I23 @T6G_MB_LIB.T6G(SCH_1):PAGE31
   U25 AN68 VSS_AN68 GENOA_SP5-SOCKET6096_13568-001,SMLF,IO,DGA^6000030    I23 @T6G_MB_LIB.T6G(SCH_1):PAGE31
   U25 AN70 VSS_AN70 GENOA_SP5-SOCKET6096_13568-001,SMLF,IO,DGA^6000030    I23 @T6G_MB_LIB.T6G(SCH_1):PAGE31
   U25 AN72 VSS_AN72 GENOA_SP5-SOCKET6096_13568-001,SMLF,IO,DGA^6000030    I23 @T6G_MB_LIB.T6G(SCH_1):PAGE31
   U25 AN75 VSS_AN75 GENOA_SP5-SOCKET6096_13568-001,SMLF,IO,DGA^6000030    I23 @T6G_MB_LIB.T6G(SCH_1):PAGE31
   U25  AP3 VSS_AP3 GENOA_SP5-SOCKET6096_13568-001,SMLF,IO,DGA^6000030    I23 @T6G_MB_LIB.T6G(SCH_1):PAGE31
   U25  AP5 VSS_AP5 GENOA_SP5-SOCKET6096_13568-001,SMLF,IO,DGA^6000030    I23 @T6G_MB_LIB.T6G(SCH_1):PAGE31
   U25  AP8 VSS_AP8 GENOA_SP5-SOCKET6096_13568-001,SMLF,IO,DGA^6000030    I23 @T6G_MB_LIB.T6G(SCH_1):PAGE31
   U25 AP10 VSS_AP10 GENOA_SP5-SOCKET6096_13568-001,SMLF,IO,DGA^6000030    I23 @T6G_MB_LIB.T6G(SCH_1):PAGE31
   U25 AP12 VSS_AP12 GENOA_SP5-SOCKET6096_13568-001,SMLF,IO,DGA^6000030    I23 @T6G_MB_LIB.T6G(SCH_1):PAGE31
   U25 AP15 VSS_AP15 GENOA_SP5-SOCKET6096_13568-001,SMLF,IO,DGA^6000030    I23 @T6G_MB_LIB.T6G(SCH_1):PAGE31
   U25 AP17 VSS_AP17 GENOA_SP5-SOCKET6096_13568-001,SMLF,IO,DGA^6000030    I23 @T6G_MB_LIB.T6G(SCH_1):PAGE31
   U25 AP19 VSS_AP19 GENOA_SP5-SOCKET6096_13568-001,SMLF,IO,DGA^6000030    I23 @T6G_MB_LIB.T6G(SCH_1):PAGE31
   U25 AP22 VSS_AP22 GENOA_SP5-SOCKET6096_13568-001,SMLF,IO,DGA^6000030    I23 @T6G_MB_LIB.T6G(SCH_1):PAGE31
   U25 AP25 VSS_AP25 GENOA_SP5-SOCKET6096_13568-001,SMLF,IO,DGA^6000030    I23 @T6G_MB_LIB.T6G(SCH_1):PAGE31
   U25 AP28 VSS_AP28 GENOA_SP5-SOCKET6096_13568-001,SMLF,IO,DGA^6000030    I23 @T6G_MB_LIB.T6G(SCH_1):PAGE31
   U25 AP31 VSS_AP31 GENOA_SP5-SOCKET6096_13568-001,SMLF,IO,DGA^6000030    I23 @T6G_MB_LIB.T6G(SCH_1):PAGE31
   U25 AP34 VSS_AP34 GENOA_SP5-SOCKET6096_13568-001,SMLF,IO,DGA^6000030    I23 @T6G_MB_LIB.T6G(SCH_1):PAGE31
   U25 AP37 VSS_AP37 GENOA_SP5-SOCKET6096_13568-001,SMLF,IO,DGA^6000030    I23 @T6G_MB_LIB.T6G(SCH_1):PAGE31
   U25 AP39 VSS_AP39 GENOA_SP5-SOCKET6096_13568-001,SMLF,IO,DGA^6000030    I23 @T6G_MB_LIB.T6G(SCH_1):PAGE31
   U25 AP42 VSS_AP42 GENOA_SP5-SOCKET6096_13568-001,SMLF,IO,DGA^6000030    I23 @T6G_MB_LIB.T6G(SCH_1):PAGE31
   U25 AP45 VSS_AP45 GENOA_SP5-SOCKET6096_13568-001,SMLF,IO,DGA^6000030    I23 @T6G_MB_LIB.T6G(SCH_1):PAGE31
   U25 AP48 VSS_AP48 GENOA_SP5-SOCKET6096_13568-001,SMLF,IO,DGA^6000030    I23 @T6G_MB_LIB.T6G(SCH_1):PAGE31
   U25 AP51 VSS_AP51 GENOA_SP5-SOCKET6096_13568-001,SMLF,IO,DGA^6000030    I23 @T6G_MB_LIB.T6G(SCH_1):PAGE31
   U25 AP54 VSS_AP54 GENOA_SP5-SOCKET6096_13568-001,SMLF,IO,DGA^6000030    I23 @T6G_MB_LIB.T6G(SCH_1):PAGE31
   U25 AP57 VSS_AP57 GENOA_SP5-SOCKET6096_13568-001,SMLF,IO,DGA^6000030    I23 @T6G_MB_LIB.T6G(SCH_1):PAGE31
   U25 AP59 VSS_AP59 GENOA_SP5-SOCKET6096_13568-001,SMLF,IO,DGA^6000030    I23 @T6G_MB_LIB.T6G(SCH_1):PAGE31
   U25 AP61 VSS_AP61 GENOA_SP5-SOCKET6096_13568-001,SMLF,IO,DGA^6000030    I23 @T6G_MB_LIB.T6G(SCH_1):PAGE31
   U25 AP64 VSS_AP64 GENOA_SP5-SOCKET6096_13568-001,SMLF,IO,DGA^6000030    I23 @T6G_MB_LIB.T6G(SCH_1):PAGE31
   U25 AP66 VSS_AP66 GENOA_SP5-SOCKET6096_13568-001,SMLF,IO,DGA^6000030    I23 @T6G_MB_LIB.T6G(SCH_1):PAGE31
   U25 AP68 VSS_AP68 GENOA_SP5-SOCKET6096_13568-001,SMLF,IO,DGA^6000030    I23 @T6G_MB_LIB.T6G(SCH_1):PAGE31
   U25 AP71 VSS_AP71 GENOA_SP5-SOCKET6096_13568-001,SMLF,IO,DGA^6000030    I23 @T6G_MB_LIB.T6G(SCH_1):PAGE31
   U25 AP73 VSS_AP73 GENOA_SP5-SOCKET6096_13568-001,SMLF,IO,DGA^6000030    I23 @T6G_MB_LIB.T6G(SCH_1):PAGE31
   U25  AR1 VSS_AR1 GENOA_SP5-SOCKET6096_13568-001,SMLF,IO,DGA^6000030    I23 @T6G_MB_LIB.T6G(SCH_1):PAGE31
   U25  AR5 VSS_AR5 GENOA_SP5-SOCKET6096_13568-001,SMLF,IO,DGA^6000030    I23 @T6G_MB_LIB.T6G(SCH_1):PAGE31
   U25  AR6 VSS_AR6 GENOA_SP5-SOCKET6096_13568-001,SMLF,IO,DGA^6000030    I23 @T6G_MB_LIB.T6G(SCH_1):PAGE31
   U25  AR8 VSS_AR8 GENOA_SP5-SOCKET6096_13568-001,SMLF,IO,DGA^6000030    I23 @T6G_MB_LIB.T6G(SCH_1):PAGE31
   U25  AR9 VSS_AR9 GENOA_SP5-SOCKET6096_13568-001,SMLF,IO,DGA^6000030    I23 @T6G_MB_LIB.T6G(SCH_1):PAGE31
   U25 AR12 VSS_AR12 GENOA_SP5-SOCKET6096_13568-001,SMLF,IO,DGA^6000030    I23 @T6G_MB_LIB.T6G(SCH_1):PAGE31
   U25 AR13 VSS_AR13 GENOA_SP5-SOCKET6096_13568-001,SMLF,IO,DGA^6000030    I23 @T6G_MB_LIB.T6G(SCH_1):PAGE31
   U25 AR15 VSS_AR15 GENOA_SP5-SOCKET6096_13568-001,SMLF,IO,DGA^6000030    I23 @T6G_MB_LIB.T6G(SCH_1):PAGE31
   U25 AR16 VSS_AR16 GENOA_SP5-SOCKET6096_13568-001,SMLF,IO,DGA^6000030    I23 @T6G_MB_LIB.T6G(SCH_1):PAGE31
   U25 AR19 VSS_AR19 GENOA_SP5-SOCKET6096_13568-001,SMLF,IO,DGA^6000030    I23 @T6G_MB_LIB.T6G(SCH_1):PAGE31
   U25 AR20 VSS_AR20 GENOA_SP5-SOCKET6096_13568-001,SMLF,IO,DGA^6000030    I23 @T6G_MB_LIB.T6G(SCH_1):PAGE31
   U25 AR22 VSS_AR22 GENOA_SP5-SOCKET6096_13568-001,SMLF,IO,DGA^6000030    I23 @T6G_MB_LIB.T6G(SCH_1):PAGE31
   U25 AR24 VSS_AR24 GENOA_SP5-SOCKET6096_13568-001,SMLF,IO,DGA^6000030    I23 @T6G_MB_LIB.T6G(SCH_1):PAGE31
   U25 AR26 VSS_AR26 GENOA_SP5-SOCKET6096_13568-001,SMLF,IO,DGA^6000030    I23 @T6G_MB_LIB.T6G(SCH_1):PAGE31
   U25 AR28 VSS_AR28 GENOA_SP5-SOCKET6096_13568-001,SMLF,IO,DGA^6000030    I23 @T6G_MB_LIB.T6G(SCH_1):PAGE31
   U25 AR30 VSS_AR30 GENOA_SP5-SOCKET6096_13568-001,SMLF,IO,DGA^6000030    I23 @T6G_MB_LIB.T6G(SCH_1):PAGE31
   U25 AR32 VSS_AR32 GENOA_SP5-SOCKET6096_13568-001,SMLF,IO,DGA^6000030    I23 @T6G_MB_LIB.T6G(SCH_1):PAGE31
   U25 AR34 VSS_AR34 GENOA_SP5-SOCKET6096_13568-001,SMLF,IO,DGA^6000030    I23 @T6G_MB_LIB.T6G(SCH_1):PAGE31
   U25 AR36 VSS_AR36 GENOA_SP5-SOCKET6096_13568-001,SMLF,IO,DGA^6000030    I23 @T6G_MB_LIB.T6G(SCH_1):PAGE31
   U25 AR41 VSS_AR41 GENOA_SP5-SOCKET6096_13568-001,SMLF,IO,DGA^6000030    I23 @T6G_MB_LIB.T6G(SCH_1):PAGE31
   U25 AR43 VSS_AR43 GENOA_SP5-SOCKET6096_13568-001,SMLF,IO,DGA^6000030    I23 @T6G_MB_LIB.T6G(SCH_1):PAGE31
   U25 AR45 VSS_AR45 GENOA_SP5-SOCKET6096_13568-001,SMLF,IO,DGA^6000030    I23 @T6G_MB_LIB.T6G(SCH_1):PAGE31
   U25 AR47 VSS_AR47 GENOA_SP5-SOCKET6096_13568-001,SMLF,IO,DGA^6000030    I23 @T6G_MB_LIB.T6G(SCH_1):PAGE31
   U25 AR49 VSS_AR49 GENOA_SP5-SOCKET6096_13568-001,SMLF,IO,DGA^6000030    I23 @T6G_MB_LIB.T6G(SCH_1):PAGE31
   U25 AR51 VSS_AR51 GENOA_SP5-SOCKET6096_13568-001,SMLF,IO,DGA^6000030    I23 @T6G_MB_LIB.T6G(SCH_1):PAGE31
   U25 AR53 VSS_AR53 GENOA_SP5-SOCKET6096_13568-001,SMLF,IO,DGA^6000030    I23 @T6G_MB_LIB.T6G(SCH_1):PAGE31
   U25 AR56 VSS_AR56 GENOA_SP5-SOCKET6096_13568-001,SMLF,IO,DGA^6000030    I23 @T6G_MB_LIB.T6G(SCH_1):PAGE31
   U25 AR57 VSS_AR57 GENOA_SP5-SOCKET6096_13568-001,SMLF,IO,DGA^6000030    I23 @T6G_MB_LIB.T6G(SCH_1):PAGE31
   U25 AR60 VSS_AR60 GENOA_SP5-SOCKET6096_13568-001,SMLF,IO,DGA^6000030    I23 @T6G_MB_LIB.T6G(SCH_1):PAGE31
   U25 AR61 VSS_AR61 GENOA_SP5-SOCKET6096_13568-001,SMLF,IO,DGA^6000030    I23 @T6G_MB_LIB.T6G(SCH_1):PAGE31
   U25 AR63 VSS_AR63 GENOA_SP5-SOCKET6096_13568-001,SMLF,IO,DGA^6000030    I23 @T6G_MB_LIB.T6G(SCH_1):PAGE31
   U25 AR64 VSS_AR64 GENOA_SP5-SOCKET6096_13568-001,SMLF,IO,DGA^6000030    I23 @T6G_MB_LIB.T6G(SCH_1):PAGE31
   U25 AR67 VSS_AR67 GENOA_SP5-SOCKET6096_13568-001,SMLF,IO,DGA^6000030    I23 @T6G_MB_LIB.T6G(SCH_1):PAGE31
   U25 AR68 VSS_AR68 GENOA_SP5-SOCKET6096_13568-001,SMLF,IO,DGA^6000030    I23 @T6G_MB_LIB.T6G(SCH_1):PAGE31
   U25 AR70 VSS_AR70 GENOA_SP5-SOCKET6096_13568-001,SMLF,IO,DGA^6000030    I23 @T6G_MB_LIB.T6G(SCH_1):PAGE31
   U25 AR71 VSS_AR71 GENOA_SP5-SOCKET6096_13568-001,SMLF,IO,DGA^6000030    I23 @T6G_MB_LIB.T6G(SCH_1):PAGE31
   U25 AR75 VSS_AR75 GENOA_SP5-SOCKET6096_13568-001,SMLF,IO,DGA^6000030    I23 @T6G_MB_LIB.T6G(SCH_1):PAGE31
   U25  AT3 VSS_AT3 GENOA_SP5-SOCKET6096_13568-001,SMLF,IO,DGA^6000030    I23 @T6G_MB_LIB.T6G(SCH_1):PAGE31
   U25  AT4 VSS_AT4 GENOA_SP5-SOCKET6096_13568-001,SMLF,IO,DGA^6000030    I23 @T6G_MB_LIB.T6G(SCH_1):PAGE31
   U25  AT5 VSS_AT5 GENOA_SP5-SOCKET6096_13568-001,SMLF,IO,DGA^6000030    I23 @T6G_MB_LIB.T6G(SCH_1):PAGE31
   U25  AT6 VSS_AT6 GENOA_SP5-SOCKET6096_13568-001,SMLF,IO,DGA^6000030    I23 @T6G_MB_LIB.T6G(SCH_1):PAGE31
   U25  AT8 VSS_AT8 GENOA_SP5-SOCKET6096_13568-001,SMLF,IO,DGA^6000030    I23 @T6G_MB_LIB.T6G(SCH_1):PAGE31
   U25  AT9 VSS_AT9 GENOA_SP5-SOCKET6096_13568-001,SMLF,IO,DGA^6000030    I23 @T6G_MB_LIB.T6G(SCH_1):PAGE31
   U25 AT10 VSS_AT10 GENOA_SP5-SOCKET6096_13568-001,SMLF,IO,DGA^6000030    I23 @T6G_MB_LIB.T6G(SCH_1):PAGE31
   U25 AT12 VSS_AT12 GENOA_SP5-SOCKET6096_13568-001,SMLF,IO,DGA^6000030    I23 @T6G_MB_LIB.T6G(SCH_1):PAGE31
   U25 AT13 VSS_AT13 GENOA_SP5-SOCKET6096_13568-001,SMLF,IO,DGA^6000030    I23 @T6G_MB_LIB.T6G(SCH_1):PAGE31
   U25 AT15 VSS_AT15 GENOA_SP5-SOCKET6096_13568-001,SMLF,IO,DGA^6000030    I23 @T6G_MB_LIB.T6G(SCH_1):PAGE31
   U25 AT16 VSS_AT16 GENOA_SP5-SOCKET6096_13568-001,SMLF,IO,DGA^6000030    I23 @T6G_MB_LIB.T6G(SCH_1):PAGE31
   U25 AT17 VSS_AT17 GENOA_SP5-SOCKET6096_13568-001,SMLF,IO,DGA^6000030    I23 @T6G_MB_LIB.T6G(SCH_1):PAGE31
   U25 AT19 VSS_AT19 GENOA_SP5-SOCKET6096_13568-001,SMLF,IO,DGA^6000030    I23 @T6G_MB_LIB.T6G(SCH_1):PAGE31
   U25 AT20 VSS_AT20 GENOA_SP5-SOCKET6096_13568-001,SMLF,IO,DGA^6000030    I23 @T6G_MB_LIB.T6G(SCH_1):PAGE31
   U25 AT23 VSS_AT23 GENOA_SP5-SOCKET6096_13568-001,SMLF,IO,DGA^6000030    I23 @T6G_MB_LIB.T6G(SCH_1):PAGE31
   U25 AT25 VSS_AT25 GENOA_SP5-SOCKET6096_13568-001,SMLF,IO,DGA^6000030    I23 @T6G_MB_LIB.T6G(SCH_1):PAGE31
   U25 AT27 VSS_AT27 GENOA_SP5-SOCKET6096_13568-001,SMLF,IO,DGA^6000030    I23 @T6G_MB_LIB.T6G(SCH_1):PAGE31
   U25 AT29 VSS_AT29 GENOA_SP5-SOCKET6096_13568-001,SMLF,IO,DGA^6000030    I23 @T6G_MB_LIB.T6G(SCH_1):PAGE31
   U25 AT31 VSS_AT31 GENOA_SP5-SOCKET6096_13568-001,SMLF,IO,DGA^6000030    I23 @T6G_MB_LIB.T6G(SCH_1):PAGE31
   U25 AT33 VSS_AT33 GENOA_SP5-SOCKET6096_13568-001,SMLF,IO,DGA^6000030    I23 @T6G_MB_LIB.T6G(SCH_1):PAGE31
   U25 AT35 VSS_AT35 GENOA_SP5-SOCKET6096_13568-001,SMLF,IO,DGA^6000030    I23 @T6G_MB_LIB.T6G(SCH_1):PAGE31
   U25 AT37 VSS_AT37 GENOA_SP5-SOCKET6096_13568-001,SMLF,IO,DGA^6000030    I23 @T6G_MB_LIB.T6G(SCH_1):PAGE31
   U25 AT40 VSS_AT40 GENOA_SP5-SOCKET6096_13568-001,SMLF,IO,DGA^6000030    I23 @T6G_MB_LIB.T6G(SCH_1):PAGE31
   U25 AT42 VSS_AT42 GENOA_SP5-SOCKET6096_13568-001,SMLF,IO,DGA^6000030    I23 @T6G_MB_LIB.T6G(SCH_1):PAGE31
   U25 AT44 VSS_AT44 GENOA_SP5-SOCKET6096_13568-001,SMLF,IO,DGA^6000030    I23 @T6G_MB_LIB.T6G(SCH_1):PAGE31
   U25 AT46 VSS_AT46 GENOA_SP5-SOCKET6096_13568-001,SMLF,IO,DGA^6000030    I23 @T6G_MB_LIB.T6G(SCH_1):PAGE31
   U25 AT48 VSS_AT48 GENOA_SP5-SOCKET6096_13568-001,SMLF,IO,DGA^6000030    I23 @T6G_MB_LIB.T6G(SCH_1):PAGE31
   U25 AT50 VSS_AT50 GENOA_SP5-SOCKET6096_13568-001,SMLF,IO,DGA^6000030    I23 @T6G_MB_LIB.T6G(SCH_1):PAGE31
   U25 AT52 VSS_AT52 GENOA_SP5-SOCKET6096_13568-001,SMLF,IO,DGA^6000030    I23 @T6G_MB_LIB.T6G(SCH_1):PAGE31
   U25 AT54 VSS_AT54 GENOA_SP5-SOCKET6096_13568-001,SMLF,IO,DGA^6000030    I23 @T6G_MB_LIB.T6G(SCH_1):PAGE31
   U25 AT56 VSS_AT56 GENOA_SP5-SOCKET6096_13568-001,SMLF,IO,DGA^6000030    I23 @T6G_MB_LIB.T6G(SCH_1):PAGE31
   U25 AT57 VSS_AT57 GENOA_SP5-SOCKET6096_13568-001,SMLF,IO,DGA^6000030    I23 @T6G_MB_LIB.T6G(SCH_1):PAGE31
   U25 AT59 VSS_AT59 GENOA_SP5-SOCKET6096_13568-001,SMLF,IO,DGA^6000030    I23 @T6G_MB_LIB.T6G(SCH_1):PAGE31
   U25 AT60 VSS_AT60 GENOA_SP5-SOCKET6096_13568-001,SMLF,IO,DGA^6000030    I23 @T6G_MB_LIB.T6G(SCH_1):PAGE31
   U25 AT61 VSS_AT61 GENOA_SP5-SOCKET6096_13568-001,SMLF,IO,DGA^6000030    I23 @T6G_MB_LIB.T6G(SCH_1):PAGE31
   U25 AT63 VSS_AT63 GENOA_SP5-SOCKET6096_13568-001,SMLF,IO,DGA^6000030    I23 @T6G_MB_LIB.T6G(SCH_1):PAGE31
   U25 AT64 VSS_AT64 GENOA_SP5-SOCKET6096_13568-001,SMLF,IO,DGA^6000030    I23 @T6G_MB_LIB.T6G(SCH_1):PAGE31
   U25 AT66 VSS_AT66 GENOA_SP5-SOCKET6096_13568-001,SMLF,IO,DGA^6000030    I23 @T6G_MB_LIB.T6G(SCH_1):PAGE31
   U25 AT67 VSS_AT67 GENOA_SP5-SOCKET6096_13568-001,SMLF,IO,DGA^6000030    I23 @T6G_MB_LIB.T6G(SCH_1):PAGE31
   U25 AT68 VSS_AT68 GENOA_SP5-SOCKET6096_13568-001,SMLF,IO,DGA^6000030    I23 @T6G_MB_LIB.T6G(SCH_1):PAGE31
   U25 AT70 VSS_AT70 GENOA_SP5-SOCKET6096_13568-001,SMLF,IO,DGA^6000030    I23 @T6G_MB_LIB.T6G(SCH_1):PAGE31
   U25 AT71 VSS_AT71 GENOA_SP5-SOCKET6096_13568-001,SMLF,IO,DGA^6000030    I23 @T6G_MB_LIB.T6G(SCH_1):PAGE31
   U25 AT72 VSS_AT72 GENOA_SP5-SOCKET6096_13568-001,SMLF,IO,DGA^6000030    I23 @T6G_MB_LIB.T6G(SCH_1):PAGE31
   U25 AT73 VSS_AT73 GENOA_SP5-SOCKET6096_13568-001,SMLF,IO,DGA^6000030    I23 @T6G_MB_LIB.T6G(SCH_1):PAGE31
   U25  AU1 VSS_AU1 GENOA_SP5-SOCKET6096_13568-001,SMLF,IO,DGA^6000030    I23 @T6G_MB_LIB.T6G(SCH_1):PAGE31
   U25  AU3 VSS_AU3 GENOA_SP5-SOCKET6096_13568-001,SMLF,IO,DGA^6000030    I23 @T6G_MB_LIB.T6G(SCH_1):PAGE31
   U25  AU4 VSS_AU4 GENOA_SP5-SOCKET6096_13568-001,SMLF,IO,DGA^6000030    I23 @T6G_MB_LIB.T6G(SCH_1):PAGE31
   U25  AU6 VSS_AU6 GENOA_SP5-SOCKET6096_13568-001,SMLF,IO,DGA^6000030    I23 @T6G_MB_LIB.T6G(SCH_1):PAGE31
   U25  AU8 VSS_AU8 GENOA_SP5-SOCKET6096_13568-001,SMLF,IO,DGA^6000030    I23 @T6G_MB_LIB.T6G(SCH_1):PAGE31
   U25 AU11 VSS_AU11 GENOA_SP5-SOCKET6096_13568-001,SMLF,IO,DGA^6000030    I23 @T6G_MB_LIB.T6G(SCH_1):PAGE31
   U25 AU13 VSS_AU13 GENOA_SP5-SOCKET6096_13568-001,SMLF,IO,DGA^6000030    I23 @T6G_MB_LIB.T6G(SCH_1):PAGE31
   U25 AU15 VSS_AU15 GENOA_SP5-SOCKET6096_13568-001,SMLF,IO,DGA^6000030    I23 @T6G_MB_LIB.T6G(SCH_1):PAGE31
   U25 AU18 VSS_AU18 GENOA_SP5-SOCKET6096_13568-001,SMLF,IO,DGA^6000030    I23 @T6G_MB_LIB.T6G(SCH_1):PAGE31
   U25 AU20 VSS_AU20 GENOA_SP5-SOCKET6096_13568-001,SMLF,IO,DGA^6000030    I23 @T6G_MB_LIB.T6G(SCH_1):PAGE31
   U25 AU22 VSS_AU22 GENOA_SP5-SOCKET6096_13568-001,SMLF,IO,DGA^6000030    I23 @T6G_MB_LIB.T6G(SCH_1):PAGE31
   U25 AU24 VSS_AU24 GENOA_SP5-SOCKET6096_13568-001,SMLF,IO,DGA^6000030    I23 @T6G_MB_LIB.T6G(SCH_1):PAGE31
   U25 AU26 VSS_AU26 GENOA_SP5-SOCKET6096_13568-001,SMLF,IO,DGA^6000030    I23 @T6G_MB_LIB.T6G(SCH_1):PAGE31
   U25 AU28 VSS_AU28 GENOA_SP5-SOCKET6096_13568-001,SMLF,IO,DGA^6000030    I23 @T6G_MB_LIB.T6G(SCH_1):PAGE31
   U25 AU30 VSS_AU30 GENOA_SP5-SOCKET6096_13568-001,SMLF,IO,DGA^6000030    I23 @T6G_MB_LIB.T6G(SCH_1):PAGE31
   U25 AU32 VSS_AU32 GENOA_SP5-SOCKET6096_13568-001,SMLF,IO,DGA^6000030    I23 @T6G_MB_LIB.T6G(SCH_1):PAGE31
   U25 AU34 VSS_AU34 GENOA_SP5-SOCKET6096_13568-001,SMLF,IO,DGA^6000030    I23 @T6G_MB_LIB.T6G(SCH_1):PAGE31
   U25 AU36 VSS_AU36 GENOA_SP5-SOCKET6096_13568-001,SMLF,IO,DGA^6000030    I23 @T6G_MB_LIB.T6G(SCH_1):PAGE31
   U25 AU41 VSS_AU41 GENOA_SP5-SOCKET6096_13568-001,SMLF,IO,DGA^6000030    I23 @T6G_MB_LIB.T6G(SCH_1):PAGE31
   U25 AU43 VSS_AU43 GENOA_SP5-SOCKET6096_13568-001,SMLF,IO,DGA^6000030    I23 @T6G_MB_LIB.T6G(SCH_1):PAGE31
   U25 AU45 VSS_AU45 GENOA_SP5-SOCKET6096_13568-001,SMLF,IO,DGA^6000030    I23 @T6G_MB_LIB.T6G(SCH_1):PAGE31
   U25 AU47 VSS_AU47 GENOA_SP5-SOCKET6096_13568-001,SMLF,IO,DGA^6000030    I23 @T6G_MB_LIB.T6G(SCH_1):PAGE31
   U25 AU49 VSS_AU49 GENOA_SP5-SOCKET6096_13568-001,SMLF,IO,DGA^6000030    I23 @T6G_MB_LIB.T6G(SCH_1):PAGE31
   U25 AU51 VSS_AU51 GENOA_SP5-SOCKET6096_13568-001,SMLF,IO,DGA^6000030    I23 @T6G_MB_LIB.T6G(SCH_1):PAGE31
   U25 AU53 VSS_AU53 GENOA_SP5-SOCKET6096_13568-001,SMLF,IO,DGA^6000030    I23 @T6G_MB_LIB.T6G(SCH_1):PAGE31
   U25 AU56 VSS_AU56 GENOA_SP5-SOCKET6096_13568-001,SMLF,IO,DGA^6000030    I23 @T6G_MB_LIB.T6G(SCH_1):PAGE31
   U25 AU58 VSS_AU58 GENOA_SP5-SOCKET6096_13568-001,SMLF,IO,DGA^6000030    I23 @T6G_MB_LIB.T6G(SCH_1):PAGE31
   U25 AU61 VSS_AU61 GENOA_SP5-SOCKET6096_13568-001,SMLF,IO,DGA^6000030    I23 @T6G_MB_LIB.T6G(SCH_1):PAGE31
   U25 AU63 VSS_AU63 GENOA_SP5-SOCKET6096_13568-001,SMLF,IO,DGA^6000030    I23 @T6G_MB_LIB.T6G(SCH_1):PAGE31
   U25 AU65 VSS_AU65 GENOA_SP5-SOCKET6096_13568-001,SMLF,IO,DGA^6000030    I23 @T6G_MB_LIB.T6G(SCH_1):PAGE31
   U25 AU68 VSS_AU68 GENOA_SP5-SOCKET6096_13568-001,SMLF,IO,DGA^6000030    I23 @T6G_MB_LIB.T6G(SCH_1):PAGE31
   U25 AU70 VSS_AU70 GENOA_SP5-SOCKET6096_13568-001,SMLF,IO,DGA^6000030    I23 @T6G_MB_LIB.T6G(SCH_1):PAGE31
   U25 AU72 VSS_AU72 GENOA_SP5-SOCKET6096_13568-001,SMLF,IO,DGA^6000030    I23 @T6G_MB_LIB.T6G(SCH_1):PAGE31
   U25 AU73 VSS_AU73 GENOA_SP5-SOCKET6096_13568-001,SMLF,IO,DGA^6000030    I23 @T6G_MB_LIB.T6G(SCH_1):PAGE31
   U25 AU75 VSS_AU75 GENOA_SP5-SOCKET6096_13568-001,SMLF,IO,DGA^6000030    I23 @T6G_MB_LIB.T6G(SCH_1):PAGE31
   U25  AV3 VSS_AV3 GENOA_SP5-SOCKET6096_13568-001,SMLF,IO,DGA^6000030    I23 @T6G_MB_LIB.T6G(SCH_1):PAGE31
   U25  AV8 VSS_AV8 GENOA_SP5-SOCKET6096_13568-001,SMLF,IO,DGA^6000030    I23 @T6G_MB_LIB.T6G(SCH_1):PAGE31
   U25 AV10 VSS_AV10 GENOA_SP5-SOCKET6096_13568-001,SMLF,IO,DGA^6000030    I23 @T6G_MB_LIB.T6G(SCH_1):PAGE31
   U25 AV15 VSS_AV15 GENOA_SP5-SOCKET6096_13568-001,SMLF,IO,DGA^6000030    I23 @T6G_MB_LIB.T6G(SCH_1):PAGE31
   U25 AV17 VSS_AV17 GENOA_SP5-SOCKET6096_13568-001,SMLF,IO,DGA^6000030    I23 @T6G_MB_LIB.T6G(SCH_1):PAGE31
   U25 AV23 VSS_AV23 GENOA_SP5-SOCKET6096_13568-001,SMLF,IO,DGA^6000030    I23 @T6G_MB_LIB.T6G(SCH_1):PAGE31
   U25 AV25 VSS_AV25 GENOA_SP5-SOCKET6096_13568-001,SMLF,IO,DGA^6000030    I23 @T6G_MB_LIB.T6G(SCH_1):PAGE31
   U25 AV27 VSS_AV27 GENOA_SP5-SOCKET6096_13568-001,SMLF,IO,DGA^6000030    I23 @T6G_MB_LIB.T6G(SCH_1):PAGE31
   U25 AV29 VSS_AV29 GENOA_SP5-SOCKET6096_13568-001,SMLF,IO,DGA^6000030    I23 @T6G_MB_LIB.T6G(SCH_1):PAGE31
   U25 AV31 VSS_AV31 GENOA_SP5-SOCKET6096_13568-001,SMLF,IO,DGA^6000030    I23 @T6G_MB_LIB.T6G(SCH_1):PAGE31
   U25 AV33 VSS_AV33 GENOA_SP5-SOCKET6096_13568-001,SMLF,IO,DGA^6000030    I23 @T6G_MB_LIB.T6G(SCH_1):PAGE31
   U25 AV35 VSS_AV35 GENOA_SP5-SOCKET6096_13568-001,SMLF,IO,DGA^6000030    I23 @T6G_MB_LIB.T6G(SCH_1):PAGE31
   U25 AV37 VSS_AV37 GENOA_SP5-SOCKET6096_13568-001,SMLF,IO,DGA^6000030    I23 @T6G_MB_LIB.T6G(SCH_1):PAGE31
   U25 AV40 VSS_AV40 GENOA_SP5-SOCKET6096_13568-001,SMLF,IO,DGA^6000030    I23 @T6G_MB_LIB.T6G(SCH_1):PAGE31
   U25 AV42 VSS_AV42 GENOA_SP5-SOCKET6096_13568-001,SMLF,IO,DGA^6000030    I23 @T6G_MB_LIB.T6G(SCH_1):PAGE31
   U25 AV44 VSS_AV44 GENOA_SP5-SOCKET6096_13568-001,SMLF,IO,DGA^6000030    I23 @T6G_MB_LIB.T6G(SCH_1):PAGE31
   U25 AV46 VSS_AV46 GENOA_SP5-SOCKET6096_13568-001,SMLF,IO,DGA^6000030    I23 @T6G_MB_LIB.T6G(SCH_1):PAGE31
   U25 AV48 VSS_AV48 GENOA_SP5-SOCKET6096_13568-001,SMLF,IO,DGA^6000030    I23 @T6G_MB_LIB.T6G(SCH_1):PAGE31
   U25 AV50 VSS_AV50 GENOA_SP5-SOCKET6096_13568-001,SMLF,IO,DGA^6000030    I23 @T6G_MB_LIB.T6G(SCH_1):PAGE31
   U25 AV52 VSS_AV52 GENOA_SP5-SOCKET6096_13568-001,SMLF,IO,DGA^6000030    I23 @T6G_MB_LIB.T6G(SCH_1):PAGE31
   U25 AV54 VSS_AV54 GENOA_SP5-SOCKET6096_13568-001,SMLF,IO,DGA^6000030    I23 @T6G_MB_LIB.T6G(SCH_1):PAGE31
   U25 AV59 VSS_AV59 GENOA_SP5-SOCKET6096_13568-001,SMLF,IO,DGA^6000030    I23 @T6G_MB_LIB.T6G(SCH_1):PAGE31
   U25 AV61 VSS_AV61 GENOA_SP5-SOCKET6096_13568-001,SMLF,IO,DGA^6000030    I23 @T6G_MB_LIB.T6G(SCH_1):PAGE31
   U25 AV66 VSS_AV66 GENOA_SP5-SOCKET6096_13568-001,SMLF,IO,DGA^6000030    I23 @T6G_MB_LIB.T6G(SCH_1):PAGE31
   U25 AV68 VSS_AV68 GENOA_SP5-SOCKET6096_13568-001,SMLF,IO,DGA^6000030    I23 @T6G_MB_LIB.T6G(SCH_1):PAGE31
   U25 AV73 VSS_AV73 GENOA_SP5-SOCKET6096_13568-001,SMLF,IO,DGA^6000030    I23 @T6G_MB_LIB.T6G(SCH_1):PAGE31
   U25  AW1 VSS_AW1 GENOA_SP5-SOCKET6096_13568-001,SMLF,IO,DGA^6000030    I23 @T6G_MB_LIB.T6G(SCH_1):PAGE31
   U25  AW4 VSS_AW4 GENOA_SP5-SOCKET6096_13568-001,SMLF,IO,DGA^6000030    I23 @T6G_MB_LIB.T6G(SCH_1):PAGE31
   U25  AW6 VSS_AW6 GENOA_SP5-SOCKET6096_13568-001,SMLF,IO,DGA^6000030    I23 @T6G_MB_LIB.T6G(SCH_1):PAGE31
   U25  AW8 VSS_AW8 GENOA_SP5-SOCKET6096_13568-001,SMLF,IO,DGA^6000030    I23 @T6G_MB_LIB.T6G(SCH_1):PAGE31
   U25 AW11 VSS_AW11 GENOA_SP5-SOCKET6096_13568-001,SMLF,IO,DGA^6000030    I23 @T6G_MB_LIB.T6G(SCH_1):PAGE31
   U25 AW13 VSS_AW13 GENOA_SP5-SOCKET6096_13568-001,SMLF,IO,DGA^6000030    I23 @T6G_MB_LIB.T6G(SCH_1):PAGE31
   U25 AW15 VSS_AW15 GENOA_SP5-SOCKET6096_13568-001,SMLF,IO,DGA^6000030    I23 @T6G_MB_LIB.T6G(SCH_1):PAGE31
   U25 AW18 VSS_AW18 GENOA_SP5-SOCKET6096_13568-001,SMLF,IO,DGA^6000030    I23 @T6G_MB_LIB.T6G(SCH_1):PAGE31
   U25 AW20 VSS_AW20 GENOA_SP5-SOCKET6096_13568-001,SMLF,IO,DGA^6000030    I23 @T6G_MB_LIB.T6G(SCH_1):PAGE31
   U25 AW22 VSS_AW22 GENOA_SP5-SOCKET6096_13568-001,SMLF,IO,DGA^6000030    I23 @T6G_MB_LIB.T6G(SCH_1):PAGE31
   U25 AW24 VSS_AW24 GENOA_SP5-SOCKET6096_13568-001,SMLF,IO,DGA^6000030    I23 @T6G_MB_LIB.T6G(SCH_1):PAGE31
   U25 AW26 VSS_AW26 GENOA_SP5-SOCKET6096_13568-001,SMLF,IO,DGA^6000030    I23 @T6G_MB_LIB.T6G(SCH_1):PAGE31
   U25 AW28 VSS_AW28 GENOA_SP5-SOCKET6096_13568-001,SMLF,IO,DGA^6000030    I23 @T6G_MB_LIB.T6G(SCH_1):PAGE31
   U25 AW49 VSS_AW49 GENOA_SP5-SOCKET6096_13568-001,SMLF,IO,DGA^6000030    I23 @T6G_MB_LIB.T6G(SCH_1):PAGE31
   U25 AW51 VSS_AW51 GENOA_SP5-SOCKET6096_13568-001,SMLF,IO,DGA^6000030    I23 @T6G_MB_LIB.T6G(SCH_1):PAGE31
   U25 AW53 VSS_AW53 GENOA_SP5-SOCKET6096_13568-001,SMLF,IO,DGA^6000030    I23 @T6G_MB_LIB.T6G(SCH_1):PAGE31
   U25 AW56 VSS_AW56 GENOA_SP5-SOCKET6096_13568-001,SMLF,IO,DGA^6000030    I23 @T6G_MB_LIB.T6G(SCH_1):PAGE31
   U25 AW58 VSS_AW58 GENOA_SP5-SOCKET6096_13568-001,SMLF,IO,DGA^6000030    I23 @T6G_MB_LIB.T6G(SCH_1):PAGE31
   U25 AW61 VSS_AW61 GENOA_SP5-SOCKET6096_13568-001,SMLF,IO,DGA^6000030    I23 @T6G_MB_LIB.T6G(SCH_1):PAGE31
   U25 AW63 VSS_AW63 GENOA_SP5-SOCKET6096_13568-001,SMLF,IO,DGA^6000030    I24 @T6G_MB_LIB.T6G(SCH_1):PAGE31
   U25 AW65 VSS_AW65 GENOA_SP5-SOCKET6096_13568-001,SMLF,IO,DGA^6000030    I24 @T6G_MB_LIB.T6G(SCH_1):PAGE31
   U25 AW68 VSS_AW68 GENOA_SP5-SOCKET6096_13568-001,SMLF,IO,DGA^6000030    I24 @T6G_MB_LIB.T6G(SCH_1):PAGE31
   U25 AW70 VSS_AW70 GENOA_SP5-SOCKET6096_13568-001,SMLF,IO,DGA^6000030    I24 @T6G_MB_LIB.T6G(SCH_1):PAGE31
   U25 AW72 VSS_AW72 GENOA_SP5-SOCKET6096_13568-001,SMLF,IO,DGA^6000030    I24 @T6G_MB_LIB.T6G(SCH_1):PAGE31
   U25 AW75 VSS_AW75 GENOA_SP5-SOCKET6096_13568-001,SMLF,IO,DGA^6000030    I24 @T6G_MB_LIB.T6G(SCH_1):PAGE31
   U25  AY3 VSS_AY3 GENOA_SP5-SOCKET6096_13568-001,SMLF,IO,DGA^6000030    I24 @T6G_MB_LIB.T6G(SCH_1):PAGE31
   U25  AY5 VSS_AY5 GENOA_SP5-SOCKET6096_13568-001,SMLF,IO,DGA^6000030    I24 @T6G_MB_LIB.T6G(SCH_1):PAGE31
   U25  AY8 VSS_AY8 GENOA_SP5-SOCKET6096_13568-001,SMLF,IO,DGA^6000030    I24 @T6G_MB_LIB.T6G(SCH_1):PAGE31
   U25 AY10 VSS_AY10 GENOA_SP5-SOCKET6096_13568-001,SMLF,IO,DGA^6000030    I24 @T6G_MB_LIB.T6G(SCH_1):PAGE31
   U25 AY12 VSS_AY12 GENOA_SP5-SOCKET6096_13568-001,SMLF,IO,DGA^6000030    I24 @T6G_MB_LIB.T6G(SCH_1):PAGE31
   U25 AY15 VSS_AY15 GENOA_SP5-SOCKET6096_13568-001,SMLF,IO,DGA^6000030    I24 @T6G_MB_LIB.T6G(SCH_1):PAGE31
   U25 AY17 VSS_AY17 GENOA_SP5-SOCKET6096_13568-001,SMLF,IO,DGA^6000030    I24 @T6G_MB_LIB.T6G(SCH_1):PAGE31
   U25 AY19 VSS_AY19 GENOA_SP5-SOCKET6096_13568-001,SMLF,IO,DGA^6000030    I24 @T6G_MB_LIB.T6G(SCH_1):PAGE31
   U25 AY23 VSS_AY23 GENOA_SP5-SOCKET6096_13568-001,SMLF,IO,DGA^6000030    I24 @T6G_MB_LIB.T6G(SCH_1):PAGE31
   U25 AY25 VSS_AY25 GENOA_SP5-SOCKET6096_13568-001,SMLF,IO,DGA^6000030    I24 @T6G_MB_LIB.T6G(SCH_1):PAGE31
   U25 AY27 VSS_AY27 GENOA_SP5-SOCKET6096_13568-001,SMLF,IO,DGA^6000030    I24 @T6G_MB_LIB.T6G(SCH_1):PAGE31
   U25 AY48 VSS_AY48 GENOA_SP5-SOCKET6096_13568-001,SMLF,IO,DGA^6000030    I24 @T6G_MB_LIB.T6G(SCH_1):PAGE31
   U25 AY50 VSS_AY50 GENOA_SP5-SOCKET6096_13568-001,SMLF,IO,DGA^6000030    I24 @T6G_MB_LIB.T6G(SCH_1):PAGE31
   U25 AY52 VSS_AY52 GENOA_SP5-SOCKET6096_13568-001,SMLF,IO,DGA^6000030    I24 @T6G_MB_LIB.T6G(SCH_1):PAGE31
   U25 AY54 VSS_AY54 GENOA_SP5-SOCKET6096_13568-001,SMLF,IO,DGA^6000030    I24 @T6G_MB_LIB.T6G(SCH_1):PAGE31
   U25 AY57 VSS_AY57 GENOA_SP5-SOCKET6096_13568-001,SMLF,IO,DGA^6000030    I24 @T6G_MB_LIB.T6G(SCH_1):PAGE31
   U25 AY59 VSS_AY59 GENOA_SP5-SOCKET6096_13568-001,SMLF,IO,DGA^6000030    I24 @T6G_MB_LIB.T6G(SCH_1):PAGE31
   U25 AY61 VSS_AY61 GENOA_SP5-SOCKET6096_13568-001,SMLF,IO,DGA^6000030    I24 @T6G_MB_LIB.T6G(SCH_1):PAGE31
   U25 AY64 VSS_AY64 GENOA_SP5-SOCKET6096_13568-001,SMLF,IO,DGA^6000030    I24 @T6G_MB_LIB.T6G(SCH_1):PAGE31
   U25 AY66 VSS_AY66 GENOA_SP5-SOCKET6096_13568-001,SMLF,IO,DGA^6000030    I24 @T6G_MB_LIB.T6G(SCH_1):PAGE31
   U25 AY68 VSS_AY68 GENOA_SP5-SOCKET6096_13568-001,SMLF,IO,DGA^6000030    I24 @T6G_MB_LIB.T6G(SCH_1):PAGE31
   U25 AY71 VSS_AY71 GENOA_SP5-SOCKET6096_13568-001,SMLF,IO,DGA^6000030    I24 @T6G_MB_LIB.T6G(SCH_1):PAGE31
   U25 AY73 VSS_AY73 GENOA_SP5-SOCKET6096_13568-001,SMLF,IO,DGA^6000030    I24 @T6G_MB_LIB.T6G(SCH_1):PAGE31
   U25  BA1 VSS_BA1 GENOA_SP5-SOCKET6096_13568-001,SMLF,IO,DGA^6000030    I24 @T6G_MB_LIB.T6G(SCH_1):PAGE31
   U25  BA6 VSS_BA6 GENOA_SP5-SOCKET6096_13568-001,SMLF,IO,DGA^6000030    I24 @T6G_MB_LIB.T6G(SCH_1):PAGE31
   U25  BA8 VSS_BA8 GENOA_SP5-SOCKET6096_13568-001,SMLF,IO,DGA^6000030    I24 @T6G_MB_LIB.T6G(SCH_1):PAGE31
   U25 BA13 VSS_BA13 GENOA_SP5-SOCKET6096_13568-001,SMLF,IO,DGA^6000030    I24 @T6G_MB_LIB.T6G(SCH_1):PAGE31
   U25 BA15 VSS_BA15 GENOA_SP5-SOCKET6096_13568-001,SMLF,IO,DGA^6000030    I24 @T6G_MB_LIB.T6G(SCH_1):PAGE31
   U25 BA20 VSS_BA20 GENOA_SP5-SOCKET6096_13568-001,SMLF,IO,DGA^6000030    I24 @T6G_MB_LIB.T6G(SCH_1):PAGE31
   U25 BA22 VSS_BA22 GENOA_SP5-SOCKET6096_13568-001,SMLF,IO,DGA^6000030    I24 @T6G_MB_LIB.T6G(SCH_1):PAGE31
   U25 BA24 VSS_BA24 GENOA_SP5-SOCKET6096_13568-001,SMLF,IO,DGA^6000030    I24 @T6G_MB_LIB.T6G(SCH_1):PAGE31
   U25 BA26 VSS_BA26 GENOA_SP5-SOCKET6096_13568-001,SMLF,IO,DGA^6000030    I24 @T6G_MB_LIB.T6G(SCH_1):PAGE31
   U25 BA28 VSS_BA28 GENOA_SP5-SOCKET6096_13568-001,SMLF,IO,DGA^6000030    I24 @T6G_MB_LIB.T6G(SCH_1):PAGE31
   U25 BA49 VSS_BA49 GENOA_SP5-SOCKET6096_13568-001,SMLF,IO,DGA^6000030    I24 @T6G_MB_LIB.T6G(SCH_1):PAGE31
   U25 BA51 VSS_BA51 GENOA_SP5-SOCKET6096_13568-001,SMLF,IO,DGA^6000030    I24 @T6G_MB_LIB.T6G(SCH_1):PAGE31
   U25 BA53 VSS_BA53 GENOA_SP5-SOCKET6096_13568-001,SMLF,IO,DGA^6000030    I24 @T6G_MB_LIB.T6G(SCH_1):PAGE31
   U25 BA56 VSS_BA56 GENOA_SP5-SOCKET6096_13568-001,SMLF,IO,DGA^6000030    I24 @T6G_MB_LIB.T6G(SCH_1):PAGE31
   U25 BA61 VSS_BA61 GENOA_SP5-SOCKET6096_13568-001,SMLF,IO,DGA^6000030    I24 @T6G_MB_LIB.T6G(SCH_1):PAGE31
   U25 BA63 VSS_BA63 GENOA_SP5-SOCKET6096_13568-001,SMLF,IO,DGA^6000030    I24 @T6G_MB_LIB.T6G(SCH_1):PAGE31
   U25 BA68 VSS_BA68 GENOA_SP5-SOCKET6096_13568-001,SMLF,IO,DGA^6000030    I24 @T6G_MB_LIB.T6G(SCH_1):PAGE31
   U25 BA70 VSS_BA70 GENOA_SP5-SOCKET6096_13568-001,SMLF,IO,DGA^6000030    I24 @T6G_MB_LIB.T6G(SCH_1):PAGE31
   U25 BA75 VSS_BA75 GENOA_SP5-SOCKET6096_13568-001,SMLF,IO,DGA^6000030    I24 @T6G_MB_LIB.T6G(SCH_1):PAGE31
   U25  BB3 VSS_BB3 GENOA_SP5-SOCKET6096_13568-001,SMLF,IO,DGA^6000030    I24 @T6G_MB_LIB.T6G(SCH_1):PAGE31
   U25  BB5 VSS_BB5 GENOA_SP5-SOCKET6096_13568-001,SMLF,IO,DGA^6000030    I24 @T6G_MB_LIB.T6G(SCH_1):PAGE31
   U25  BB8 VSS_BB8 GENOA_SP5-SOCKET6096_13568-001,SMLF,IO,DGA^6000030    I24 @T6G_MB_LIB.T6G(SCH_1):PAGE31
   U25 BB10 VSS_BB10 GENOA_SP5-SOCKET6096_13568-001,SMLF,IO,DGA^6000030    I24 @T6G_MB_LIB.T6G(SCH_1):PAGE31
   U25 BB12 VSS_BB12 GENOA_SP5-SOCKET6096_13568-001,SMLF,IO,DGA^6000030    I24 @T6G_MB_LIB.T6G(SCH_1):PAGE31
   U25 BB15 VSS_BB15 GENOA_SP5-SOCKET6096_13568-001,SMLF,IO,DGA^6000030    I24 @T6G_MB_LIB.T6G(SCH_1):PAGE31
   U25 BB17 VSS_BB17 GENOA_SP5-SOCKET6096_13568-001,SMLF,IO,DGA^6000030    I24 @T6G_MB_LIB.T6G(SCH_1):PAGE31
   U25 BB19 VSS_BB19 GENOA_SP5-SOCKET6096_13568-001,SMLF,IO,DGA^6000030    I24 @T6G_MB_LIB.T6G(SCH_1):PAGE31
   U25 BB23 VSS_BB23 GENOA_SP5-SOCKET6096_13568-001,SMLF,IO,DGA^6000030    I24 @T6G_MB_LIB.T6G(SCH_1):PAGE31
   U25 BB25 VSS_BB25 GENOA_SP5-SOCKET6096_13568-001,SMLF,IO,DGA^6000030    I24 @T6G_MB_LIB.T6G(SCH_1):PAGE31
   U25 BB27 VSS_BB27 GENOA_SP5-SOCKET6096_13568-001,SMLF,IO,DGA^6000030    I24 @T6G_MB_LIB.T6G(SCH_1):PAGE31
   U25 BB48 VSS_BB48 GENOA_SP5-SOCKET6096_13568-001,SMLF,IO,DGA^6000030    I24 @T6G_MB_LIB.T6G(SCH_1):PAGE31
   U25 BB50 VSS_BB50 GENOA_SP5-SOCKET6096_13568-001,SMLF,IO,DGA^6000030    I24 @T6G_MB_LIB.T6G(SCH_1):PAGE31
   U25 BB52 VSS_BB52 GENOA_SP5-SOCKET6096_13568-001,SMLF,IO,DGA^6000030    I24 @T6G_MB_LIB.T6G(SCH_1):PAGE31
   U25 BB54 VSS_BB54 GENOA_SP5-SOCKET6096_13568-001,SMLF,IO,DGA^6000030    I24 @T6G_MB_LIB.T6G(SCH_1):PAGE31
   U25 BB57 VSS_BB57 GENOA_SP5-SOCKET6096_13568-001,SMLF,IO,DGA^6000030    I24 @T6G_MB_LIB.T6G(SCH_1):PAGE31
   U25 BB59 VSS_BB59 GENOA_SP5-SOCKET6096_13568-001,SMLF,IO,DGA^6000030    I24 @T6G_MB_LIB.T6G(SCH_1):PAGE31
   U25 BB61 VSS_BB61 GENOA_SP5-SOCKET6096_13568-001,SMLF,IO,DGA^6000030    I24 @T6G_MB_LIB.T6G(SCH_1):PAGE31
   U25 BB64 VSS_BB64 GENOA_SP5-SOCKET6096_13568-001,SMLF,IO,DGA^6000030    I24 @T6G_MB_LIB.T6G(SCH_1):PAGE31
   U25 BB66 VSS_BB66 GENOA_SP5-SOCKET6096_13568-001,SMLF,IO,DGA^6000030    I24 @T6G_MB_LIB.T6G(SCH_1):PAGE31
   U25 BB68 VSS_BB68 GENOA_SP5-SOCKET6096_13568-001,SMLF,IO,DGA^6000030    I24 @T6G_MB_LIB.T6G(SCH_1):PAGE31
   U25 BB71 VSS_BB71 GENOA_SP5-SOCKET6096_13568-001,SMLF,IO,DGA^6000030    I24 @T6G_MB_LIB.T6G(SCH_1):PAGE31
   U25 BB73 VSS_BB73 GENOA_SP5-SOCKET6096_13568-001,SMLF,IO,DGA^6000030    I24 @T6G_MB_LIB.T6G(SCH_1):PAGE31
   U25  BC1 VSS_BC1 GENOA_SP5-SOCKET6096_13568-001,SMLF,IO,DGA^6000030    I24 @T6G_MB_LIB.T6G(SCH_1):PAGE31
   U25  BC4 VSS_BC4 GENOA_SP5-SOCKET6096_13568-001,SMLF,IO,DGA^6000030    I24 @T6G_MB_LIB.T6G(SCH_1):PAGE31
   U25  BC6 VSS_BC6 GENOA_SP5-SOCKET6096_13568-001,SMLF,IO,DGA^6000030    I24 @T6G_MB_LIB.T6G(SCH_1):PAGE31
   U25  BC8 VSS_BC8 GENOA_SP5-SOCKET6096_13568-001,SMLF,IO,DGA^6000030    I24 @T6G_MB_LIB.T6G(SCH_1):PAGE31
   U25 BC11 VSS_BC11 GENOA_SP5-SOCKET6096_13568-001,SMLF,IO,DGA^6000030    I24 @T6G_MB_LIB.T6G(SCH_1):PAGE31
   U25 BC13 VSS_BC13 GENOA_SP5-SOCKET6096_13568-001,SMLF,IO,DGA^6000030    I24 @T6G_MB_LIB.T6G(SCH_1):PAGE31
   U25 BC15 VSS_BC15 GENOA_SP5-SOCKET6096_13568-001,SMLF,IO,DGA^6000030    I24 @T6G_MB_LIB.T6G(SCH_1):PAGE31
   U25 BC18 VSS_BC18 GENOA_SP5-SOCKET6096_13568-001,SMLF,IO,DGA^6000030    I24 @T6G_MB_LIB.T6G(SCH_1):PAGE31
   U25 BC20 VSS_BC20 GENOA_SP5-SOCKET6096_13568-001,SMLF,IO,DGA^6000030    I24 @T6G_MB_LIB.T6G(SCH_1):PAGE31
   U25 BC22 VSS_BC22 GENOA_SP5-SOCKET6096_13568-001,SMLF,IO,DGA^6000030    I24 @T6G_MB_LIB.T6G(SCH_1):PAGE31
   U25 BC24 VSS_BC24 GENOA_SP5-SOCKET6096_13568-001,SMLF,IO,DGA^6000030    I24 @T6G_MB_LIB.T6G(SCH_1):PAGE31
   U25 BC26 VSS_BC26 GENOA_SP5-SOCKET6096_13568-001,SMLF,IO,DGA^6000030    I24 @T6G_MB_LIB.T6G(SCH_1):PAGE31
   U25 BC28 VSS_BC28 GENOA_SP5-SOCKET6096_13568-001,SMLF,IO,DGA^6000030    I24 @T6G_MB_LIB.T6G(SCH_1):PAGE31
   U25 BC49 VSS_BC49 GENOA_SP5-SOCKET6096_13568-001,SMLF,IO,DGA^6000030    I24 @T6G_MB_LIB.T6G(SCH_1):PAGE31
   U25 BC50 VSS_BC50 GENOA_SP5-SOCKET6096_13568-001,SMLF,IO,DGA^6000030    I24 @T6G_MB_LIB.T6G(SCH_1):PAGE31
   U25 BC51 VSS_BC51 GENOA_SP5-SOCKET6096_13568-001,SMLF,IO,DGA^6000030    I24 @T6G_MB_LIB.T6G(SCH_1):PAGE31
   U25 BC53 VSS_BC53 GENOA_SP5-SOCKET6096_13568-001,SMLF,IO,DGA^6000030    I24 @T6G_MB_LIB.T6G(SCH_1):PAGE31
   U25 BC56 VSS_BC56 GENOA_SP5-SOCKET6096_13568-001,SMLF,IO,DGA^6000030    I24 @T6G_MB_LIB.T6G(SCH_1):PAGE31
   U25 BC58 VSS_BC58 GENOA_SP5-SOCKET6096_13568-001,SMLF,IO,DGA^6000030    I24 @T6G_MB_LIB.T6G(SCH_1):PAGE31
   U25 BC61 VSS_BC61 GENOA_SP5-SOCKET6096_13568-001,SMLF,IO,DGA^6000030    I24 @T6G_MB_LIB.T6G(SCH_1):PAGE31
   U25 BC63 VSS_BC63 GENOA_SP5-SOCKET6096_13568-001,SMLF,IO,DGA^6000030    I24 @T6G_MB_LIB.T6G(SCH_1):PAGE31
   U25 BC65 VSS_BC65 GENOA_SP5-SOCKET6096_13568-001,SMLF,IO,DGA^6000030    I24 @T6G_MB_LIB.T6G(SCH_1):PAGE31
   U25 BC68 VSS_BC68 GENOA_SP5-SOCKET6096_13568-001,SMLF,IO,DGA^6000030    I24 @T6G_MB_LIB.T6G(SCH_1):PAGE31
   U25 BC70 VSS_BC70 GENOA_SP5-SOCKET6096_13568-001,SMLF,IO,DGA^6000030    I24 @T6G_MB_LIB.T6G(SCH_1):PAGE31
   U25 BC72 VSS_BC72 GENOA_SP5-SOCKET6096_13568-001,SMLF,IO,DGA^6000030    I24 @T6G_MB_LIB.T6G(SCH_1):PAGE31
   U25 BC75 VSS_BC75 GENOA_SP5-SOCKET6096_13568-001,SMLF,IO,DGA^6000030    I24 @T6G_MB_LIB.T6G(SCH_1):PAGE31
   U25  BD3 VSS_BD3 GENOA_SP5-SOCKET6096_13568-001,SMLF,IO,DGA^6000030    I24 @T6G_MB_LIB.T6G(SCH_1):PAGE31
   U25  BD8 VSS_BD8 GENOA_SP5-SOCKET6096_13568-001,SMLF,IO,DGA^6000030    I24 @T6G_MB_LIB.T6G(SCH_1):PAGE31
   U25 BD10 VSS_BD10 GENOA_SP5-SOCKET6096_13568-001,SMLF,IO,DGA^6000030    I24 @T6G_MB_LIB.T6G(SCH_1):PAGE31
   U25 BD15 VSS_BD15 GENOA_SP5-SOCKET6096_13568-001,SMLF,IO,DGA^6000030    I24 @T6G_MB_LIB.T6G(SCH_1):PAGE31
   U25 BD17 VSS_BD17 GENOA_SP5-SOCKET6096_13568-001,SMLF,IO,DGA^6000030    I24 @T6G_MB_LIB.T6G(SCH_1):PAGE31
   U25 BD23 VSS_BD23 GENOA_SP5-SOCKET6096_13568-001,SMLF,IO,DGA^6000030    I24 @T6G_MB_LIB.T6G(SCH_1):PAGE31
   U25 BD25 VSS_BD25 GENOA_SP5-SOCKET6096_13568-001,SMLF,IO,DGA^6000030    I24 @T6G_MB_LIB.T6G(SCH_1):PAGE31
   U25 BD27 VSS_BD27 GENOA_SP5-SOCKET6096_13568-001,SMLF,IO,DGA^6000030    I24 @T6G_MB_LIB.T6G(SCH_1):PAGE31
   U25 BD49 VSS_BD49 GENOA_SP5-SOCKET6096_13568-001,SMLF,IO,DGA^6000030    I24 @T6G_MB_LIB.T6G(SCH_1):PAGE31
   U25 BD51 VSS_BD51 GENOA_SP5-SOCKET6096_13568-001,SMLF,IO,DGA^6000030    I24 @T6G_MB_LIB.T6G(SCH_1):PAGE31
   U25 BD53 VSS_BD53 GENOA_SP5-SOCKET6096_13568-001,SMLF,IO,DGA^6000030    I24 @T6G_MB_LIB.T6G(SCH_1):PAGE31
   U25 BD57 VSS_BD57 GENOA_SP5-SOCKET6096_13568-001,SMLF,IO,DGA^6000030    I24 @T6G_MB_LIB.T6G(SCH_1):PAGE31
   U25 BD59 VSS_BD59 GENOA_SP5-SOCKET6096_13568-001,SMLF,IO,DGA^6000030    I24 @T6G_MB_LIB.T6G(SCH_1):PAGE31
   U25 BD61 VSS_BD61 GENOA_SP5-SOCKET6096_13568-001,SMLF,IO,DGA^6000030    I24 @T6G_MB_LIB.T6G(SCH_1):PAGE31
   U25 BD64 VSS_BD64 GENOA_SP5-SOCKET6096_13568-001,SMLF,IO,DGA^6000030    I24 @T6G_MB_LIB.T6G(SCH_1):PAGE31
   U25 BD66 VSS_BD66 GENOA_SP5-SOCKET6096_13568-001,SMLF,IO,DGA^6000030    I24 @T6G_MB_LIB.T6G(SCH_1):PAGE31
   U25 BD68 VSS_BD68 GENOA_SP5-SOCKET6096_13568-001,SMLF,IO,DGA^6000030    I24 @T6G_MB_LIB.T6G(SCH_1):PAGE31
   U25 BD71 VSS_BD71 GENOA_SP5-SOCKET6096_13568-001,SMLF,IO,DGA^6000030    I24 @T6G_MB_LIB.T6G(SCH_1):PAGE31
   U25 BD73 VSS_BD73 GENOA_SP5-SOCKET6096_13568-001,SMLF,IO,DGA^6000030    I24 @T6G_MB_LIB.T6G(SCH_1):PAGE31
   U25  BF3 VSS_BF3 GENOA_SP5-SOCKET6096_13568-001,SMLF,IO,DGA^6000030    I24 @T6G_MB_LIB.T6G(SCH_1):PAGE31
   U25  BF5 VSS_BF5 GENOA_SP5-SOCKET6096_13568-001,SMLF,IO,DGA^6000030    I24 @T6G_MB_LIB.T6G(SCH_1):PAGE31
   U25  BF8 VSS_BF8 GENOA_SP5-SOCKET6096_13568-001,SMLF,IO,DGA^6000030    I24 @T6G_MB_LIB.T6G(SCH_1):PAGE31
   U25 BF10 VSS_BF10 GENOA_SP5-SOCKET6096_13568-001,SMLF,IO,DGA^6000030    I24 @T6G_MB_LIB.T6G(SCH_1):PAGE31
   U25 BF12 VSS_BF12 GENOA_SP5-SOCKET6096_13568-001,SMLF,IO,DGA^6000030    I24 @T6G_MB_LIB.T6G(SCH_1):PAGE31
   U25 BF15 VSS_BF15 GENOA_SP5-SOCKET6096_13568-001,SMLF,IO,DGA^6000030    I24 @T6G_MB_LIB.T6G(SCH_1):PAGE31
   U25 BF17 VSS_BF17 GENOA_SP5-SOCKET6096_13568-001,SMLF,IO,DGA^6000030    I24 @T6G_MB_LIB.T6G(SCH_1):PAGE31
   U25 BF19 VSS_BF19 GENOA_SP5-SOCKET6096_13568-001,SMLF,IO,DGA^6000030    I24 @T6G_MB_LIB.T6G(SCH_1):PAGE31
   U25 BF22 VSS_BF22 GENOA_SP5-SOCKET6096_13568-001,SMLF,IO,DGA^6000030    I24 @T6G_MB_LIB.T6G(SCH_1):PAGE31
   U25 BF24 VSS_BF24 GENOA_SP5-SOCKET6096_13568-001,SMLF,IO,DGA^6000030    I24 @T6G_MB_LIB.T6G(SCH_1):PAGE31
   U25 BF26 VSS_BF26 GENOA_SP5-SOCKET6096_13568-001,SMLF,IO,DGA^6000030    I24 @T6G_MB_LIB.T6G(SCH_1):PAGE31
   U25 BF28 VSS_BF28 GENOA_SP5-SOCKET6096_13568-001,SMLF,IO,DGA^6000030    I24 @T6G_MB_LIB.T6G(SCH_1):PAGE31
   U25 BF49 VSS_BF49 GENOA_SP5-SOCKET6096_13568-001,SMLF,IO,DGA^6000030    I24 @T6G_MB_LIB.T6G(SCH_1):PAGE31
   U25 BF50 VSS_BF50 GENOA_SP5-SOCKET6096_13568-001,SMLF,IO,DGA^6000030    I24 @T6G_MB_LIB.T6G(SCH_1):PAGE31
   U25 BF52 VSS_BF52 GENOA_SP5-SOCKET6096_13568-001,SMLF,IO,DGA^6000030    I24 @T6G_MB_LIB.T6G(SCH_1):PAGE31
   U25 BF54 VSS_BF54 GENOA_SP5-SOCKET6096_13568-001,SMLF,IO,DGA^6000030    I24 @T6G_MB_LIB.T6G(SCH_1):PAGE31
   U25 BF59 VSS_BF59 GENOA_SP5-SOCKET6096_13568-001,SMLF,IO,DGA^6000030    I24 @T6G_MB_LIB.T6G(SCH_1):PAGE31
   U25 BF61 VSS_BF61 GENOA_SP5-SOCKET6096_13568-001,SMLF,IO,DGA^6000030    I24 @T6G_MB_LIB.T6G(SCH_1):PAGE31
   U25 BF66 VSS_BF66 GENOA_SP5-SOCKET6096_13568-001,SMLF,IO,DGA^6000030    I24 @T6G_MB_LIB.T6G(SCH_1):PAGE31
   U25 BF68 VSS_BF68 GENOA_SP5-SOCKET6096_13568-001,SMLF,IO,DGA^6000030    I24 @T6G_MB_LIB.T6G(SCH_1):PAGE31
   U25 BF73 VSS_BF73 GENOA_SP5-SOCKET6096_13568-001,SMLF,IO,DGA^6000030    I24 @T6G_MB_LIB.T6G(SCH_1):PAGE31
   U25  BG1 VSS_BG1 GENOA_SP5-SOCKET6096_13568-001,SMLF,IO,DGA^6000030    I24 @T6G_MB_LIB.T6G(SCH_1):PAGE31
   U25  BG4 VSS_BG4 GENOA_SP5-SOCKET6096_13568-001,SMLF,IO,DGA^6000030    I24 @T6G_MB_LIB.T6G(SCH_1):PAGE31
   U25  BG6 VSS_BG6 GENOA_SP5-SOCKET6096_13568-001,SMLF,IO,DGA^6000030    I24 @T6G_MB_LIB.T6G(SCH_1):PAGE31
   U25  BG8 VSS_BG8 GENOA_SP5-SOCKET6096_13568-001,SMLF,IO,DGA^6000030    I24 @T6G_MB_LIB.T6G(SCH_1):PAGE31
   U25 BG11 VSS_BG11 GENOA_SP5-SOCKET6096_13568-001,SMLF,IO,DGA^6000030    I24 @T6G_MB_LIB.T6G(SCH_1):PAGE31
   U25 BG13 VSS_BG13 GENOA_SP5-SOCKET6096_13568-001,SMLF,IO,DGA^6000030    I24 @T6G_MB_LIB.T6G(SCH_1):PAGE31
   U25 BG15 VSS_BG15 GENOA_SP5-SOCKET6096_13568-001,SMLF,IO,DGA^6000030    I24 @T6G_MB_LIB.T6G(SCH_1):PAGE31
   U25 BG18 VSS_BG18 GENOA_SP5-SOCKET6096_13568-001,SMLF,IO,DGA^6000030    I24 @T6G_MB_LIB.T6G(SCH_1):PAGE31
   U25 BG20 VSS_BG20 GENOA_SP5-SOCKET6096_13568-001,SMLF,IO,DGA^6000030    I24 @T6G_MB_LIB.T6G(SCH_1):PAGE31
   U25 BG23 VSS_BG23 GENOA_SP5-SOCKET6096_13568-001,SMLF,IO,DGA^6000030    I24 @T6G_MB_LIB.T6G(SCH_1):PAGE31
   U25 BG25 VSS_BG25 GENOA_SP5-SOCKET6096_13568-001,SMLF,IO,DGA^6000030    I24 @T6G_MB_LIB.T6G(SCH_1):PAGE31
   U25 BG27 VSS_BG27 GENOA_SP5-SOCKET6096_13568-001,SMLF,IO,DGA^6000030    I24 @T6G_MB_LIB.T6G(SCH_1):PAGE31
   U25 BG49 VSS_BG49 GENOA_SP5-SOCKET6096_13568-001,SMLF,IO,DGA^6000030    I24 @T6G_MB_LIB.T6G(SCH_1):PAGE31
   U25 BG51 VSS_BG51 GENOA_SP5-SOCKET6096_13568-001,SMLF,IO,DGA^6000030    I24 @T6G_MB_LIB.T6G(SCH_1):PAGE31
   U25 BG53 VSS_BG53 GENOA_SP5-SOCKET6096_13568-001,SMLF,IO,DGA^6000030    I24 @T6G_MB_LIB.T6G(SCH_1):PAGE31
   U25 BG56 VSS_BG56 GENOA_SP5-SOCKET6096_13568-001,SMLF,IO,DGA^6000030    I24 @T6G_MB_LIB.T6G(SCH_1):PAGE31
   U25 BG58 VSS_BG58 GENOA_SP5-SOCKET6096_13568-001,SMLF,IO,DGA^6000030    I24 @T6G_MB_LIB.T6G(SCH_1):PAGE31
   U25 BG61 VSS_BG61 GENOA_SP5-SOCKET6096_13568-001,SMLF,IO,DGA^6000030    I24 @T6G_MB_LIB.T6G(SCH_1):PAGE31
   U25 BG63 VSS_BG63 GENOA_SP5-SOCKET6096_13568-001,SMLF,IO,DGA^6000030    I24 @T6G_MB_LIB.T6G(SCH_1):PAGE31
   U25 BG65 VSS_BG65 GENOA_SP5-SOCKET6096_13568-001,SMLF,IO,DGA^6000030    I24 @T6G_MB_LIB.T6G(SCH_1):PAGE31
   U25 BG68 VSS_BG68 GENOA_SP5-SOCKET6096_13568-001,SMLF,IO,DGA^6000030    I24 @T6G_MB_LIB.T6G(SCH_1):PAGE31
   U25 BG70 VSS_BG70 GENOA_SP5-SOCKET6096_13568-001,SMLF,IO,DGA^6000030    I24 @T6G_MB_LIB.T6G(SCH_1):PAGE31
   U25 BG72 VSS_BG72 GENOA_SP5-SOCKET6096_13568-001,SMLF,IO,DGA^6000030    I24 @T6G_MB_LIB.T6G(SCH_1):PAGE31
   U25 BG75 VSS_BG75 GENOA_SP5-SOCKET6096_13568-001,SMLF,IO,DGA^6000030    I24 @T6G_MB_LIB.T6G(SCH_1):PAGE31
   U25  BH3 VSS_BH3 GENOA_SP5-SOCKET6096_13568-001,SMLF,IO,DGA^6000030    I24 @T6G_MB_LIB.T6G(SCH_1):PAGE31
   U25  BH5 VSS_BH5 GENOA_SP5-SOCKET6096_13568-001,SMLF,IO,DGA^6000030    I24 @T6G_MB_LIB.T6G(SCH_1):PAGE31
   U25  BH8 VSS_BH8 GENOA_SP5-SOCKET6096_13568-001,SMLF,IO,DGA^6000030    I24 @T6G_MB_LIB.T6G(SCH_1):PAGE31
   U25 BH10 VSS_BH10 GENOA_SP5-SOCKET6096_13568-001,SMLF,IO,DGA^6000030    I24 @T6G_MB_LIB.T6G(SCH_1):PAGE31
   U25 BH12 VSS_BH12 GENOA_SP5-SOCKET6096_13568-001,SMLF,IO,DGA^6000030    I24 @T6G_MB_LIB.T6G(SCH_1):PAGE31
   U25 BH15 VSS_BH15 GENOA_SP5-SOCKET6096_13568-001,SMLF,IO,DGA^6000030    I24 @T6G_MB_LIB.T6G(SCH_1):PAGE31
   U25 BH17 VSS_BH17 GENOA_SP5-SOCKET6096_13568-001,SMLF,IO,DGA^6000030    I24 @T6G_MB_LIB.T6G(SCH_1):PAGE31
   U25 BH19 VSS_BH19 GENOA_SP5-SOCKET6096_13568-001,SMLF,IO,DGA^6000030    I24 @T6G_MB_LIB.T6G(SCH_1):PAGE31
   U25 BH22 VSS_BH22 GENOA_SP5-SOCKET6096_13568-001,SMLF,IO,DGA^6000030    I24 @T6G_MB_LIB.T6G(SCH_1):PAGE31
   U25 BH24 VSS_BH24 GENOA_SP5-SOCKET6096_13568-001,SMLF,IO,DGA^6000030    I24 @T6G_MB_LIB.T6G(SCH_1):PAGE31
   U25 BH26 VSS_BH26 GENOA_SP5-SOCKET6096_13568-001,SMLF,IO,DGA^6000030    I24 @T6G_MB_LIB.T6G(SCH_1):PAGE31
   U25 BH28 VSS_BH28 GENOA_SP5-SOCKET6096_13568-001,SMLF,IO,DGA^6000030    I24 @T6G_MB_LIB.T6G(SCH_1):PAGE31
   U25 BH49 VSS_BH49 GENOA_SP5-SOCKET6096_13568-001,SMLF,IO,DGA^6000030    I24 @T6G_MB_LIB.T6G(SCH_1):PAGE31
   U25 BH50 VSS_BH50 GENOA_SP5-SOCKET6096_13568-001,SMLF,IO,DGA^6000030    I24 @T6G_MB_LIB.T6G(SCH_1):PAGE31
   U25 BH52 VSS_BH52 GENOA_SP5-SOCKET6096_13568-001,SMLF,IO,DGA^6000030    I24 @T6G_MB_LIB.T6G(SCH_1):PAGE31
   U25 BH54 VSS_BH54 GENOA_SP5-SOCKET6096_13568-001,SMLF,IO,DGA^6000030    I24 @T6G_MB_LIB.T6G(SCH_1):PAGE31
   U25 BH57 VSS_BH57 GENOA_SP5-SOCKET6096_13568-001,SMLF,IO,DGA^6000030    I24 @T6G_MB_LIB.T6G(SCH_1):PAGE31
   U25 BH59 VSS_BH59 GENOA_SP5-SOCKET6096_13568-001,SMLF,IO,DGA^6000030    I24 @T6G_MB_LIB.T6G(SCH_1):PAGE31
   U25 BH61 VSS_BH61 GENOA_SP5-SOCKET6096_13568-001,SMLF,IO,DGA^6000030    I24 @T6G_MB_LIB.T6G(SCH_1):PAGE31
   U25 BH64 VSS_BH64 GENOA_SP5-SOCKET6096_13568-001,SMLF,IO,DGA^6000030    I24 @T6G_MB_LIB.T6G(SCH_1):PAGE31
   U25 BH66 VSS_BH66 GENOA_SP5-SOCKET6096_13568-001,SMLF,IO,DGA^6000030    I24 @T6G_MB_LIB.T6G(SCH_1):PAGE31
   U25 BH68 VSS_BH68 GENOA_SP5-SOCKET6096_13568-001,SMLF,IO,DGA^6000030    I24 @T6G_MB_LIB.T6G(SCH_1):PAGE31
   U25 BH71 VSS_BH71 GENOA_SP5-SOCKET6096_13568-001,SMLF,IO,DGA^6000030    I24 @T6G_MB_LIB.T6G(SCH_1):PAGE31
   U25 BH73 VSS_BH73 GENOA_SP5-SOCKET6096_13568-001,SMLF,IO,DGA^6000030    I24 @T6G_MB_LIB.T6G(SCH_1):PAGE31
   U25  BJ1 VSS_BJ1 GENOA_SP5-SOCKET6096_13568-001,SMLF,IO,DGA^6000030    I24 @T6G_MB_LIB.T6G(SCH_1):PAGE31
   U25  BJ6 VSS_BJ6 GENOA_SP5-SOCKET6096_13568-001,SMLF,IO,DGA^6000030    I24 @T6G_MB_LIB.T6G(SCH_1):PAGE31
   U25  BJ8 VSS_BJ8 GENOA_SP5-SOCKET6096_13568-001,SMLF,IO,DGA^6000030    I24 @T6G_MB_LIB.T6G(SCH_1):PAGE31
   U25 BJ13 VSS_BJ13 GENOA_SP5-SOCKET6096_13568-001,SMLF,IO,DGA^6000030    I24 @T6G_MB_LIB.T6G(SCH_1):PAGE31
   U25 BJ15 VSS_BJ15 GENOA_SP5-SOCKET6096_13568-001,SMLF,IO,DGA^6000030    I24 @T6G_MB_LIB.T6G(SCH_1):PAGE31
   U25 BJ20 VSS_BJ20 GENOA_SP5-SOCKET6096_13568-001,SMLF,IO,DGA^6000030    I24 @T6G_MB_LIB.T6G(SCH_1):PAGE31
   U25 BJ22 VSS_BJ22 GENOA_SP5-SOCKET6096_13568-001,SMLF,IO,DGA^6000030    I24 @T6G_MB_LIB.T6G(SCH_1):PAGE31
   U25 BJ24 VSS_BJ24 GENOA_SP5-SOCKET6096_13568-001,SMLF,IO,DGA^6000030    I24 @T6G_MB_LIB.T6G(SCH_1):PAGE31
   U25 BJ26 VSS_BJ26 GENOA_SP5-SOCKET6096_13568-001,SMLF,IO,DGA^6000030    I24 @T6G_MB_LIB.T6G(SCH_1):PAGE31
   U25 BJ28 VSS_BJ28 GENOA_SP5-SOCKET6096_13568-001,SMLF,IO,DGA^6000030    I24 @T6G_MB_LIB.T6G(SCH_1):PAGE31
   U25 BJ49 VSS_BJ49 GENOA_SP5-SOCKET6096_13568-001,SMLF,IO,DGA^6000030    I24 @T6G_MB_LIB.T6G(SCH_1):PAGE31
   U25 BJ51 VSS_BJ51 GENOA_SP5-SOCKET6096_13568-001,SMLF,IO,DGA^6000030    I24 @T6G_MB_LIB.T6G(SCH_1):PAGE31
   U25 BJ53 VSS_BJ53 GENOA_SP5-SOCKET6096_13568-001,SMLF,IO,DGA^6000030    I24 @T6G_MB_LIB.T6G(SCH_1):PAGE31
   U25 BJ56 VSS_BJ56 GENOA_SP5-SOCKET6096_13568-001,SMLF,IO,DGA^6000030    I24 @T6G_MB_LIB.T6G(SCH_1):PAGE31
   U25 BJ61 VSS_BJ61 GENOA_SP5-SOCKET6096_13568-001,SMLF,IO,DGA^6000030    I24 @T6G_MB_LIB.T6G(SCH_1):PAGE31
   U25 BJ63 VSS_BJ63 GENOA_SP5-SOCKET6096_13568-001,SMLF,IO,DGA^6000030    I24 @T6G_MB_LIB.T6G(SCH_1):PAGE31
   U25 BJ68 VSS_BJ68 GENOA_SP5-SOCKET6096_13568-001,SMLF,IO,DGA^6000030    I24 @T6G_MB_LIB.T6G(SCH_1):PAGE31
   U25 BJ70 VSS_BJ70 GENOA_SP5-SOCKET6096_13568-001,SMLF,IO,DGA^6000030    I24 @T6G_MB_LIB.T6G(SCH_1):PAGE31
   U25 BJ75 VSS_BJ75 GENOA_SP5-SOCKET6096_13568-001,SMLF,IO,DGA^6000030    I24 @T6G_MB_LIB.T6G(SCH_1):PAGE31
   U25  BK3 VSS_BK3 GENOA_SP5-SOCKET6096_13568-001,SMLF,IO,DGA^6000030    I24 @T6G_MB_LIB.T6G(SCH_1):PAGE31
   U25  BK5 VSS_BK5 GENOA_SP5-SOCKET6096_13568-001,SMLF,IO,DGA^6000030    I24 @T6G_MB_LIB.T6G(SCH_1):PAGE31
   U25  BK8 VSS_BK8 GENOA_SP5-SOCKET6096_13568-001,SMLF,IO,DGA^6000030    I24 @T6G_MB_LIB.T6G(SCH_1):PAGE31
   U25 BK10 VSS_BK10 GENOA_SP5-SOCKET6096_13568-001,SMLF,IO,DGA^6000030    I24 @T6G_MB_LIB.T6G(SCH_1):PAGE31
   U25 BK12 VSS_BK12 GENOA_SP5-SOCKET6096_13568-001,SMLF,IO,DGA^6000030    I24 @T6G_MB_LIB.T6G(SCH_1):PAGE31
   U25 BK15 VSS_BK15 GENOA_SP5-SOCKET6096_13568-001,SMLF,IO,DGA^6000030    I24 @T6G_MB_LIB.T6G(SCH_1):PAGE31
   U25 BK17 VSS_BK17 GENOA_SP5-SOCKET6096_13568-001,SMLF,IO,DGA^6000030    I24 @T6G_MB_LIB.T6G(SCH_1):PAGE31
   U25 BK19 VSS_BK19 GENOA_SP5-SOCKET6096_13568-001,SMLF,IO,DGA^6000030    I24 @T6G_MB_LIB.T6G(SCH_1):PAGE31
   U25 BK23 VSS_BK23 GENOA_SP5-SOCKET6096_13568-001,SMLF,IO,DGA^6000030    I24 @T6G_MB_LIB.T6G(SCH_1):PAGE31
   U25 BK25 VSS_BK25 GENOA_SP5-SOCKET6096_13568-001,SMLF,IO,DGA^6000030    I24 @T6G_MB_LIB.T6G(SCH_1):PAGE31
   U25 BK27 VSS_BK27 GENOA_SP5-SOCKET6096_13568-001,SMLF,IO,DGA^6000030    I24 @T6G_MB_LIB.T6G(SCH_1):PAGE31
   U25 BK48 VSS_BK48 GENOA_SP5-SOCKET6096_13568-001,SMLF,IO,DGA^6000030    I24 @T6G_MB_LIB.T6G(SCH_1):PAGE31
   U25 BK50 VSS_BK50 GENOA_SP5-SOCKET6096_13568-001,SMLF,IO,DGA^6000030    I24 @T6G_MB_LIB.T6G(SCH_1):PAGE31
   U25 BK52 VSS_BK52 GENOA_SP5-SOCKET6096_13568-001,SMLF,IO,DGA^6000030    I24 @T6G_MB_LIB.T6G(SCH_1):PAGE31
   U25 BK54 VSS_BK54 GENOA_SP5-SOCKET6096_13568-001,SMLF,IO,DGA^6000030    I24 @T6G_MB_LIB.T6G(SCH_1):PAGE31
   U25 BK57 VSS_BK57 GENOA_SP5-SOCKET6096_13568-001,SMLF,IO,DGA^6000030    I24 @T6G_MB_LIB.T6G(SCH_1):PAGE31
   U25 BK59 VSS_BK59 GENOA_SP5-SOCKET6096_13568-001,SMLF,IO,DGA^6000030    I24 @T6G_MB_LIB.T6G(SCH_1):PAGE31
   U25 BK61 VSS_BK61 GENOA_SP5-SOCKET6096_13568-001,SMLF,IO,DGA^6000030    I24 @T6G_MB_LIB.T6G(SCH_1):PAGE31
   U25 BK64 VSS_BK64 GENOA_SP5-SOCKET6096_13568-001,SMLF,IO,DGA^6000030    I24 @T6G_MB_LIB.T6G(SCH_1):PAGE31
   U25 BK66 VSS_BK66 GENOA_SP5-SOCKET6096_13568-001,SMLF,IO,DGA^6000030    I24 @T6G_MB_LIB.T6G(SCH_1):PAGE31
   U25 BK68 VSS_BK68 GENOA_SP5-SOCKET6096_13568-001,SMLF,IO,DGA^6000030    I24 @T6G_MB_LIB.T6G(SCH_1):PAGE31
   U25 BK71 VSS_BK71 GENOA_SP5-SOCKET6096_13568-001,SMLF,IO,DGA^6000030    I24 @T6G_MB_LIB.T6G(SCH_1):PAGE31
   U25 BK73 VSS_BK73 GENOA_SP5-SOCKET6096_13568-001,SMLF,IO,DGA^6000030    I24 @T6G_MB_LIB.T6G(SCH_1):PAGE31
   U25  BL1 VSS_BL1 GENOA_SP5-SOCKET6096_13568-001,SMLF,IO,DGA^6000030    I24 @T6G_MB_LIB.T6G(SCH_1):PAGE31
   U25  BL4 VSS_BL4 GENOA_SP5-SOCKET6096_13568-001,SMLF,IO,DGA^6000030    I24 @T6G_MB_LIB.T6G(SCH_1):PAGE31
   U25  BL6 VSS_BL6 GENOA_SP5-SOCKET6096_13568-001,SMLF,IO,DGA^6000030    I24 @T6G_MB_LIB.T6G(SCH_1):PAGE31
   U25  BL8 VSS_BL8 GENOA_SP5-SOCKET6096_13568-001,SMLF,IO,DGA^6000030    I24 @T6G_MB_LIB.T6G(SCH_1):PAGE31
   U25 BL11 VSS_BL11 GENOA_SP5-SOCKET6096_13568-001,SMLF,IO,DGA^6000030    I24 @T6G_MB_LIB.T6G(SCH_1):PAGE31
   U25 BL13 VSS_BL13 GENOA_SP5-SOCKET6096_13568-001,SMLF,IO,DGA^6000030    I24 @T6G_MB_LIB.T6G(SCH_1):PAGE31
   U25 BL15 VSS_BL15 GENOA_SP5-SOCKET6096_13568-001,SMLF,IO,DGA^6000030    I24 @T6G_MB_LIB.T6G(SCH_1):PAGE31
   U25 BL18 VSS_BL18 GENOA_SP5-SOCKET6096_13568-001,SMLF,IO,DGA^6000030    I24 @T6G_MB_LIB.T6G(SCH_1):PAGE31
   U25 BL20 VSS_BL20 GENOA_SP5-SOCKET6096_13568-001,SMLF,IO,DGA^6000030    I24 @T6G_MB_LIB.T6G(SCH_1):PAGE31
   U25 BL22 VSS_BL22 GENOA_SP5-SOCKET6096_13568-001,SMLF,IO,DGA^6000030    I24 @T6G_MB_LIB.T6G(SCH_1):PAGE31
   U25 BL24 VSS_BL24 GENOA_SP5-SOCKET6096_13568-001,SMLF,IO,DGA^6000030    I24 @T6G_MB_LIB.T6G(SCH_1):PAGE31
   U25 BL26 VSS_BL26 GENOA_SP5-SOCKET6096_13568-001,SMLF,IO,DGA^6000030    I13 @T6G_MB_LIB.T6G(SCH_1):PAGE32
   U25 BL28 VSS_BL28 GENOA_SP5-SOCKET6096_13568-001,SMLF,IO,DGA^6000030    I13 @T6G_MB_LIB.T6G(SCH_1):PAGE32
   U25 BL49 VSS_BL49 GENOA_SP5-SOCKET6096_13568-001,SMLF,IO,DGA^6000030    I13 @T6G_MB_LIB.T6G(SCH_1):PAGE32
   U25 BL51 VSS_BL51 GENOA_SP5-SOCKET6096_13568-001,SMLF,IO,DGA^6000030    I13 @T6G_MB_LIB.T6G(SCH_1):PAGE32
   U25 BL53 VSS_BL53 GENOA_SP5-SOCKET6096_13568-001,SMLF,IO,DGA^6000030    I13 @T6G_MB_LIB.T6G(SCH_1):PAGE32
   U25 BL56 VSS_BL56 GENOA_SP5-SOCKET6096_13568-001,SMLF,IO,DGA^6000030    I13 @T6G_MB_LIB.T6G(SCH_1):PAGE32
   U25 BL58 VSS_BL58 GENOA_SP5-SOCKET6096_13568-001,SMLF,IO,DGA^6000030    I13 @T6G_MB_LIB.T6G(SCH_1):PAGE32
   U25 BL61 VSS_BL61 GENOA_SP5-SOCKET6096_13568-001,SMLF,IO,DGA^6000030    I13 @T6G_MB_LIB.T6G(SCH_1):PAGE32
   U25 BL63 VSS_BL63 GENOA_SP5-SOCKET6096_13568-001,SMLF,IO,DGA^6000030    I13 @T6G_MB_LIB.T6G(SCH_1):PAGE32
   U25 BL65 VSS_BL65 GENOA_SP5-SOCKET6096_13568-001,SMLF,IO,DGA^6000030    I13 @T6G_MB_LIB.T6G(SCH_1):PAGE32
   U25 BL68 VSS_BL68 GENOA_SP5-SOCKET6096_13568-001,SMLF,IO,DGA^6000030    I13 @T6G_MB_LIB.T6G(SCH_1):PAGE32
   U25 BL70 VSS_BL70 GENOA_SP5-SOCKET6096_13568-001,SMLF,IO,DGA^6000030    I13 @T6G_MB_LIB.T6G(SCH_1):PAGE32
   U25 BL72 VSS_BL72 GENOA_SP5-SOCKET6096_13568-001,SMLF,IO,DGA^6000030    I13 @T6G_MB_LIB.T6G(SCH_1):PAGE32
   U25 BL75 VSS_BL75 GENOA_SP5-SOCKET6096_13568-001,SMLF,IO,DGA^6000030    I13 @T6G_MB_LIB.T6G(SCH_1):PAGE32
   U25  BM3 VSS_BM3 GENOA_SP5-SOCKET6096_13568-001,SMLF,IO,DGA^6000030    I13 @T6G_MB_LIB.T6G(SCH_1):PAGE32
   U25  BM8 VSS_BM8 GENOA_SP5-SOCKET6096_13568-001,SMLF,IO,DGA^6000030    I13 @T6G_MB_LIB.T6G(SCH_1):PAGE32
   U25 BM10 VSS_BM10 GENOA_SP5-SOCKET6096_13568-001,SMLF,IO,DGA^6000030    I13 @T6G_MB_LIB.T6G(SCH_1):PAGE32
   U25 BM15 VSS_BM15 GENOA_SP5-SOCKET6096_13568-001,SMLF,IO,DGA^6000030    I13 @T6G_MB_LIB.T6G(SCH_1):PAGE32
   U25 BM17 VSS_BM17 GENOA_SP5-SOCKET6096_13568-001,SMLF,IO,DGA^6000030    I13 @T6G_MB_LIB.T6G(SCH_1):PAGE32
   U25 BM23 VSS_BM23 GENOA_SP5-SOCKET6096_13568-001,SMLF,IO,DGA^6000030    I13 @T6G_MB_LIB.T6G(SCH_1):PAGE32
   U25 BM25 VSS_BM25 GENOA_SP5-SOCKET6096_13568-001,SMLF,IO,DGA^6000030    I13 @T6G_MB_LIB.T6G(SCH_1):PAGE32
   U25 BM27 VSS_BM27 GENOA_SP5-SOCKET6096_13568-001,SMLF,IO,DGA^6000030    I13 @T6G_MB_LIB.T6G(SCH_1):PAGE32
   U25 BM29 VSS_BM29 GENOA_SP5-SOCKET6096_13568-001,SMLF,IO,DGA^6000030    I13 @T6G_MB_LIB.T6G(SCH_1):PAGE32
   U25 BM31 VSS_BM31 GENOA_SP5-SOCKET6096_13568-001,SMLF,IO,DGA^6000030    I13 @T6G_MB_LIB.T6G(SCH_1):PAGE32
   U25 BM33 VSS_BM33 GENOA_SP5-SOCKET6096_13568-001,SMLF,IO,DGA^6000030    I13 @T6G_MB_LIB.T6G(SCH_1):PAGE32
   U25 BM35 VSS_BM35 GENOA_SP5-SOCKET6096_13568-001,SMLF,IO,DGA^6000030    I13 @T6G_MB_LIB.T6G(SCH_1):PAGE32
   U25 BM37 VSS_BM37 GENOA_SP5-SOCKET6096_13568-001,SMLF,IO,DGA^6000030    I13 @T6G_MB_LIB.T6G(SCH_1):PAGE32
   U25 BM40 VSS_BM40 GENOA_SP5-SOCKET6096_13568-001,SMLF,IO,DGA^6000030    I13 @T6G_MB_LIB.T6G(SCH_1):PAGE32
   U25 BM42 VSS_BM42 GENOA_SP5-SOCKET6096_13568-001,SMLF,IO,DGA^6000030    I13 @T6G_MB_LIB.T6G(SCH_1):PAGE32
   U25 BM44 VSS_BM44 GENOA_SP5-SOCKET6096_13568-001,SMLF,IO,DGA^6000030    I13 @T6G_MB_LIB.T6G(SCH_1):PAGE32
   U25 BM46 VSS_BM46 GENOA_SP5-SOCKET6096_13568-001,SMLF,IO,DGA^6000030    I13 @T6G_MB_LIB.T6G(SCH_1):PAGE32
   U25 BM48 VSS_BM48 GENOA_SP5-SOCKET6096_13568-001,SMLF,IO,DGA^6000030    I13 @T6G_MB_LIB.T6G(SCH_1):PAGE32
   U25 BM50 VSS_BM50 GENOA_SP5-SOCKET6096_13568-001,SMLF,IO,DGA^6000030    I13 @T6G_MB_LIB.T6G(SCH_1):PAGE32
   U25 BM52 VSS_BM52 GENOA_SP5-SOCKET6096_13568-001,SMLF,IO,DGA^6000030    I13 @T6G_MB_LIB.T6G(SCH_1):PAGE32
   U25 BM54 VSS_BM54 GENOA_SP5-SOCKET6096_13568-001,SMLF,IO,DGA^6000030    I13 @T6G_MB_LIB.T6G(SCH_1):PAGE32
   U25 BM59 VSS_BM59 GENOA_SP5-SOCKET6096_13568-001,SMLF,IO,DGA^6000030    I13 @T6G_MB_LIB.T6G(SCH_1):PAGE32
   U25 BM61 VSS_BM61 GENOA_SP5-SOCKET6096_13568-001,SMLF,IO,DGA^6000030    I13 @T6G_MB_LIB.T6G(SCH_1):PAGE32
   U25 BM66 VSS_BM66 GENOA_SP5-SOCKET6096_13568-001,SMLF,IO,DGA^6000030    I13 @T6G_MB_LIB.T6G(SCH_1):PAGE32
   U25 BM68 VSS_BM68 GENOA_SP5-SOCKET6096_13568-001,SMLF,IO,DGA^6000030    I13 @T6G_MB_LIB.T6G(SCH_1):PAGE32
   U25 BM73 VSS_BM73 GENOA_SP5-SOCKET6096_13568-001,SMLF,IO,DGA^6000030    I13 @T6G_MB_LIB.T6G(SCH_1):PAGE32
   U25  BN1 VSS_BN1 GENOA_SP5-SOCKET6096_13568-001,SMLF,IO,DGA^6000030    I13 @T6G_MB_LIB.T6G(SCH_1):PAGE32
   U25  BN4 VSS_BN4 GENOA_SP5-SOCKET6096_13568-001,SMLF,IO,DGA^6000030    I13 @T6G_MB_LIB.T6G(SCH_1):PAGE32
   U25  BN6 VSS_BN6 GENOA_SP5-SOCKET6096_13568-001,SMLF,IO,DGA^6000030    I13 @T6G_MB_LIB.T6G(SCH_1):PAGE32
   U25  BN8 VSS_BN8 GENOA_SP5-SOCKET6096_13568-001,SMLF,IO,DGA^6000030    I13 @T6G_MB_LIB.T6G(SCH_1):PAGE32
   U25 BN11 VSS_BN11 GENOA_SP5-SOCKET6096_13568-001,SMLF,IO,DGA^6000030    I13 @T6G_MB_LIB.T6G(SCH_1):PAGE32
   U25 BN13 VSS_BN13 GENOA_SP5-SOCKET6096_13568-001,SMLF,IO,DGA^6000030    I13 @T6G_MB_LIB.T6G(SCH_1):PAGE32
   U25 BN15 VSS_BN15 GENOA_SP5-SOCKET6096_13568-001,SMLF,IO,DGA^6000030    I13 @T6G_MB_LIB.T6G(SCH_1):PAGE32
   U25 BN18 VSS_BN18 GENOA_SP5-SOCKET6096_13568-001,SMLF,IO,DGA^6000030    I13 @T6G_MB_LIB.T6G(SCH_1):PAGE32
   U25 BN20 VSS_BN20 GENOA_SP5-SOCKET6096_13568-001,SMLF,IO,DGA^6000030    I13 @T6G_MB_LIB.T6G(SCH_1):PAGE32
   U25 BN22 VSS_BN22 GENOA_SP5-SOCKET6096_13568-001,SMLF,IO,DGA^6000030    I13 @T6G_MB_LIB.T6G(SCH_1):PAGE32
   U25 BN24 VSS_BN24 GENOA_SP5-SOCKET6096_13568-001,SMLF,IO,DGA^6000030    I13 @T6G_MB_LIB.T6G(SCH_1):PAGE32
   U25 BN26 VSS_BN26 GENOA_SP5-SOCKET6096_13568-001,SMLF,IO,DGA^6000030    I13 @T6G_MB_LIB.T6G(SCH_1):PAGE32
   U25 BN28 VSS_BN28 GENOA_SP5-SOCKET6096_13568-001,SMLF,IO,DGA^6000030    I13 @T6G_MB_LIB.T6G(SCH_1):PAGE32
   U25 BN30 VSS_BN30 GENOA_SP5-SOCKET6096_13568-001,SMLF,IO,DGA^6000030    I13 @T6G_MB_LIB.T6G(SCH_1):PAGE32
   U25 BN32 VSS_BN32 GENOA_SP5-SOCKET6096_13568-001,SMLF,IO,DGA^6000030    I13 @T6G_MB_LIB.T6G(SCH_1):PAGE32
   U25 BN34 VSS_BN34 GENOA_SP5-SOCKET6096_13568-001,SMLF,IO,DGA^6000030    I13 @T6G_MB_LIB.T6G(SCH_1):PAGE32
   U25 BN36 VSS_BN36 GENOA_SP5-SOCKET6096_13568-001,SMLF,IO,DGA^6000030    I13 @T6G_MB_LIB.T6G(SCH_1):PAGE32
   U25 BN41 VSS_BN41 GENOA_SP5-SOCKET6096_13568-001,SMLF,IO,DGA^6000030    I13 @T6G_MB_LIB.T6G(SCH_1):PAGE32
   U25 BN43 VSS_BN43 GENOA_SP5-SOCKET6096_13568-001,SMLF,IO,DGA^6000030    I13 @T6G_MB_LIB.T6G(SCH_1):PAGE32
   U25 BN45 VSS_BN45 GENOA_SP5-SOCKET6096_13568-001,SMLF,IO,DGA^6000030    I13 @T6G_MB_LIB.T6G(SCH_1):PAGE32
   U25 BN47 VSS_BN47 GENOA_SP5-SOCKET6096_13568-001,SMLF,IO,DGA^6000030    I13 @T6G_MB_LIB.T6G(SCH_1):PAGE32
   U25 BN49 VSS_BN49 GENOA_SP5-SOCKET6096_13568-001,SMLF,IO,DGA^6000030    I13 @T6G_MB_LIB.T6G(SCH_1):PAGE32
   U25 BN51 VSS_BN51 GENOA_SP5-SOCKET6096_13568-001,SMLF,IO,DGA^6000030    I13 @T6G_MB_LIB.T6G(SCH_1):PAGE32
   U25 BN53 VSS_BN53 GENOA_SP5-SOCKET6096_13568-001,SMLF,IO,DGA^6000030    I13 @T6G_MB_LIB.T6G(SCH_1):PAGE32
   U25 BN56 VSS_BN56 GENOA_SP5-SOCKET6096_13568-001,SMLF,IO,DGA^6000030    I13 @T6G_MB_LIB.T6G(SCH_1):PAGE32
   U25 BN58 VSS_BN58 GENOA_SP5-SOCKET6096_13568-001,SMLF,IO,DGA^6000030    I13 @T6G_MB_LIB.T6G(SCH_1):PAGE32
   U25 BN61 VSS_BN61 GENOA_SP5-SOCKET6096_13568-001,SMLF,IO,DGA^6000030    I13 @T6G_MB_LIB.T6G(SCH_1):PAGE32
   U25 BN63 VSS_BN63 GENOA_SP5-SOCKET6096_13568-001,SMLF,IO,DGA^6000030    I13 @T6G_MB_LIB.T6G(SCH_1):PAGE32
   U25 BN65 VSS_BN65 GENOA_SP5-SOCKET6096_13568-001,SMLF,IO,DGA^6000030    I13 @T6G_MB_LIB.T6G(SCH_1):PAGE32
   U25 BN68 VSS_BN68 GENOA_SP5-SOCKET6096_13568-001,SMLF,IO,DGA^6000030    I13 @T6G_MB_LIB.T6G(SCH_1):PAGE32
   U25 BN70 VSS_BN70 GENOA_SP5-SOCKET6096_13568-001,SMLF,IO,DGA^6000030    I13 @T6G_MB_LIB.T6G(SCH_1):PAGE32
   U25 BN72 VSS_BN72 GENOA_SP5-SOCKET6096_13568-001,SMLF,IO,DGA^6000030    I13 @T6G_MB_LIB.T6G(SCH_1):PAGE32
   U25 BN75 VSS_BN75 GENOA_SP5-SOCKET6096_13568-001,SMLF,IO,DGA^6000030    I13 @T6G_MB_LIB.T6G(SCH_1):PAGE32
   U25  BP3 VSS_BP3 GENOA_SP5-SOCKET6096_13568-001,SMLF,IO,DGA^6000030    I13 @T6G_MB_LIB.T6G(SCH_1):PAGE32
   U25  BP5 VSS_BP5 GENOA_SP5-SOCKET6096_13568-001,SMLF,IO,DGA^6000030    I13 @T6G_MB_LIB.T6G(SCH_1):PAGE32
   U25  BP8 VSS_BP8 GENOA_SP5-SOCKET6096_13568-001,SMLF,IO,DGA^6000030    I13 @T6G_MB_LIB.T6G(SCH_1):PAGE32
   U25 BP10 VSS_BP10 GENOA_SP5-SOCKET6096_13568-001,SMLF,IO,DGA^6000030    I13 @T6G_MB_LIB.T6G(SCH_1):PAGE32
   U25 BP12 VSS_BP12 GENOA_SP5-SOCKET6096_13568-001,SMLF,IO,DGA^6000030    I13 @T6G_MB_LIB.T6G(SCH_1):PAGE32
   U25 BP15 VSS_BP15 GENOA_SP5-SOCKET6096_13568-001,SMLF,IO,DGA^6000030    I13 @T6G_MB_LIB.T6G(SCH_1):PAGE32
   U25 BP17 VSS_BP17 GENOA_SP5-SOCKET6096_13568-001,SMLF,IO,DGA^6000030    I13 @T6G_MB_LIB.T6G(SCH_1):PAGE32
   U25 BP19 VSS_BP19 GENOA_SP5-SOCKET6096_13568-001,SMLF,IO,DGA^6000030    I13 @T6G_MB_LIB.T6G(SCH_1):PAGE32
   U25 BP23 VSS_BP23 GENOA_SP5-SOCKET6096_13568-001,SMLF,IO,DGA^6000030    I13 @T6G_MB_LIB.T6G(SCH_1):PAGE32
   U25 BP25 VSS_BP25 GENOA_SP5-SOCKET6096_13568-001,SMLF,IO,DGA^6000030    I13 @T6G_MB_LIB.T6G(SCH_1):PAGE32
   U25 BP27 VSS_BP27 GENOA_SP5-SOCKET6096_13568-001,SMLF,IO,DGA^6000030    I13 @T6G_MB_LIB.T6G(SCH_1):PAGE32
   U25 BP29 VSS_BP29 GENOA_SP5-SOCKET6096_13568-001,SMLF,IO,DGA^6000030    I13 @T6G_MB_LIB.T6G(SCH_1):PAGE32
   U25 BP31 VSS_BP31 GENOA_SP5-SOCKET6096_13568-001,SMLF,IO,DGA^6000030    I13 @T6G_MB_LIB.T6G(SCH_1):PAGE32
   U25 BP33 VSS_BP33 GENOA_SP5-SOCKET6096_13568-001,SMLF,IO,DGA^6000030    I13 @T6G_MB_LIB.T6G(SCH_1):PAGE32
   U25 BP35 VSS_BP35 GENOA_SP5-SOCKET6096_13568-001,SMLF,IO,DGA^6000030    I13 @T6G_MB_LIB.T6G(SCH_1):PAGE32
   U25 BP37 VSS_BP37 GENOA_SP5-SOCKET6096_13568-001,SMLF,IO,DGA^6000030    I13 @T6G_MB_LIB.T6G(SCH_1):PAGE32
   U25 BP40 VSS_BP40 GENOA_SP5-SOCKET6096_13568-001,SMLF,IO,DGA^6000030    I13 @T6G_MB_LIB.T6G(SCH_1):PAGE32
   U25 BP42 VSS_BP42 GENOA_SP5-SOCKET6096_13568-001,SMLF,IO,DGA^6000030    I13 @T6G_MB_LIB.T6G(SCH_1):PAGE32
   U25 BP44 VSS_BP44 GENOA_SP5-SOCKET6096_13568-001,SMLF,IO,DGA^6000030    I13 @T6G_MB_LIB.T6G(SCH_1):PAGE32
   U25 BP46 VSS_BP46 GENOA_SP5-SOCKET6096_13568-001,SMLF,IO,DGA^6000030    I13 @T6G_MB_LIB.T6G(SCH_1):PAGE32
   U25 BP48 VSS_BP48 GENOA_SP5-SOCKET6096_13568-001,SMLF,IO,DGA^6000030    I13 @T6G_MB_LIB.T6G(SCH_1):PAGE32
   U25 BP50 VSS_BP50 GENOA_SP5-SOCKET6096_13568-001,SMLF,IO,DGA^6000030    I13 @T6G_MB_LIB.T6G(SCH_1):PAGE32
   U25 BP52 VSS_BP52 GENOA_SP5-SOCKET6096_13568-001,SMLF,IO,DGA^6000030    I13 @T6G_MB_LIB.T6G(SCH_1):PAGE32
   U25 BP54 VSS_BP54 GENOA_SP5-SOCKET6096_13568-001,SMLF,IO,DGA^6000030    I13 @T6G_MB_LIB.T6G(SCH_1):PAGE32
   U25 BP57 VSS_BP57 GENOA_SP5-SOCKET6096_13568-001,SMLF,IO,DGA^6000030    I13 @T6G_MB_LIB.T6G(SCH_1):PAGE32
   U25 BP59 VSS_BP59 GENOA_SP5-SOCKET6096_13568-001,SMLF,IO,DGA^6000030    I13 @T6G_MB_LIB.T6G(SCH_1):PAGE32
   U25 BP61 VSS_BP61 GENOA_SP5-SOCKET6096_13568-001,SMLF,IO,DGA^6000030    I13 @T6G_MB_LIB.T6G(SCH_1):PAGE32
   U25 BP64 VSS_BP64 GENOA_SP5-SOCKET6096_13568-001,SMLF,IO,DGA^6000030    I13 @T6G_MB_LIB.T6G(SCH_1):PAGE32
   U25 BP66 VSS_BP66 GENOA_SP5-SOCKET6096_13568-001,SMLF,IO,DGA^6000030    I13 @T6G_MB_LIB.T6G(SCH_1):PAGE32
   U25 BP68 VSS_BP68 GENOA_SP5-SOCKET6096_13568-001,SMLF,IO,DGA^6000030    I13 @T6G_MB_LIB.T6G(SCH_1):PAGE32
   U25 BP71 VSS_BP71 GENOA_SP5-SOCKET6096_13568-001,SMLF,IO,DGA^6000030    I13 @T6G_MB_LIB.T6G(SCH_1):PAGE32
   U25 BP73 VSS_BP73 GENOA_SP5-SOCKET6096_13568-001,SMLF,IO,DGA^6000030    I13 @T6G_MB_LIB.T6G(SCH_1):PAGE32
   U25  BR1 VSS_BR1 GENOA_SP5-SOCKET6096_13568-001,SMLF,IO,DGA^6000030    I13 @T6G_MB_LIB.T6G(SCH_1):PAGE32
   U25  BR3 VSS_BR3 GENOA_SP5-SOCKET6096_13568-001,SMLF,IO,DGA^6000030    I13 @T6G_MB_LIB.T6G(SCH_1):PAGE32
   U25  BR6 VSS_BR6 GENOA_SP5-SOCKET6096_13568-001,SMLF,IO,DGA^6000030    I13 @T6G_MB_LIB.T6G(SCH_1):PAGE32
   U25  BR7 VSS_BR7 GENOA_SP5-SOCKET6096_13568-001,SMLF,IO,DGA^6000030    I13 @T6G_MB_LIB.T6G(SCH_1):PAGE32
   U25  BR8 VSS_BR8 GENOA_SP5-SOCKET6096_13568-001,SMLF,IO,DGA^6000030    I13 @T6G_MB_LIB.T6G(SCH_1):PAGE32
   U25 BR10 VSS_BR10 GENOA_SP5-SOCKET6096_13568-001,SMLF,IO,DGA^6000030    I13 @T6G_MB_LIB.T6G(SCH_1):PAGE32
   U25 BR13 VSS_BR13 GENOA_SP5-SOCKET6096_13568-001,SMLF,IO,DGA^6000030    I13 @T6G_MB_LIB.T6G(SCH_1):PAGE32
   U25 BR14 VSS_BR14 GENOA_SP5-SOCKET6096_13568-001,SMLF,IO,DGA^6000030    I13 @T6G_MB_LIB.T6G(SCH_1):PAGE32
   U25 BR15 VSS_BR15 GENOA_SP5-SOCKET6096_13568-001,SMLF,IO,DGA^6000030    I13 @T6G_MB_LIB.T6G(SCH_1):PAGE32
   U25 BR17 VSS_BR17 GENOA_SP5-SOCKET6096_13568-001,SMLF,IO,DGA^6000030    I13 @T6G_MB_LIB.T6G(SCH_1):PAGE32
   U25 BR20 VSS_BR20 GENOA_SP5-SOCKET6096_13568-001,SMLF,IO,DGA^6000030    I13 @T6G_MB_LIB.T6G(SCH_1):PAGE32
   U25 BR21 VSS_BR21 GENOA_SP5-SOCKET6096_13568-001,SMLF,IO,DGA^6000030    I13 @T6G_MB_LIB.T6G(SCH_1):PAGE32
   U25 BR22 VSS_BR22 GENOA_SP5-SOCKET6096_13568-001,SMLF,IO,DGA^6000030    I13 @T6G_MB_LIB.T6G(SCH_1):PAGE32
   U25 BR24 VSS_BR24 GENOA_SP5-SOCKET6096_13568-001,SMLF,IO,DGA^6000030    I13 @T6G_MB_LIB.T6G(SCH_1):PAGE32
   U25 BR26 VSS_BR26 GENOA_SP5-SOCKET6096_13568-001,SMLF,IO,DGA^6000030    I13 @T6G_MB_LIB.T6G(SCH_1):PAGE32
   U25 BR28 VSS_BR28 GENOA_SP5-SOCKET6096_13568-001,SMLF,IO,DGA^6000030    I13 @T6G_MB_LIB.T6G(SCH_1):PAGE32
   U25 BR30 VSS_BR30 GENOA_SP5-SOCKET6096_13568-001,SMLF,IO,DGA^6000030    I13 @T6G_MB_LIB.T6G(SCH_1):PAGE32
   U25 BR32 VSS_BR32 GENOA_SP5-SOCKET6096_13568-001,SMLF,IO,DGA^6000030    I13 @T6G_MB_LIB.T6G(SCH_1):PAGE32
   U25 BR34 VSS_BR34 GENOA_SP5-SOCKET6096_13568-001,SMLF,IO,DGA^6000030    I13 @T6G_MB_LIB.T6G(SCH_1):PAGE32
   U25 BR36 VSS_BR36 GENOA_SP5-SOCKET6096_13568-001,SMLF,IO,DGA^6000030    I13 @T6G_MB_LIB.T6G(SCH_1):PAGE32
   U25 BR41 VSS_BR41 GENOA_SP5-SOCKET6096_13568-001,SMLF,IO,DGA^6000030    I13 @T6G_MB_LIB.T6G(SCH_1):PAGE32
   U25 BR43 VSS_BR43 GENOA_SP5-SOCKET6096_13568-001,SMLF,IO,DGA^6000030    I13 @T6G_MB_LIB.T6G(SCH_1):PAGE32
   U25 BR45 VSS_BR45 GENOA_SP5-SOCKET6096_13568-001,SMLF,IO,DGA^6000030    I13 @T6G_MB_LIB.T6G(SCH_1):PAGE32
   U25 BR47 VSS_BR47 GENOA_SP5-SOCKET6096_13568-001,SMLF,IO,DGA^6000030    I13 @T6G_MB_LIB.T6G(SCH_1):PAGE32
   U25 BR49 VSS_BR49 GENOA_SP5-SOCKET6096_13568-001,SMLF,IO,DGA^6000030    I13 @T6G_MB_LIB.T6G(SCH_1):PAGE32
   U25 BR51 VSS_BR51 GENOA_SP5-SOCKET6096_13568-001,SMLF,IO,DGA^6000030    I13 @T6G_MB_LIB.T6G(SCH_1):PAGE32
   U25 BR55 VSS_BR55 GENOA_SP5-SOCKET6096_13568-001,SMLF,IO,DGA^6000030    I13 @T6G_MB_LIB.T6G(SCH_1):PAGE32
   U25 BR56 VSS_BR56 GENOA_SP5-SOCKET6096_13568-001,SMLF,IO,DGA^6000030    I13 @T6G_MB_LIB.T6G(SCH_1):PAGE32
   U25 BR59 VSS_BR59 GENOA_SP5-SOCKET6096_13568-001,SMLF,IO,DGA^6000030    I13 @T6G_MB_LIB.T6G(SCH_1):PAGE32
   U25 BR61 VSS_BR61 GENOA_SP5-SOCKET6096_13568-001,SMLF,IO,DGA^6000030    I13 @T6G_MB_LIB.T6G(SCH_1):PAGE32
   U25 BR62 VSS_BR62 GENOA_SP5-SOCKET6096_13568-001,SMLF,IO,DGA^6000030    I13 @T6G_MB_LIB.T6G(SCH_1):PAGE32
   U25 BR63 VSS_BR63 GENOA_SP5-SOCKET6096_13568-001,SMLF,IO,DGA^6000030    I13 @T6G_MB_LIB.T6G(SCH_1):PAGE32
   U25 BR66 VSS_BR66 GENOA_SP5-SOCKET6096_13568-001,SMLF,IO,DGA^6000030    I13 @T6G_MB_LIB.T6G(SCH_1):PAGE32
   U25 BR68 VSS_BR68 GENOA_SP5-SOCKET6096_13568-001,SMLF,IO,DGA^6000030    I13 @T6G_MB_LIB.T6G(SCH_1):PAGE32
   U25 BR69 VSS_BR69 GENOA_SP5-SOCKET6096_13568-001,SMLF,IO,DGA^6000030    I13 @T6G_MB_LIB.T6G(SCH_1):PAGE32
   U25 BR70 VSS_BR70 GENOA_SP5-SOCKET6096_13568-001,SMLF,IO,DGA^6000030    I13 @T6G_MB_LIB.T6G(SCH_1):PAGE32
   U25 BR73 VSS_BR73 GENOA_SP5-SOCKET6096_13568-001,SMLF,IO,DGA^6000030    I13 @T6G_MB_LIB.T6G(SCH_1):PAGE32
   U25 BR75 VSS_BR75 GENOA_SP5-SOCKET6096_13568-001,SMLF,IO,DGA^6000030    I13 @T6G_MB_LIB.T6G(SCH_1):PAGE32
   U25  BT3 VSS_BT3 GENOA_SP5-SOCKET6096_13568-001,SMLF,IO,DGA^6000030    I13 @T6G_MB_LIB.T6G(SCH_1):PAGE32
   U25  BT4 VSS_BT4 GENOA_SP5-SOCKET6096_13568-001,SMLF,IO,DGA^6000030    I13 @T6G_MB_LIB.T6G(SCH_1):PAGE32
   U25  BT5 VSS_BT5 GENOA_SP5-SOCKET6096_13568-001,SMLF,IO,DGA^6000030    I13 @T6G_MB_LIB.T6G(SCH_1):PAGE32
   U25  BT7 VSS_BT7 GENOA_SP5-SOCKET6096_13568-001,SMLF,IO,DGA^6000030    I13 @T6G_MB_LIB.T6G(SCH_1):PAGE32
   U25  BT8 VSS_BT8 GENOA_SP5-SOCKET6096_13568-001,SMLF,IO,DGA^6000030    I13 @T6G_MB_LIB.T6G(SCH_1):PAGE32
   U25 BT10 VSS_BT10 GENOA_SP5-SOCKET6096_13568-001,SMLF,IO,DGA^6000030    I13 @T6G_MB_LIB.T6G(SCH_1):PAGE32
   U25 BT11 VSS_BT11 GENOA_SP5-SOCKET6096_13568-001,SMLF,IO,DGA^6000030    I13 @T6G_MB_LIB.T6G(SCH_1):PAGE32
   U25 BT12 VSS_BT12 GENOA_SP5-SOCKET6096_13568-001,SMLF,IO,DGA^6000030    I13 @T6G_MB_LIB.T6G(SCH_1):PAGE32
   U25 BT14 VSS_BT14 GENOA_SP5-SOCKET6096_13568-001,SMLF,IO,DGA^6000030    I13 @T6G_MB_LIB.T6G(SCH_1):PAGE32
   U25 BT15 VSS_BT15 GENOA_SP5-SOCKET6096_13568-001,SMLF,IO,DGA^6000030    I13 @T6G_MB_LIB.T6G(SCH_1):PAGE32
   U25 BT17 VSS_BT17 GENOA_SP5-SOCKET6096_13568-001,SMLF,IO,DGA^6000030    I13 @T6G_MB_LIB.T6G(SCH_1):PAGE32
   U25 BT18 VSS_BT18 GENOA_SP5-SOCKET6096_13568-001,SMLF,IO,DGA^6000030    I13 @T6G_MB_LIB.T6G(SCH_1):PAGE32
   U25 BT19 VSS_BT19 GENOA_SP5-SOCKET6096_13568-001,SMLF,IO,DGA^6000030    I13 @T6G_MB_LIB.T6G(SCH_1):PAGE32
   U25 BT21 VSS_BT21 GENOA_SP5-SOCKET6096_13568-001,SMLF,IO,DGA^6000030    I13 @T6G_MB_LIB.T6G(SCH_1):PAGE32
   U25 BT22 VSS_BT22 GENOA_SP5-SOCKET6096_13568-001,SMLF,IO,DGA^6000030    I13 @T6G_MB_LIB.T6G(SCH_1):PAGE32
   U25 BT25 VSS_BT25 GENOA_SP5-SOCKET6096_13568-001,SMLF,IO,DGA^6000030    I13 @T6G_MB_LIB.T6G(SCH_1):PAGE32
   U25 BT28 VSS_BT28 GENOA_SP5-SOCKET6096_13568-001,SMLF,IO,DGA^6000030    I13 @T6G_MB_LIB.T6G(SCH_1):PAGE32
   U25 BT31 VSS_BT31 GENOA_SP5-SOCKET6096_13568-001,SMLF,IO,DGA^6000030    I13 @T6G_MB_LIB.T6G(SCH_1):PAGE32
   U25 BT34 VSS_BT34 GENOA_SP5-SOCKET6096_13568-001,SMLF,IO,DGA^6000030    I13 @T6G_MB_LIB.T6G(SCH_1):PAGE32
   U25 BT37 VSS_BT37 GENOA_SP5-SOCKET6096_13568-001,SMLF,IO,DGA^6000030    I13 @T6G_MB_LIB.T6G(SCH_1):PAGE32
   U25 BT39 VSS_BT39 GENOA_SP5-SOCKET6096_13568-001,SMLF,IO,DGA^6000030    I13 @T6G_MB_LIB.T6G(SCH_1):PAGE32
   U25 BT42 VSS_BT42 GENOA_SP5-SOCKET6096_13568-001,SMLF,IO,DGA^6000030    I13 @T6G_MB_LIB.T6G(SCH_1):PAGE32
   U25 BT45 VSS_BT45 GENOA_SP5-SOCKET6096_13568-001,SMLF,IO,DGA^6000030    I13 @T6G_MB_LIB.T6G(SCH_1):PAGE32
   U25 BT48 VSS_BT48 GENOA_SP5-SOCKET6096_13568-001,SMLF,IO,DGA^6000030    I13 @T6G_MB_LIB.T6G(SCH_1):PAGE32
   U25 BT51 VSS_BT51 GENOA_SP5-SOCKET6096_13568-001,SMLF,IO,DGA^6000030    I13 @T6G_MB_LIB.T6G(SCH_1):PAGE32
   U25 BT54 VSS_BT54 GENOA_SP5-SOCKET6096_13568-001,SMLF,IO,DGA^6000030    I13 @T6G_MB_LIB.T6G(SCH_1):PAGE32
   U25 BT55 VSS_BT55 GENOA_SP5-SOCKET6096_13568-001,SMLF,IO,DGA^6000030    I13 @T6G_MB_LIB.T6G(SCH_1):PAGE32
   U25 BT57 VSS_BT57 GENOA_SP5-SOCKET6096_13568-001,SMLF,IO,DGA^6000030    I13 @T6G_MB_LIB.T6G(SCH_1):PAGE32
   U25 BT58 VSS_BT58 GENOA_SP5-SOCKET6096_13568-001,SMLF,IO,DGA^6000030    I13 @T6G_MB_LIB.T6G(SCH_1):PAGE32
   U25 BT59 VSS_BT59 GENOA_SP5-SOCKET6096_13568-001,SMLF,IO,DGA^6000030    I13 @T6G_MB_LIB.T6G(SCH_1):PAGE32
   U25 BT61 VSS_BT61 GENOA_SP5-SOCKET6096_13568-001,SMLF,IO,DGA^6000030    I13 @T6G_MB_LIB.T6G(SCH_1):PAGE32
   U25 BT62 VSS_BT62 GENOA_SP5-SOCKET6096_13568-001,SMLF,IO,DGA^6000030    I13 @T6G_MB_LIB.T6G(SCH_1):PAGE32
   U25 BT64 VSS_BT64 GENOA_SP5-SOCKET6096_13568-001,SMLF,IO,DGA^6000030    I13 @T6G_MB_LIB.T6G(SCH_1):PAGE32
   U25 BT65 VSS_BT65 GENOA_SP5-SOCKET6096_13568-001,SMLF,IO,DGA^6000030    I13 @T6G_MB_LIB.T6G(SCH_1):PAGE32
   U25 BT66 VSS_BT66 GENOA_SP5-SOCKET6096_13568-001,SMLF,IO,DGA^6000030    I13 @T6G_MB_LIB.T6G(SCH_1):PAGE32
   U25 BT68 VSS_BT68 GENOA_SP5-SOCKET6096_13568-001,SMLF,IO,DGA^6000030    I13 @T6G_MB_LIB.T6G(SCH_1):PAGE32
   U25 BT69 VSS_BT69 GENOA_SP5-SOCKET6096_13568-001,SMLF,IO,DGA^6000030    I13 @T6G_MB_LIB.T6G(SCH_1):PAGE32
   U25 BT71 VSS_BT71 GENOA_SP5-SOCKET6096_13568-001,SMLF,IO,DGA^6000030    I13 @T6G_MB_LIB.T6G(SCH_1):PAGE32
   U25 BT72 VSS_BT72 GENOA_SP5-SOCKET6096_13568-001,SMLF,IO,DGA^6000030    I13 @T6G_MB_LIB.T6G(SCH_1):PAGE32
   U25 BT73 VSS_BT73 GENOA_SP5-SOCKET6096_13568-001,SMLF,IO,DGA^6000030    I13 @T6G_MB_LIB.T6G(SCH_1):PAGE32
   U25  BU1 VSS_BU1 GENOA_SP5-SOCKET6096_13568-001,SMLF,IO,DGA^6000030    I13 @T6G_MB_LIB.T6G(SCH_1):PAGE32
   U25  BU4 VSS_BU4 GENOA_SP5-SOCKET6096_13568-001,SMLF,IO,DGA^6000030    I13 @T6G_MB_LIB.T6G(SCH_1):PAGE32
   U25  BU6 VSS_BU6 GENOA_SP5-SOCKET6096_13568-001,SMLF,IO,DGA^6000030    I13 @T6G_MB_LIB.T6G(SCH_1):PAGE32
   U25  BU8 VSS_BU8 GENOA_SP5-SOCKET6096_13568-001,SMLF,IO,DGA^6000030    I13 @T6G_MB_LIB.T6G(SCH_1):PAGE32
   U25 BU11 VSS_BU11 GENOA_SP5-SOCKET6096_13568-001,SMLF,IO,DGA^6000030    I13 @T6G_MB_LIB.T6G(SCH_1):PAGE32
   U25 BU13 VSS_BU13 GENOA_SP5-SOCKET6096_13568-001,SMLF,IO,DGA^6000030    I13 @T6G_MB_LIB.T6G(SCH_1):PAGE32
   U25 BU15 VSS_BU15 GENOA_SP5-SOCKET6096_13568-001,SMLF,IO,DGA^6000030    I13 @T6G_MB_LIB.T6G(SCH_1):PAGE32
   U25 BU18 VSS_BU18 GENOA_SP5-SOCKET6096_13568-001,SMLF,IO,DGA^6000030    I13 @T6G_MB_LIB.T6G(SCH_1):PAGE32
   U25 BU20 VSS_BU20 GENOA_SP5-SOCKET6096_13568-001,SMLF,IO,DGA^6000030    I13 @T6G_MB_LIB.T6G(SCH_1):PAGE32
   U25 BU22 VSS_BU22 GENOA_SP5-SOCKET6096_13568-001,SMLF,IO,DGA^6000030    I13 @T6G_MB_LIB.T6G(SCH_1):PAGE32
   U25 BU25 VSS_BU25 GENOA_SP5-SOCKET6096_13568-001,SMLF,IO,DGA^6000030    I13 @T6G_MB_LIB.T6G(SCH_1):PAGE32
   U25 BU28 VSS_BU28 GENOA_SP5-SOCKET6096_13568-001,SMLF,IO,DGA^6000030    I13 @T6G_MB_LIB.T6G(SCH_1):PAGE32
   U25 BU31 VSS_BU31 GENOA_SP5-SOCKET6096_13568-001,SMLF,IO,DGA^6000030    I13 @T6G_MB_LIB.T6G(SCH_1):PAGE32
   U25 BU34 VSS_BU34 GENOA_SP5-SOCKET6096_13568-001,SMLF,IO,DGA^6000030    I13 @T6G_MB_LIB.T6G(SCH_1):PAGE32
   U25 BU35 VSS_BU35 GENOA_SP5-SOCKET6096_13568-001,SMLF,IO,DGA^6000030    I13 @T6G_MB_LIB.T6G(SCH_1):PAGE32
   U25 BU36 VSS_BU36 GENOA_SP5-SOCKET6096_13568-001,SMLF,IO,DGA^6000030    I13 @T6G_MB_LIB.T6G(SCH_1):PAGE32
   U25 BU40 VSS_BU40 GENOA_SP5-SOCKET6096_13568-001,SMLF,IO,DGA^6000030    I13 @T6G_MB_LIB.T6G(SCH_1):PAGE32
   U25 BU41 VSS_BU41 GENOA_SP5-SOCKET6096_13568-001,SMLF,IO,DGA^6000030    I13 @T6G_MB_LIB.T6G(SCH_1):PAGE32
   U25 BU42 VSS_BU42 GENOA_SP5-SOCKET6096_13568-001,SMLF,IO,DGA^6000030    I13 @T6G_MB_LIB.T6G(SCH_1):PAGE32
   U25 BU45 VSS_BU45 GENOA_SP5-SOCKET6096_13568-001,SMLF,IO,DGA^6000030    I13 @T6G_MB_LIB.T6G(SCH_1):PAGE32
   U25 BU48 VSS_BU48 GENOA_SP5-SOCKET6096_13568-001,SMLF,IO,DGA^6000030    I13 @T6G_MB_LIB.T6G(SCH_1):PAGE32
   U25 BU51 VSS_BU51 GENOA_SP5-SOCKET6096_13568-001,SMLF,IO,DGA^6000030    I13 @T6G_MB_LIB.T6G(SCH_1):PAGE32
   U25 BU54 VSS_BU54 GENOA_SP5-SOCKET6096_13568-001,SMLF,IO,DGA^6000030    I13 @T6G_MB_LIB.T6G(SCH_1):PAGE32
   U25 BU56 VSS_BU56 GENOA_SP5-SOCKET6096_13568-001,SMLF,IO,DGA^6000030    I13 @T6G_MB_LIB.T6G(SCH_1):PAGE32
   U25 BU58 VSS_BU58 GENOA_SP5-SOCKET6096_13568-001,SMLF,IO,DGA^6000030    I13 @T6G_MB_LIB.T6G(SCH_1):PAGE32
   U25 BU61 VSS_BU61 GENOA_SP5-SOCKET6096_13568-001,SMLF,IO,DGA^6000030    I13 @T6G_MB_LIB.T6G(SCH_1):PAGE32
   U25 BU63 VSS_BU63 GENOA_SP5-SOCKET6096_13568-001,SMLF,IO,DGA^6000030    I13 @T6G_MB_LIB.T6G(SCH_1):PAGE32
   U25 BU65 VSS_BU65 GENOA_SP5-SOCKET6096_13568-001,SMLF,IO,DGA^6000030    I13 @T6G_MB_LIB.T6G(SCH_1):PAGE32
   U25 BU68 VSS_BU68 GENOA_SP5-SOCKET6096_13568-001,SMLF,IO,DGA^6000030    I13 @T6G_MB_LIB.T6G(SCH_1):PAGE32
   U25 BU70 VSS_BU70 GENOA_SP5-SOCKET6096_13568-001,SMLF,IO,DGA^6000030    I13 @T6G_MB_LIB.T6G(SCH_1):PAGE32
   U25 BU72 VSS_BU72 GENOA_SP5-SOCKET6096_13568-001,SMLF,IO,DGA^6000030    I13 @T6G_MB_LIB.T6G(SCH_1):PAGE32
   U25 BU75 VSS_BU75 GENOA_SP5-SOCKET6096_13568-001,SMLF,IO,DGA^6000030    I13 @T6G_MB_LIB.T6G(SCH_1):PAGE32
   U25  BV3 VSS_BV3 GENOA_SP5-SOCKET6096_13568-001,SMLF,IO,DGA^6000030    I13 @T6G_MB_LIB.T6G(SCH_1):PAGE32
   U25  BV8 VSS_BV8 GENOA_SP5-SOCKET6096_13568-001,SMLF,IO,DGA^6000030    I13 @T6G_MB_LIB.T6G(SCH_1):PAGE32
   U25 BV10 VSS_BV10 GENOA_SP5-SOCKET6096_13568-001,SMLF,IO,DGA^6000030    I13 @T6G_MB_LIB.T6G(SCH_1):PAGE32
   U25 BV15 VSS_BV15 GENOA_SP5-SOCKET6096_13568-001,SMLF,IO,DGA^6000030    I13 @T6G_MB_LIB.T6G(SCH_1):PAGE32
   U25 BV17 VSS_BV17 GENOA_SP5-SOCKET6096_13568-001,SMLF,IO,DGA^6000030    I13 @T6G_MB_LIB.T6G(SCH_1):PAGE32
   U25 BV23 VSS_BV23 GENOA_SP5-SOCKET6096_13568-001,SMLF,IO,DGA^6000030    I13 @T6G_MB_LIB.T6G(SCH_1):PAGE32
   U25 BV24 VSS_BV24 GENOA_SP5-SOCKET6096_13568-001,SMLF,IO,DGA^6000030    I13 @T6G_MB_LIB.T6G(SCH_1):PAGE32
   U25 BV25 VSS_BV25 GENOA_SP5-SOCKET6096_13568-001,SMLF,IO,DGA^6000030    I13 @T6G_MB_LIB.T6G(SCH_1):PAGE32
   U25 BV26 VSS_BV26 GENOA_SP5-SOCKET6096_13568-001,SMLF,IO,DGA^6000030    I13 @T6G_MB_LIB.T6G(SCH_1):PAGE32
   U25 BV27 VSS_BV27 GENOA_SP5-SOCKET6096_13568-001,SMLF,IO,DGA^6000030    I13 @T6G_MB_LIB.T6G(SCH_1):PAGE32
   U25 BV28 VSS_BV28 GENOA_SP5-SOCKET6096_13568-001,SMLF,IO,DGA^6000030    I13 @T6G_MB_LIB.T6G(SCH_1):PAGE32
   U25 BV29 VSS_BV29 GENOA_SP5-SOCKET6096_13568-001,SMLF,IO,DGA^6000030    I13 @T6G_MB_LIB.T6G(SCH_1):PAGE32
   U25 BV30 VSS_BV30 GENOA_SP5-SOCKET6096_13568-001,SMLF,IO,DGA^6000030    I13 @T6G_MB_LIB.T6G(SCH_1):PAGE32
   U25 BV31 VSS_BV31 GENOA_SP5-SOCKET6096_13568-001,SMLF,IO,DGA^6000030    I13 @T6G_MB_LIB.T6G(SCH_1):PAGE32
   U25 BV32 VSS_BV32 GENOA_SP5-SOCKET6096_13568-001,SMLF,IO,DGA^6000030    I13 @T6G_MB_LIB.T6G(SCH_1):PAGE32
   U25 BV33 VSS_BV33 GENOA_SP5-SOCKET6096_13568-001,SMLF,IO,DGA^6000030    I13 @T6G_MB_LIB.T6G(SCH_1):PAGE32
   U25 BV34 VSS_BV34 GENOA_SP5-SOCKET6096_13568-001,SMLF,IO,DGA^6000030    I13 @T6G_MB_LIB.T6G(SCH_1):PAGE32
   U25 BV37 VSS_BV37 GENOA_SP5-SOCKET6096_13568-001,SMLF,IO,DGA^6000030    I13 @T6G_MB_LIB.T6G(SCH_1):PAGE32
   U25 BV39 VSS_BV39 GENOA_SP5-SOCKET6096_13568-001,SMLF,IO,DGA^6000030    I13 @T6G_MB_LIB.T6G(SCH_1):PAGE32
   U25 BV43 VSS_BV43 GENOA_SP5-SOCKET6096_13568-001,SMLF,IO,DGA^6000030    I13 @T6G_MB_LIB.T6G(SCH_1):PAGE32
   U25 BV44 VSS_BV44 GENOA_SP5-SOCKET6096_13568-001,SMLF,IO,DGA^6000030    I13 @T6G_MB_LIB.T6G(SCH_1):PAGE32
   U25 BV45 VSS_BV45 GENOA_SP5-SOCKET6096_13568-001,SMLF,IO,DGA^6000030    I13 @T6G_MB_LIB.T6G(SCH_1):PAGE32
   U25 BV46 VSS_BV46 GENOA_SP5-SOCKET6096_13568-001,SMLF,IO,DGA^6000030    I14 @T6G_MB_LIB.T6G(SCH_1):PAGE32
   U25 BV47 VSS_BV47 GENOA_SP5-SOCKET6096_13568-001,SMLF,IO,DGA^6000030    I14 @T6G_MB_LIB.T6G(SCH_1):PAGE32
   U25 BV48 VSS_BV48 GENOA_SP5-SOCKET6096_13568-001,SMLF,IO,DGA^6000030    I14 @T6G_MB_LIB.T6G(SCH_1):PAGE32
   U25 BV49 VSS_BV49 GENOA_SP5-SOCKET6096_13568-001,SMLF,IO,DGA^6000030    I14 @T6G_MB_LIB.T6G(SCH_1):PAGE32
   U25 BV50 VSS_BV50 GENOA_SP5-SOCKET6096_13568-001,SMLF,IO,DGA^6000030    I14 @T6G_MB_LIB.T6G(SCH_1):PAGE32
   U25 BV51 VSS_BV51 GENOA_SP5-SOCKET6096_13568-001,SMLF,IO,DGA^6000030    I14 @T6G_MB_LIB.T6G(SCH_1):PAGE32
   U25 BV52 VSS_BV52 GENOA_SP5-SOCKET6096_13568-001,SMLF,IO,DGA^6000030    I14 @T6G_MB_LIB.T6G(SCH_1):PAGE32
   U25 BV53 VSS_BV53 GENOA_SP5-SOCKET6096_13568-001,SMLF,IO,DGA^6000030    I14 @T6G_MB_LIB.T6G(SCH_1):PAGE32
   U25 BV59 VSS_BV59 GENOA_SP5-SOCKET6096_13568-001,SMLF,IO,DGA^6000030    I14 @T6G_MB_LIB.T6G(SCH_1):PAGE32
   U25 BV61 VSS_BV61 GENOA_SP5-SOCKET6096_13568-001,SMLF,IO,DGA^6000030    I14 @T6G_MB_LIB.T6G(SCH_1):PAGE32
   U25 BV66 VSS_BV66 GENOA_SP5-SOCKET6096_13568-001,SMLF,IO,DGA^6000030    I14 @T6G_MB_LIB.T6G(SCH_1):PAGE32
   U25 BV68 VSS_BV68 GENOA_SP5-SOCKET6096_13568-001,SMLF,IO,DGA^6000030    I14 @T6G_MB_LIB.T6G(SCH_1):PAGE32
   U25 BV73 VSS_BV73 GENOA_SP5-SOCKET6096_13568-001,SMLF,IO,DGA^6000030    I14 @T6G_MB_LIB.T6G(SCH_1):PAGE32
   U25  BW1 VSS_BW1 GENOA_SP5-SOCKET6096_13568-001,SMLF,IO,DGA^6000030    I14 @T6G_MB_LIB.T6G(SCH_1):PAGE32
   U25  BW4 VSS_BW4 GENOA_SP5-SOCKET6096_13568-001,SMLF,IO,DGA^6000030    I14 @T6G_MB_LIB.T6G(SCH_1):PAGE32
   U25  BW6 VSS_BW6 GENOA_SP5-SOCKET6096_13568-001,SMLF,IO,DGA^6000030    I14 @T6G_MB_LIB.T6G(SCH_1):PAGE32
   U25  BW8 VSS_BW8 GENOA_SP5-SOCKET6096_13568-001,SMLF,IO,DGA^6000030    I14 @T6G_MB_LIB.T6G(SCH_1):PAGE32
   U25 BW11 VSS_BW11 GENOA_SP5-SOCKET6096_13568-001,SMLF,IO,DGA^6000030    I14 @T6G_MB_LIB.T6G(SCH_1):PAGE32
   U25 BW13 VSS_BW13 GENOA_SP5-SOCKET6096_13568-001,SMLF,IO,DGA^6000030    I14 @T6G_MB_LIB.T6G(SCH_1):PAGE32
   U25 BW15 VSS_BW15 GENOA_SP5-SOCKET6096_13568-001,SMLF,IO,DGA^6000030    I14 @T6G_MB_LIB.T6G(SCH_1):PAGE32
   U25 BW18 VSS_BW18 GENOA_SP5-SOCKET6096_13568-001,SMLF,IO,DGA^6000030    I14 @T6G_MB_LIB.T6G(SCH_1):PAGE32
   U25 BW20 VSS_BW20 GENOA_SP5-SOCKET6096_13568-001,SMLF,IO,DGA^6000030    I14 @T6G_MB_LIB.T6G(SCH_1):PAGE32
   U25 BW22 VSS_BW22 GENOA_SP5-SOCKET6096_13568-001,SMLF,IO,DGA^6000030    I14 @T6G_MB_LIB.T6G(SCH_1):PAGE32
   U25 BW28 VSS_BW28 GENOA_SP5-SOCKET6096_13568-001,SMLF,IO,DGA^6000030    I14 @T6G_MB_LIB.T6G(SCH_1):PAGE32
   U25 BW31 VSS_BW31 GENOA_SP5-SOCKET6096_13568-001,SMLF,IO,DGA^6000030    I14 @T6G_MB_LIB.T6G(SCH_1):PAGE32
   U25 BW34 VSS_BW34 GENOA_SP5-SOCKET6096_13568-001,SMLF,IO,DGA^6000030    I14 @T6G_MB_LIB.T6G(SCH_1):PAGE32
   U25 BW42 VSS_BW42 GENOA_SP5-SOCKET6096_13568-001,SMLF,IO,DGA^6000030    I14 @T6G_MB_LIB.T6G(SCH_1):PAGE32
   U25 BW45 VSS_BW45 GENOA_SP5-SOCKET6096_13568-001,SMLF,IO,DGA^6000030    I14 @T6G_MB_LIB.T6G(SCH_1):PAGE32
   U25 BW48 VSS_BW48 GENOA_SP5-SOCKET6096_13568-001,SMLF,IO,DGA^6000030    I14 @T6G_MB_LIB.T6G(SCH_1):PAGE32
   U25 BW51 VSS_BW51 GENOA_SP5-SOCKET6096_13568-001,SMLF,IO,DGA^6000030    I14 @T6G_MB_LIB.T6G(SCH_1):PAGE32
   U25 BW54 VSS_BW54 GENOA_SP5-SOCKET6096_13568-001,SMLF,IO,DGA^6000030    I14 @T6G_MB_LIB.T6G(SCH_1):PAGE32
   U25 BW56 VSS_BW56 GENOA_SP5-SOCKET6096_13568-001,SMLF,IO,DGA^6000030    I14 @T6G_MB_LIB.T6G(SCH_1):PAGE32
   U25 BW58 VSS_BW58 GENOA_SP5-SOCKET6096_13568-001,SMLF,IO,DGA^6000030    I14 @T6G_MB_LIB.T6G(SCH_1):PAGE32
   U25 BW61 VSS_BW61 GENOA_SP5-SOCKET6096_13568-001,SMLF,IO,DGA^6000030    I14 @T6G_MB_LIB.T6G(SCH_1):PAGE32
   U25 BW63 VSS_BW63 GENOA_SP5-SOCKET6096_13568-001,SMLF,IO,DGA^6000030    I14 @T6G_MB_LIB.T6G(SCH_1):PAGE32
   U25 BW65 VSS_BW65 GENOA_SP5-SOCKET6096_13568-001,SMLF,IO,DGA^6000030    I14 @T6G_MB_LIB.T6G(SCH_1):PAGE32
   U25 BW68 VSS_BW68 GENOA_SP5-SOCKET6096_13568-001,SMLF,IO,DGA^6000030    I14 @T6G_MB_LIB.T6G(SCH_1):PAGE32
   U25 BW70 VSS_BW70 GENOA_SP5-SOCKET6096_13568-001,SMLF,IO,DGA^6000030    I14 @T6G_MB_LIB.T6G(SCH_1):PAGE32
   U25 BW72 VSS_BW72 GENOA_SP5-SOCKET6096_13568-001,SMLF,IO,DGA^6000030    I14 @T6G_MB_LIB.T6G(SCH_1):PAGE32
   U25 BW75 VSS_BW75 GENOA_SP5-SOCKET6096_13568-001,SMLF,IO,DGA^6000030    I14 @T6G_MB_LIB.T6G(SCH_1):PAGE32
   U25  BY3 VSS_BY3 GENOA_SP5-SOCKET6096_13568-001,SMLF,IO,DGA^6000030    I14 @T6G_MB_LIB.T6G(SCH_1):PAGE32
   U25  BY5 VSS_BY5 GENOA_SP5-SOCKET6096_13568-001,SMLF,IO,DGA^6000030    I14 @T6G_MB_LIB.T6G(SCH_1):PAGE32
   U25  BY8 VSS_BY8 GENOA_SP5-SOCKET6096_13568-001,SMLF,IO,DGA^6000030    I14 @T6G_MB_LIB.T6G(SCH_1):PAGE32
   U25 BY10 VSS_BY10 GENOA_SP5-SOCKET6096_13568-001,SMLF,IO,DGA^6000030    I14 @T6G_MB_LIB.T6G(SCH_1):PAGE32
   U25 BY12 VSS_BY12 GENOA_SP5-SOCKET6096_13568-001,SMLF,IO,DGA^6000030    I14 @T6G_MB_LIB.T6G(SCH_1):PAGE32
   U25 BY15 VSS_BY15 GENOA_SP5-SOCKET6096_13568-001,SMLF,IO,DGA^6000030    I14 @T6G_MB_LIB.T6G(SCH_1):PAGE32
   U25 BY17 VSS_BY17 GENOA_SP5-SOCKET6096_13568-001,SMLF,IO,DGA^6000030    I14 @T6G_MB_LIB.T6G(SCH_1):PAGE32
   U25 BY19 VSS_BY19 GENOA_SP5-SOCKET6096_13568-001,SMLF,IO,DGA^6000030    I14 @T6G_MB_LIB.T6G(SCH_1):PAGE32
   U25 BY22 VSS_BY22 GENOA_SP5-SOCKET6096_13568-001,SMLF,IO,DGA^6000030    I14 @T6G_MB_LIB.T6G(SCH_1):PAGE32
   U25 BY25 VSS_BY25 GENOA_SP5-SOCKET6096_13568-001,SMLF,IO,DGA^6000030    I14 @T6G_MB_LIB.T6G(SCH_1):PAGE32
   U25 BY28 VSS_BY28 GENOA_SP5-SOCKET6096_13568-001,SMLF,IO,DGA^6000030    I14 @T6G_MB_LIB.T6G(SCH_1):PAGE32
   U25 BY31 VSS_BY31 GENOA_SP5-SOCKET6096_13568-001,SMLF,IO,DGA^6000030    I14 @T6G_MB_LIB.T6G(SCH_1):PAGE32
   U25 BY34 VSS_BY34 GENOA_SP5-SOCKET6096_13568-001,SMLF,IO,DGA^6000030    I14 @T6G_MB_LIB.T6G(SCH_1):PAGE32
   U25 BY37 VSS_BY37 GENOA_SP5-SOCKET6096_13568-001,SMLF,IO,DGA^6000030    I14 @T6G_MB_LIB.T6G(SCH_1):PAGE32
   U25 BY39 VSS_BY39 GENOA_SP5-SOCKET6096_13568-001,SMLF,IO,DGA^6000030    I14 @T6G_MB_LIB.T6G(SCH_1):PAGE32
   U25 BY42 VSS_BY42 GENOA_SP5-SOCKET6096_13568-001,SMLF,IO,DGA^6000030    I14 @T6G_MB_LIB.T6G(SCH_1):PAGE32
   U25 BY45 VSS_BY45 GENOA_SP5-SOCKET6096_13568-001,SMLF,IO,DGA^6000030    I14 @T6G_MB_LIB.T6G(SCH_1):PAGE32
   U25 BY48 VSS_BY48 GENOA_SP5-SOCKET6096_13568-001,SMLF,IO,DGA^6000030    I14 @T6G_MB_LIB.T6G(SCH_1):PAGE32
   U25 BY51 VSS_BY51 GENOA_SP5-SOCKET6096_13568-001,SMLF,IO,DGA^6000030    I14 @T6G_MB_LIB.T6G(SCH_1):PAGE32
   U25 BY54 VSS_BY54 GENOA_SP5-SOCKET6096_13568-001,SMLF,IO,DGA^6000030    I14 @T6G_MB_LIB.T6G(SCH_1):PAGE32
   U25 BY57 VSS_BY57 GENOA_SP5-SOCKET6096_13568-001,SMLF,IO,DGA^6000030    I14 @T6G_MB_LIB.T6G(SCH_1):PAGE32
   U25 BY59 VSS_BY59 GENOA_SP5-SOCKET6096_13568-001,SMLF,IO,DGA^6000030    I14 @T6G_MB_LIB.T6G(SCH_1):PAGE32
   U25 BY61 VSS_BY61 GENOA_SP5-SOCKET6096_13568-001,SMLF,IO,DGA^6000030    I14 @T6G_MB_LIB.T6G(SCH_1):PAGE32
   U25 BY64 VSS_BY64 GENOA_SP5-SOCKET6096_13568-001,SMLF,IO,DGA^6000030    I14 @T6G_MB_LIB.T6G(SCH_1):PAGE32
   U25 BY66 VSS_BY66 GENOA_SP5-SOCKET6096_13568-001,SMLF,IO,DGA^6000030    I14 @T6G_MB_LIB.T6G(SCH_1):PAGE32
   U25 BY68 VSS_BY68 GENOA_SP5-SOCKET6096_13568-001,SMLF,IO,DGA^6000030    I14 @T6G_MB_LIB.T6G(SCH_1):PAGE32
   U25 BY71 VSS_BY71 GENOA_SP5-SOCKET6096_13568-001,SMLF,IO,DGA^6000030    I14 @T6G_MB_LIB.T6G(SCH_1):PAGE32
   U25 BY73 VSS_BY73 GENOA_SP5-SOCKET6096_13568-001,SMLF,IO,DGA^6000030    I14 @T6G_MB_LIB.T6G(SCH_1):PAGE32
   U25  CA1 VSS_CA1 GENOA_SP5-SOCKET6096_13568-001,SMLF,IO,DGA^6000030    I14 @T6G_MB_LIB.T6G(SCH_1):PAGE32
   U25  CA6 VSS_CA6 GENOA_SP5-SOCKET6096_13568-001,SMLF,IO,DGA^6000030    I14 @T6G_MB_LIB.T6G(SCH_1):PAGE32
   U25  CA8 VSS_CA8 GENOA_SP5-SOCKET6096_13568-001,SMLF,IO,DGA^6000030    I14 @T6G_MB_LIB.T6G(SCH_1):PAGE32
   U25 CA13 VSS_CA13 GENOA_SP5-SOCKET6096_13568-001,SMLF,IO,DGA^6000030    I14 @T6G_MB_LIB.T6G(SCH_1):PAGE32
   U25 CA15 VSS_CA15 GENOA_SP5-SOCKET6096_13568-001,SMLF,IO,DGA^6000030    I14 @T6G_MB_LIB.T6G(SCH_1):PAGE32
   U25 CA20 VSS_CA20 GENOA_SP5-SOCKET6096_13568-001,SMLF,IO,DGA^6000030    I14 @T6G_MB_LIB.T6G(SCH_1):PAGE32
   U25 CA22 VSS_CA22 GENOA_SP5-SOCKET6096_13568-001,SMLF,IO,DGA^6000030    I14 @T6G_MB_LIB.T6G(SCH_1):PAGE32
   U25 CA25 VSS_CA25 GENOA_SP5-SOCKET6096_13568-001,SMLF,IO,DGA^6000030    I14 @T6G_MB_LIB.T6G(SCH_1):PAGE32
   U25 CA28 VSS_CA28 GENOA_SP5-SOCKET6096_13568-001,SMLF,IO,DGA^6000030    I14 @T6G_MB_LIB.T6G(SCH_1):PAGE32
   U25 CA31 VSS_CA31 GENOA_SP5-SOCKET6096_13568-001,SMLF,IO,DGA^6000030    I14 @T6G_MB_LIB.T6G(SCH_1):PAGE32
   U25 CA34 VSS_CA34 GENOA_SP5-SOCKET6096_13568-001,SMLF,IO,DGA^6000030    I14 @T6G_MB_LIB.T6G(SCH_1):PAGE32
   U25 CA35 VSS_CA35 GENOA_SP5-SOCKET6096_13568-001,SMLF,IO,DGA^6000030    I14 @T6G_MB_LIB.T6G(SCH_1):PAGE32
   U25 CA36 VSS_CA36 GENOA_SP5-SOCKET6096_13568-001,SMLF,IO,DGA^6000030    I14 @T6G_MB_LIB.T6G(SCH_1):PAGE32
   U25 CA40 VSS_CA40 GENOA_SP5-SOCKET6096_13568-001,SMLF,IO,DGA^6000030    I14 @T6G_MB_LIB.T6G(SCH_1):PAGE32
   U25 CA41 VSS_CA41 GENOA_SP5-SOCKET6096_13568-001,SMLF,IO,DGA^6000030    I14 @T6G_MB_LIB.T6G(SCH_1):PAGE32
   U25 CA42 VSS_CA42 GENOA_SP5-SOCKET6096_13568-001,SMLF,IO,DGA^6000030    I14 @T6G_MB_LIB.T6G(SCH_1):PAGE32
   U25 CA45 VSS_CA45 GENOA_SP5-SOCKET6096_13568-001,SMLF,IO,DGA^6000030    I14 @T6G_MB_LIB.T6G(SCH_1):PAGE32
   U25 CA48 VSS_CA48 GENOA_SP5-SOCKET6096_13568-001,SMLF,IO,DGA^6000030    I14 @T6G_MB_LIB.T6G(SCH_1):PAGE32
   U25 CA51 VSS_CA51 GENOA_SP5-SOCKET6096_13568-001,SMLF,IO,DGA^6000030    I14 @T6G_MB_LIB.T6G(SCH_1):PAGE32
   U25 CA54 VSS_CA54 GENOA_SP5-SOCKET6096_13568-001,SMLF,IO,DGA^6000030    I14 @T6G_MB_LIB.T6G(SCH_1):PAGE32
   U25 CA56 VSS_CA56 GENOA_SP5-SOCKET6096_13568-001,SMLF,IO,DGA^6000030    I14 @T6G_MB_LIB.T6G(SCH_1):PAGE32
   U25 CA61 VSS_CA61 GENOA_SP5-SOCKET6096_13568-001,SMLF,IO,DGA^6000030    I14 @T6G_MB_LIB.T6G(SCH_1):PAGE32
   U25 CA63 VSS_CA63 GENOA_SP5-SOCKET6096_13568-001,SMLF,IO,DGA^6000030    I14 @T6G_MB_LIB.T6G(SCH_1):PAGE32
   U25 CA68 VSS_CA68 GENOA_SP5-SOCKET6096_13568-001,SMLF,IO,DGA^6000030    I14 @T6G_MB_LIB.T6G(SCH_1):PAGE32
   U25 CA70 VSS_CA70 GENOA_SP5-SOCKET6096_13568-001,SMLF,IO,DGA^6000030    I14 @T6G_MB_LIB.T6G(SCH_1):PAGE32
   U25 CA75 VSS_CA75 GENOA_SP5-SOCKET6096_13568-001,SMLF,IO,DGA^6000030    I14 @T6G_MB_LIB.T6G(SCH_1):PAGE32
   U25  CB3 VSS_CB3 GENOA_SP5-SOCKET6096_13568-001,SMLF,IO,DGA^6000030    I14 @T6G_MB_LIB.T6G(SCH_1):PAGE32
   U25  CB5 VSS_CB5 GENOA_SP5-SOCKET6096_13568-001,SMLF,IO,DGA^6000030    I14 @T6G_MB_LIB.T6G(SCH_1):PAGE32
   U25  CB8 VSS_CB8 GENOA_SP5-SOCKET6096_13568-001,SMLF,IO,DGA^6000030    I14 @T6G_MB_LIB.T6G(SCH_1):PAGE32
   U25 CB10 VSS_CB10 GENOA_SP5-SOCKET6096_13568-001,SMLF,IO,DGA^6000030    I14 @T6G_MB_LIB.T6G(SCH_1):PAGE32
   U25 CB12 VSS_CB12 GENOA_SP5-SOCKET6096_13568-001,SMLF,IO,DGA^6000030    I14 @T6G_MB_LIB.T6G(SCH_1):PAGE32
   U25 CB15 VSS_CB15 GENOA_SP5-SOCKET6096_13568-001,SMLF,IO,DGA^6000030    I14 @T6G_MB_LIB.T6G(SCH_1):PAGE32
   U25 CB17 VSS_CB17 GENOA_SP5-SOCKET6096_13568-001,SMLF,IO,DGA^6000030    I14 @T6G_MB_LIB.T6G(SCH_1):PAGE32
   U25 CB19 VSS_CB19 GENOA_SP5-SOCKET6096_13568-001,SMLF,IO,DGA^6000030    I14 @T6G_MB_LIB.T6G(SCH_1):PAGE32
   U25 CB23 VSS_CB23 GENOA_SP5-SOCKET6096_13568-001,SMLF,IO,DGA^6000030    I14 @T6G_MB_LIB.T6G(SCH_1):PAGE32
   U25 CB24 VSS_CB24 GENOA_SP5-SOCKET6096_13568-001,SMLF,IO,DGA^6000030    I14 @T6G_MB_LIB.T6G(SCH_1):PAGE32
   U25 CB25 VSS_CB25 GENOA_SP5-SOCKET6096_13568-001,SMLF,IO,DGA^6000030    I14 @T6G_MB_LIB.T6G(SCH_1):PAGE32
   U25 CB26 VSS_CB26 GENOA_SP5-SOCKET6096_13568-001,SMLF,IO,DGA^6000030    I14 @T6G_MB_LIB.T6G(SCH_1):PAGE32
   U25 CB27 VSS_CB27 GENOA_SP5-SOCKET6096_13568-001,SMLF,IO,DGA^6000030    I14 @T6G_MB_LIB.T6G(SCH_1):PAGE32
   U25 CB28 VSS_CB28 GENOA_SP5-SOCKET6096_13568-001,SMLF,IO,DGA^6000030    I14 @T6G_MB_LIB.T6G(SCH_1):PAGE32
   U25 CB29 VSS_CB29 GENOA_SP5-SOCKET6096_13568-001,SMLF,IO,DGA^6000030    I14 @T6G_MB_LIB.T6G(SCH_1):PAGE32
   U25 CB30 VSS_CB30 GENOA_SP5-SOCKET6096_13568-001,SMLF,IO,DGA^6000030    I14 @T6G_MB_LIB.T6G(SCH_1):PAGE32
   U25 CB31 VSS_CB31 GENOA_SP5-SOCKET6096_13568-001,SMLF,IO,DGA^6000030    I14 @T6G_MB_LIB.T6G(SCH_1):PAGE32
   U25 CB32 VSS_CB32 GENOA_SP5-SOCKET6096_13568-001,SMLF,IO,DGA^6000030    I14 @T6G_MB_LIB.T6G(SCH_1):PAGE32
   U25 CB33 VSS_CB33 GENOA_SP5-SOCKET6096_13568-001,SMLF,IO,DGA^6000030    I14 @T6G_MB_LIB.T6G(SCH_1):PAGE32
   U25 CB34 VSS_CB34 GENOA_SP5-SOCKET6096_13568-001,SMLF,IO,DGA^6000030    I14 @T6G_MB_LIB.T6G(SCH_1):PAGE32
   U25 CB37 VSS_CB37 GENOA_SP5-SOCKET6096_13568-001,SMLF,IO,DGA^6000030    I14 @T6G_MB_LIB.T6G(SCH_1):PAGE32
   U25 CB39 VSS_CB39 GENOA_SP5-SOCKET6096_13568-001,SMLF,IO,DGA^6000030    I14 @T6G_MB_LIB.T6G(SCH_1):PAGE32
   U25 CB42 VSS_CB42 GENOA_SP5-SOCKET6096_13568-001,SMLF,IO,DGA^6000030    I14 @T6G_MB_LIB.T6G(SCH_1):PAGE32
   U25 CB43 VSS_CB43 GENOA_SP5-SOCKET6096_13568-001,SMLF,IO,DGA^6000030    I14 @T6G_MB_LIB.T6G(SCH_1):PAGE32
   U25 CB45 VSS_CB45 GENOA_SP5-SOCKET6096_13568-001,SMLF,IO,DGA^6000030    I14 @T6G_MB_LIB.T6G(SCH_1):PAGE32
   U25 CB46 VSS_CB46 GENOA_SP5-SOCKET6096_13568-001,SMLF,IO,DGA^6000030    I14 @T6G_MB_LIB.T6G(SCH_1):PAGE32
   U25 CB47 VSS_CB47 GENOA_SP5-SOCKET6096_13568-001,SMLF,IO,DGA^6000030    I14 @T6G_MB_LIB.T6G(SCH_1):PAGE32
   U25 CB48 VSS_CB48 GENOA_SP5-SOCKET6096_13568-001,SMLF,IO,DGA^6000030    I14 @T6G_MB_LIB.T6G(SCH_1):PAGE32
   U25 CB49 VSS_CB49 GENOA_SP5-SOCKET6096_13568-001,SMLF,IO,DGA^6000030    I14 @T6G_MB_LIB.T6G(SCH_1):PAGE32
   U25 CB50 VSS_CB50 GENOA_SP5-SOCKET6096_13568-001,SMLF,IO,DGA^6000030    I14 @T6G_MB_LIB.T6G(SCH_1):PAGE32
   U25 CB51 VSS_CB51 GENOA_SP5-SOCKET6096_13568-001,SMLF,IO,DGA^6000030    I14 @T6G_MB_LIB.T6G(SCH_1):PAGE32
   U25 CB52 VSS_CB52 GENOA_SP5-SOCKET6096_13568-001,SMLF,IO,DGA^6000030    I14 @T6G_MB_LIB.T6G(SCH_1):PAGE32
   U25 CB53 VSS_CB53 GENOA_SP5-SOCKET6096_13568-001,SMLF,IO,DGA^6000030    I14 @T6G_MB_LIB.T6G(SCH_1):PAGE32
   U25 CB57 VSS_CB57 GENOA_SP5-SOCKET6096_13568-001,SMLF,IO,DGA^6000030    I14 @T6G_MB_LIB.T6G(SCH_1):PAGE32
   U25 CB59 VSS_CB59 GENOA_SP5-SOCKET6096_13568-001,SMLF,IO,DGA^6000030    I14 @T6G_MB_LIB.T6G(SCH_1):PAGE32
   U25 CB61 VSS_CB61 GENOA_SP5-SOCKET6096_13568-001,SMLF,IO,DGA^6000030    I14 @T6G_MB_LIB.T6G(SCH_1):PAGE32
   U25 CB64 VSS_CB64 GENOA_SP5-SOCKET6096_13568-001,SMLF,IO,DGA^6000030    I14 @T6G_MB_LIB.T6G(SCH_1):PAGE32
   U25 CB66 VSS_CB66 GENOA_SP5-SOCKET6096_13568-001,SMLF,IO,DGA^6000030    I14 @T6G_MB_LIB.T6G(SCH_1):PAGE32
   U25 CB68 VSS_CB68 GENOA_SP5-SOCKET6096_13568-001,SMLF,IO,DGA^6000030    I14 @T6G_MB_LIB.T6G(SCH_1):PAGE32
   U25 CB71 VSS_CB71 GENOA_SP5-SOCKET6096_13568-001,SMLF,IO,DGA^6000030    I14 @T6G_MB_LIB.T6G(SCH_1):PAGE32
   U25 CB73 VSS_CB73 GENOA_SP5-SOCKET6096_13568-001,SMLF,IO,DGA^6000030    I14 @T6G_MB_LIB.T6G(SCH_1):PAGE32
   U25  CC1 VSS_CC1 GENOA_SP5-SOCKET6096_13568-001,SMLF,IO,DGA^6000030    I14 @T6G_MB_LIB.T6G(SCH_1):PAGE32
   U25  CC4 VSS_CC4 GENOA_SP5-SOCKET6096_13568-001,SMLF,IO,DGA^6000030    I14 @T6G_MB_LIB.T6G(SCH_1):PAGE32
   U25  CC6 VSS_CC6 GENOA_SP5-SOCKET6096_13568-001,SMLF,IO,DGA^6000030    I14 @T6G_MB_LIB.T6G(SCH_1):PAGE32
   U25  CC8 VSS_CC8 GENOA_SP5-SOCKET6096_13568-001,SMLF,IO,DGA^6000030    I14 @T6G_MB_LIB.T6G(SCH_1):PAGE32
   U25 CC11 VSS_CC11 GENOA_SP5-SOCKET6096_13568-001,SMLF,IO,DGA^6000030    I14 @T6G_MB_LIB.T6G(SCH_1):PAGE32
   U25 CC13 VSS_CC13 GENOA_SP5-SOCKET6096_13568-001,SMLF,IO,DGA^6000030    I14 @T6G_MB_LIB.T6G(SCH_1):PAGE32
   U25 CC15 VSS_CC15 GENOA_SP5-SOCKET6096_13568-001,SMLF,IO,DGA^6000030    I14 @T6G_MB_LIB.T6G(SCH_1):PAGE32
   U25 CC18 VSS_CC18 GENOA_SP5-SOCKET6096_13568-001,SMLF,IO,DGA^6000030    I14 @T6G_MB_LIB.T6G(SCH_1):PAGE32
   U25 CC20 VSS_CC20 GENOA_SP5-SOCKET6096_13568-001,SMLF,IO,DGA^6000030    I14 @T6G_MB_LIB.T6G(SCH_1):PAGE32
   U25 CC25 VSS_CC25 GENOA_SP5-SOCKET6096_13568-001,SMLF,IO,DGA^6000030    I14 @T6G_MB_LIB.T6G(SCH_1):PAGE32
   U25 CC28 VSS_CC28 GENOA_SP5-SOCKET6096_13568-001,SMLF,IO,DGA^6000030    I14 @T6G_MB_LIB.T6G(SCH_1):PAGE32
   U25 CC31 VSS_CC31 GENOA_SP5-SOCKET6096_13568-001,SMLF,IO,DGA^6000030    I14 @T6G_MB_LIB.T6G(SCH_1):PAGE32
   U25 CC34 VSS_CC34 GENOA_SP5-SOCKET6096_13568-001,SMLF,IO,DGA^6000030    I14 @T6G_MB_LIB.T6G(SCH_1):PAGE32
   U25 CC42 VSS_CC42 GENOA_SP5-SOCKET6096_13568-001,SMLF,IO,DGA^6000030    I14 @T6G_MB_LIB.T6G(SCH_1):PAGE32
   U25 CC45 VSS_CC45 GENOA_SP5-SOCKET6096_13568-001,SMLF,IO,DGA^6000030    I14 @T6G_MB_LIB.T6G(SCH_1):PAGE32
   U25 CC48 VSS_CC48 GENOA_SP5-SOCKET6096_13568-001,SMLF,IO,DGA^6000030    I14 @T6G_MB_LIB.T6G(SCH_1):PAGE32
   U25 CC51 VSS_CC51 GENOA_SP5-SOCKET6096_13568-001,SMLF,IO,DGA^6000030    I14 @T6G_MB_LIB.T6G(SCH_1):PAGE32
   U25 CC54 VSS_CC54 GENOA_SP5-SOCKET6096_13568-001,SMLF,IO,DGA^6000030    I14 @T6G_MB_LIB.T6G(SCH_1):PAGE32
   U25 CC56 VSS_CC56 GENOA_SP5-SOCKET6096_13568-001,SMLF,IO,DGA^6000030    I14 @T6G_MB_LIB.T6G(SCH_1):PAGE32
   U25 CC58 VSS_CC58 GENOA_SP5-SOCKET6096_13568-001,SMLF,IO,DGA^6000030    I14 @T6G_MB_LIB.T6G(SCH_1):PAGE32
   U25 CC61 VSS_CC61 GENOA_SP5-SOCKET6096_13568-001,SMLF,IO,DGA^6000030    I14 @T6G_MB_LIB.T6G(SCH_1):PAGE32
   U25 CC63 VSS_CC63 GENOA_SP5-SOCKET6096_13568-001,SMLF,IO,DGA^6000030    I14 @T6G_MB_LIB.T6G(SCH_1):PAGE32
   U25 CC65 VSS_CC65 GENOA_SP5-SOCKET6096_13568-001,SMLF,IO,DGA^6000030    I14 @T6G_MB_LIB.T6G(SCH_1):PAGE32
   U25 CC68 VSS_CC68 GENOA_SP5-SOCKET6096_13568-001,SMLF,IO,DGA^6000030    I14 @T6G_MB_LIB.T6G(SCH_1):PAGE32
   U25 CC70 VSS_CC70 GENOA_SP5-SOCKET6096_13568-001,SMLF,IO,DGA^6000030    I14 @T6G_MB_LIB.T6G(SCH_1):PAGE32
   U25 CC72 VSS_CC72 GENOA_SP5-SOCKET6096_13568-001,SMLF,IO,DGA^6000030    I14 @T6G_MB_LIB.T6G(SCH_1):PAGE32
   U25 CC75 VSS_CC75 GENOA_SP5-SOCKET6096_13568-001,SMLF,IO,DGA^6000030    I14 @T6G_MB_LIB.T6G(SCH_1):PAGE32
   U25  CD3 VSS_CD3 GENOA_SP5-SOCKET6096_13568-001,SMLF,IO,DGA^6000030    I14 @T6G_MB_LIB.T6G(SCH_1):PAGE32
   U25  CD8 VSS_CD8 GENOA_SP5-SOCKET6096_13568-001,SMLF,IO,DGA^6000030    I14 @T6G_MB_LIB.T6G(SCH_1):PAGE32
   U25 CD10 VSS_CD10 GENOA_SP5-SOCKET6096_13568-001,SMLF,IO,DGA^6000030    I14 @T6G_MB_LIB.T6G(SCH_1):PAGE32
   U25 CD15 VSS_CD15 GENOA_SP5-SOCKET6096_13568-001,SMLF,IO,DGA^6000030    I14 @T6G_MB_LIB.T6G(SCH_1):PAGE32
   U25 CD17 VSS_CD17 GENOA_SP5-SOCKET6096_13568-001,SMLF,IO,DGA^6000030    I14 @T6G_MB_LIB.T6G(SCH_1):PAGE32
   U25 CD22 VSS_CD22 GENOA_SP5-SOCKET6096_13568-001,SMLF,IO,DGA^6000030    I14 @T6G_MB_LIB.T6G(SCH_1):PAGE32
   U25 CD25 VSS_CD25 GENOA_SP5-SOCKET6096_13568-001,SMLF,IO,DGA^6000030    I14 @T6G_MB_LIB.T6G(SCH_1):PAGE32
   U25 CD28 VSS_CD28 GENOA_SP5-SOCKET6096_13568-001,SMLF,IO,DGA^6000030    I14 @T6G_MB_LIB.T6G(SCH_1):PAGE32
   U25 CD31 VSS_CD31 GENOA_SP5-SOCKET6096_13568-001,SMLF,IO,DGA^6000030    I14 @T6G_MB_LIB.T6G(SCH_1):PAGE32
   U25 CD34 VSS_CD34 GENOA_SP5-SOCKET6096_13568-001,SMLF,IO,DGA^6000030    I14 @T6G_MB_LIB.T6G(SCH_1):PAGE32
   U25 CD37 VSS_CD37 GENOA_SP5-SOCKET6096_13568-001,SMLF,IO,DGA^6000030    I14 @T6G_MB_LIB.T6G(SCH_1):PAGE32
   U25 CD39 VSS_CD39 GENOA_SP5-SOCKET6096_13568-001,SMLF,IO,DGA^6000030    I14 @T6G_MB_LIB.T6G(SCH_1):PAGE32
   U25 CD42 VSS_CD42 GENOA_SP5-SOCKET6096_13568-001,SMLF,IO,DGA^6000030    I14 @T6G_MB_LIB.T6G(SCH_1):PAGE32
   U25 CD45 VSS_CD45 GENOA_SP5-SOCKET6096_13568-001,SMLF,IO,DGA^6000030    I14 @T6G_MB_LIB.T6G(SCH_1):PAGE32
   U25 CD48 VSS_CD48 GENOA_SP5-SOCKET6096_13568-001,SMLF,IO,DGA^6000030    I14 @T6G_MB_LIB.T6G(SCH_1):PAGE32
   U25 CD51 VSS_CD51 GENOA_SP5-SOCKET6096_13568-001,SMLF,IO,DGA^6000030    I14 @T6G_MB_LIB.T6G(SCH_1):PAGE32
   U25 CD54 VSS_CD54 GENOA_SP5-SOCKET6096_13568-001,SMLF,IO,DGA^6000030    I14 @T6G_MB_LIB.T6G(SCH_1):PAGE32
   U25 CD59 VSS_CD59 GENOA_SP5-SOCKET6096_13568-001,SMLF,IO,DGA^6000030    I14 @T6G_MB_LIB.T6G(SCH_1):PAGE32
   U25 CD61 VSS_CD61 GENOA_SP5-SOCKET6096_13568-001,SMLF,IO,DGA^6000030    I14 @T6G_MB_LIB.T6G(SCH_1):PAGE32
   U25 CD66 VSS_CD66 GENOA_SP5-SOCKET6096_13568-001,SMLF,IO,DGA^6000030    I14 @T6G_MB_LIB.T6G(SCH_1):PAGE32
   U25 CD68 VSS_CD68 GENOA_SP5-SOCKET6096_13568-001,SMLF,IO,DGA^6000030    I14 @T6G_MB_LIB.T6G(SCH_1):PAGE32
   U25 CD73 VSS_CD73 GENOA_SP5-SOCKET6096_13568-001,SMLF,IO,DGA^6000030    I14 @T6G_MB_LIB.T6G(SCH_1):PAGE32
   U25  CE1 VSS_CE1 GENOA_SP5-SOCKET6096_13568-001,SMLF,IO,DGA^6000030    I14 @T6G_MB_LIB.T6G(SCH_1):PAGE32
   U25  CE4 VSS_CE4 GENOA_SP5-SOCKET6096_13568-001,SMLF,IO,DGA^6000030    I14 @T6G_MB_LIB.T6G(SCH_1):PAGE32
   U25  CE6 VSS_CE6 GENOA_SP5-SOCKET6096_13568-001,SMLF,IO,DGA^6000030    I14 @T6G_MB_LIB.T6G(SCH_1):PAGE32
   U25  CE8 VSS_CE8 GENOA_SP5-SOCKET6096_13568-001,SMLF,IO,DGA^6000030    I14 @T6G_MB_LIB.T6G(SCH_1):PAGE32
   U25 CE11 VSS_CE11 GENOA_SP5-SOCKET6096_13568-001,SMLF,IO,DGA^6000030    I14 @T6G_MB_LIB.T6G(SCH_1):PAGE32
   U25 CE13 VSS_CE13 GENOA_SP5-SOCKET6096_13568-001,SMLF,IO,DGA^6000030    I14 @T6G_MB_LIB.T6G(SCH_1):PAGE32
   U25 CE15 VSS_CE15 GENOA_SP5-SOCKET6096_13568-001,SMLF,IO,DGA^6000030    I14 @T6G_MB_LIB.T6G(SCH_1):PAGE32
   U25 CE18 VSS_CE18 GENOA_SP5-SOCKET6096_13568-001,SMLF,IO,DGA^6000030    I14 @T6G_MB_LIB.T6G(SCH_1):PAGE32
   U25 CE20 VSS_CE20 GENOA_SP5-SOCKET6096_13568-001,SMLF,IO,DGA^6000030    I14 @T6G_MB_LIB.T6G(SCH_1):PAGE32
   U25 CE22 VSS_CE22 GENOA_SP5-SOCKET6096_13568-001,SMLF,IO,DGA^6000030    I14 @T6G_MB_LIB.T6G(SCH_1):PAGE32
   U25 CE25 VSS_CE25 GENOA_SP5-SOCKET6096_13568-001,SMLF,IO,DGA^6000030    I14 @T6G_MB_LIB.T6G(SCH_1):PAGE32
   U25 CE28 VSS_CE28 GENOA_SP5-SOCKET6096_13568-001,SMLF,IO,DGA^6000030    I14 @T6G_MB_LIB.T6G(SCH_1):PAGE32
   U25 CE31 VSS_CE31 GENOA_SP5-SOCKET6096_13568-001,SMLF,IO,DGA^6000030    I14 @T6G_MB_LIB.T6G(SCH_1):PAGE32
   U25 CE34 VSS_CE34 GENOA_SP5-SOCKET6096_13568-001,SMLF,IO,DGA^6000030    I14 @T6G_MB_LIB.T6G(SCH_1):PAGE32
   U25 CE35 VSS_CE35 GENOA_SP5-SOCKET6096_13568-001,SMLF,IO,DGA^6000030    I14 @T6G_MB_LIB.T6G(SCH_1):PAGE32
   U25 CE36 VSS_CE36 GENOA_SP5-SOCKET6096_13568-001,SMLF,IO,DGA^6000030    I14 @T6G_MB_LIB.T6G(SCH_1):PAGE32
   U25 CE40 VSS_CE40 GENOA_SP5-SOCKET6096_13568-001,SMLF,IO,DGA^6000030    I14 @T6G_MB_LIB.T6G(SCH_1):PAGE32
   U25 CE41 VSS_CE41 GENOA_SP5-SOCKET6096_13568-001,SMLF,IO,DGA^6000030    I14 @T6G_MB_LIB.T6G(SCH_1):PAGE32
   U25 CE42 VSS_CE42 GENOA_SP5-SOCKET6096_13568-001,SMLF,IO,DGA^6000030    I14 @T6G_MB_LIB.T6G(SCH_1):PAGE32
   U25 CE45 VSS_CE45 GENOA_SP5-SOCKET6096_13568-001,SMLF,IO,DGA^6000030    I14 @T6G_MB_LIB.T6G(SCH_1):PAGE32
   U25 CE48 VSS_CE48 GENOA_SP5-SOCKET6096_13568-001,SMLF,IO,DGA^6000030    I14 @T6G_MB_LIB.T6G(SCH_1):PAGE32
   U25 CE51 VSS_CE51 GENOA_SP5-SOCKET6096_13568-001,SMLF,IO,DGA^6000030    I14 @T6G_MB_LIB.T6G(SCH_1):PAGE32
   U25 CE54 VSS_CE54 GENOA_SP5-SOCKET6096_13568-001,SMLF,IO,DGA^6000030    I14 @T6G_MB_LIB.T6G(SCH_1):PAGE32
   U25 CE56 VSS_CE56 GENOA_SP5-SOCKET6096_13568-001,SMLF,IO,DGA^6000030    I14 @T6G_MB_LIB.T6G(SCH_1):PAGE32
   U25 CE58 VSS_CE58 GENOA_SP5-SOCKET6096_13568-001,SMLF,IO,DGA^6000030    I14 @T6G_MB_LIB.T6G(SCH_1):PAGE32
   U25 CE61 VSS_CE61 GENOA_SP5-SOCKET6096_13568-001,SMLF,IO,DGA^6000030    I14 @T6G_MB_LIB.T6G(SCH_1):PAGE32
   U25 CE63 VSS_CE63 GENOA_SP5-SOCKET6096_13568-001,SMLF,IO,DGA^6000030    I14 @T6G_MB_LIB.T6G(SCH_1):PAGE32
   U25 CE65 VSS_CE65 GENOA_SP5-SOCKET6096_13568-001,SMLF,IO,DGA^6000030    I14 @T6G_MB_LIB.T6G(SCH_1):PAGE32
   U25 CE68 VSS_CE68 GENOA_SP5-SOCKET6096_13568-001,SMLF,IO,DGA^6000030    I14 @T6G_MB_LIB.T6G(SCH_1):PAGE32
   U25 CE70 VSS_CE70 GENOA_SP5-SOCKET6096_13568-001,SMLF,IO,DGA^6000030    I14 @T6G_MB_LIB.T6G(SCH_1):PAGE32
   U25 CE72 VSS_CE72 GENOA_SP5-SOCKET6096_13568-001,SMLF,IO,DGA^6000030    I14 @T6G_MB_LIB.T6G(SCH_1):PAGE32
   U25 CE75 VSS_CE75 GENOA_SP5-SOCKET6096_13568-001,SMLF,IO,DGA^6000030    I14 @T6G_MB_LIB.T6G(SCH_1):PAGE32
   U25  CF3 VSS_CF3 GENOA_SP5-SOCKET6096_13568-001,SMLF,IO,DGA^6000030    I14 @T6G_MB_LIB.T6G(SCH_1):PAGE32
   U25  CF5 VSS_CF5 GENOA_SP5-SOCKET6096_13568-001,SMLF,IO,DGA^6000030    I14 @T6G_MB_LIB.T6G(SCH_1):PAGE32
   U25  CF8 VSS_CF8 GENOA_SP5-SOCKET6096_13568-001,SMLF,IO,DGA^6000030    I14 @T6G_MB_LIB.T6G(SCH_1):PAGE32
   U25 CF10 VSS_CF10 GENOA_SP5-SOCKET6096_13568-001,SMLF,IO,DGA^6000030    I14 @T6G_MB_LIB.T6G(SCH_1):PAGE32
   U25 CF12 VSS_CF12 GENOA_SP5-SOCKET6096_13568-001,SMLF,IO,DGA^6000030    I14 @T6G_MB_LIB.T6G(SCH_1):PAGE32
   U25 CF15 VSS_CF15 GENOA_SP5-SOCKET6096_13568-001,SMLF,IO,DGA^6000030    I14 @T6G_MB_LIB.T6G(SCH_1):PAGE32
   U25 CF17 VSS_CF17 GENOA_SP5-SOCKET6096_13568-001,SMLF,IO,DGA^6000030    I14 @T6G_MB_LIB.T6G(SCH_1):PAGE32
   U25 CF19 VSS_CF19 GENOA_SP5-SOCKET6096_13568-001,SMLF,IO,DGA^6000030    I14 @T6G_MB_LIB.T6G(SCH_1):PAGE32
   U25 CF23 VSS_CF23 GENOA_SP5-SOCKET6096_13568-001,SMLF,IO,DGA^6000030    I14 @T6G_MB_LIB.T6G(SCH_1):PAGE32
   U25 CF24 VSS_CF24 GENOA_SP5-SOCKET6096_13568-001,SMLF,IO,DGA^6000030    I14 @T6G_MB_LIB.T6G(SCH_1):PAGE32
   U25 CF25 VSS_CF25 GENOA_SP5-SOCKET6096_13568-001,SMLF,IO,DGA^6000030    I14 @T6G_MB_LIB.T6G(SCH_1):PAGE32
   U25 CF26 VSS_CF26 GENOA_SP5-SOCKET6096_13568-001,SMLF,IO,DGA^6000030    I14 @T6G_MB_LIB.T6G(SCH_1):PAGE32
   U25 CF27 VSS_CF27 GENOA_SP5-SOCKET6096_13568-001,SMLF,IO,DGA^6000030    I14 @T6G_MB_LIB.T6G(SCH_1):PAGE32
   U25 CF28 VSS_CF28 GENOA_SP5-SOCKET6096_13568-001,SMLF,IO,DGA^6000030    I14 @T6G_MB_LIB.T6G(SCH_1):PAGE32
   U25 CF29 VSS_CF29 GENOA_SP5-SOCKET6096_13568-001,SMLF,IO,DGA^6000030    I14 @T6G_MB_LIB.T6G(SCH_1):PAGE32
   U25 CF30 VSS_CF30 GENOA_SP5-SOCKET6096_13568-001,SMLF,IO,DGA^6000030    I14 @T6G_MB_LIB.T6G(SCH_1):PAGE32
   U25 CF31 VSS_CF31 GENOA_SP5-SOCKET6096_13568-001,SMLF,IO,DGA^6000030    I14 @T6G_MB_LIB.T6G(SCH_1):PAGE32
   U25 CF32 VSS_CF32 GENOA_SP5-SOCKET6096_13568-001,SMLF,IO,DGA^6000030    I14 @T6G_MB_LIB.T6G(SCH_1):PAGE32
   U25 CF33 VSS_CF33 GENOA_SP5-SOCKET6096_13568-001,SMLF,IO,DGA^6000030    I14 @T6G_MB_LIB.T6G(SCH_1):PAGE32
   U25 CF34 VSS_CF34 GENOA_SP5-SOCKET6096_13568-001,SMLF,IO,DGA^6000030    I15 @T6G_MB_LIB.T6G(SCH_1):PAGE32
   U25 CF37 VSS_CF37 GENOA_SP5-SOCKET6096_13568-001,SMLF,IO,DGA^6000030    I15 @T6G_MB_LIB.T6G(SCH_1):PAGE32
   U25 CF39 VSS_CF39 GENOA_SP5-SOCKET6096_13568-001,SMLF,IO,DGA^6000030    I15 @T6G_MB_LIB.T6G(SCH_1):PAGE32
   U25 CF42 VSS_CF42 GENOA_SP5-SOCKET6096_13568-001,SMLF,IO,DGA^6000030    I15 @T6G_MB_LIB.T6G(SCH_1):PAGE32
   U25 CF43 VSS_CF43 GENOA_SP5-SOCKET6096_13568-001,SMLF,IO,DGA^6000030    I15 @T6G_MB_LIB.T6G(SCH_1):PAGE32
   U25 CF44 VSS_CF44 GENOA_SP5-SOCKET6096_13568-001,SMLF,IO,DGA^6000030    I15 @T6G_MB_LIB.T6G(SCH_1):PAGE32
   U25 CF45 VSS_CF45 GENOA_SP5-SOCKET6096_13568-001,SMLF,IO,DGA^6000030    I15 @T6G_MB_LIB.T6G(SCH_1):PAGE32
   U25 CF47 VSS_CF47 GENOA_SP5-SOCKET6096_13568-001,SMLF,IO,DGA^6000030    I15 @T6G_MB_LIB.T6G(SCH_1):PAGE32
   U25 CF48 VSS_CF48 GENOA_SP5-SOCKET6096_13568-001,SMLF,IO,DGA^6000030    I15 @T6G_MB_LIB.T6G(SCH_1):PAGE32
   U25 CF49 VSS_CF49 GENOA_SP5-SOCKET6096_13568-001,SMLF,IO,DGA^6000030    I15 @T6G_MB_LIB.T6G(SCH_1):PAGE32
   U25 CF50 VSS_CF50 GENOA_SP5-SOCKET6096_13568-001,SMLF,IO,DGA^6000030    I15 @T6G_MB_LIB.T6G(SCH_1):PAGE32
   U25 CF51 VSS_CF51 GENOA_SP5-SOCKET6096_13568-001,SMLF,IO,DGA^6000030    I15 @T6G_MB_LIB.T6G(SCH_1):PAGE32
   U25 CF52 VSS_CF52 GENOA_SP5-SOCKET6096_13568-001,SMLF,IO,DGA^6000030    I15 @T6G_MB_LIB.T6G(SCH_1):PAGE32
   U25 CF53 VSS_CF53 GENOA_SP5-SOCKET6096_13568-001,SMLF,IO,DGA^6000030    I15 @T6G_MB_LIB.T6G(SCH_1):PAGE32
   U25 CF57 VSS_CF57 GENOA_SP5-SOCKET6096_13568-001,SMLF,IO,DGA^6000030    I15 @T6G_MB_LIB.T6G(SCH_1):PAGE32
   U25 CF59 VSS_CF59 GENOA_SP5-SOCKET6096_13568-001,SMLF,IO,DGA^6000030    I15 @T6G_MB_LIB.T6G(SCH_1):PAGE32
   U25 CF61 VSS_CF61 GENOA_SP5-SOCKET6096_13568-001,SMLF,IO,DGA^6000030    I15 @T6G_MB_LIB.T6G(SCH_1):PAGE32
   U25 CF64 VSS_CF64 GENOA_SP5-SOCKET6096_13568-001,SMLF,IO,DGA^6000030    I15 @T6G_MB_LIB.T6G(SCH_1):PAGE32
   U25 CF66 VSS_CF66 GENOA_SP5-SOCKET6096_13568-001,SMLF,IO,DGA^6000030    I15 @T6G_MB_LIB.T6G(SCH_1):PAGE32
   U25 CF68 VSS_CF68 GENOA_SP5-SOCKET6096_13568-001,SMLF,IO,DGA^6000030    I15 @T6G_MB_LIB.T6G(SCH_1):PAGE32
   U25 CF71 VSS_CF71 GENOA_SP5-SOCKET6096_13568-001,SMLF,IO,DGA^6000030    I15 @T6G_MB_LIB.T6G(SCH_1):PAGE32
   U25 CF73 VSS_CF73 GENOA_SP5-SOCKET6096_13568-001,SMLF,IO,DGA^6000030    I15 @T6G_MB_LIB.T6G(SCH_1):PAGE32
   U25  CG1 VSS_CG1 GENOA_SP5-SOCKET6096_13568-001,SMLF,IO,DGA^6000030    I15 @T6G_MB_LIB.T6G(SCH_1):PAGE32
   U25  CG6 VSS_CG6 GENOA_SP5-SOCKET6096_13568-001,SMLF,IO,DGA^6000030    I15 @T6G_MB_LIB.T6G(SCH_1):PAGE32
   U25  CG8 VSS_CG8 GENOA_SP5-SOCKET6096_13568-001,SMLF,IO,DGA^6000030    I15 @T6G_MB_LIB.T6G(SCH_1):PAGE32
   U25 CG13 VSS_CG13 GENOA_SP5-SOCKET6096_13568-001,SMLF,IO,DGA^6000030    I15 @T6G_MB_LIB.T6G(SCH_1):PAGE32
   U25 CG15 VSS_CG15 GENOA_SP5-SOCKET6096_13568-001,SMLF,IO,DGA^6000030    I15 @T6G_MB_LIB.T6G(SCH_1):PAGE32
   U25 CG20 VSS_CG20 GENOA_SP5-SOCKET6096_13568-001,SMLF,IO,DGA^6000030    I15 @T6G_MB_LIB.T6G(SCH_1):PAGE32
   U25 CG22 VSS_CG22 GENOA_SP5-SOCKET6096_13568-001,SMLF,IO,DGA^6000030    I15 @T6G_MB_LIB.T6G(SCH_1):PAGE32
   U25 CG25 VSS_CG25 GENOA_SP5-SOCKET6096_13568-001,SMLF,IO,DGA^6000030    I15 @T6G_MB_LIB.T6G(SCH_1):PAGE32
   U25 CG28 VSS_CG28 GENOA_SP5-SOCKET6096_13568-001,SMLF,IO,DGA^6000030    I15 @T6G_MB_LIB.T6G(SCH_1):PAGE32
   U25 CG31 VSS_CG31 GENOA_SP5-SOCKET6096_13568-001,SMLF,IO,DGA^6000030    I15 @T6G_MB_LIB.T6G(SCH_1):PAGE32
   U25 CG34 VSS_CG34 GENOA_SP5-SOCKET6096_13568-001,SMLF,IO,DGA^6000030    I15 @T6G_MB_LIB.T6G(SCH_1):PAGE32
   U25 CG45 VSS_CG45 GENOA_SP5-SOCKET6096_13568-001,SMLF,IO,DGA^6000030    I15 @T6G_MB_LIB.T6G(SCH_1):PAGE32
   U25 CG48 VSS_CG48 GENOA_SP5-SOCKET6096_13568-001,SMLF,IO,DGA^6000030    I15 @T6G_MB_LIB.T6G(SCH_1):PAGE32
   U25 CG51 VSS_CG51 GENOA_SP5-SOCKET6096_13568-001,SMLF,IO,DGA^6000030    I15 @T6G_MB_LIB.T6G(SCH_1):PAGE32
   U25 CG54 VSS_CG54 GENOA_SP5-SOCKET6096_13568-001,SMLF,IO,DGA^6000030    I15 @T6G_MB_LIB.T6G(SCH_1):PAGE32
   U25 CG56 VSS_CG56 GENOA_SP5-SOCKET6096_13568-001,SMLF,IO,DGA^6000030    I15 @T6G_MB_LIB.T6G(SCH_1):PAGE32
   U25 CG61 VSS_CG61 GENOA_SP5-SOCKET6096_13568-001,SMLF,IO,DGA^6000030    I15 @T6G_MB_LIB.T6G(SCH_1):PAGE32
   U25 CG63 VSS_CG63 GENOA_SP5-SOCKET6096_13568-001,SMLF,IO,DGA^6000030    I15 @T6G_MB_LIB.T6G(SCH_1):PAGE32
   U25 CG68 VSS_CG68 GENOA_SP5-SOCKET6096_13568-001,SMLF,IO,DGA^6000030    I15 @T6G_MB_LIB.T6G(SCH_1):PAGE32
   U25 CG70 VSS_CG70 GENOA_SP5-SOCKET6096_13568-001,SMLF,IO,DGA^6000030    I15 @T6G_MB_LIB.T6G(SCH_1):PAGE32
   U25 CG75 VSS_CG75 GENOA_SP5-SOCKET6096_13568-001,SMLF,IO,DGA^6000030    I15 @T6G_MB_LIB.T6G(SCH_1):PAGE32
   U25  CH3 VSS_CH3 GENOA_SP5-SOCKET6096_13568-001,SMLF,IO,DGA^6000030    I15 @T6G_MB_LIB.T6G(SCH_1):PAGE32
   U25  CH5 VSS_CH5 GENOA_SP5-SOCKET6096_13568-001,SMLF,IO,DGA^6000030    I15 @T6G_MB_LIB.T6G(SCH_1):PAGE32
   U25  CH8 VSS_CH8 GENOA_SP5-SOCKET6096_13568-001,SMLF,IO,DGA^6000030    I15 @T6G_MB_LIB.T6G(SCH_1):PAGE32
   U25 CH10 VSS_CH10 GENOA_SP5-SOCKET6096_13568-001,SMLF,IO,DGA^6000030    I15 @T6G_MB_LIB.T6G(SCH_1):PAGE32
   U25 CH12 VSS_CH12 GENOA_SP5-SOCKET6096_13568-001,SMLF,IO,DGA^6000030    I15 @T6G_MB_LIB.T6G(SCH_1):PAGE32
   U25 CH15 VSS_CH15 GENOA_SP5-SOCKET6096_13568-001,SMLF,IO,DGA^6000030    I15 @T6G_MB_LIB.T6G(SCH_1):PAGE32
   U25 CH17 VSS_CH17 GENOA_SP5-SOCKET6096_13568-001,SMLF,IO,DGA^6000030    I15 @T6G_MB_LIB.T6G(SCH_1):PAGE32
   U25 CH19 VSS_CH19 GENOA_SP5-SOCKET6096_13568-001,SMLF,IO,DGA^6000030    I15 @T6G_MB_LIB.T6G(SCH_1):PAGE32
   U25 CH22 VSS_CH22 GENOA_SP5-SOCKET6096_13568-001,SMLF,IO,DGA^6000030    I15 @T6G_MB_LIB.T6G(SCH_1):PAGE32
   U25 CH25 VSS_CH25 GENOA_SP5-SOCKET6096_13568-001,SMLF,IO,DGA^6000030    I15 @T6G_MB_LIB.T6G(SCH_1):PAGE32
   U25 CH28 VSS_CH28 GENOA_SP5-SOCKET6096_13568-001,SMLF,IO,DGA^6000030    I15 @T6G_MB_LIB.T6G(SCH_1):PAGE32
   U25 CH31 VSS_CH31 GENOA_SP5-SOCKET6096_13568-001,SMLF,IO,DGA^6000030    I15 @T6G_MB_LIB.T6G(SCH_1):PAGE32
   U25 CH34 VSS_CH34 GENOA_SP5-SOCKET6096_13568-001,SMLF,IO,DGA^6000030    I15 @T6G_MB_LIB.T6G(SCH_1):PAGE32
   U25 CH37 VSS_CH37 GENOA_SP5-SOCKET6096_13568-001,SMLF,IO,DGA^6000030    I15 @T6G_MB_LIB.T6G(SCH_1):PAGE32
   U25 CH39 VSS_CH39 GENOA_SP5-SOCKET6096_13568-001,SMLF,IO,DGA^6000030    I15 @T6G_MB_LIB.T6G(SCH_1):PAGE32
   U25 CH42 VSS_CH42 GENOA_SP5-SOCKET6096_13568-001,SMLF,IO,DGA^6000030    I15 @T6G_MB_LIB.T6G(SCH_1):PAGE32
   U25 CH45 VSS_CH45 GENOA_SP5-SOCKET6096_13568-001,SMLF,IO,DGA^6000030    I15 @T6G_MB_LIB.T6G(SCH_1):PAGE32
   U25 CH48 VSS_CH48 GENOA_SP5-SOCKET6096_13568-001,SMLF,IO,DGA^6000030    I15 @T6G_MB_LIB.T6G(SCH_1):PAGE32
   U25 CH51 VSS_CH51 GENOA_SP5-SOCKET6096_13568-001,SMLF,IO,DGA^6000030    I15 @T6G_MB_LIB.T6G(SCH_1):PAGE32
   U25 CH54 VSS_CH54 GENOA_SP5-SOCKET6096_13568-001,SMLF,IO,DGA^6000030    I15 @T6G_MB_LIB.T6G(SCH_1):PAGE32
   U25 CH57 VSS_CH57 GENOA_SP5-SOCKET6096_13568-001,SMLF,IO,DGA^6000030    I15 @T6G_MB_LIB.T6G(SCH_1):PAGE32
   U25 CH59 VSS_CH59 GENOA_SP5-SOCKET6096_13568-001,SMLF,IO,DGA^6000030    I15 @T6G_MB_LIB.T6G(SCH_1):PAGE32
   U25 CH61 VSS_CH61 GENOA_SP5-SOCKET6096_13568-001,SMLF,IO,DGA^6000030    I15 @T6G_MB_LIB.T6G(SCH_1):PAGE32
   U25 CH64 VSS_CH64 GENOA_SP5-SOCKET6096_13568-001,SMLF,IO,DGA^6000030    I15 @T6G_MB_LIB.T6G(SCH_1):PAGE32
   U25 CH66 VSS_CH66 GENOA_SP5-SOCKET6096_13568-001,SMLF,IO,DGA^6000030    I15 @T6G_MB_LIB.T6G(SCH_1):PAGE32
   U25 CH68 VSS_CH68 GENOA_SP5-SOCKET6096_13568-001,SMLF,IO,DGA^6000030    I15 @T6G_MB_LIB.T6G(SCH_1):PAGE32
   U25 CH71 VSS_CH71 GENOA_SP5-SOCKET6096_13568-001,SMLF,IO,DGA^6000030    I15 @T6G_MB_LIB.T6G(SCH_1):PAGE32
   U25 CH73 VSS_CH73 GENOA_SP5-SOCKET6096_13568-001,SMLF,IO,DGA^6000030    I15 @T6G_MB_LIB.T6G(SCH_1):PAGE32
   U25  CJ1 VSS_CJ1 GENOA_SP5-SOCKET6096_13568-001,SMLF,IO,DGA^6000030    I15 @T6G_MB_LIB.T6G(SCH_1):PAGE32
   U25  CJ4 VSS_CJ4 GENOA_SP5-SOCKET6096_13568-001,SMLF,IO,DGA^6000030    I15 @T6G_MB_LIB.T6G(SCH_1):PAGE32
   U25  CJ6 VSS_CJ6 GENOA_SP5-SOCKET6096_13568-001,SMLF,IO,DGA^6000030    I15 @T6G_MB_LIB.T6G(SCH_1):PAGE32
   U25  CJ8 VSS_CJ8 GENOA_SP5-SOCKET6096_13568-001,SMLF,IO,DGA^6000030    I15 @T6G_MB_LIB.T6G(SCH_1):PAGE32
   U25 CJ11 VSS_CJ11 GENOA_SP5-SOCKET6096_13568-001,SMLF,IO,DGA^6000030    I15 @T6G_MB_LIB.T6G(SCH_1):PAGE32
   U25 CJ13 VSS_CJ13 GENOA_SP5-SOCKET6096_13568-001,SMLF,IO,DGA^6000030    I15 @T6G_MB_LIB.T6G(SCH_1):PAGE32
   U25 CJ15 VSS_CJ15 GENOA_SP5-SOCKET6096_13568-001,SMLF,IO,DGA^6000030    I15 @T6G_MB_LIB.T6G(SCH_1):PAGE32
   U25 CJ18 VSS_CJ18 GENOA_SP5-SOCKET6096_13568-001,SMLF,IO,DGA^6000030    I15 @T6G_MB_LIB.T6G(SCH_1):PAGE32
   U25 CJ20 VSS_CJ20 GENOA_SP5-SOCKET6096_13568-001,SMLF,IO,DGA^6000030    I15 @T6G_MB_LIB.T6G(SCH_1):PAGE32
   U25 CJ23 VSS_CJ23 GENOA_SP5-SOCKET6096_13568-001,SMLF,IO,DGA^6000030    I15 @T6G_MB_LIB.T6G(SCH_1):PAGE32
   U25 CJ31 VSS_CJ31 GENOA_SP5-SOCKET6096_13568-001,SMLF,IO,DGA^6000030    I15 @T6G_MB_LIB.T6G(SCH_1):PAGE32
   U25 CJ34 VSS_CJ34 GENOA_SP5-SOCKET6096_13568-001,SMLF,IO,DGA^6000030    I15 @T6G_MB_LIB.T6G(SCH_1):PAGE32
   U25 CJ35 VSS_CJ35 GENOA_SP5-SOCKET6096_13568-001,SMLF,IO,DGA^6000030    I15 @T6G_MB_LIB.T6G(SCH_1):PAGE32
   U25 CJ36 VSS_CJ36 GENOA_SP5-SOCKET6096_13568-001,SMLF,IO,DGA^6000030    I15 @T6G_MB_LIB.T6G(SCH_1):PAGE32
   U25 CJ40 VSS_CJ40 GENOA_SP5-SOCKET6096_13568-001,SMLF,IO,DGA^6000030    I15 @T6G_MB_LIB.T6G(SCH_1):PAGE32
   U25 CJ41 VSS_CJ41 GENOA_SP5-SOCKET6096_13568-001,SMLF,IO,DGA^6000030    I15 @T6G_MB_LIB.T6G(SCH_1):PAGE32
   U25 CJ42 VSS_CJ42 GENOA_SP5-SOCKET6096_13568-001,SMLF,IO,DGA^6000030    I15 @T6G_MB_LIB.T6G(SCH_1):PAGE32
   U25 CJ45 VSS_CJ45 GENOA_SP5-SOCKET6096_13568-001,SMLF,IO,DGA^6000030    I15 @T6G_MB_LIB.T6G(SCH_1):PAGE32
   U25 CJ56 VSS_CJ56 GENOA_SP5-SOCKET6096_13568-001,SMLF,IO,DGA^6000030    I15 @T6G_MB_LIB.T6G(SCH_1):PAGE32
   U25 CJ58 VSS_CJ58 GENOA_SP5-SOCKET6096_13568-001,SMLF,IO,DGA^6000030    I15 @T6G_MB_LIB.T6G(SCH_1):PAGE32
   U25 CJ61 VSS_CJ61 GENOA_SP5-SOCKET6096_13568-001,SMLF,IO,DGA^6000030    I15 @T6G_MB_LIB.T6G(SCH_1):PAGE32
   U25 CJ63 VSS_CJ63 GENOA_SP5-SOCKET6096_13568-001,SMLF,IO,DGA^6000030    I15 @T6G_MB_LIB.T6G(SCH_1):PAGE32
   U25 CJ65 VSS_CJ65 GENOA_SP5-SOCKET6096_13568-001,SMLF,IO,DGA^6000030    I15 @T6G_MB_LIB.T6G(SCH_1):PAGE32
   U25 CJ68 VSS_CJ68 GENOA_SP5-SOCKET6096_13568-001,SMLF,IO,DGA^6000030    I15 @T6G_MB_LIB.T6G(SCH_1):PAGE32
   U25 CJ70 VSS_CJ70 GENOA_SP5-SOCKET6096_13568-001,SMLF,IO,DGA^6000030    I15 @T6G_MB_LIB.T6G(SCH_1):PAGE32
   U25 CJ72 VSS_CJ72 GENOA_SP5-SOCKET6096_13568-001,SMLF,IO,DGA^6000030    I15 @T6G_MB_LIB.T6G(SCH_1):PAGE32
   U25 CJ75 VSS_CJ75 GENOA_SP5-SOCKET6096_13568-001,SMLF,IO,DGA^6000030    I15 @T6G_MB_LIB.T6G(SCH_1):PAGE32
   U25  CK3 VSS_CK3 GENOA_SP5-SOCKET6096_13568-001,SMLF,IO,DGA^6000030    I15 @T6G_MB_LIB.T6G(SCH_1):PAGE32
   U25  CK8 VSS_CK8 GENOA_SP5-SOCKET6096_13568-001,SMLF,IO,DGA^6000030    I15 @T6G_MB_LIB.T6G(SCH_1):PAGE32
   U25 CK15 VSS_CK15 GENOA_SP5-SOCKET6096_13568-001,SMLF,IO,DGA^6000030    I15 @T6G_MB_LIB.T6G(SCH_1):PAGE32
   U25 CK17 VSS_CK17 GENOA_SP5-SOCKET6096_13568-001,SMLF,IO,DGA^6000030    I15 @T6G_MB_LIB.T6G(SCH_1):PAGE32
   U25 CK22 VSS_CK22 GENOA_SP5-SOCKET6096_13568-001,SMLF,IO,DGA^6000030    I15 @T6G_MB_LIB.T6G(SCH_1):PAGE32
   U25 CK23 VSS_CK23 GENOA_SP5-SOCKET6096_13568-001,SMLF,IO,DGA^6000030    I15 @T6G_MB_LIB.T6G(SCH_1):PAGE32
   U25 CK24 VSS_CK24 GENOA_SP5-SOCKET6096_13568-001,SMLF,IO,DGA^6000030    I15 @T6G_MB_LIB.T6G(SCH_1):PAGE32
   U25 CK25 VSS_CK25 GENOA_SP5-SOCKET6096_13568-001,SMLF,IO,DGA^6000030    I15 @T6G_MB_LIB.T6G(SCH_1):PAGE32
   U25 CK26 VSS_CK26 GENOA_SP5-SOCKET6096_13568-001,SMLF,IO,DGA^6000030    I15 @T6G_MB_LIB.T6G(SCH_1):PAGE32
   U25 CK27 VSS_CK27 GENOA_SP5-SOCKET6096_13568-001,SMLF,IO,DGA^6000030    I15 @T6G_MB_LIB.T6G(SCH_1):PAGE32
   U25 CK28 VSS_CK28 GENOA_SP5-SOCKET6096_13568-001,SMLF,IO,DGA^6000030    I15 @T6G_MB_LIB.T6G(SCH_1):PAGE32
   U25 CK32 VSS_CK32 GENOA_SP5-SOCKET6096_13568-001,SMLF,IO,DGA^6000030    I15 @T6G_MB_LIB.T6G(SCH_1):PAGE32
   U25 CK33 VSS_CK33 GENOA_SP5-SOCKET6096_13568-001,SMLF,IO,DGA^6000030    I15 @T6G_MB_LIB.T6G(SCH_1):PAGE32
   U25 CK34 VSS_CK34 GENOA_SP5-SOCKET6096_13568-001,SMLF,IO,DGA^6000030    I15 @T6G_MB_LIB.T6G(SCH_1):PAGE32
   U25 CK37 VSS_CK37 GENOA_SP5-SOCKET6096_13568-001,SMLF,IO,DGA^6000030    I15 @T6G_MB_LIB.T6G(SCH_1):PAGE32
   U25 CK39 VSS_CK39 GENOA_SP5-SOCKET6096_13568-001,SMLF,IO,DGA^6000030    I15 @T6G_MB_LIB.T6G(SCH_1):PAGE32
   U25 CK42 VSS_CK42 GENOA_SP5-SOCKET6096_13568-001,SMLF,IO,DGA^6000030    I15 @T6G_MB_LIB.T6G(SCH_1):PAGE32
   U25 CK43 VSS_CK43 GENOA_SP5-SOCKET6096_13568-001,SMLF,IO,DGA^6000030    I15 @T6G_MB_LIB.T6G(SCH_1):PAGE32
   U25 CK44 VSS_CK44 GENOA_SP5-SOCKET6096_13568-001,SMLF,IO,DGA^6000030    I15 @T6G_MB_LIB.T6G(SCH_1):PAGE32
   U25 CK45 VSS_CK45 GENOA_SP5-SOCKET6096_13568-001,SMLF,IO,DGA^6000030    I15 @T6G_MB_LIB.T6G(SCH_1):PAGE32
   U25 CK48 VSS_CK48 GENOA_SP5-SOCKET6096_13568-001,SMLF,IO,DGA^6000030    I15 @T6G_MB_LIB.T6G(SCH_1):PAGE32
   U25 CK49 VSS_CK49 GENOA_SP5-SOCKET6096_13568-001,SMLF,IO,DGA^6000030    I15 @T6G_MB_LIB.T6G(SCH_1):PAGE32
   U25 CK50 VSS_CK50 GENOA_SP5-SOCKET6096_13568-001,SMLF,IO,DGA^6000030    I15 @T6G_MB_LIB.T6G(SCH_1):PAGE32
   U25 CK51 VSS_CK51 GENOA_SP5-SOCKET6096_13568-001,SMLF,IO,DGA^6000030    I15 @T6G_MB_LIB.T6G(SCH_1):PAGE32
   U25 CK52 VSS_CK52 GENOA_SP5-SOCKET6096_13568-001,SMLF,IO,DGA^6000030    I15 @T6G_MB_LIB.T6G(SCH_1):PAGE32
   U25 CK53 VSS_CK53 GENOA_SP5-SOCKET6096_13568-001,SMLF,IO,DGA^6000030    I15 @T6G_MB_LIB.T6G(SCH_1):PAGE32
   U25 CK54 VSS_CK54 GENOA_SP5-SOCKET6096_13568-001,SMLF,IO,DGA^6000030    I15 @T6G_MB_LIB.T6G(SCH_1):PAGE32
   U25 CK59 VSS_CK59 GENOA_SP5-SOCKET6096_13568-001,SMLF,IO,DGA^6000030    I15 @T6G_MB_LIB.T6G(SCH_1):PAGE32
   U25 CK61 VSS_CK61 GENOA_SP5-SOCKET6096_13568-001,SMLF,IO,DGA^6000030    I15 @T6G_MB_LIB.T6G(SCH_1):PAGE32
   U25 CK66 VSS_CK66 GENOA_SP5-SOCKET6096_13568-001,SMLF,IO,DGA^6000030    I15 @T6G_MB_LIB.T6G(SCH_1):PAGE32
   U25 CK68 VSS_CK68 GENOA_SP5-SOCKET6096_13568-001,SMLF,IO,DGA^6000030    I15 @T6G_MB_LIB.T6G(SCH_1):PAGE32
   U25 CK73 VSS_CK73 GENOA_SP5-SOCKET6096_13568-001,SMLF,IO,DGA^6000030    I15 @T6G_MB_LIB.T6G(SCH_1):PAGE32
   U25  CL1 VSS_CL1 GENOA_SP5-SOCKET6096_13568-001,SMLF,IO,DGA^6000030    I15 @T6G_MB_LIB.T6G(SCH_1):PAGE32
   U25  CL4 VSS_CL4 GENOA_SP5-SOCKET6096_13568-001,SMLF,IO,DGA^6000030    I15 @T6G_MB_LIB.T6G(SCH_1):PAGE32
   U25  CL6 VSS_CL6 GENOA_SP5-SOCKET6096_13568-001,SMLF,IO,DGA^6000030    I15 @T6G_MB_LIB.T6G(SCH_1):PAGE32
   U25  CL8 VSS_CL8 GENOA_SP5-SOCKET6096_13568-001,SMLF,IO,DGA^6000030    I15 @T6G_MB_LIB.T6G(SCH_1):PAGE32
   U25 CL11 VSS_CL11 GENOA_SP5-SOCKET6096_13568-001,SMLF,IO,DGA^6000030    I15 @T6G_MB_LIB.T6G(SCH_1):PAGE32
   U25 CL13 VSS_CL13 GENOA_SP5-SOCKET6096_13568-001,SMLF,IO,DGA^6000030    I15 @T6G_MB_LIB.T6G(SCH_1):PAGE32
   U25 CL15 VSS_CL15 GENOA_SP5-SOCKET6096_13568-001,SMLF,IO,DGA^6000030    I15 @T6G_MB_LIB.T6G(SCH_1):PAGE32
   U25 CL18 VSS_CL18 GENOA_SP5-SOCKET6096_13568-001,SMLF,IO,DGA^6000030    I15 @T6G_MB_LIB.T6G(SCH_1):PAGE32
   U25 CL20 VSS_CL20 GENOA_SP5-SOCKET6096_13568-001,SMLF,IO,DGA^6000030    I15 @T6G_MB_LIB.T6G(SCH_1):PAGE32
   U25 CL22 VSS_CL22 GENOA_SP5-SOCKET6096_13568-001,SMLF,IO,DGA^6000030    I15 @T6G_MB_LIB.T6G(SCH_1):PAGE32
   U25 CL25 VSS_CL25 GENOA_SP5-SOCKET6096_13568-001,SMLF,IO,DGA^6000030    I15 @T6G_MB_LIB.T6G(SCH_1):PAGE32
   U25 CL28 VSS_CL28 GENOA_SP5-SOCKET6096_13568-001,SMLF,IO,DGA^6000030    I15 @T6G_MB_LIB.T6G(SCH_1):PAGE32
   U25 CL31 VSS_CL31 GENOA_SP5-SOCKET6096_13568-001,SMLF,IO,DGA^6000030    I15 @T6G_MB_LIB.T6G(SCH_1):PAGE32
   U25 CL34 VSS_CL34 GENOA_SP5-SOCKET6096_13568-001,SMLF,IO,DGA^6000030    I15 @T6G_MB_LIB.T6G(SCH_1):PAGE32
   U25 CL35 VSS_CL35 GENOA_SP5-SOCKET6096_13568-001,SMLF,IO,DGA^6000030    I15 @T6G_MB_LIB.T6G(SCH_1):PAGE32
   U25 CL36 VSS_CL36 GENOA_SP5-SOCKET6096_13568-001,SMLF,IO,DGA^6000030    I15 @T6G_MB_LIB.T6G(SCH_1):PAGE32
   U25 CL40 VSS_CL40 GENOA_SP5-SOCKET6096_13568-001,SMLF,IO,DGA^6000030    I15 @T6G_MB_LIB.T6G(SCH_1):PAGE32
   U25 CL41 VSS_CL41 GENOA_SP5-SOCKET6096_13568-001,SMLF,IO,DGA^6000030    I15 @T6G_MB_LIB.T6G(SCH_1):PAGE32
   U25 CL42 VSS_CL42 GENOA_SP5-SOCKET6096_13568-001,SMLF,IO,DGA^6000030    I15 @T6G_MB_LIB.T6G(SCH_1):PAGE32
   U25 CL45 VSS_CL45 GENOA_SP5-SOCKET6096_13568-001,SMLF,IO,DGA^6000030    I15 @T6G_MB_LIB.T6G(SCH_1):PAGE32
   U25 CL48 VSS_CL48 GENOA_SP5-SOCKET6096_13568-001,SMLF,IO,DGA^6000030    I15 @T6G_MB_LIB.T6G(SCH_1):PAGE32
   U25 CL51 VSS_CL51 GENOA_SP5-SOCKET6096_13568-001,SMLF,IO,DGA^6000030    I15 @T6G_MB_LIB.T6G(SCH_1):PAGE32
   U25 CL54 VSS_CL54 GENOA_SP5-SOCKET6096_13568-001,SMLF,IO,DGA^6000030    I15 @T6G_MB_LIB.T6G(SCH_1):PAGE32
   U25 CL56 VSS_CL56 GENOA_SP5-SOCKET6096_13568-001,SMLF,IO,DGA^6000030    I15 @T6G_MB_LIB.T6G(SCH_1):PAGE32
   U25 CL58 VSS_CL58 GENOA_SP5-SOCKET6096_13568-001,SMLF,IO,DGA^6000030    I15 @T6G_MB_LIB.T6G(SCH_1):PAGE32
   U25 CL61 VSS_CL61 GENOA_SP5-SOCKET6096_13568-001,SMLF,IO,DGA^6000030    I15 @T6G_MB_LIB.T6G(SCH_1):PAGE32
   U25 CL63 VSS_CL63 GENOA_SP5-SOCKET6096_13568-001,SMLF,IO,DGA^6000030    I15 @T6G_MB_LIB.T6G(SCH_1):PAGE32
   U25 CL65 VSS_CL65 GENOA_SP5-SOCKET6096_13568-001,SMLF,IO,DGA^6000030    I15 @T6G_MB_LIB.T6G(SCH_1):PAGE32
   U25 CL68 VSS_CL68 GENOA_SP5-SOCKET6096_13568-001,SMLF,IO,DGA^6000030    I15 @T6G_MB_LIB.T6G(SCH_1):PAGE32
   U25 CL70 VSS_CL70 GENOA_SP5-SOCKET6096_13568-001,SMLF,IO,DGA^6000030    I15 @T6G_MB_LIB.T6G(SCH_1):PAGE32
   U25 CL72 VSS_CL72 GENOA_SP5-SOCKET6096_13568-001,SMLF,IO,DGA^6000030    I15 @T6G_MB_LIB.T6G(SCH_1):PAGE32
   U25 CL75 VSS_CL75 GENOA_SP5-SOCKET6096_13568-001,SMLF,IO,DGA^6000030    I15 @T6G_MB_LIB.T6G(SCH_1):PAGE32
   U25  CM3 VSS_CM3 GENOA_SP5-SOCKET6096_13568-001,SMLF,IO,DGA^6000030    I15 @T6G_MB_LIB.T6G(SCH_1):PAGE32
   U25  CM5 VSS_CM5 GENOA_SP5-SOCKET6096_13568-001,SMLF,IO,DGA^6000030    I15 @T6G_MB_LIB.T6G(SCH_1):PAGE32
   U25  CM8 VSS_CM8 GENOA_SP5-SOCKET6096_13568-001,SMLF,IO,DGA^6000030    I15 @T6G_MB_LIB.T6G(SCH_1):PAGE32
   U25 CM10 VSS_CM10 GENOA_SP5-SOCKET6096_13568-001,SMLF,IO,DGA^6000030    I15 @T6G_MB_LIB.T6G(SCH_1):PAGE32
   U25 CM12 VSS_CM12 GENOA_SP5-SOCKET6096_13568-001,SMLF,IO,DGA^6000030    I15 @T6G_MB_LIB.T6G(SCH_1):PAGE32
   U25 CM15 VSS_CM15 GENOA_SP5-SOCKET6096_13568-001,SMLF,IO,DGA^6000030    I15 @T6G_MB_LIB.T6G(SCH_1):PAGE32
   U25 CM17 VSS_CM17 GENOA_SP5-SOCKET6096_13568-001,SMLF,IO,DGA^6000030    I15 @T6G_MB_LIB.T6G(SCH_1):PAGE32
   U25 CM19 VSS_CM19 GENOA_SP5-SOCKET6096_13568-001,SMLF,IO,DGA^6000030    I15 @T6G_MB_LIB.T6G(SCH_1):PAGE32
   U25 CM23 VSS_CM23 GENOA_SP5-SOCKET6096_13568-001,SMLF,IO,DGA^6000030    I15 @T6G_MB_LIB.T6G(SCH_1):PAGE32
   U25 CM24 VSS_CM24 GENOA_SP5-SOCKET6096_13568-001,SMLF,IO,DGA^6000030    I15 @T6G_MB_LIB.T6G(SCH_1):PAGE32
   U25 CM25 VSS_CM25 GENOA_SP5-SOCKET6096_13568-001,SMLF,IO,DGA^6000030    I15 @T6G_MB_LIB.T6G(SCH_1):PAGE32
   U25 CM26 VSS_CM26 GENOA_SP5-SOCKET6096_13568-001,SMLF,IO,DGA^6000030    I15 @T6G_MB_LIB.T6G(SCH_1):PAGE32
   U25 CM27 VSS_CM27 GENOA_SP5-SOCKET6096_13568-001,SMLF,IO,DGA^6000030    I15 @T6G_MB_LIB.T6G(SCH_1):PAGE32
   U25 CM28 VSS_CM28 GENOA_SP5-SOCKET6096_13568-001,SMLF,IO,DGA^6000030    I15 @T6G_MB_LIB.T6G(SCH_1):PAGE32
   U25 CM29 VSS_CM29 GENOA_SP5-SOCKET6096_13568-001,SMLF,IO,DGA^6000030    I15 @T6G_MB_LIB.T6G(SCH_1):PAGE32
   U25 CM30 VSS_CM30 GENOA_SP5-SOCKET6096_13568-001,SMLF,IO,DGA^6000030    I15 @T6G_MB_LIB.T6G(SCH_1):PAGE32
   U25 CM31 VSS_CM31 GENOA_SP5-SOCKET6096_13568-001,SMLF,IO,DGA^6000030    I15 @T6G_MB_LIB.T6G(SCH_1):PAGE32
   U25 CM32 VSS_CM32 GENOA_SP5-SOCKET6096_13568-001,SMLF,IO,DGA^6000030    I15 @T6G_MB_LIB.T6G(SCH_1):PAGE32
   U25 CM33 VSS_CM33 GENOA_SP5-SOCKET6096_13568-001,SMLF,IO,DGA^6000030    I15 @T6G_MB_LIB.T6G(SCH_1):PAGE32
   U25 CM34 VSS_CM34 GENOA_SP5-SOCKET6096_13568-001,SMLF,IO,DGA^6000030    I15 @T6G_MB_LIB.T6G(SCH_1):PAGE32
   U25 CM37 VSS_CM37 GENOA_SP5-SOCKET6096_13568-001,SMLF,IO,DGA^6000030    I15 @T6G_MB_LIB.T6G(SCH_1):PAGE32
   U25 CM39 VSS_CM39 GENOA_SP5-SOCKET6096_13568-001,SMLF,IO,DGA^6000030    I15 @T6G_MB_LIB.T6G(SCH_1):PAGE32
   U25 CM42 VSS_CM42 GENOA_SP5-SOCKET6096_13568-001,SMLF,IO,DGA^6000030    I15 @T6G_MB_LIB.T6G(SCH_1):PAGE32
   U25 CM43 VSS_CM43 GENOA_SP5-SOCKET6096_13568-001,SMLF,IO,DGA^6000030    I15 @T6G_MB_LIB.T6G(SCH_1):PAGE32
   U25 CM44 VSS_CM44 GENOA_SP5-SOCKET6096_13568-001,SMLF,IO,DGA^6000030    I15 @T6G_MB_LIB.T6G(SCH_1):PAGE32
   U25 CM45 VSS_CM45 GENOA_SP5-SOCKET6096_13568-001,SMLF,IO,DGA^6000030    I15 @T6G_MB_LIB.T6G(SCH_1):PAGE32
   U25 CM46 VSS_CM46 GENOA_SP5-SOCKET6096_13568-001,SMLF,IO,DGA^6000030    I15 @T6G_MB_LIB.T6G(SCH_1):PAGE32
   U25 CM47 VSS_CM47 GENOA_SP5-SOCKET6096_13568-001,SMLF,IO,DGA^6000030    I15 @T6G_MB_LIB.T6G(SCH_1):PAGE32
   U25 CM48 VSS_CM48 GENOA_SP5-SOCKET6096_13568-001,SMLF,IO,DGA^6000030    I15 @T6G_MB_LIB.T6G(SCH_1):PAGE32
   U25 CM49 VSS_CM49 GENOA_SP5-SOCKET6096_13568-001,SMLF,IO,DGA^6000030    I15 @T6G_MB_LIB.T6G(SCH_1):PAGE32
   U25 CM51 VSS_CM51 GENOA_SP5-SOCKET6096_13568-001,SMLF,IO,DGA^6000030    I15 @T6G_MB_LIB.T6G(SCH_1):PAGE32
   U25 CM52 VSS_CM52 GENOA_SP5-SOCKET6096_13568-001,SMLF,IO,DGA^6000030    I15 @T6G_MB_LIB.T6G(SCH_1):PAGE32
   U25 CM53 VSS_CM53 GENOA_SP5-SOCKET6096_13568-001,SMLF,IO,DGA^6000030    I15 @T6G_MB_LIB.T6G(SCH_1):PAGE32
   U25 CM57 VSS_CM57 GENOA_SP5-SOCKET6096_13568-001,SMLF,IO,DGA^6000030    I15 @T6G_MB_LIB.T6G(SCH_1):PAGE32
   U25 CM59 VSS_CM59 GENOA_SP5-SOCKET6096_13568-001,SMLF,IO,DGA^6000030    I15 @T6G_MB_LIB.T6G(SCH_1):PAGE32
   U25 CM61 VSS_CM61 GENOA_SP5-SOCKET6096_13568-001,SMLF,IO,DGA^6000030    I15 @T6G_MB_LIB.T6G(SCH_1):PAGE32
   U25 CM64 VSS_CM64 GENOA_SP5-SOCKET6096_13568-001,SMLF,IO,DGA^6000030    I15 @T6G_MB_LIB.T6G(SCH_1):PAGE32
   U25 CM66 VSS_CM66 GENOA_SP5-SOCKET6096_13568-001,SMLF,IO,DGA^6000030    I15 @T6G_MB_LIB.T6G(SCH_1):PAGE32
   U25 CM68 VSS_CM68 GENOA_SP5-SOCKET6096_13568-001,SMLF,IO,DGA^6000030    I15 @T6G_MB_LIB.T6G(SCH_1):PAGE32
   U25 CM71 VSS_CM71 GENOA_SP5-SOCKET6096_13568-001,SMLF,IO,DGA^6000030    I15 @T6G_MB_LIB.T6G(SCH_1):PAGE32
   U25 CM73 VSS_CM73 GENOA_SP5-SOCKET6096_13568-001,SMLF,IO,DGA^6000030    I15 @T6G_MB_LIB.T6G(SCH_1):PAGE32
   U25  CN1 VSS_CN1 GENOA_SP5-SOCKET6096_13568-001,SMLF,IO,DGA^6000030    I15 @T6G_MB_LIB.T6G(SCH_1):PAGE32
   U25  CN6 VSS_CN6 GENOA_SP5-SOCKET6096_13568-001,SMLF,IO,DGA^6000030    I15 @T6G_MB_LIB.T6G(SCH_1):PAGE32
   U25  CN8 VSS_CN8 GENOA_SP5-SOCKET6096_13568-001,SMLF,IO,DGA^6000030    I15 @T6G_MB_LIB.T6G(SCH_1):PAGE32
   U25 CN13 VSS_CN13 GENOA_SP5-SOCKET6096_13568-001,SMLF,IO,DGA^6000030    I15 @T6G_MB_LIB.T6G(SCH_1):PAGE32
   U25 CN15 VSS_CN15 GENOA_SP5-SOCKET6096_13568-001,SMLF,IO,DGA^6000030    I15 @T6G_MB_LIB.T6G(SCH_1):PAGE32
   U25 CN20 VSS_CN20 GENOA_SP5-SOCKET6096_13568-001,SMLF,IO,DGA^6000030    I15 @T6G_MB_LIB.T6G(SCH_1):PAGE32
   U25 CN22 VSS_CN22 GENOA_SP5-SOCKET6096_13568-001,SMLF,IO,DGA^6000030    I15 @T6G_MB_LIB.T6G(SCH_1):PAGE32
   U25 CN25 VSS_CN25 GENOA_SP5-SOCKET6096_13568-001,SMLF,IO,DGA^6000030    I15 @T6G_MB_LIB.T6G(SCH_1):PAGE32
   U25 CN28 VSS_CN28 GENOA_SP5-SOCKET6096_13568-001,SMLF,IO,DGA^6000030    I15 @T6G_MB_LIB.T6G(SCH_1):PAGE32
   U25 CN31 VSS_CN31 GENOA_SP5-SOCKET6096_13568-001,SMLF,IO,DGA^6000030    I15 @T6G_MB_LIB.T6G(SCH_1):PAGE32
   U25 CN34 VSS_CN34 GENOA_SP5-SOCKET6096_13568-001,SMLF,IO,DGA^6000030    I15 @T6G_MB_LIB.T6G(SCH_1):PAGE32
   U25 CN42 VSS_CN42 GENOA_SP5-SOCKET6096_13568-001,SMLF,IO,DGA^6000030    I15 @T6G_MB_LIB.T6G(SCH_1):PAGE32
   U25 CN45 VSS_CN45 GENOA_SP5-SOCKET6096_13568-001,SMLF,IO,DGA^6000030    I15 @T6G_MB_LIB.T6G(SCH_1):PAGE32
   U25 CN48 VSS_CN48 GENOA_SP5-SOCKET6096_13568-001,SMLF,IO,DGA^6000030    I15 @T6G_MB_LIB.T6G(SCH_1):PAGE32
   U25 CN51 VSS_CN51 GENOA_SP5-SOCKET6096_13568-001,SMLF,IO,DGA^6000030    I15 @T6G_MB_LIB.T6G(SCH_1):PAGE32
   U25 CN56 VSS_CN56 GENOA_SP5-SOCKET6096_13568-001,SMLF,IO,DGA^6000030    I15 @T6G_MB_LIB.T6G(SCH_1):PAGE32
   U25 CN61 VSS_CN61 GENOA_SP5-SOCKET6096_13568-001,SMLF,IO,DGA^6000030    I15 @T6G_MB_LIB.T6G(SCH_1):PAGE32
   U25 CN63 VSS_CN63 GENOA_SP5-SOCKET6096_13568-001,SMLF,IO,DGA^6000030    I15 @T6G_MB_LIB.T6G(SCH_1):PAGE32
   U25 CN68 VSS_CN68 GENOA_SP5-SOCKET6096_13568-001,SMLF,IO,DGA^6000030    I15 @T6G_MB_LIB.T6G(SCH_1):PAGE32
   U25 CN70 VSS_CN70 GENOA_SP5-SOCKET6096_13568-001,SMLF,IO,DGA^6000030    I15 @T6G_MB_LIB.T6G(SCH_1):PAGE32
   U25 CN75 VSS_CN75 GENOA_SP5-SOCKET6096_13568-001,SMLF,IO,DGA^6000030    I15 @T6G_MB_LIB.T6G(SCH_1):PAGE32
   U25  CP3 VSS_CP3 GENOA_SP5-SOCKET6096_13568-001,SMLF,IO,DGA^6000030    I15 @T6G_MB_LIB.T6G(SCH_1):PAGE32
   U25  CP5 VSS_CP5 GENOA_SP5-SOCKET6096_13568-001,SMLF,IO,DGA^6000030    I15 @T6G_MB_LIB.T6G(SCH_1):PAGE32
   U25  CP8 VSS_CP8 GENOA_SP5-SOCKET6096_13568-001,SMLF,IO,DGA^6000030    I15 @T6G_MB_LIB.T6G(SCH_1):PAGE32
   U25 CP10 VSS_CP10 GENOA_SP5-SOCKET6096_13568-001,SMLF,IO,DGA^6000030    I15 @T6G_MB_LIB.T6G(SCH_1):PAGE32
   U25 CP12 VSS_CP12 GENOA_SP5-SOCKET6096_13568-001,SMLF,IO,DGA^6000030    I15 @T6G_MB_LIB.T6G(SCH_1):PAGE32
   U25 CP15 VSS_CP15 GENOA_SP5-SOCKET6096_13568-001,SMLF,IO,DGA^6000030    I15 @T6G_MB_LIB.T6G(SCH_1):PAGE32
   U25 CP17 VSS_CP17 GENOA_SP5-SOCKET6096_13568-001,SMLF,IO,DGA^6000030    I15 @T6G_MB_LIB.T6G(SCH_1):PAGE32
   U25 CP19 VSS_CP19 GENOA_SP5-SOCKET6096_13568-001,SMLF,IO,DGA^6000030    I15 @T6G_MB_LIB.T6G(SCH_1):PAGE32
   U25 CP22 VSS_CP22 GENOA_SP5-SOCKET6096_13568-001,SMLF,IO,DGA^6000030    I16 @T6G_MB_LIB.T6G(SCH_1):PAGE32
   U25 CP25 VSS_CP25 GENOA_SP5-SOCKET6096_13568-001,SMLF,IO,DGA^6000030    I16 @T6G_MB_LIB.T6G(SCH_1):PAGE32
   U25 CP28 VSS_CP28 GENOA_SP5-SOCKET6096_13568-001,SMLF,IO,DGA^6000030    I16 @T6G_MB_LIB.T6G(SCH_1):PAGE32
   U25 CP31 VSS_CP31 GENOA_SP5-SOCKET6096_13568-001,SMLF,IO,DGA^6000030    I16 @T6G_MB_LIB.T6G(SCH_1):PAGE32
   U25 CP34 VSS_CP34 GENOA_SP5-SOCKET6096_13568-001,SMLF,IO,DGA^6000030    I16 @T6G_MB_LIB.T6G(SCH_1):PAGE32
   U25 CP37 VSS_CP37 GENOA_SP5-SOCKET6096_13568-001,SMLF,IO,DGA^6000030    I16 @T6G_MB_LIB.T6G(SCH_1):PAGE32
   U25 CP39 VSS_CP39 GENOA_SP5-SOCKET6096_13568-001,SMLF,IO,DGA^6000030    I16 @T6G_MB_LIB.T6G(SCH_1):PAGE32
   U25 CP42 VSS_CP42 GENOA_SP5-SOCKET6096_13568-001,SMLF,IO,DGA^6000030    I16 @T6G_MB_LIB.T6G(SCH_1):PAGE32
   U25 CP45 VSS_CP45 GENOA_SP5-SOCKET6096_13568-001,SMLF,IO,DGA^6000030    I16 @T6G_MB_LIB.T6G(SCH_1):PAGE32
   U25 CP48 VSS_CP48 GENOA_SP5-SOCKET6096_13568-001,SMLF,IO,DGA^6000030    I16 @T6G_MB_LIB.T6G(SCH_1):PAGE32
   U25 CP51 VSS_CP51 GENOA_SP5-SOCKET6096_13568-001,SMLF,IO,DGA^6000030    I16 @T6G_MB_LIB.T6G(SCH_1):PAGE32
   U25 CP54 VSS_CP54 GENOA_SP5-SOCKET6096_13568-001,SMLF,IO,DGA^6000030    I16 @T6G_MB_LIB.T6G(SCH_1):PAGE32
   U25 CP57 VSS_CP57 GENOA_SP5-SOCKET6096_13568-001,SMLF,IO,DGA^6000030    I16 @T6G_MB_LIB.T6G(SCH_1):PAGE32
   U25 CP59 VSS_CP59 GENOA_SP5-SOCKET6096_13568-001,SMLF,IO,DGA^6000030    I16 @T6G_MB_LIB.T6G(SCH_1):PAGE32
   U25 CP61 VSS_CP61 GENOA_SP5-SOCKET6096_13568-001,SMLF,IO,DGA^6000030    I16 @T6G_MB_LIB.T6G(SCH_1):PAGE32
   U25 CP64 VSS_CP64 GENOA_SP5-SOCKET6096_13568-001,SMLF,IO,DGA^6000030    I16 @T6G_MB_LIB.T6G(SCH_1):PAGE32
   U25 CP66 VSS_CP66 GENOA_SP5-SOCKET6096_13568-001,SMLF,IO,DGA^6000030    I16 @T6G_MB_LIB.T6G(SCH_1):PAGE32
   U25 CP68 VSS_CP68 GENOA_SP5-SOCKET6096_13568-001,SMLF,IO,DGA^6000030    I16 @T6G_MB_LIB.T6G(SCH_1):PAGE32
   U25 CP71 VSS_CP71 GENOA_SP5-SOCKET6096_13568-001,SMLF,IO,DGA^6000030    I16 @T6G_MB_LIB.T6G(SCH_1):PAGE32
   U25 CP73 VSS_CP73 GENOA_SP5-SOCKET6096_13568-001,SMLF,IO,DGA^6000030    I16 @T6G_MB_LIB.T6G(SCH_1):PAGE32
   U25  CR1 VSS_CR1 GENOA_SP5-SOCKET6096_13568-001,SMLF,IO,DGA^6000030    I16 @T6G_MB_LIB.T6G(SCH_1):PAGE32
   U25  CR4 VSS_CR4 GENOA_SP5-SOCKET6096_13568-001,SMLF,IO,DGA^6000030    I16 @T6G_MB_LIB.T6G(SCH_1):PAGE32
   U25  CR6 VSS_CR6 GENOA_SP5-SOCKET6096_13568-001,SMLF,IO,DGA^6000030    I16 @T6G_MB_LIB.T6G(SCH_1):PAGE32
   U25  CR8 VSS_CR8 GENOA_SP5-SOCKET6096_13568-001,SMLF,IO,DGA^6000030    I16 @T6G_MB_LIB.T6G(SCH_1):PAGE32
   U25 CR11 VSS_CR11 GENOA_SP5-SOCKET6096_13568-001,SMLF,IO,DGA^6000030    I16 @T6G_MB_LIB.T6G(SCH_1):PAGE32
   U25 CR13 VSS_CR13 GENOA_SP5-SOCKET6096_13568-001,SMLF,IO,DGA^6000030    I16 @T6G_MB_LIB.T6G(SCH_1):PAGE32
   U25 CR15 VSS_CR15 GENOA_SP5-SOCKET6096_13568-001,SMLF,IO,DGA^6000030    I16 @T6G_MB_LIB.T6G(SCH_1):PAGE32
   U25 CR18 VSS_CR18 GENOA_SP5-SOCKET6096_13568-001,SMLF,IO,DGA^6000030    I16 @T6G_MB_LIB.T6G(SCH_1):PAGE32
   U25 CR20 VSS_CR20 GENOA_SP5-SOCKET6096_13568-001,SMLF,IO,DGA^6000030    I16 @T6G_MB_LIB.T6G(SCH_1):PAGE32
   U25 CR22 VSS_CR22 GENOA_SP5-SOCKET6096_13568-001,SMLF,IO,DGA^6000030    I16 @T6G_MB_LIB.T6G(SCH_1):PAGE32
   U25 CR25 VSS_CR25 GENOA_SP5-SOCKET6096_13568-001,SMLF,IO,DGA^6000030    I16 @T6G_MB_LIB.T6G(SCH_1):PAGE32
   U25 CR28 VSS_CR28 GENOA_SP5-SOCKET6096_13568-001,SMLF,IO,DGA^6000030    I16 @T6G_MB_LIB.T6G(SCH_1):PAGE32
   U25 CR31 VSS_CR31 GENOA_SP5-SOCKET6096_13568-001,SMLF,IO,DGA^6000030    I16 @T6G_MB_LIB.T6G(SCH_1):PAGE32
   U25 CR34 VSS_CR34 GENOA_SP5-SOCKET6096_13568-001,SMLF,IO,DGA^6000030    I16 @T6G_MB_LIB.T6G(SCH_1):PAGE32
   U25 CR35 VSS_CR35 GENOA_SP5-SOCKET6096_13568-001,SMLF,IO,DGA^6000030    I16 @T6G_MB_LIB.T6G(SCH_1):PAGE32
   U25 CR36 VSS_CR36 GENOA_SP5-SOCKET6096_13568-001,SMLF,IO,DGA^6000030    I16 @T6G_MB_LIB.T6G(SCH_1):PAGE32
   U25 CR40 VSS_CR40 GENOA_SP5-SOCKET6096_13568-001,SMLF,IO,DGA^6000030    I16 @T6G_MB_LIB.T6G(SCH_1):PAGE32
   U25 CR41 VSS_CR41 GENOA_SP5-SOCKET6096_13568-001,SMLF,IO,DGA^6000030    I16 @T6G_MB_LIB.T6G(SCH_1):PAGE32
   U25 CR42 VSS_CR42 GENOA_SP5-SOCKET6096_13568-001,SMLF,IO,DGA^6000030    I16 @T6G_MB_LIB.T6G(SCH_1):PAGE32
   U25 CR45 VSS_CR45 GENOA_SP5-SOCKET6096_13568-001,SMLF,IO,DGA^6000030    I16 @T6G_MB_LIB.T6G(SCH_1):PAGE32
   U25 CR48 VSS_CR48 GENOA_SP5-SOCKET6096_13568-001,SMLF,IO,DGA^6000030    I16 @T6G_MB_LIB.T6G(SCH_1):PAGE32
   U25 CR51 VSS_CR51 GENOA_SP5-SOCKET6096_13568-001,SMLF,IO,DGA^6000030    I16 @T6G_MB_LIB.T6G(SCH_1):PAGE32
   U25 CR54 VSS_CR54 GENOA_SP5-SOCKET6096_13568-001,SMLF,IO,DGA^6000030    I16 @T6G_MB_LIB.T6G(SCH_1):PAGE32
   U25 CR56 VSS_CR56 GENOA_SP5-SOCKET6096_13568-001,SMLF,IO,DGA^6000030    I16 @T6G_MB_LIB.T6G(SCH_1):PAGE32
   U25 CR58 VSS_CR58 GENOA_SP5-SOCKET6096_13568-001,SMLF,IO,DGA^6000030    I16 @T6G_MB_LIB.T6G(SCH_1):PAGE32
   U25 CR61 VSS_CR61 GENOA_SP5-SOCKET6096_13568-001,SMLF,IO,DGA^6000030    I16 @T6G_MB_LIB.T6G(SCH_1):PAGE32
   U25 CR63 VSS_CR63 GENOA_SP5-SOCKET6096_13568-001,SMLF,IO,DGA^6000030    I16 @T6G_MB_LIB.T6G(SCH_1):PAGE32
   U25 CR65 VSS_CR65 GENOA_SP5-SOCKET6096_13568-001,SMLF,IO,DGA^6000030    I16 @T6G_MB_LIB.T6G(SCH_1):PAGE32
   U25 CR68 VSS_CR68 GENOA_SP5-SOCKET6096_13568-001,SMLF,IO,DGA^6000030    I16 @T6G_MB_LIB.T6G(SCH_1):PAGE32
   U25 CR70 VSS_CR70 GENOA_SP5-SOCKET6096_13568-001,SMLF,IO,DGA^6000030    I16 @T6G_MB_LIB.T6G(SCH_1):PAGE32
   U25 CR72 VSS_CR72 GENOA_SP5-SOCKET6096_13568-001,SMLF,IO,DGA^6000030    I16 @T6G_MB_LIB.T6G(SCH_1):PAGE32
   U25 CR75 VSS_CR75 GENOA_SP5-SOCKET6096_13568-001,SMLF,IO,DGA^6000030    I16 @T6G_MB_LIB.T6G(SCH_1):PAGE32
   U25  CT3 VSS_CT3 GENOA_SP5-SOCKET6096_13568-001,SMLF,IO,DGA^6000030    I16 @T6G_MB_LIB.T6G(SCH_1):PAGE32
   U25  CT8 VSS_CT8 GENOA_SP5-SOCKET6096_13568-001,SMLF,IO,DGA^6000030    I16 @T6G_MB_LIB.T6G(SCH_1):PAGE32
   U25 CT10 VSS_CT10 GENOA_SP5-SOCKET6096_13568-001,SMLF,IO,DGA^6000030    I16 @T6G_MB_LIB.T6G(SCH_1):PAGE32
   U25 CT15 VSS_CT15 GENOA_SP5-SOCKET6096_13568-001,SMLF,IO,DGA^6000030    I16 @T6G_MB_LIB.T6G(SCH_1):PAGE32
   U25 CT17 VSS_CT17 GENOA_SP5-SOCKET6096_13568-001,SMLF,IO,DGA^6000030    I16 @T6G_MB_LIB.T6G(SCH_1):PAGE32
   U25 CT23 VSS_CT23 GENOA_SP5-SOCKET6096_13568-001,SMLF,IO,DGA^6000030    I16 @T6G_MB_LIB.T6G(SCH_1):PAGE32
   U25 CT24 VSS_CT24 GENOA_SP5-SOCKET6096_13568-001,SMLF,IO,DGA^6000030    I16 @T6G_MB_LIB.T6G(SCH_1):PAGE32
   U25 CT25 VSS_CT25 GENOA_SP5-SOCKET6096_13568-001,SMLF,IO,DGA^6000030    I16 @T6G_MB_LIB.T6G(SCH_1):PAGE32
   U25 CT26 VSS_CT26 GENOA_SP5-SOCKET6096_13568-001,SMLF,IO,DGA^6000030    I16 @T6G_MB_LIB.T6G(SCH_1):PAGE32
   U25 CT27 VSS_CT27 GENOA_SP5-SOCKET6096_13568-001,SMLF,IO,DGA^6000030    I16 @T6G_MB_LIB.T6G(SCH_1):PAGE32
   U25 CT28 VSS_CT28 GENOA_SP5-SOCKET6096_13568-001,SMLF,IO,DGA^6000030    I16 @T6G_MB_LIB.T6G(SCH_1):PAGE32
   U25 CT29 VSS_CT29 GENOA_SP5-SOCKET6096_13568-001,SMLF,IO,DGA^6000030    I16 @T6G_MB_LIB.T6G(SCH_1):PAGE32
   U25 CT30 VSS_CT30 GENOA_SP5-SOCKET6096_13568-001,SMLF,IO,DGA^6000030    I16 @T6G_MB_LIB.T6G(SCH_1):PAGE32
   U25 CT31 VSS_CT31 GENOA_SP5-SOCKET6096_13568-001,SMLF,IO,DGA^6000030    I16 @T6G_MB_LIB.T6G(SCH_1):PAGE32
   U25 CT32 VSS_CT32 GENOA_SP5-SOCKET6096_13568-001,SMLF,IO,DGA^6000030    I16 @T6G_MB_LIB.T6G(SCH_1):PAGE32
   U25 CT33 VSS_CT33 GENOA_SP5-SOCKET6096_13568-001,SMLF,IO,DGA^6000030    I16 @T6G_MB_LIB.T6G(SCH_1):PAGE32
   U25 CT34 VSS_CT34 GENOA_SP5-SOCKET6096_13568-001,SMLF,IO,DGA^6000030    I16 @T6G_MB_LIB.T6G(SCH_1):PAGE32
   U25 CT37 VSS_CT37 GENOA_SP5-SOCKET6096_13568-001,SMLF,IO,DGA^6000030    I16 @T6G_MB_LIB.T6G(SCH_1):PAGE32
   U25 CT39 VSS_CT39 GENOA_SP5-SOCKET6096_13568-001,SMLF,IO,DGA^6000030    I16 @T6G_MB_LIB.T6G(SCH_1):PAGE32
   U25 CT42 VSS_CT42 GENOA_SP5-SOCKET6096_13568-001,SMLF,IO,DGA^6000030    I16 @T6G_MB_LIB.T6G(SCH_1):PAGE32
   U25 CT43 VSS_CT43 GENOA_SP5-SOCKET6096_13568-001,SMLF,IO,DGA^6000030    I16 @T6G_MB_LIB.T6G(SCH_1):PAGE32
   U25 CT44 VSS_CT44 GENOA_SP5-SOCKET6096_13568-001,SMLF,IO,DGA^6000030    I16 @T6G_MB_LIB.T6G(SCH_1):PAGE32
   U25 CT45 VSS_CT45 GENOA_SP5-SOCKET6096_13568-001,SMLF,IO,DGA^6000030    I16 @T6G_MB_LIB.T6G(SCH_1):PAGE32
   U25 CT46 VSS_CT46 GENOA_SP5-SOCKET6096_13568-001,SMLF,IO,DGA^6000030    I16 @T6G_MB_LIB.T6G(SCH_1):PAGE32
   U25 CT47 VSS_CT47 GENOA_SP5-SOCKET6096_13568-001,SMLF,IO,DGA^6000030    I16 @T6G_MB_LIB.T6G(SCH_1):PAGE32
   U25 CT48 VSS_CT48 GENOA_SP5-SOCKET6096_13568-001,SMLF,IO,DGA^6000030    I16 @T6G_MB_LIB.T6G(SCH_1):PAGE32
   U25 CT49 VSS_CT49 GENOA_SP5-SOCKET6096_13568-001,SMLF,IO,DGA^6000030    I16 @T6G_MB_LIB.T6G(SCH_1):PAGE32
   U25 CT50 VSS_CT50 GENOA_SP5-SOCKET6096_13568-001,SMLF,IO,DGA^6000030    I16 @T6G_MB_LIB.T6G(SCH_1):PAGE32
   U25 CT51 VSS_CT51 GENOA_SP5-SOCKET6096_13568-001,SMLF,IO,DGA^6000030    I16 @T6G_MB_LIB.T6G(SCH_1):PAGE32
   U25 CT53 VSS_CT53 GENOA_SP5-SOCKET6096_13568-001,SMLF,IO,DGA^6000030    I16 @T6G_MB_LIB.T6G(SCH_1):PAGE32
   U25 CT59 VSS_CT59 GENOA_SP5-SOCKET6096_13568-001,SMLF,IO,DGA^6000030    I16 @T6G_MB_LIB.T6G(SCH_1):PAGE32
   U25 CT61 VSS_CT61 GENOA_SP5-SOCKET6096_13568-001,SMLF,IO,DGA^6000030    I16 @T6G_MB_LIB.T6G(SCH_1):PAGE32
   U25 CT66 VSS_CT66 GENOA_SP5-SOCKET6096_13568-001,SMLF,IO,DGA^6000030    I16 @T6G_MB_LIB.T6G(SCH_1):PAGE32
   U25 CT68 VSS_CT68 GENOA_SP5-SOCKET6096_13568-001,SMLF,IO,DGA^6000030    I16 @T6G_MB_LIB.T6G(SCH_1):PAGE32
   U25 CT73 VSS_CT73 GENOA_SP5-SOCKET6096_13568-001,SMLF,IO,DGA^6000030    I16 @T6G_MB_LIB.T6G(SCH_1):PAGE32
   U25  CU1 VSS_CU1 GENOA_SP5-SOCKET6096_13568-001,SMLF,IO,DGA^6000030    I16 @T6G_MB_LIB.T6G(SCH_1):PAGE32
   U25  CU4 VSS_CU4 GENOA_SP5-SOCKET6096_13568-001,SMLF,IO,DGA^6000030    I16 @T6G_MB_LIB.T6G(SCH_1):PAGE32
   U25  CU6 VSS_CU6 GENOA_SP5-SOCKET6096_13568-001,SMLF,IO,DGA^6000030    I16 @T6G_MB_LIB.T6G(SCH_1):PAGE32
   U25  CU8 VSS_CU8 GENOA_SP5-SOCKET6096_13568-001,SMLF,IO,DGA^6000030    I16 @T6G_MB_LIB.T6G(SCH_1):PAGE32
   U25 CU11 VSS_CU11 GENOA_SP5-SOCKET6096_13568-001,SMLF,IO,DGA^6000030    I16 @T6G_MB_LIB.T6G(SCH_1):PAGE32
   U25 CU13 VSS_CU13 GENOA_SP5-SOCKET6096_13568-001,SMLF,IO,DGA^6000030    I16 @T6G_MB_LIB.T6G(SCH_1):PAGE32
   U25 CU15 VSS_CU15 GENOA_SP5-SOCKET6096_13568-001,SMLF,IO,DGA^6000030    I16 @T6G_MB_LIB.T6G(SCH_1):PAGE32
   U25 CU18 VSS_CU18 GENOA_SP5-SOCKET6096_13568-001,SMLF,IO,DGA^6000030    I16 @T6G_MB_LIB.T6G(SCH_1):PAGE32
   U25 CU20 VSS_CU20 GENOA_SP5-SOCKET6096_13568-001,SMLF,IO,DGA^6000030    I16 @T6G_MB_LIB.T6G(SCH_1):PAGE32
   U25 CU22 VSS_CU22 GENOA_SP5-SOCKET6096_13568-001,SMLF,IO,DGA^6000030    I16 @T6G_MB_LIB.T6G(SCH_1):PAGE32
   U25 CU25 VSS_CU25 GENOA_SP5-SOCKET6096_13568-001,SMLF,IO,DGA^6000030    I16 @T6G_MB_LIB.T6G(SCH_1):PAGE32
   U25 CU28 VSS_CU28 GENOA_SP5-SOCKET6096_13568-001,SMLF,IO,DGA^6000030    I16 @T6G_MB_LIB.T6G(SCH_1):PAGE32
   U25 CU31 VSS_CU31 GENOA_SP5-SOCKET6096_13568-001,SMLF,IO,DGA^6000030    I16 @T6G_MB_LIB.T6G(SCH_1):PAGE32
   U25 CU34 VSS_CU34 GENOA_SP5-SOCKET6096_13568-001,SMLF,IO,DGA^6000030    I16 @T6G_MB_LIB.T6G(SCH_1):PAGE32
   U25 CU42 VSS_CU42 GENOA_SP5-SOCKET6096_13568-001,SMLF,IO,DGA^6000030    I16 @T6G_MB_LIB.T6G(SCH_1):PAGE32
   U25 CU45 VSS_CU45 GENOA_SP5-SOCKET6096_13568-001,SMLF,IO,DGA^6000030    I16 @T6G_MB_LIB.T6G(SCH_1):PAGE32
   U25 CU48 VSS_CU48 GENOA_SP5-SOCKET6096_13568-001,SMLF,IO,DGA^6000030    I16 @T6G_MB_LIB.T6G(SCH_1):PAGE32
   U25 CU51 VSS_CU51 GENOA_SP5-SOCKET6096_13568-001,SMLF,IO,DGA^6000030    I16 @T6G_MB_LIB.T6G(SCH_1):PAGE32
   U25 CU54 VSS_CU54 GENOA_SP5-SOCKET6096_13568-001,SMLF,IO,DGA^6000030    I16 @T6G_MB_LIB.T6G(SCH_1):PAGE32
   U25 CU56 VSS_CU56 GENOA_SP5-SOCKET6096_13568-001,SMLF,IO,DGA^6000030    I16 @T6G_MB_LIB.T6G(SCH_1):PAGE32
   U25 CU61 VSS_CU61 GENOA_SP5-SOCKET6096_13568-001,SMLF,IO,DGA^6000030    I16 @T6G_MB_LIB.T6G(SCH_1):PAGE32
   U25 CU63 VSS_CU63 GENOA_SP5-SOCKET6096_13568-001,SMLF,IO,DGA^6000030    I16 @T6G_MB_LIB.T6G(SCH_1):PAGE32
   U25 CU65 VSS_CU65 GENOA_SP5-SOCKET6096_13568-001,SMLF,IO,DGA^6000030    I16 @T6G_MB_LIB.T6G(SCH_1):PAGE32
   U25 CU68 VSS_CU68 GENOA_SP5-SOCKET6096_13568-001,SMLF,IO,DGA^6000030    I16 @T6G_MB_LIB.T6G(SCH_1):PAGE32
   U25 CU70 VSS_CU70 GENOA_SP5-SOCKET6096_13568-001,SMLF,IO,DGA^6000030    I16 @T6G_MB_LIB.T6G(SCH_1):PAGE32
   U25 CU72 VSS_CU72 GENOA_SP5-SOCKET6096_13568-001,SMLF,IO,DGA^6000030    I16 @T6G_MB_LIB.T6G(SCH_1):PAGE32
   U25 CU75 VSS_CU75 GENOA_SP5-SOCKET6096_13568-001,SMLF,IO,DGA^6000030    I16 @T6G_MB_LIB.T6G(SCH_1):PAGE32
   U25  CV3 VSS_CV3 GENOA_SP5-SOCKET6096_13568-001,SMLF,IO,DGA^6000030    I16 @T6G_MB_LIB.T6G(SCH_1):PAGE32
   U25  CV5 VSS_CV5 GENOA_SP5-SOCKET6096_13568-001,SMLF,IO,DGA^6000030    I16 @T6G_MB_LIB.T6G(SCH_1):PAGE32
   U25  CV8 VSS_CV8 GENOA_SP5-SOCKET6096_13568-001,SMLF,IO,DGA^6000030    I16 @T6G_MB_LIB.T6G(SCH_1):PAGE32
   U25 CV10 VSS_CV10 GENOA_SP5-SOCKET6096_13568-001,SMLF,IO,DGA^6000030    I16 @T6G_MB_LIB.T6G(SCH_1):PAGE32
   U25 CV12 VSS_CV12 GENOA_SP5-SOCKET6096_13568-001,SMLF,IO,DGA^6000030    I16 @T6G_MB_LIB.T6G(SCH_1):PAGE32
   U25 CV15 VSS_CV15 GENOA_SP5-SOCKET6096_13568-001,SMLF,IO,DGA^6000030    I16 @T6G_MB_LIB.T6G(SCH_1):PAGE32
   U25 CV17 VSS_CV17 GENOA_SP5-SOCKET6096_13568-001,SMLF,IO,DGA^6000030    I16 @T6G_MB_LIB.T6G(SCH_1):PAGE32
   U25 CV19 VSS_CV19 GENOA_SP5-SOCKET6096_13568-001,SMLF,IO,DGA^6000030    I16 @T6G_MB_LIB.T6G(SCH_1):PAGE32
   U25 CV22 VSS_CV22 GENOA_SP5-SOCKET6096_13568-001,SMLF,IO,DGA^6000030    I16 @T6G_MB_LIB.T6G(SCH_1):PAGE32
   U25 CV25 VSS_CV25 GENOA_SP5-SOCKET6096_13568-001,SMLF,IO,DGA^6000030    I16 @T6G_MB_LIB.T6G(SCH_1):PAGE32
   U25 CV28 VSS_CV28 GENOA_SP5-SOCKET6096_13568-001,SMLF,IO,DGA^6000030    I16 @T6G_MB_LIB.T6G(SCH_1):PAGE32
   U25 CV31 VSS_CV31 GENOA_SP5-SOCKET6096_13568-001,SMLF,IO,DGA^6000030    I16 @T6G_MB_LIB.T6G(SCH_1):PAGE32
   U25 CV34 VSS_CV34 GENOA_SP5-SOCKET6096_13568-001,SMLF,IO,DGA^6000030    I16 @T6G_MB_LIB.T6G(SCH_1):PAGE32
   U25 CV37 VSS_CV37 GENOA_SP5-SOCKET6096_13568-001,SMLF,IO,DGA^6000030    I16 @T6G_MB_LIB.T6G(SCH_1):PAGE32
   U25 CV39 VSS_CV39 GENOA_SP5-SOCKET6096_13568-001,SMLF,IO,DGA^6000030    I16 @T6G_MB_LIB.T6G(SCH_1):PAGE32
   U25 CV42 VSS_CV42 GENOA_SP5-SOCKET6096_13568-001,SMLF,IO,DGA^6000030    I16 @T6G_MB_LIB.T6G(SCH_1):PAGE32
   U25 CV45 VSS_CV45 GENOA_SP5-SOCKET6096_13568-001,SMLF,IO,DGA^6000030    I16 @T6G_MB_LIB.T6G(SCH_1):PAGE32
   U25 CV48 VSS_CV48 GENOA_SP5-SOCKET6096_13568-001,SMLF,IO,DGA^6000030    I16 @T6G_MB_LIB.T6G(SCH_1):PAGE32
   U25 CV51 VSS_CV51 GENOA_SP5-SOCKET6096_13568-001,SMLF,IO,DGA^6000030    I16 @T6G_MB_LIB.T6G(SCH_1):PAGE32
   U25 CV54 VSS_CV54 GENOA_SP5-SOCKET6096_13568-001,SMLF,IO,DGA^6000030    I16 @T6G_MB_LIB.T6G(SCH_1):PAGE32
   U25 CV57 VSS_CV57 GENOA_SP5-SOCKET6096_13568-001,SMLF,IO,DGA^6000030    I16 @T6G_MB_LIB.T6G(SCH_1):PAGE32
   U25 CV59 VSS_CV59 GENOA_SP5-SOCKET6096_13568-001,SMLF,IO,DGA^6000030    I16 @T6G_MB_LIB.T6G(SCH_1):PAGE32
   U25 CV61 VSS_CV61 GENOA_SP5-SOCKET6096_13568-001,SMLF,IO,DGA^6000030    I16 @T6G_MB_LIB.T6G(SCH_1):PAGE32
   U25 CV64 VSS_CV64 GENOA_SP5-SOCKET6096_13568-001,SMLF,IO,DGA^6000030    I16 @T6G_MB_LIB.T6G(SCH_1):PAGE32
   U25 CV66 VSS_CV66 GENOA_SP5-SOCKET6096_13568-001,SMLF,IO,DGA^6000030    I16 @T6G_MB_LIB.T6G(SCH_1):PAGE32
   U25 CV68 VSS_CV68 GENOA_SP5-SOCKET6096_13568-001,SMLF,IO,DGA^6000030    I16 @T6G_MB_LIB.T6G(SCH_1):PAGE32
   U25 CV71 VSS_CV71 GENOA_SP5-SOCKET6096_13568-001,SMLF,IO,DGA^6000030    I16 @T6G_MB_LIB.T6G(SCH_1):PAGE32
   U25 CV73 VSS_CV73 GENOA_SP5-SOCKET6096_13568-001,SMLF,IO,DGA^6000030    I16 @T6G_MB_LIB.T6G(SCH_1):PAGE32
   U25  CW1 VSS_CW1 GENOA_SP5-SOCKET6096_13568-001,SMLF,IO,DGA^6000030    I16 @T6G_MB_LIB.T6G(SCH_1):PAGE32
   U25  CW6 VSS_CW6 GENOA_SP5-SOCKET6096_13568-001,SMLF,IO,DGA^6000030    I16 @T6G_MB_LIB.T6G(SCH_1):PAGE32
   U25  CW8 VSS_CW8 GENOA_SP5-SOCKET6096_13568-001,SMLF,IO,DGA^6000030    I16 @T6G_MB_LIB.T6G(SCH_1):PAGE32
   U25 CW13 VSS_CW13 GENOA_SP5-SOCKET6096_13568-001,SMLF,IO,DGA^6000030    I16 @T6G_MB_LIB.T6G(SCH_1):PAGE32
   U25 CW15 VSS_CW15 GENOA_SP5-SOCKET6096_13568-001,SMLF,IO,DGA^6000030    I16 @T6G_MB_LIB.T6G(SCH_1):PAGE32
   U25 CW20 VSS_CW20 GENOA_SP5-SOCKET6096_13568-001,SMLF,IO,DGA^6000030    I16 @T6G_MB_LIB.T6G(SCH_1):PAGE32
   U25 CW22 VSS_CW22 GENOA_SP5-SOCKET6096_13568-001,SMLF,IO,DGA^6000030    I16 @T6G_MB_LIB.T6G(SCH_1):PAGE32
   U25 CW25 VSS_CW25 GENOA_SP5-SOCKET6096_13568-001,SMLF,IO,DGA^6000030    I16 @T6G_MB_LIB.T6G(SCH_1):PAGE32
   U25 CW28 VSS_CW28 GENOA_SP5-SOCKET6096_13568-001,SMLF,IO,DGA^6000030    I16 @T6G_MB_LIB.T6G(SCH_1):PAGE32
   U25 CW31 VSS_CW31 GENOA_SP5-SOCKET6096_13568-001,SMLF,IO,DGA^6000030    I16 @T6G_MB_LIB.T6G(SCH_1):PAGE32
   U25 CW34 VSS_CW34 GENOA_SP5-SOCKET6096_13568-001,SMLF,IO,DGA^6000030    I16 @T6G_MB_LIB.T6G(SCH_1):PAGE32
   U25 CW35 VSS_CW35 GENOA_SP5-SOCKET6096_13568-001,SMLF,IO,DGA^6000030    I16 @T6G_MB_LIB.T6G(SCH_1):PAGE32
   U25 CW36 VSS_CW36 GENOA_SP5-SOCKET6096_13568-001,SMLF,IO,DGA^6000030    I16 @T6G_MB_LIB.T6G(SCH_1):PAGE32
   U25 CW40 VSS_CW40 GENOA_SP5-SOCKET6096_13568-001,SMLF,IO,DGA^6000030    I16 @T6G_MB_LIB.T6G(SCH_1):PAGE32
   U25 CW41 VSS_CW41 GENOA_SP5-SOCKET6096_13568-001,SMLF,IO,DGA^6000030    I16 @T6G_MB_LIB.T6G(SCH_1):PAGE32
   U25 CW42 VSS_CW42 GENOA_SP5-SOCKET6096_13568-001,SMLF,IO,DGA^6000030    I16 @T6G_MB_LIB.T6G(SCH_1):PAGE32
   U25 CW45 VSS_CW45 GENOA_SP5-SOCKET6096_13568-001,SMLF,IO,DGA^6000030    I16 @T6G_MB_LIB.T6G(SCH_1):PAGE32
   U25 CW48 VSS_CW48 GENOA_SP5-SOCKET6096_13568-001,SMLF,IO,DGA^6000030    I16 @T6G_MB_LIB.T6G(SCH_1):PAGE32
   U25 CW51 VSS_CW51 GENOA_SP5-SOCKET6096_13568-001,SMLF,IO,DGA^6000030    I16 @T6G_MB_LIB.T6G(SCH_1):PAGE32
   U25 CW54 VSS_CW54 GENOA_SP5-SOCKET6096_13568-001,SMLF,IO,DGA^6000030    I16 @T6G_MB_LIB.T6G(SCH_1):PAGE32
   U25 CW56 VSS_CW56 GENOA_SP5-SOCKET6096_13568-001,SMLF,IO,DGA^6000030    I16 @T6G_MB_LIB.T6G(SCH_1):PAGE32
   U25 CW61 VSS_CW61 GENOA_SP5-SOCKET6096_13568-001,SMLF,IO,DGA^6000030    I16 @T6G_MB_LIB.T6G(SCH_1):PAGE32
   U25 CW63 VSS_CW63 GENOA_SP5-SOCKET6096_13568-001,SMLF,IO,DGA^6000030    I16 @T6G_MB_LIB.T6G(SCH_1):PAGE32
   U25 CW68 VSS_CW68 GENOA_SP5-SOCKET6096_13568-001,SMLF,IO,DGA^6000030    I16 @T6G_MB_LIB.T6G(SCH_1):PAGE32
   U25 CW70 VSS_CW70 GENOA_SP5-SOCKET6096_13568-001,SMLF,IO,DGA^6000030    I16 @T6G_MB_LIB.T6G(SCH_1):PAGE32
   U25 CW75 VSS_CW75 GENOA_SP5-SOCKET6096_13568-001,SMLF,IO,DGA^6000030    I16 @T6G_MB_LIB.T6G(SCH_1):PAGE32
   U25  CY3 VSS_CY3 GENOA_SP5-SOCKET6096_13568-001,SMLF,IO,DGA^6000030    I16 @T6G_MB_LIB.T6G(SCH_1):PAGE32
   U25  CY5 VSS_CY5 GENOA_SP5-SOCKET6096_13568-001,SMLF,IO,DGA^6000030    I16 @T6G_MB_LIB.T6G(SCH_1):PAGE32
   U25  CY8 VSS_CY8 GENOA_SP5-SOCKET6096_13568-001,SMLF,IO,DGA^6000030    I16 @T6G_MB_LIB.T6G(SCH_1):PAGE32
   U25 CY10 VSS_CY10 GENOA_SP5-SOCKET6096_13568-001,SMLF,IO,DGA^6000030    I16 @T6G_MB_LIB.T6G(SCH_1):PAGE32
   U25 CY12 VSS_CY12 GENOA_SP5-SOCKET6096_13568-001,SMLF,IO,DGA^6000030    I16 @T6G_MB_LIB.T6G(SCH_1):PAGE32
   U25 CY15 VSS_CY15 GENOA_SP5-SOCKET6096_13568-001,SMLF,IO,DGA^6000030    I16 @T6G_MB_LIB.T6G(SCH_1):PAGE32
   U25 CY17 VSS_CY17 GENOA_SP5-SOCKET6096_13568-001,SMLF,IO,DGA^6000030    I16 @T6G_MB_LIB.T6G(SCH_1):PAGE32
   U25 CY19 VSS_CY19 GENOA_SP5-SOCKET6096_13568-001,SMLF,IO,DGA^6000030    I16 @T6G_MB_LIB.T6G(SCH_1):PAGE32
   U25 CY23 VSS_CY23 GENOA_SP5-SOCKET6096_13568-001,SMLF,IO,DGA^6000030    I16 @T6G_MB_LIB.T6G(SCH_1):PAGE32
   U25 CY24 VSS_CY24 GENOA_SP5-SOCKET6096_13568-001,SMLF,IO,DGA^6000030    I16 @T6G_MB_LIB.T6G(SCH_1):PAGE32
   U25 CY25 VSS_CY25 GENOA_SP5-SOCKET6096_13568-001,SMLF,IO,DGA^6000030    I16 @T6G_MB_LIB.T6G(SCH_1):PAGE32
   U25 CY26 VSS_CY26 GENOA_SP5-SOCKET6096_13568-001,SMLF,IO,DGA^6000030    I16 @T6G_MB_LIB.T6G(SCH_1):PAGE32
   U25 CY27 VSS_CY27 GENOA_SP5-SOCKET6096_13568-001,SMLF,IO,DGA^6000030    I16 @T6G_MB_LIB.T6G(SCH_1):PAGE32
   U25 CY28 VSS_CY28 GENOA_SP5-SOCKET6096_13568-001,SMLF,IO,DGA^6000030    I16 @T6G_MB_LIB.T6G(SCH_1):PAGE32
   U25 CY29 VSS_CY29 GENOA_SP5-SOCKET6096_13568-001,SMLF,IO,DGA^6000030    I16 @T6G_MB_LIB.T6G(SCH_1):PAGE32
   U25 CY30 VSS_CY30 GENOA_SP5-SOCKET6096_13568-001,SMLF,IO,DGA^6000030    I16 @T6G_MB_LIB.T6G(SCH_1):PAGE32
   U25 CY31 VSS_CY31 GENOA_SP5-SOCKET6096_13568-001,SMLF,IO,DGA^6000030    I16 @T6G_MB_LIB.T6G(SCH_1):PAGE32
   U25 CY32 VSS_CY32 GENOA_SP5-SOCKET6096_13568-001,SMLF,IO,DGA^6000030    I16 @T6G_MB_LIB.T6G(SCH_1):PAGE32
   U25 CY33 VSS_CY33 GENOA_SP5-SOCKET6096_13568-001,SMLF,IO,DGA^6000030    I16 @T6G_MB_LIB.T6G(SCH_1):PAGE32
   U25 CY34 VSS_CY34 GENOA_SP5-SOCKET6096_13568-001,SMLF,IO,DGA^6000030    I16 @T6G_MB_LIB.T6G(SCH_1):PAGE32
   U25 CY37 VSS_CY37 GENOA_SP5-SOCKET6096_13568-001,SMLF,IO,DGA^6000030    I16 @T6G_MB_LIB.T6G(SCH_1):PAGE32
   U25 CY39 VSS_CY39 GENOA_SP5-SOCKET6096_13568-001,SMLF,IO,DGA^6000030    I16 @T6G_MB_LIB.T6G(SCH_1):PAGE32
   U25 CY42 VSS_CY42 GENOA_SP5-SOCKET6096_13568-001,SMLF,IO,DGA^6000030    I16 @T6G_MB_LIB.T6G(SCH_1):PAGE32
   U25 CY43 VSS_CY43 GENOA_SP5-SOCKET6096_13568-001,SMLF,IO,DGA^6000030    I16 @T6G_MB_LIB.T6G(SCH_1):PAGE32
   U25 CY44 VSS_CY44 GENOA_SP5-SOCKET6096_13568-001,SMLF,IO,DGA^6000030    I16 @T6G_MB_LIB.T6G(SCH_1):PAGE32
   U25 CY45 VSS_CY45 GENOA_SP5-SOCKET6096_13568-001,SMLF,IO,DGA^6000030    I16 @T6G_MB_LIB.T6G(SCH_1):PAGE32
   U25 CY46 VSS_CY46 GENOA_SP5-SOCKET6096_13568-001,SMLF,IO,DGA^6000030    I16 @T6G_MB_LIB.T6G(SCH_1):PAGE32
   U25 CY47 VSS_CY47 GENOA_SP5-SOCKET6096_13568-001,SMLF,IO,DGA^6000030    I16 @T6G_MB_LIB.T6G(SCH_1):PAGE32
   U25 CY48 VSS_CY48 GENOA_SP5-SOCKET6096_13568-001,SMLF,IO,DGA^6000030    I16 @T6G_MB_LIB.T6G(SCH_1):PAGE32
   U25 CY49 VSS_CY49 GENOA_SP5-SOCKET6096_13568-001,SMLF,IO,DGA^6000030    I16 @T6G_MB_LIB.T6G(SCH_1):PAGE32
   U25 CY50 VSS_CY50 GENOA_SP5-SOCKET6096_13568-001,SMLF,IO,DGA^6000030    I16 @T6G_MB_LIB.T6G(SCH_1):PAGE32
   U25 CY51 VSS_CY51 GENOA_SP5-SOCKET6096_13568-001,SMLF,IO,DGA^6000030    I16 @T6G_MB_LIB.T6G(SCH_1):PAGE32
   U25 CY52 VSS_CY52 GENOA_SP5-SOCKET6096_13568-001,SMLF,IO,DGA^6000030    I16 @T6G_MB_LIB.T6G(SCH_1):PAGE32
   U25 CY53 VSS_CY53 GENOA_SP5-SOCKET6096_13568-001,SMLF,IO,DGA^6000030    I16 @T6G_MB_LIB.T6G(SCH_1):PAGE32
   U25 CY59 VSS_CY59 GENOA_SP5-SOCKET6096_13568-001,SMLF,IO,DGA^6000030    I16 @T6G_MB_LIB.T6G(SCH_1):PAGE32
   U25 CY61 VSS_CY61 GENOA_SP5-SOCKET6096_13568-001,SMLF,IO,DGA^6000030    I16 @T6G_MB_LIB.T6G(SCH_1):PAGE32
   U25 CY64 VSS_CY64 GENOA_SP5-SOCKET6096_13568-001,SMLF,IO,DGA^6000030    I16 @T6G_MB_LIB.T6G(SCH_1):PAGE32
   U25 CY66 VSS_CY66 GENOA_SP5-SOCKET6096_13568-001,SMLF,IO,DGA^6000030    I16 @T6G_MB_LIB.T6G(SCH_1):PAGE32
   U25 CY68 VSS_CY68 GENOA_SP5-SOCKET6096_13568-001,SMLF,IO,DGA^6000030    I16 @T6G_MB_LIB.T6G(SCH_1):PAGE32
   U25 CY71 VSS_CY71 GENOA_SP5-SOCKET6096_13568-001,SMLF,IO,DGA^6000030    I16 @T6G_MB_LIB.T6G(SCH_1):PAGE32
   U25 CY73 VSS_CY73 GENOA_SP5-SOCKET6096_13568-001,SMLF,IO,DGA^6000030    I16 @T6G_MB_LIB.T6G(SCH_1):PAGE32
   U25  DA1 VSS_DA1 GENOA_SP5-SOCKET6096_13568-001,SMLF,IO,DGA^6000030    I16 @T6G_MB_LIB.T6G(SCH_1):PAGE32
   U25  DA4 VSS_DA4 GENOA_SP5-SOCKET6096_13568-001,SMLF,IO,DGA^6000030    I16 @T6G_MB_LIB.T6G(SCH_1):PAGE32
   U25  DA6 VSS_DA6 GENOA_SP5-SOCKET6096_13568-001,SMLF,IO,DGA^6000030    I16 @T6G_MB_LIB.T6G(SCH_1):PAGE32
   U25  DA8 VSS_DA8 GENOA_SP5-SOCKET6096_13568-001,SMLF,IO,DGA^6000030    I16 @T6G_MB_LIB.T6G(SCH_1):PAGE32
   U25 DA11 VSS_DA11 GENOA_SP5-SOCKET6096_13568-001,SMLF,IO,DGA^6000030    I16 @T6G_MB_LIB.T6G(SCH_1):PAGE32
   U25 DA13 VSS_DA13 GENOA_SP5-SOCKET6096_13568-001,SMLF,IO,DGA^6000030    I16 @T6G_MB_LIB.T6G(SCH_1):PAGE32
   U25 DA15 VSS_DA15 GENOA_SP5-SOCKET6096_13568-001,SMLF,IO,DGA^6000030    I16 @T6G_MB_LIB.T6G(SCH_1):PAGE32
   U25 DA18 VSS_DA18 GENOA_SP5-SOCKET6096_13568-001,SMLF,IO,DGA^6000030    I16 @T6G_MB_LIB.T6G(SCH_1):PAGE32
   U25 DA20 VSS_DA20 GENOA_SP5-SOCKET6096_13568-001,SMLF,IO,DGA^6000030    I16 @T6G_MB_LIB.T6G(SCH_1):PAGE32
   U25 DA22 VSS_DA22 GENOA_SP5-SOCKET6096_13568-001,SMLF,IO,DGA^6000030    I16 @T6G_MB_LIB.T6G(SCH_1):PAGE32
   U25 DA25 VSS_DA25 GENOA_SP5-SOCKET6096_13568-001,SMLF,IO,DGA^6000030    I16 @T6G_MB_LIB.T6G(SCH_1):PAGE32
   U25 DA28 VSS_DA28 GENOA_SP5-SOCKET6096_13568-001,SMLF,IO,DGA^6000030    I16 @T6G_MB_LIB.T6G(SCH_1):PAGE32
   U25 DA31 VSS_DA31 GENOA_SP5-SOCKET6096_13568-001,SMLF,IO,DGA^6000030    I16 @T6G_MB_LIB.T6G(SCH_1):PAGE32
   U25 DA34 VSS_DA34 GENOA_SP5-SOCKET6096_13568-001,SMLF,IO,DGA^6000030    I16 @T6G_MB_LIB.T6G(SCH_1):PAGE32
   U25 DA42 VSS_DA42 GENOA_SP5-SOCKET6096_13568-001,SMLF,IO,DGA^6000030    I16 @T6G_MB_LIB.T6G(SCH_1):PAGE32
   U25 DA45 VSS_DA45 GENOA_SP5-SOCKET6096_13568-001,SMLF,IO,DGA^6000030    I16 @T6G_MB_LIB.T6G(SCH_1):PAGE32
   U25 DA48 VSS_DA48 GENOA_SP5-SOCKET6096_13568-001,SMLF,IO,DGA^6000030    I16 @T6G_MB_LIB.T6G(SCH_1):PAGE32
   U25 DA51 VSS_DA51 GENOA_SP5-SOCKET6096_13568-001,SMLF,IO,DGA^6000030    I16 @T6G_MB_LIB.T6G(SCH_1):PAGE32
   U25 DA54 VSS_DA54 GENOA_SP5-SOCKET6096_13568-001,SMLF,IO,DGA^6000030    I16 @T6G_MB_LIB.T6G(SCH_1):PAGE32
   U25 DA58 VSS_DA58 GENOA_SP5-SOCKET6096_13568-001,SMLF,IO,DGA^6000030    I16 @T6G_MB_LIB.T6G(SCH_1):PAGE32
   U25 DA61 VSS_DA61 GENOA_SP5-SOCKET6096_13568-001,SMLF,IO,DGA^6000030    I16 @T6G_MB_LIB.T6G(SCH_1):PAGE32
   U25 DA63 VSS_DA63 GENOA_SP5-SOCKET6096_13568-001,SMLF,IO,DGA^6000030    I16 @T6G_MB_LIB.T6G(SCH_1):PAGE32
   U25 DA65 VSS_DA65 GENOA_SP5-SOCKET6096_13568-001,SMLF,IO,DGA^6000030    I16 @T6G_MB_LIB.T6G(SCH_1):PAGE32
   U25 DA68 VSS_DA68 GENOA_SP5-SOCKET6096_13568-001,SMLF,IO,DGA^6000030    I16 @T6G_MB_LIB.T6G(SCH_1):PAGE32
   U25 DA70 VSS_DA70 GENOA_SP5-SOCKET6096_13568-001,SMLF,IO,DGA^6000030    I16 @T6G_MB_LIB.T6G(SCH_1):PAGE32
   U25 AA42 VSS_AA42 GENOA_SP5-SOCKET6096_13568-001,SMLF,IO,DGA^6000030     I4 @T6G_MB_LIB.T6G(SCH_1):PAGE33
   U25 AA72 VSS_AA72 GENOA_SP5-SOCKET6096_13568-001,SMLF,IO,DGA^6000030     I4 @T6G_MB_LIB.T6G(SCH_1):PAGE33
   U25 AD31 VSS_AD31 GENOA_SP5-SOCKET6096_13568-001,SMLF,IO,DGA^6000030     I4 @T6G_MB_LIB.T6G(SCH_1):PAGE33
   U25  AE4 VSS_AE4 GENOA_SP5-SOCKET6096_13568-001,SMLF,IO,DGA^6000030     I4 @T6G_MB_LIB.T6G(SCH_1):PAGE33
   U25 AH33 VSS_AH33 GENOA_SP5-SOCKET6096_13568-001,SMLF,IO,DGA^6000030     I4 @T6G_MB_LIB.T6G(SCH_1):PAGE33
   U25 AJ13 VSS_AJ13 GENOA_SP5-SOCKET6096_13568-001,SMLF,IO,DGA^6000030     I4 @T6G_MB_LIB.T6G(SCH_1):PAGE33
   U25 AM37 VSS_AM37 GENOA_SP5-SOCKET6096_13568-001,SMLF,IO,DGA^6000030     I4 @T6G_MB_LIB.T6G(SCH_1):PAGE33
   U25 AN20 VSS_AN20 GENOA_SP5-SOCKET6096_13568-001,SMLF,IO,DGA^6000030     I4 @T6G_MB_LIB.T6G(SCH_1):PAGE33
   U25 BV42 VSS_BV42 GENOA_SP5-SOCKET6096_13568-001,SMLF,IO,DGA^6000030     I4 @T6G_MB_LIB.T6G(SCH_1):PAGE33
   U25 BW25 VSS_BW25 GENOA_SP5-SOCKET6096_13568-001,SMLF,IO,DGA^6000030     I4 @T6G_MB_LIB.T6G(SCH_1):PAGE33
   U25 CB44 VSS_CB44 GENOA_SP5-SOCKET6096_13568-001,SMLF,IO,DGA^6000030     I4 @T6G_MB_LIB.T6G(SCH_1):PAGE33
   U25 CC22 VSS_CC22 GENOA_SP5-SOCKET6096_13568-001,SMLF,IO,DGA^6000030     I4 @T6G_MB_LIB.T6G(SCH_1):PAGE33
   U25 CF46 VSS_CF46 GENOA_SP5-SOCKET6096_13568-001,SMLF,IO,DGA^6000030     I4 @T6G_MB_LIB.T6G(SCH_1):PAGE33
   U25 CG42 VSS_CG42 GENOA_SP5-SOCKET6096_13568-001,SMLF,IO,DGA^6000030     I4 @T6G_MB_LIB.T6G(SCH_1):PAGE33
   U25 CK10 VSS_CK10 GENOA_SP5-SOCKET6096_13568-001,SMLF,IO,DGA^6000030     I4 @T6G_MB_LIB.T6G(SCH_1):PAGE33
   U25 CK31 VSS_CK31 GENOA_SP5-SOCKET6096_13568-001,SMLF,IO,DGA^6000030     I4 @T6G_MB_LIB.T6G(SCH_1):PAGE33
   U25 CM50 VSS_CM50 GENOA_SP5-SOCKET6096_13568-001,SMLF,IO,DGA^6000030     I4 @T6G_MB_LIB.T6G(SCH_1):PAGE33
   U25 CN54 VSS_CN54 GENOA_SP5-SOCKET6096_13568-001,SMLF,IO,DGA^6000030     I4 @T6G_MB_LIB.T6G(SCH_1):PAGE33
   U25 CT52 VSS_CT52 GENOA_SP5-SOCKET6096_13568-001,SMLF,IO,DGA^6000030     I4 @T6G_MB_LIB.T6G(SCH_1):PAGE33
   U25 CU58 VSS_CU58 GENOA_SP5-SOCKET6096_13568-001,SMLF,IO,DGA^6000030     I4 @T6G_MB_LIB.T6G(SCH_1):PAGE33
   U25 CY57 VSS_CY57 GENOA_SP5-SOCKET6096_13568-001,SMLF,IO,DGA^6000030     I4 @T6G_MB_LIB.T6G(SCH_1):PAGE33
   U25 DA56 VSS_DA56 GENOA_SP5-SOCKET6096_13568-001,SMLF,IO,DGA^6000030     I4 @T6G_MB_LIB.T6G(SCH_1):PAGE33
   U25 DA72 VSS_DA72 GENOA_SP5-SOCKET6096_13568-001,SMLF,IO,DGA^6000030     I4 @T6G_MB_LIB.T6G(SCH_1):PAGE33
   U25 DA75 VSS_DA75 GENOA_SP5-SOCKET6096_13568-001,SMLF,IO,DGA^6000030     I4 @T6G_MB_LIB.T6G(SCH_1):PAGE33
   U25  DB3 VSS_DB3 GENOA_SP5-SOCKET6096_13568-001,SMLF,IO,DGA^6000030     I4 @T6G_MB_LIB.T6G(SCH_1):PAGE33
   U25  DB8 VSS_DB8 GENOA_SP5-SOCKET6096_13568-001,SMLF,IO,DGA^6000030     I4 @T6G_MB_LIB.T6G(SCH_1):PAGE33
   U25 DB10 VSS_DB10 GENOA_SP5-SOCKET6096_13568-001,SMLF,IO,DGA^6000030     I4 @T6G_MB_LIB.T6G(SCH_1):PAGE33
   U25 DB15 VSS_DB15 GENOA_SP5-SOCKET6096_13568-001,SMLF,IO,DGA^6000030     I4 @T6G_MB_LIB.T6G(SCH_1):PAGE33
   U25 DB17 VSS_DB17 GENOA_SP5-SOCKET6096_13568-001,SMLF,IO,DGA^6000030     I4 @T6G_MB_LIB.T6G(SCH_1):PAGE33
   U25 DB22 VSS_DB22 GENOA_SP5-SOCKET6096_13568-001,SMLF,IO,DGA^6000030     I4 @T6G_MB_LIB.T6G(SCH_1):PAGE33
   U25 DB25 VSS_DB25 GENOA_SP5-SOCKET6096_13568-001,SMLF,IO,DGA^6000030     I4 @T6G_MB_LIB.T6G(SCH_1):PAGE33
   U25 DB28 VSS_DB28 GENOA_SP5-SOCKET6096_13568-001,SMLF,IO,DGA^6000030     I4 @T6G_MB_LIB.T6G(SCH_1):PAGE33
   U25 DB31 VSS_DB31 GENOA_SP5-SOCKET6096_13568-001,SMLF,IO,DGA^6000030     I4 @T6G_MB_LIB.T6G(SCH_1):PAGE33
   U25 DB34 VSS_DB34 GENOA_SP5-SOCKET6096_13568-001,SMLF,IO,DGA^6000030     I4 @T6G_MB_LIB.T6G(SCH_1):PAGE33
   U25 DB37 VSS_DB37 GENOA_SP5-SOCKET6096_13568-001,SMLF,IO,DGA^6000030     I4 @T6G_MB_LIB.T6G(SCH_1):PAGE33
   U25 DB39 VSS_DB39 GENOA_SP5-SOCKET6096_13568-001,SMLF,IO,DGA^6000030     I4 @T6G_MB_LIB.T6G(SCH_1):PAGE33
   U25 DB42 VSS_DB42 GENOA_SP5-SOCKET6096_13568-001,SMLF,IO,DGA^6000030     I4 @T6G_MB_LIB.T6G(SCH_1):PAGE33
   U25 DB45 VSS_DB45 GENOA_SP5-SOCKET6096_13568-001,SMLF,IO,DGA^6000030     I4 @T6G_MB_LIB.T6G(SCH_1):PAGE33
   U25 DB48 VSS_DB48 GENOA_SP5-SOCKET6096_13568-001,SMLF,IO,DGA^6000030     I4 @T6G_MB_LIB.T6G(SCH_1):PAGE33
   U25 DB51 VSS_DB51 GENOA_SP5-SOCKET6096_13568-001,SMLF,IO,DGA^6000030     I4 @T6G_MB_LIB.T6G(SCH_1):PAGE33
   U25 DB54 VSS_DB54 GENOA_SP5-SOCKET6096_13568-001,SMLF,IO,DGA^6000030     I4 @T6G_MB_LIB.T6G(SCH_1):PAGE33
   U25 DB59 VSS_DB59 GENOA_SP5-SOCKET6096_13568-001,SMLF,IO,DGA^6000030     I4 @T6G_MB_LIB.T6G(SCH_1):PAGE33
   U25 DB61 VSS_DB61 GENOA_SP5-SOCKET6096_13568-001,SMLF,IO,DGA^6000030     I4 @T6G_MB_LIB.T6G(SCH_1):PAGE33
   U25 DB66 VSS_DB66 GENOA_SP5-SOCKET6096_13568-001,SMLF,IO,DGA^6000030     I4 @T6G_MB_LIB.T6G(SCH_1):PAGE33
   U25 DB68 VSS_DB68 GENOA_SP5-SOCKET6096_13568-001,SMLF,IO,DGA^6000030     I4 @T6G_MB_LIB.T6G(SCH_1):PAGE33
   U25 DB73 VSS_DB73 GENOA_SP5-SOCKET6096_13568-001,SMLF,IO,DGA^6000030     I4 @T6G_MB_LIB.T6G(SCH_1):PAGE33
   U25  DC1 VSS_DC1 GENOA_SP5-SOCKET6096_13568-001,SMLF,IO,DGA^6000030     I4 @T6G_MB_LIB.T6G(SCH_1):PAGE33
   U25  DC4 VSS_DC4 GENOA_SP5-SOCKET6096_13568-001,SMLF,IO,DGA^6000030     I4 @T6G_MB_LIB.T6G(SCH_1):PAGE33
   U25  DC6 VSS_DC6 GENOA_SP5-SOCKET6096_13568-001,SMLF,IO,DGA^6000030     I4 @T6G_MB_LIB.T6G(SCH_1):PAGE33
   U25  DC8 VSS_DC8 GENOA_SP5-SOCKET6096_13568-001,SMLF,IO,DGA^6000030     I4 @T6G_MB_LIB.T6G(SCH_1):PAGE33
   U25 DC11 VSS_DC11 GENOA_SP5-SOCKET6096_13568-001,SMLF,IO,DGA^6000030     I4 @T6G_MB_LIB.T6G(SCH_1):PAGE33
   U25 DC13 VSS_DC13 GENOA_SP5-SOCKET6096_13568-001,SMLF,IO,DGA^6000030     I4 @T6G_MB_LIB.T6G(SCH_1):PAGE33
   U25 DC15 VSS_DC15 GENOA_SP5-SOCKET6096_13568-001,SMLF,IO,DGA^6000030     I4 @T6G_MB_LIB.T6G(SCH_1):PAGE33
   U25 DC18 VSS_DC18 GENOA_SP5-SOCKET6096_13568-001,SMLF,IO,DGA^6000030     I4 @T6G_MB_LIB.T6G(SCH_1):PAGE33
   U25 DC20 VSS_DC20 GENOA_SP5-SOCKET6096_13568-001,SMLF,IO,DGA^6000030     I4 @T6G_MB_LIB.T6G(SCH_1):PAGE33
   U25 DC22 VSS_DC22 GENOA_SP5-SOCKET6096_13568-001,SMLF,IO,DGA^6000030     I4 @T6G_MB_LIB.T6G(SCH_1):PAGE33
   U25 DC25 VSS_DC25 GENOA_SP5-SOCKET6096_13568-001,SMLF,IO,DGA^6000030     I4 @T6G_MB_LIB.T6G(SCH_1):PAGE33
   U25 DC28 VSS_DC28 GENOA_SP5-SOCKET6096_13568-001,SMLF,IO,DGA^6000030     I4 @T6G_MB_LIB.T6G(SCH_1):PAGE33
   U25 DC31 VSS_DC31 GENOA_SP5-SOCKET6096_13568-001,SMLF,IO,DGA^6000030     I4 @T6G_MB_LIB.T6G(SCH_1):PAGE33
   U25 DC34 VSS_DC34 GENOA_SP5-SOCKET6096_13568-001,SMLF,IO,DGA^6000030     I4 @T6G_MB_LIB.T6G(SCH_1):PAGE33
   U25 DC42 VSS_DC42 GENOA_SP5-SOCKET6096_13568-001,SMLF,IO,DGA^6000030     I4 @T6G_MB_LIB.T6G(SCH_1):PAGE33
   U25 DC45 VSS_DC45 GENOA_SP5-SOCKET6096_13568-001,SMLF,IO,DGA^6000030     I4 @T6G_MB_LIB.T6G(SCH_1):PAGE33
   U25 DC48 VSS_DC48 GENOA_SP5-SOCKET6096_13568-001,SMLF,IO,DGA^6000030     I4 @T6G_MB_LIB.T6G(SCH_1):PAGE33
   U25 DC51 VSS_DC51 GENOA_SP5-SOCKET6096_13568-001,SMLF,IO,DGA^6000030     I4 @T6G_MB_LIB.T6G(SCH_1):PAGE33
   U25 DC54 VSS_DC54 GENOA_SP5-SOCKET6096_13568-001,SMLF,IO,DGA^6000030     I4 @T6G_MB_LIB.T6G(SCH_1):PAGE33
   U25 DC56 VSS_DC56 GENOA_SP5-SOCKET6096_13568-001,SMLF,IO,DGA^6000030     I4 @T6G_MB_LIB.T6G(SCH_1):PAGE33
   U25 DC58 VSS_DC58 GENOA_SP5-SOCKET6096_13568-001,SMLF,IO,DGA^6000030     I4 @T6G_MB_LIB.T6G(SCH_1):PAGE33
   U25 DC61 VSS_DC61 GENOA_SP5-SOCKET6096_13568-001,SMLF,IO,DGA^6000030     I4 @T6G_MB_LIB.T6G(SCH_1):PAGE33
   U25 DC63 VSS_DC63 GENOA_SP5-SOCKET6096_13568-001,SMLF,IO,DGA^6000030     I4 @T6G_MB_LIB.T6G(SCH_1):PAGE33
   U25 DC65 VSS_DC65 GENOA_SP5-SOCKET6096_13568-001,SMLF,IO,DGA^6000030     I4 @T6G_MB_LIB.T6G(SCH_1):PAGE33
   U25 DC68 VSS_DC68 GENOA_SP5-SOCKET6096_13568-001,SMLF,IO,DGA^6000030     I4 @T6G_MB_LIB.T6G(SCH_1):PAGE33
   U25 DC70 VSS_DC70 GENOA_SP5-SOCKET6096_13568-001,SMLF,IO,DGA^6000030     I4 @T6G_MB_LIB.T6G(SCH_1):PAGE33
   U25 DC72 VSS_DC72 GENOA_SP5-SOCKET6096_13568-001,SMLF,IO,DGA^6000030     I4 @T6G_MB_LIB.T6G(SCH_1):PAGE33
   U25 DC75 VSS_DC75 GENOA_SP5-SOCKET6096_13568-001,SMLF,IO,DGA^6000030     I4 @T6G_MB_LIB.T6G(SCH_1):PAGE33
   U25  DD3 VSS_DD3 GENOA_SP5-SOCKET6096_13568-001,SMLF,IO,DGA^6000030     I4 @T6G_MB_LIB.T6G(SCH_1):PAGE33
   U25  DD5 VSS_DD5 GENOA_SP5-SOCKET6096_13568-001,SMLF,IO,DGA^6000030     I4 @T6G_MB_LIB.T6G(SCH_1):PAGE33
   U25  DD8 VSS_DD8 GENOA_SP5-SOCKET6096_13568-001,SMLF,IO,DGA^6000030     I4 @T6G_MB_LIB.T6G(SCH_1):PAGE33
   U25 DD10 VSS_DD10 GENOA_SP5-SOCKET6096_13568-001,SMLF,IO,DGA^6000030     I4 @T6G_MB_LIB.T6G(SCH_1):PAGE33
   U25 DD12 VSS_DD12 GENOA_SP5-SOCKET6096_13568-001,SMLF,IO,DGA^6000030     I4 @T6G_MB_LIB.T6G(SCH_1):PAGE33
   U25 DD15 VSS_DD15 GENOA_SP5-SOCKET6096_13568-001,SMLF,IO,DGA^6000030     I4 @T6G_MB_LIB.T6G(SCH_1):PAGE33
   U25 DD17 VSS_DD17 GENOA_SP5-SOCKET6096_13568-001,SMLF,IO,DGA^6000030     I4 @T6G_MB_LIB.T6G(SCH_1):PAGE33
   U25 DD19 VSS_DD19 GENOA_SP5-SOCKET6096_13568-001,SMLF,IO,DGA^6000030     I4 @T6G_MB_LIB.T6G(SCH_1):PAGE33
   U25 DD23 VSS_DD23 GENOA_SP5-SOCKET6096_13568-001,SMLF,IO,DGA^6000030     I4 @T6G_MB_LIB.T6G(SCH_1):PAGE33
   U25 DD24 VSS_DD24 GENOA_SP5-SOCKET6096_13568-001,SMLF,IO,DGA^6000030     I4 @T6G_MB_LIB.T6G(SCH_1):PAGE33
   U25 DD26 VSS_DD26 GENOA_SP5-SOCKET6096_13568-001,SMLF,IO,DGA^6000030     I4 @T6G_MB_LIB.T6G(SCH_1):PAGE33
   U25 DD27 VSS_DD27 GENOA_SP5-SOCKET6096_13568-001,SMLF,IO,DGA^6000030     I4 @T6G_MB_LIB.T6G(SCH_1):PAGE33
   U25 DD29 VSS_DD29 GENOA_SP5-SOCKET6096_13568-001,SMLF,IO,DGA^6000030     I4 @T6G_MB_LIB.T6G(SCH_1):PAGE33
   U25 DD30 VSS_DD30 GENOA_SP5-SOCKET6096_13568-001,SMLF,IO,DGA^6000030     I4 @T6G_MB_LIB.T6G(SCH_1):PAGE33
   U25 DD32 VSS_DD32 GENOA_SP5-SOCKET6096_13568-001,SMLF,IO,DGA^6000030     I4 @T6G_MB_LIB.T6G(SCH_1):PAGE33
   U25 DD33 VSS_DD33 GENOA_SP5-SOCKET6096_13568-001,SMLF,IO,DGA^6000030     I4 @T6G_MB_LIB.T6G(SCH_1):PAGE33
   U25 DD35 VSS_DD35 GENOA_SP5-SOCKET6096_13568-001,SMLF,IO,DGA^6000030     I4 @T6G_MB_LIB.T6G(SCH_1):PAGE33
   U25 DD36 VSS_DD36 GENOA_SP5-SOCKET6096_13568-001,SMLF,IO,DGA^6000030     I4 @T6G_MB_LIB.T6G(SCH_1):PAGE33
   U25 DD37 VSS_DD37 GENOA_SP5-SOCKET6096_13568-001,SMLF,IO,DGA^6000030     I4 @T6G_MB_LIB.T6G(SCH_1):PAGE33
   U25 DD39 VSS_DD39 GENOA_SP5-SOCKET6096_13568-001,SMLF,IO,DGA^6000030     I4 @T6G_MB_LIB.T6G(SCH_1):PAGE33
   U25 DD40 VSS_DD40 GENOA_SP5-SOCKET6096_13568-001,SMLF,IO,DGA^6000030     I4 @T6G_MB_LIB.T6G(SCH_1):PAGE33
   U25 DD41 VSS_DD41 GENOA_SP5-SOCKET6096_13568-001,SMLF,IO,DGA^6000030     I4 @T6G_MB_LIB.T6G(SCH_1):PAGE33
   U25 DD43 VSS_DD43 GENOA_SP5-SOCKET6096_13568-001,SMLF,IO,DGA^6000030     I4 @T6G_MB_LIB.T6G(SCH_1):PAGE33
   U25 DD44 VSS_DD44 GENOA_SP5-SOCKET6096_13568-001,SMLF,IO,DGA^6000030     I4 @T6G_MB_LIB.T6G(SCH_1):PAGE33
   U25 DD46 VSS_DD46 GENOA_SP5-SOCKET6096_13568-001,SMLF,IO,DGA^6000030     I4 @T6G_MB_LIB.T6G(SCH_1):PAGE33
   U25 DD47 VSS_DD47 GENOA_SP5-SOCKET6096_13568-001,SMLF,IO,DGA^6000030     I4 @T6G_MB_LIB.T6G(SCH_1):PAGE33
   U25 DD49 VSS_DD49 GENOA_SP5-SOCKET6096_13568-001,SMLF,IO,DGA^6000030     I4 @T6G_MB_LIB.T6G(SCH_1):PAGE33
   U25 DD50 VSS_DD50 GENOA_SP5-SOCKET6096_13568-001,SMLF,IO,DGA^6000030     I4 @T6G_MB_LIB.T6G(SCH_1):PAGE33
   U25 DD52 VSS_DD52 GENOA_SP5-SOCKET6096_13568-001,SMLF,IO,DGA^6000030     I4 @T6G_MB_LIB.T6G(SCH_1):PAGE33
   U25 DD53 VSS_DD53 GENOA_SP5-SOCKET6096_13568-001,SMLF,IO,DGA^6000030     I4 @T6G_MB_LIB.T6G(SCH_1):PAGE33
   U25 DD57 VSS_DD57 GENOA_SP5-SOCKET6096_13568-001,SMLF,IO,DGA^6000030     I4 @T6G_MB_LIB.T6G(SCH_1):PAGE33
   U25 DD59 VSS_DD59 GENOA_SP5-SOCKET6096_13568-001,SMLF,IO,DGA^6000030     I4 @T6G_MB_LIB.T6G(SCH_1):PAGE33
   U25 DD61 VSS_DD61 GENOA_SP5-SOCKET6096_13568-001,SMLF,IO,DGA^6000030     I4 @T6G_MB_LIB.T6G(SCH_1):PAGE33
   U25 DD64 VSS_DD64 GENOA_SP5-SOCKET6096_13568-001,SMLF,IO,DGA^6000030     I4 @T6G_MB_LIB.T6G(SCH_1):PAGE33
   U25 DD66 VSS_DD66 GENOA_SP5-SOCKET6096_13568-001,SMLF,IO,DGA^6000030     I4 @T6G_MB_LIB.T6G(SCH_1):PAGE33
   U25 DD68 VSS_DD68 GENOA_SP5-SOCKET6096_13568-001,SMLF,IO,DGA^6000030     I4 @T6G_MB_LIB.T6G(SCH_1):PAGE33
   U25 DD71 VSS_DD71 GENOA_SP5-SOCKET6096_13568-001,SMLF,IO,DGA^6000030     I4 @T6G_MB_LIB.T6G(SCH_1):PAGE33
   U25 DD73 VSS_DD73 GENOA_SP5-SOCKET6096_13568-001,SMLF,IO,DGA^6000030     I4 @T6G_MB_LIB.T6G(SCH_1):PAGE33
   U25  DE1 VSS_DE1 GENOA_SP5-SOCKET6096_13568-001,SMLF,IO,DGA^6000030     I4 @T6G_MB_LIB.T6G(SCH_1):PAGE33
   U25  DE6 VSS_DE6 GENOA_SP5-SOCKET6096_13568-001,SMLF,IO,DGA^6000030     I4 @T6G_MB_LIB.T6G(SCH_1):PAGE33
   U25  DE8 VSS_DE8 GENOA_SP5-SOCKET6096_13568-001,SMLF,IO,DGA^6000030     I4 @T6G_MB_LIB.T6G(SCH_1):PAGE33
   U25 DE13 VSS_DE13 GENOA_SP5-SOCKET6096_13568-001,SMLF,IO,DGA^6000030     I4 @T6G_MB_LIB.T6G(SCH_1):PAGE33
   U25 DE15 VSS_DE15 GENOA_SP5-SOCKET6096_13568-001,SMLF,IO,DGA^6000030     I4 @T6G_MB_LIB.T6G(SCH_1):PAGE33
   U25 DE20 VSS_DE20 GENOA_SP5-SOCKET6096_13568-001,SMLF,IO,DGA^6000030     I4 @T6G_MB_LIB.T6G(SCH_1):PAGE33
   U25 DE23 VSS_DE23 GENOA_SP5-SOCKET6096_13568-001,SMLF,IO,DGA^6000030     I4 @T6G_MB_LIB.T6G(SCH_1):PAGE33
   U25 DE26 VSS_DE26 GENOA_SP5-SOCKET6096_13568-001,SMLF,IO,DGA^6000030     I4 @T6G_MB_LIB.T6G(SCH_1):PAGE33
   U25 DE29 VSS_DE29 GENOA_SP5-SOCKET6096_13568-001,SMLF,IO,DGA^6000030     I4 @T6G_MB_LIB.T6G(SCH_1):PAGE33
   U25 DE33 VSS_DE33 GENOA_SP5-SOCKET6096_13568-001,SMLF,IO,DGA^6000030     I4 @T6G_MB_LIB.T6G(SCH_1):PAGE33
   U25 DE56 VSS_DE56 GENOA_SP5-SOCKET6096_13568-001,SMLF,IO,DGA^6000030     I4 @T6G_MB_LIB.T6G(SCH_1):PAGE33
   U25 DE61 VSS_DE61 GENOA_SP5-SOCKET6096_13568-001,SMLF,IO,DGA^6000030     I4 @T6G_MB_LIB.T6G(SCH_1):PAGE33
   U25 DE63 VSS_DE63 GENOA_SP5-SOCKET6096_13568-001,SMLF,IO,DGA^6000030     I4 @T6G_MB_LIB.T6G(SCH_1):PAGE33
   U25 DE68 VSS_DE68 GENOA_SP5-SOCKET6096_13568-001,SMLF,IO,DGA^6000030     I4 @T6G_MB_LIB.T6G(SCH_1):PAGE33
   U25 DE70 VSS_DE70 GENOA_SP5-SOCKET6096_13568-001,SMLF,IO,DGA^6000030     I4 @T6G_MB_LIB.T6G(SCH_1):PAGE33
   U25 DE75 VSS_DE75 GENOA_SP5-SOCKET6096_13568-001,SMLF,IO,DGA^6000030     I4 @T6G_MB_LIB.T6G(SCH_1):PAGE33
   U25  DF3 VSS_DF3 GENOA_SP5-SOCKET6096_13568-001,SMLF,IO,DGA^6000030     I4 @T6G_MB_LIB.T6G(SCH_1):PAGE33
   U25  DF4 VSS_DF4 GENOA_SP5-SOCKET6096_13568-001,SMLF,IO,DGA^6000030     I4 @T6G_MB_LIB.T6G(SCH_1):PAGE33
   U25  DF5 VSS_DF5 GENOA_SP5-SOCKET6096_13568-001,SMLF,IO,DGA^6000030     I4 @T6G_MB_LIB.T6G(SCH_1):PAGE33
   U25  DF6 VSS_DF6 GENOA_SP5-SOCKET6096_13568-001,SMLF,IO,DGA^6000030     I4 @T6G_MB_LIB.T6G(SCH_1):PAGE33
   U25  DF8 VSS_DF8 GENOA_SP5-SOCKET6096_13568-001,SMLF,IO,DGA^6000030     I4 @T6G_MB_LIB.T6G(SCH_1):PAGE33
   U25 DF10 VSS_DF10 GENOA_SP5-SOCKET6096_13568-001,SMLF,IO,DGA^6000030     I4 @T6G_MB_LIB.T6G(SCH_1):PAGE33
   U25 DF11 VSS_DF11 GENOA_SP5-SOCKET6096_13568-001,SMLF,IO,DGA^6000030     I4 @T6G_MB_LIB.T6G(SCH_1):PAGE33
   U25 DF12 VSS_DF12 GENOA_SP5-SOCKET6096_13568-001,SMLF,IO,DGA^6000030     I4 @T6G_MB_LIB.T6G(SCH_1):PAGE33
   U25 DF13 VSS_DF13 GENOA_SP5-SOCKET6096_13568-001,SMLF,IO,DGA^6000030     I4 @T6G_MB_LIB.T6G(SCH_1):PAGE33
   U25 DF15 VSS_DF15 GENOA_SP5-SOCKET6096_13568-001,SMLF,IO,DGA^6000030     I4 @T6G_MB_LIB.T6G(SCH_1):PAGE33
   U25 DF17 VSS_DF17 GENOA_SP5-SOCKET6096_13568-001,SMLF,IO,DGA^6000030     I4 @T6G_MB_LIB.T6G(SCH_1):PAGE33
   U25 DF18 VSS_DF18 GENOA_SP5-SOCKET6096_13568-001,SMLF,IO,DGA^6000030     I4 @T6G_MB_LIB.T6G(SCH_1):PAGE33
   U25 DF19 VSS_DF19 GENOA_SP5-SOCKET6096_13568-001,SMLF,IO,DGA^6000030     I4 @T6G_MB_LIB.T6G(SCH_1):PAGE33
   U25 DF20 VSS_DF20 GENOA_SP5-SOCKET6096_13568-001,SMLF,IO,DGA^6000030     I4 @T6G_MB_LIB.T6G(SCH_1):PAGE33
   U25 DF22 VSS_DF22 GENOA_SP5-SOCKET6096_13568-001,SMLF,IO,DGA^6000030     I4 @T6G_MB_LIB.T6G(SCH_1):PAGE33
   U25 DF23 VSS_DF23 GENOA_SP5-SOCKET6096_13568-001,SMLF,IO,DGA^6000030     I4 @T6G_MB_LIB.T6G(SCH_1):PAGE33
   U25 DF26 VSS_DF26 GENOA_SP5-SOCKET6096_13568-001,SMLF,IO,DGA^6000030     I4 @T6G_MB_LIB.T6G(SCH_1):PAGE33
   U25 DF29 VSS_DF29 GENOA_SP5-SOCKET6096_13568-001,SMLF,IO,DGA^6000030     I4 @T6G_MB_LIB.T6G(SCH_1):PAGE33
   U25 DF32 VSS_DF32 GENOA_SP5-SOCKET6096_13568-001,SMLF,IO,DGA^6000030     I4 @T6G_MB_LIB.T6G(SCH_1):PAGE33
   U25 DF35 VSS_DF35 GENOA_SP5-SOCKET6096_13568-001,SMLF,IO,DGA^6000030     I4 @T6G_MB_LIB.T6G(SCH_1):PAGE33
   U25 DF37 VSS_DF37 GENOA_SP5-SOCKET6096_13568-001,SMLF,IO,DGA^6000030     I4 @T6G_MB_LIB.T6G(SCH_1):PAGE33
   U25 DF39 VSS_DF39 GENOA_SP5-SOCKET6096_13568-001,SMLF,IO,DGA^6000030     I4 @T6G_MB_LIB.T6G(SCH_1):PAGE33
   U25 DF42 VSS_DF42 GENOA_SP5-SOCKET6096_13568-001,SMLF,IO,DGA^6000030     I4 @T6G_MB_LIB.T6G(SCH_1):PAGE33
   U25 DF43 VSS_DF43 GENOA_SP5-SOCKET6096_13568-001,SMLF,IO,DGA^6000030     I4 @T6G_MB_LIB.T6G(SCH_1):PAGE33
   U25 DF44 VSS_DF44 GENOA_SP5-SOCKET6096_13568-001,SMLF,IO,DGA^6000030     I4 @T6G_MB_LIB.T6G(SCH_1):PAGE33
   U25 DF45 VSS_DF45 GENOA_SP5-SOCKET6096_13568-001,SMLF,IO,DGA^6000030     I4 @T6G_MB_LIB.T6G(SCH_1):PAGE33
   U25 DF46 VSS_DF46 GENOA_SP5-SOCKET6096_13568-001,SMLF,IO,DGA^6000030     I4 @T6G_MB_LIB.T6G(SCH_1):PAGE33
   U25 DF47 VSS_DF47 GENOA_SP5-SOCKET6096_13568-001,SMLF,IO,DGA^6000030     I4 @T6G_MB_LIB.T6G(SCH_1):PAGE33
   U25 DF48 VSS_DF48 GENOA_SP5-SOCKET6096_13568-001,SMLF,IO,DGA^6000030     I4 @T6G_MB_LIB.T6G(SCH_1):PAGE33
   U25 DF49 VSS_DF49 GENOA_SP5-SOCKET6096_13568-001,SMLF,IO,DGA^6000030     I4 @T6G_MB_LIB.T6G(SCH_1):PAGE33
   U25 DF50 VSS_DF50 GENOA_SP5-SOCKET6096_13568-001,SMLF,IO,DGA^6000030     I4 @T6G_MB_LIB.T6G(SCH_1):PAGE33
   U25 DF51 VSS_DF51 GENOA_SP5-SOCKET6096_13568-001,SMLF,IO,DGA^6000030     I4 @T6G_MB_LIB.T6G(SCH_1):PAGE33
   U25 DF52 VSS_DF52 GENOA_SP5-SOCKET6096_13568-001,SMLF,IO,DGA^6000030     I4 @T6G_MB_LIB.T6G(SCH_1):PAGE33
   U25 DF53 VSS_DF53 GENOA_SP5-SOCKET6096_13568-001,SMLF,IO,DGA^6000030     I4 @T6G_MB_LIB.T6G(SCH_1):PAGE33
   U25 DF54 VSS_DF54 GENOA_SP5-SOCKET6096_13568-001,SMLF,IO,DGA^6000030     I4 @T6G_MB_LIB.T6G(SCH_1):PAGE33
   U25 DF56 VSS_DF56 GENOA_SP5-SOCKET6096_13568-001,SMLF,IO,DGA^6000030     I4 @T6G_MB_LIB.T6G(SCH_1):PAGE33
   U25 DF57 VSS_DF57 GENOA_SP5-SOCKET6096_13568-001,SMLF,IO,DGA^6000030     I4 @T6G_MB_LIB.T6G(SCH_1):PAGE33
   U25 DF58 VSS_DF58 GENOA_SP5-SOCKET6096_13568-001,SMLF,IO,DGA^6000030     I4 @T6G_MB_LIB.T6G(SCH_1):PAGE33
   U25 DF59 VSS_DF59 GENOA_SP5-SOCKET6096_13568-001,SMLF,IO,DGA^6000030     I4 @T6G_MB_LIB.T6G(SCH_1):PAGE33
   U25 DF61 VSS_DF61 GENOA_SP5-SOCKET6096_13568-001,SMLF,IO,DGA^6000030     I4 @T6G_MB_LIB.T6G(SCH_1):PAGE33
   U25 DF63 VSS_DF63 GENOA_SP5-SOCKET6096_13568-001,SMLF,IO,DGA^6000030     I4 @T6G_MB_LIB.T6G(SCH_1):PAGE33
   U25 DF64 VSS_DF64 GENOA_SP5-SOCKET6096_13568-001,SMLF,IO,DGA^6000030     I4 @T6G_MB_LIB.T6G(SCH_1):PAGE33
   U25 DF65 VSS_DF65 GENOA_SP5-SOCKET6096_13568-001,SMLF,IO,DGA^6000030     I4 @T6G_MB_LIB.T6G(SCH_1):PAGE33
   U25 DF66 VSS_DF66 GENOA_SP5-SOCKET6096_13568-001,SMLF,IO,DGA^6000030     I4 @T6G_MB_LIB.T6G(SCH_1):PAGE33
   U25 DF68 VSS_DF68 GENOA_SP5-SOCKET6096_13568-001,SMLF,IO,DGA^6000030     I4 @T6G_MB_LIB.T6G(SCH_1):PAGE33
   U25 DF70 VSS_DF70 GENOA_SP5-SOCKET6096_13568-001,SMLF,IO,DGA^6000030     I4 @T6G_MB_LIB.T6G(SCH_1):PAGE33
   U25 DF71 VSS_DF71 GENOA_SP5-SOCKET6096_13568-001,SMLF,IO,DGA^6000030     I4 @T6G_MB_LIB.T6G(SCH_1):PAGE33
   U25 DF72 VSS_DF72 GENOA_SP5-SOCKET6096_13568-001,SMLF,IO,DGA^6000030     I4 @T6G_MB_LIB.T6G(SCH_1):PAGE33
   U25 DF73 VSS_DF73 GENOA_SP5-SOCKET6096_13568-001,SMLF,IO,DGA^6000030     I4 @T6G_MB_LIB.T6G(SCH_1):PAGE33
   U25  DG1 VSS_DG1 GENOA_SP5-SOCKET6096_13568-001,SMLF,IO,DGA^6000030     I4 @T6G_MB_LIB.T6G(SCH_1):PAGE33
   U25  DG2 VSS_DG2 GENOA_SP5-SOCKET6096_13568-001,SMLF,IO,DGA^6000030     I4 @T6G_MB_LIB.T6G(SCH_1):PAGE33
   U25  DG6 VSS_DG6 GENOA_SP5-SOCKET6096_13568-001,SMLF,IO,DGA^6000030     I4 @T6G_MB_LIB.T6G(SCH_1):PAGE33
   U25  DG7 VSS_DG7 GENOA_SP5-SOCKET6096_13568-001,SMLF,IO,DGA^6000030     I4 @T6G_MB_LIB.T6G(SCH_1):PAGE33
   U25  DG8 VSS_DG8 GENOA_SP5-SOCKET6096_13568-001,SMLF,IO,DGA^6000030     I4 @T6G_MB_LIB.T6G(SCH_1):PAGE33
   U25  DG9 VSS_DG9 GENOA_SP5-SOCKET6096_13568-001,SMLF,IO,DGA^6000030     I4 @T6G_MB_LIB.T6G(SCH_1):PAGE33
   U25 DG13 VSS_DG13 GENOA_SP5-SOCKET6096_13568-001,SMLF,IO,DGA^6000030     I4 @T6G_MB_LIB.T6G(SCH_1):PAGE33
   U25 DG14 VSS_DG14 GENOA_SP5-SOCKET6096_13568-001,SMLF,IO,DGA^6000030     I4 @T6G_MB_LIB.T6G(SCH_1):PAGE33
   U25 DG15 VSS_DG15 GENOA_SP5-SOCKET6096_13568-001,SMLF,IO,DGA^6000030     I4 @T6G_MB_LIB.T6G(SCH_1):PAGE33
   U25 DG16 VSS_DG16 GENOA_SP5-SOCKET6096_13568-001,SMLF,IO,DGA^6000030     I4 @T6G_MB_LIB.T6G(SCH_1):PAGE33
   U25 DG18 VSS_DG18 GENOA_SP5-SOCKET6096_13568-001,SMLF,IO,DGA^6000030     I4 @T6G_MB_LIB.T6G(SCH_1):PAGE33
   U25 DG20 VSS_DG20 GENOA_SP5-SOCKET6096_13568-001,SMLF,IO,DGA^6000030     I4 @T6G_MB_LIB.T6G(SCH_1):PAGE33
   U25 DG21 VSS_DG21 GENOA_SP5-SOCKET6096_13568-001,SMLF,IO,DGA^6000030     I4 @T6G_MB_LIB.T6G(SCH_1):PAGE33
   U25 DG24 VSS_DG24 GENOA_SP5-SOCKET6096_13568-001,SMLF,IO,DGA^6000030     I4 @T6G_MB_LIB.T6G(SCH_1):PAGE33
   U25 DG27 VSS_DG27 GENOA_SP5-SOCKET6096_13568-001,SMLF,IO,DGA^6000030     I4 @T6G_MB_LIB.T6G(SCH_1):PAGE33
   U25 DG30 VSS_DG30 GENOA_SP5-SOCKET6096_13568-001,SMLF,IO,DGA^6000030     I4 @T6G_MB_LIB.T6G(SCH_1):PAGE33
   U25 DG33 VSS_DG33 GENOA_SP5-SOCKET6096_13568-001,SMLF,IO,DGA^6000030     I4 @T6G_MB_LIB.T6G(SCH_1):PAGE33
   U25 DG41 VSS_DG41 GENOA_SP5-SOCKET6096_13568-001,SMLF,IO,DGA^6000030     I4 @T6G_MB_LIB.T6G(SCH_1):PAGE33
   U25 DG43 VSS_DG43 GENOA_SP5-SOCKET6096_13568-001,SMLF,IO,DGA^6000030     I4 @T6G_MB_LIB.T6G(SCH_1):PAGE33
   U25 DG46 VSS_DG46 GENOA_SP5-SOCKET6096_13568-001,SMLF,IO,DGA^6000030     I4 @T6G_MB_LIB.T6G(SCH_1):PAGE33
   U25 DG49 VSS_DG49 GENOA_SP5-SOCKET6096_13568-001,SMLF,IO,DGA^6000030     I4 @T6G_MB_LIB.T6G(SCH_1):PAGE33
   U25 DG52 VSS_DG52 GENOA_SP5-SOCKET6096_13568-001,SMLF,IO,DGA^6000030     I4 @T6G_MB_LIB.T6G(SCH_1):PAGE33
   U25 DG55 VSS_DG55 GENOA_SP5-SOCKET6096_13568-001,SMLF,IO,DGA^6000030     I4 @T6G_MB_LIB.T6G(SCH_1):PAGE33
   U25 DG56 VSS_DG56 GENOA_SP5-SOCKET6096_13568-001,SMLF,IO,DGA^6000030     I4 @T6G_MB_LIB.T6G(SCH_1):PAGE33
   U25 DG59 VSS_DG59 GENOA_SP5-SOCKET6096_13568-001,SMLF,IO,DGA^6000030     I4 @T6G_MB_LIB.T6G(SCH_1):PAGE33
   U25 DG60 VSS_DG60 GENOA_SP5-SOCKET6096_13568-001,SMLF,IO,DGA^6000030     I4 @T6G_MB_LIB.T6G(SCH_1):PAGE33
   U25 DG61 VSS_DG61 GENOA_SP5-SOCKET6096_13568-001,SMLF,IO,DGA^6000030     I4 @T6G_MB_LIB.T6G(SCH_1):PAGE33
   U25 DG62 VSS_DG62 GENOA_SP5-SOCKET6096_13568-001,SMLF,IO,DGA^6000030     I4 @T6G_MB_LIB.T6G(SCH_1):PAGE33
   U25 DG63 VSS_DG63 GENOA_SP5-SOCKET6096_13568-001,SMLF,IO,DGA^6000030     I4 @T6G_MB_LIB.T6G(SCH_1):PAGE33
   U25 DG65 VSS_DG65 GENOA_SP5-SOCKET6096_13568-001,SMLF,IO,DGA^6000030     I4 @T6G_MB_LIB.T6G(SCH_1):PAGE33
   U25 DG66 VSS_DG66 GENOA_SP5-SOCKET6096_13568-001,SMLF,IO,DGA^6000030     I4 @T6G_MB_LIB.T6G(SCH_1):PAGE33
   U25 DG67 VSS_DG67 GENOA_SP5-SOCKET6096_13568-001,SMLF,IO,DGA^6000030     I4 @T6G_MB_LIB.T6G(SCH_1):PAGE33
   U25 DG68 VSS_DG68 GENOA_SP5-SOCKET6096_13568-001,SMLF,IO,DGA^6000030     I4 @T6G_MB_LIB.T6G(SCH_1):PAGE33
   U25 DG69 VSS_DG69 GENOA_SP5-SOCKET6096_13568-001,SMLF,IO,DGA^6000030     I4 @T6G_MB_LIB.T6G(SCH_1):PAGE33
   U25 DG70 VSS_DG70 GENOA_SP5-SOCKET6096_13568-001,SMLF,IO,DGA^6000030     I4 @T6G_MB_LIB.T6G(SCH_1):PAGE33
   U25 DG74 VSS_DG74 GENOA_SP5-SOCKET6096_13568-001,SMLF,IO,DGA^6000030     I4 @T6G_MB_LIB.T6G(SCH_1):PAGE33
   U25 DG75 VSS_DG75 GENOA_SP5-SOCKET6096_13568-001,SMLF,IO,DGA^6000030     I4 @T6G_MB_LIB.T6G(SCH_1):PAGE33
   U25  DH5 VSS_DH5 GENOA_SP5-SOCKET6096_13568-001,SMLF,IO,DGA^6000030     I4 @T6G_MB_LIB.T6G(SCH_1):PAGE33
   U25 DH11 VSS_DH11 GENOA_SP5-SOCKET6096_13568-001,SMLF,IO,DGA^6000030     I4 @T6G_MB_LIB.T6G(SCH_1):PAGE33
   U25 DH18 VSS_DH18 GENOA_SP5-SOCKET6096_13568-001,SMLF,IO,DGA^6000030     I4 @T6G_MB_LIB.T6G(SCH_1):PAGE33
   U25 DH37 VSS_DH37 GENOA_SP5-SOCKET6096_13568-001,SMLF,IO,DGA^6000030     I4 @T6G_MB_LIB.T6G(SCH_1):PAGE33
   U25 DH39 VSS_DH39 GENOA_SP5-SOCKET6096_13568-001,SMLF,IO,DGA^6000030     I4 @T6G_MB_LIB.T6G(SCH_1):PAGE33
   U25 DH43 VSS_DH43 GENOA_SP5-SOCKET6096_13568-001,SMLF,IO,DGA^6000030     I4 @T6G_MB_LIB.T6G(SCH_1):PAGE33
   U25 DH46 VSS_DH46 GENOA_SP5-SOCKET6096_13568-001,SMLF,IO,DGA^6000030     I4 @T6G_MB_LIB.T6G(SCH_1):PAGE33
   U25 DH49 VSS_DH49 GENOA_SP5-SOCKET6096_13568-001,SMLF,IO,DGA^6000030     I4 @T6G_MB_LIB.T6G(SCH_1):PAGE33
   U25 DH52 VSS_DH52 GENOA_SP5-SOCKET6096_13568-001,SMLF,IO,DGA^6000030     I4 @T6G_MB_LIB.T6G(SCH_1):PAGE33
   U25 DH55 VSS_DH55 GENOA_SP5-SOCKET6096_13568-001,SMLF,IO,DGA^6000030     I4 @T6G_MB_LIB.T6G(SCH_1):PAGE33
   U25 DH59 VSS_DH59 GENOA_SP5-SOCKET6096_13568-001,SMLF,IO,DGA^6000030     I4 @T6G_MB_LIB.T6G(SCH_1):PAGE33
   U25 DH61 VSS_DH61 GENOA_SP5-SOCKET6096_13568-001,SMLF,IO,DGA^6000030     I4 @T6G_MB_LIB.T6G(SCH_1):PAGE33
   U25 DH63 VSS_DH63 GENOA_SP5-SOCKET6096_13568-001,SMLF,IO,DGA^6000030     I4 @T6G_MB_LIB.T6G(SCH_1):PAGE33
   U25 DH64 VSS_DH64 GENOA_SP5-SOCKET6096_13568-001,SMLF,IO,DGA^6000030     I4 @T6G_MB_LIB.T6G(SCH_1):PAGE33
   U25 DH66 VSS_DH66 GENOA_SP5-SOCKET6096_13568-001,SMLF,IO,DGA^6000030     I4 @T6G_MB_LIB.T6G(SCH_1):PAGE33
   U25 DH68 VSS_DH68 GENOA_SP5-SOCKET6096_13568-001,SMLF,IO,DGA^6000030     I4 @T6G_MB_LIB.T6G(SCH_1):PAGE33
   U25 DH70 VSS_DH70 GENOA_SP5-SOCKET6096_13568-001,SMLF,IO,DGA^6000030     I4 @T6G_MB_LIB.T6G(SCH_1):PAGE33
   U25  DJ7 VSS_DJ7 GENOA_SP5-SOCKET6096_13568-001,SMLF,IO,DGA^6000030     I4 @T6G_MB_LIB.T6G(SCH_1):PAGE33
   U25 DJ15 VSS_DJ15 GENOA_SP5-SOCKET6096_13568-001,SMLF,IO,DGA^6000030     I4 @T6G_MB_LIB.T6G(SCH_1):PAGE33
   U25 DJ19 VSS_DJ19 GENOA_SP5-SOCKET6096_13568-001,SMLF,IO,DGA^6000030     I4 @T6G_MB_LIB.T6G(SCH_1):PAGE33
   U25 DJ43 VSS_DJ43 GENOA_SP5-SOCKET6096_13568-001,SMLF,IO,DGA^6000030     I4 @T6G_MB_LIB.T6G(SCH_1):PAGE33
   U25 DJ49 VSS_DJ49 GENOA_SP5-SOCKET6096_13568-001,SMLF,IO,DGA^6000030     I4 @T6G_MB_LIB.T6G(SCH_1):PAGE33
   U25 DJ59 VSS_DJ59 GENOA_SP5-SOCKET6096_13568-001,SMLF,IO,DGA^6000030     I4 @T6G_MB_LIB.T6G(SCH_1):PAGE33
   U25 DJ61 VSS_DJ61 GENOA_SP5-SOCKET6096_13568-001,SMLF,IO,DGA^6000030     I4 @T6G_MB_LIB.T6G(SCH_1):PAGE33
   U25 DJ63 VSS_DJ63 GENOA_SP5-SOCKET6096_13568-001,SMLF,IO,DGA^6000030     I4 @T6G_MB_LIB.T6G(SCH_1):PAGE33
   U25 DJ66 VSS_DJ66 GENOA_SP5-SOCKET6096_13568-001,SMLF,IO,DGA^6000030     I4 @T6G_MB_LIB.T6G(SCH_1):PAGE33
   U25 DJ68 VSS_DJ68 GENOA_SP5-SOCKET6096_13568-001,SMLF,IO,DGA^6000030     I4 @T6G_MB_LIB.T6G(SCH_1):PAGE33
   U25 DJ73 VSS_DJ73 GENOA_SP5-SOCKET6096_13568-001,SMLF,IO,DGA^6000030     I4 @T6G_MB_LIB.T6G(SCH_1):PAGE33
   U25  K23 VSS_K23 GENOA_SP5-SOCKET6096_13568-001,SMLF,IO,DGA^6000030     I4 @T6G_MB_LIB.T6G(SCH_1):PAGE33
   U25  K59 VSS_K59 GENOA_SP5-SOCKET6096_13568-001,SMLF,IO,DGA^6000030     I4 @T6G_MB_LIB.T6G(SCH_1):PAGE33
   U25  P25 VSS_P25 GENOA_SP5-SOCKET6096_13568-001,SMLF,IO,DGA^6000030     I4 @T6G_MB_LIB.T6G(SCH_1):PAGE33
   U25  P68 VSS_P68 GENOA_SP5-SOCKET6096_13568-001,SMLF,IO,DGA^6000030     I4 @T6G_MB_LIB.T6G(SCH_1):PAGE33
   U25  V27 VSS_V27 GENOA_SP5-SOCKET6096_13568-001,SMLF,IO,DGA^6000030     I4 @T6G_MB_LIB.T6G(SCH_1):PAGE33
   U25  V68 VSS_V68 GENOA_SP5-SOCKET6096_13568-001,SMLF,IO,DGA^6000030     I4 @T6G_MB_LIB.T6G(SCH_1):PAGE33
   U27    4    GND PCA9617ADP-PCA9617ADP,SMLF,IC,AL009617K02    I18 @T6G_MB_LIB.T6G(SCH_1):PAGE34
   C42    2      B Q_CAP_0402-0.1UF,25V,10%,X7R,CH4104K1B00    I44 @T6G_MB_LIB.T6G(SCH_1):PAGE34
   C43    2      B Q_CAP_0402-0.1UF,25V,10%,X7R,CH4104K1B00    I47 @T6G_MB_LIB.T6G(SCH_1):PAGE34
  U101    3    GND SN74LVC1G07DBVR_SMLF-SN74LVC1G07DBVR,IC,AL1G0007024    I55 @T6G_MB_LIB.T6G(SCH_1):PAGE34
  C226    2      B Q_CAP_0402-0.1UF,25V,10%,X7R,CH4104K1B00    I59 @T6G_MB_LIB.T6G(SCH_1):PAGE34
   U26  DH8 RTC_LDO_SELECT GENOA_SP5-SOCKET6096_13568-001,SMLF,IO,DGA^6000030   I190 @T6G_MB_LIB.T6G(SCH_1):PAGE54
  C235    2      B Q_CAP_C0402-0.001UF,50V,10%,EMPTY,CH30106KB19   I310 @T6G_MB_LIB.T6G(SCH_1):PAGE54
  C234    2      B Q_CAP_C0402-0.001UF,50V,10%,EMPTY,CH30106KB19   I311 @T6G_MB_LIB.T6G(SCH_1):PAGE54
  C233    2      B Q_CAP_C0402-0.001UF,50V,10%,EMPTY,CH30106KB19   I315 @T6G_MB_LIB.T6G(SCH_1):PAGE54
  C232    2      B Q_CAP_C0402-0.001UF,50V,10%,EMPTY,CH30106KB19   I318 @T6G_MB_LIB.T6G(SCH_1):PAGE54
  C231    2      B Q_CAP_C0402-0.001UF,50V,10%,EMPTY,CH30106KB19   I319 @T6G_MB_LIB.T6G(SCH_1):PAGE54
  C230    2      B Q_CAP_C0402-0.001UF,50V,10%,EMPTY,CH30106KB19   I325 @T6G_MB_LIB.T6G(SCH_1):PAGE54
  R519    2      B Q_RES_0402LF-2.2K,5%,1/16W,EMPTY,CS22202JB07   I404 @T6G_MB_LIB.T6G(SCH_1):PAGE54
  R521    2      B Q_RES_0402LF-2.2K,5%,1/16W,CHIP,CS22202JB07   I405 @T6G_MB_LIB.T6G(SCH_1):PAGE54
  C236    2      B Q_CAP_C0402-2.7PF,50V,0.1PF,NPO,CH-276B0B00     I3 @T6G_MB_LIB.T6G(SCH_1):PAGE55
  C238    2      B Q_CAP_0402-10PF,50V,1%,NPO,TMP_QCH0106F0B00     I5 @T6G_MB_LIB.T6G(SCH_1):PAGE55
  C239    2      B Q_CAP_0402-10PF,50V,1%,NPO,TMP_QCH0106F0B00     I9 @T6G_MB_LIB.T6G(SCH_1):PAGE55
    Y4    2     G1 Q_XTAL_4P_13BI_24GND-48MHZ,SMLF,MISC,BG648000076    I12 @T6G_MB_LIB.T6G(SCH_1):PAGE55
    Y4    4     G2 Q_XTAL_4P_13BI_24GND-48MHZ,SMLF,MISC,BG648000076    I12 @T6G_MB_LIB.T6G(SCH_1):PAGE55
  C237    2      B Q_CAP_C0402-2.7PF,50V,0.1PF,NPO,CH-276B0B00    I15 @T6G_MB_LIB.T6G(SCH_1):PAGE55
   U26   A3 VSS_A3 GENOA_SP5-SOCKET6096_13568-001,SMLF,IO,DGA^6000030     I1 @T6G_MB_LIB.T6G(SCH_1):PAGE58
   U26   A9 VSS_A9 GENOA_SP5-SOCKET6096_13568-001,SMLF,IO,DGA^6000030     I1 @T6G_MB_LIB.T6G(SCH_1):PAGE58
   U26  A15 VSS_A15 GENOA_SP5-SOCKET6096_13568-001,SMLF,IO,DGA^6000030     I1 @T6G_MB_LIB.T6G(SCH_1):PAGE58
   U26  A21 VSS_A21 GENOA_SP5-SOCKET6096_13568-001,SMLF,IO,DGA^6000030     I1 @T6G_MB_LIB.T6G(SCH_1):PAGE58
   U26  A27 VSS_A27 GENOA_SP5-SOCKET6096_13568-001,SMLF,IO,DGA^6000030     I1 @T6G_MB_LIB.T6G(SCH_1):PAGE58
   U26  A43 VSS_A43 GENOA_SP5-SOCKET6096_13568-001,SMLF,IO,DGA^6000030     I1 @T6G_MB_LIB.T6G(SCH_1):PAGE58
   U26  A44 VSS_A44 GENOA_SP5-SOCKET6096_13568-001,SMLF,IO,DGA^6000030     I1 @T6G_MB_LIB.T6G(SCH_1):PAGE58
   U26  A47 VSS_A47 GENOA_SP5-SOCKET6096_13568-001,SMLF,IO,DGA^6000030     I1 @T6G_MB_LIB.T6G(SCH_1):PAGE58
   U26  A49 VSS_A49 GENOA_SP5-SOCKET6096_13568-001,SMLF,IO,DGA^6000030     I1 @T6G_MB_LIB.T6G(SCH_1):PAGE58
   U26  A53 VSS_A53 GENOA_SP5-SOCKET6096_13568-001,SMLF,IO,DGA^6000030     I1 @T6G_MB_LIB.T6G(SCH_1):PAGE58
   U26  A61 VSS_A61 GENOA_SP5-SOCKET6096_13568-001,SMLF,IO,DGA^6000030     I1 @T6G_MB_LIB.T6G(SCH_1):PAGE58
   U26  A67 VSS_A67 GENOA_SP5-SOCKET6096_13568-001,SMLF,IO,DGA^6000030     I1 @T6G_MB_LIB.T6G(SCH_1):PAGE58
   U26  A72 VSS_A72 GENOA_SP5-SOCKET6096_13568-001,SMLF,IO,DGA^6000030     I1 @T6G_MB_LIB.T6G(SCH_1):PAGE58
   U26  A73 VSS_A73 GENOA_SP5-SOCKET6096_13568-001,SMLF,IO,DGA^6000030     I1 @T6G_MB_LIB.T6G(SCH_1):PAGE58
   U26   B7 VSS_B7 GENOA_SP5-SOCKET6096_13568-001,SMLF,IO,DGA^6000030     I1 @T6G_MB_LIB.T6G(SCH_1):PAGE58
   U26   B8 VSS_B8 GENOA_SP5-SOCKET6096_13568-001,SMLF,IO,DGA^6000030     I1 @T6G_MB_LIB.T6G(SCH_1):PAGE58
   U26  B10 VSS_B10 GENOA_SP5-SOCKET6096_13568-001,SMLF,IO,DGA^6000030     I1 @T6G_MB_LIB.T6G(SCH_1):PAGE58
   U26  B11 VSS_B11 GENOA_SP5-SOCKET6096_13568-001,SMLF,IO,DGA^6000030     I1 @T6G_MB_LIB.T6G(SCH_1):PAGE58
   U26  B13 VSS_B13 GENOA_SP5-SOCKET6096_13568-001,SMLF,IO,DGA^6000030     I1 @T6G_MB_LIB.T6G(SCH_1):PAGE58
   U26  B18 VSS_B18 GENOA_SP5-SOCKET6096_13568-001,SMLF,IO,DGA^6000030     I1 @T6G_MB_LIB.T6G(SCH_1):PAGE58
   U26  B24 VSS_B24 GENOA_SP5-SOCKET6096_13568-001,SMLF,IO,DGA^6000030     I1 @T6G_MB_LIB.T6G(SCH_1):PAGE58
   U26  B27 VSS_B27 GENOA_SP5-SOCKET6096_13568-001,SMLF,IO,DGA^6000030     I1 @T6G_MB_LIB.T6G(SCH_1):PAGE58
   U26  B30 VSS_B30 GENOA_SP5-SOCKET6096_13568-001,SMLF,IO,DGA^6000030     I1 @T6G_MB_LIB.T6G(SCH_1):PAGE58
   U26  B33 VSS_B33 GENOA_SP5-SOCKET6096_13568-001,SMLF,IO,DGA^6000030     I1 @T6G_MB_LIB.T6G(SCH_1):PAGE58
   U26  B37 VSS_B37 GENOA_SP5-SOCKET6096_13568-001,SMLF,IO,DGA^6000030     I1 @T6G_MB_LIB.T6G(SCH_1):PAGE58
   U26  B39 VSS_B39 GENOA_SP5-SOCKET6096_13568-001,SMLF,IO,DGA^6000030     I1 @T6G_MB_LIB.T6G(SCH_1):PAGE58
   U26  B43 VSS_B43 GENOA_SP5-SOCKET6096_13568-001,SMLF,IO,DGA^6000030     I1 @T6G_MB_LIB.T6G(SCH_1):PAGE58
   U26  B46 VSS_B46 GENOA_SP5-SOCKET6096_13568-001,SMLF,IO,DGA^6000030     I1 @T6G_MB_LIB.T6G(SCH_1):PAGE58
   U26  B49 VSS_B49 GENOA_SP5-SOCKET6096_13568-001,SMLF,IO,DGA^6000030     I1 @T6G_MB_LIB.T6G(SCH_1):PAGE58
   U26  B52 VSS_B52 GENOA_SP5-SOCKET6096_13568-001,SMLF,IO,DGA^6000030     I1 @T6G_MB_LIB.T6G(SCH_1):PAGE58
   U26  B55 VSS_B55 GENOA_SP5-SOCKET6096_13568-001,SMLF,IO,DGA^6000030     I1 @T6G_MB_LIB.T6G(SCH_1):PAGE58
   U26  B59 VSS_B59 GENOA_SP5-SOCKET6096_13568-001,SMLF,IO,DGA^6000030     I1 @T6G_MB_LIB.T6G(SCH_1):PAGE58
   U26  B62 VSS_B62 GENOA_SP5-SOCKET6096_13568-001,SMLF,IO,DGA^6000030     I1 @T6G_MB_LIB.T6G(SCH_1):PAGE58
   U26  B65 VSS_B65 GENOA_SP5-SOCKET6096_13568-001,SMLF,IO,DGA^6000030     I1 @T6G_MB_LIB.T6G(SCH_1):PAGE58
   U26  B68 VSS_B68 GENOA_SP5-SOCKET6096_13568-001,SMLF,IO,DGA^6000030     I1 @T6G_MB_LIB.T6G(SCH_1):PAGE58
   U26  B70 VSS_B70 GENOA_SP5-SOCKET6096_13568-001,SMLF,IO,DGA^6000030     I1 @T6G_MB_LIB.T6G(SCH_1):PAGE58
   U26   C1 VSS_C1 GENOA_SP5-SOCKET6096_13568-001,SMLF,IO,DGA^6000030     I1 @T6G_MB_LIB.T6G(SCH_1):PAGE58
   U26   C5 VSS_C5 GENOA_SP5-SOCKET6096_13568-001,SMLF,IO,DGA^6000030     I1 @T6G_MB_LIB.T6G(SCH_1):PAGE58
   U26   C8 VSS_C8 GENOA_SP5-SOCKET6096_13568-001,SMLF,IO,DGA^6000030     I1 @T6G_MB_LIB.T6G(SCH_1):PAGE58
   U26  C10 VSS_C10 GENOA_SP5-SOCKET6096_13568-001,SMLF,IO,DGA^6000030     I1 @T6G_MB_LIB.T6G(SCH_1):PAGE58
   U26  C11 VSS_C11 GENOA_SP5-SOCKET6096_13568-001,SMLF,IO,DGA^6000030     I1 @T6G_MB_LIB.T6G(SCH_1):PAGE58
   U26  C13 VSS_C13 GENOA_SP5-SOCKET6096_13568-001,SMLF,IO,DGA^6000030     I1 @T6G_MB_LIB.T6G(SCH_1):PAGE58
   U26  C15 VSS_C15 GENOA_SP5-SOCKET6096_13568-001,SMLF,IO,DGA^6000030     I1 @T6G_MB_LIB.T6G(SCH_1):PAGE58
   U26  C21 VSS_C21 GENOA_SP5-SOCKET6096_13568-001,SMLF,IO,DGA^6000030     I1 @T6G_MB_LIB.T6G(SCH_1):PAGE58
   U26  C24 VSS_C24 GENOA_SP5-SOCKET6096_13568-001,SMLF,IO,DGA^6000030     I1 @T6G_MB_LIB.T6G(SCH_1):PAGE58
   U26  C27 VSS_C27 GENOA_SP5-SOCKET6096_13568-001,SMLF,IO,DGA^6000030     I1 @T6G_MB_LIB.T6G(SCH_1):PAGE58
   U26  C30 VSS_C30 GENOA_SP5-SOCKET6096_13568-001,SMLF,IO,DGA^6000030     I1 @T6G_MB_LIB.T6G(SCH_1):PAGE58
   U26  C36 VSS_C36 GENOA_SP5-SOCKET6096_13568-001,SMLF,IO,DGA^6000030     I1 @T6G_MB_LIB.T6G(SCH_1):PAGE58
   U26  C40 VSS_C40 GENOA_SP5-SOCKET6096_13568-001,SMLF,IO,DGA^6000030     I1 @T6G_MB_LIB.T6G(SCH_1):PAGE58
   U26  C43 VSS_C43 GENOA_SP5-SOCKET6096_13568-001,SMLF,IO,DGA^6000030     I1 @T6G_MB_LIB.T6G(SCH_1):PAGE58
   U26  C46 VSS_C46 GENOA_SP5-SOCKET6096_13568-001,SMLF,IO,DGA^6000030     I1 @T6G_MB_LIB.T6G(SCH_1):PAGE58
   U26  C49 VSS_C49 GENOA_SP5-SOCKET6096_13568-001,SMLF,IO,DGA^6000030     I1 @T6G_MB_LIB.T6G(SCH_1):PAGE58
   U26  C52 VSS_C52 GENOA_SP5-SOCKET6096_13568-001,SMLF,IO,DGA^6000030     I1 @T6G_MB_LIB.T6G(SCH_1):PAGE58
   U26  C55 VSS_C55 GENOA_SP5-SOCKET6096_13568-001,SMLF,IO,DGA^6000030     I1 @T6G_MB_LIB.T6G(SCH_1):PAGE58
   U26  C56 VSS_C56 GENOA_SP5-SOCKET6096_13568-001,SMLF,IO,DGA^6000030     I1 @T6G_MB_LIB.T6G(SCH_1):PAGE58
   U26  C57 VSS_C57 GENOA_SP5-SOCKET6096_13568-001,SMLF,IO,DGA^6000030     I1 @T6G_MB_LIB.T6G(SCH_1):PAGE58
   U26  C61 VSS_C61 GENOA_SP5-SOCKET6096_13568-001,SMLF,IO,DGA^6000030     I1 @T6G_MB_LIB.T6G(SCH_1):PAGE58
   U26  C64 VSS_C64 GENOA_SP5-SOCKET6096_13568-001,SMLF,IO,DGA^6000030     I1 @T6G_MB_LIB.T6G(SCH_1):PAGE58
   U26  C67 VSS_C67 GENOA_SP5-SOCKET6096_13568-001,SMLF,IO,DGA^6000030     I1 @T6G_MB_LIB.T6G(SCH_1):PAGE58
   U26  C69 VSS_C69 GENOA_SP5-SOCKET6096_13568-001,SMLF,IO,DGA^6000030     I1 @T6G_MB_LIB.T6G(SCH_1):PAGE58
   U26  C71 VSS_C71 GENOA_SP5-SOCKET6096_13568-001,SMLF,IO,DGA^6000030     I1 @T6G_MB_LIB.T6G(SCH_1):PAGE58
   U26  C73 VSS_C73 GENOA_SP5-SOCKET6096_13568-001,SMLF,IO,DGA^6000030     I1 @T6G_MB_LIB.T6G(SCH_1):PAGE58
   U26  C75 VSS_C75 GENOA_SP5-SOCKET6096_13568-001,SMLF,IO,DGA^6000030     I1 @T6G_MB_LIB.T6G(SCH_1):PAGE58
   U26   D2 VSS_D2 GENOA_SP5-SOCKET6096_13568-001,SMLF,IO,DGA^6000030     I1 @T6G_MB_LIB.T6G(SCH_1):PAGE58
   U26   D3 VSS_D3 GENOA_SP5-SOCKET6096_13568-001,SMLF,IO,DGA^6000030     I1 @T6G_MB_LIB.T6G(SCH_1):PAGE58
   U26   D5 VSS_D5 GENOA_SP5-SOCKET6096_13568-001,SMLF,IO,DGA^6000030     I1 @T6G_MB_LIB.T6G(SCH_1):PAGE58
   U26   D6 VSS_D6 GENOA_SP5-SOCKET6096_13568-001,SMLF,IO,DGA^6000030     I1 @T6G_MB_LIB.T6G(SCH_1):PAGE58
   U26   D9 VSS_D9 GENOA_SP5-SOCKET6096_13568-001,SMLF,IO,DGA^6000030     I1 @T6G_MB_LIB.T6G(SCH_1):PAGE58
   U26  D10 VSS_D10 GENOA_SP5-SOCKET6096_13568-001,SMLF,IO,DGA^6000030     I1 @T6G_MB_LIB.T6G(SCH_1):PAGE58
   U26  D12 VSS_D12 GENOA_SP5-SOCKET6096_13568-001,SMLF,IO,DGA^6000030     I1 @T6G_MB_LIB.T6G(SCH_1):PAGE58
   U26  D13 VSS_D13 GENOA_SP5-SOCKET6096_13568-001,SMLF,IO,DGA^6000030     I1 @T6G_MB_LIB.T6G(SCH_1):PAGE58
   U26  D16 VSS_D16 GENOA_SP5-SOCKET6096_13568-001,SMLF,IO,DGA^6000030     I1 @T6G_MB_LIB.T6G(SCH_1):PAGE58
   U26  D17 VSS_D17 GENOA_SP5-SOCKET6096_13568-001,SMLF,IO,DGA^6000030     I1 @T6G_MB_LIB.T6G(SCH_1):PAGE58
   U26  D19 VSS_D19 GENOA_SP5-SOCKET6096_13568-001,SMLF,IO,DGA^6000030     I1 @T6G_MB_LIB.T6G(SCH_1):PAGE58
   U26  D20 VSS_D20 GENOA_SP5-SOCKET6096_13568-001,SMLF,IO,DGA^6000030     I1 @T6G_MB_LIB.T6G(SCH_1):PAGE58
   U26  D21 VSS_D21 GENOA_SP5-SOCKET6096_13568-001,SMLF,IO,DGA^6000030     I1 @T6G_MB_LIB.T6G(SCH_1):PAGE58
   U26  D24 VSS_D24 GENOA_SP5-SOCKET6096_13568-001,SMLF,IO,DGA^6000030     I1 @T6G_MB_LIB.T6G(SCH_1):PAGE58
   U26  D25 VSS_D25 GENOA_SP5-SOCKET6096_13568-001,SMLF,IO,DGA^6000030     I1 @T6G_MB_LIB.T6G(SCH_1):PAGE58
   U26  D26 VSS_D26 GENOA_SP5-SOCKET6096_13568-001,SMLF,IO,DGA^6000030     I1 @T6G_MB_LIB.T6G(SCH_1):PAGE58
   U26  D27 VSS_D27 GENOA_SP5-SOCKET6096_13568-001,SMLF,IO,DGA^6000030     I1 @T6G_MB_LIB.T6G(SCH_1):PAGE58
   U26  D28 VSS_D28 GENOA_SP5-SOCKET6096_13568-001,SMLF,IO,DGA^6000030     I1 @T6G_MB_LIB.T6G(SCH_1):PAGE58
   U26  D29 VSS_D29 GENOA_SP5-SOCKET6096_13568-001,SMLF,IO,DGA^6000030     I1 @T6G_MB_LIB.T6G(SCH_1):PAGE58
   U26  D30 VSS_D30 GENOA_SP5-SOCKET6096_13568-001,SMLF,IO,DGA^6000030     I1 @T6G_MB_LIB.T6G(SCH_1):PAGE58
   U26  D31 VSS_D31 GENOA_SP5-SOCKET6096_13568-001,SMLF,IO,DGA^6000030     I1 @T6G_MB_LIB.T6G(SCH_1):PAGE58
   U26  D35 VSS_D35 GENOA_SP5-SOCKET6096_13568-001,SMLF,IO,DGA^6000030     I1 @T6G_MB_LIB.T6G(SCH_1):PAGE58
   U26  D37 VSS_D37 GENOA_SP5-SOCKET6096_13568-001,SMLF,IO,DGA^6000030     I1 @T6G_MB_LIB.T6G(SCH_1):PAGE58
   U26  D39 VSS_D39 GENOA_SP5-SOCKET6096_13568-001,SMLF,IO,DGA^6000030     I1 @T6G_MB_LIB.T6G(SCH_1):PAGE58
   U26  D40 VSS_D40 GENOA_SP5-SOCKET6096_13568-001,SMLF,IO,DGA^6000030     I1 @T6G_MB_LIB.T6G(SCH_1):PAGE58
   U26  D41 VSS_D41 GENOA_SP5-SOCKET6096_13568-001,SMLF,IO,DGA^6000030     I1 @T6G_MB_LIB.T6G(SCH_1):PAGE58
   U26  D42 VSS_D42 GENOA_SP5-SOCKET6096_13568-001,SMLF,IO,DGA^6000030     I1 @T6G_MB_LIB.T6G(SCH_1):PAGE58
   U26  D43 VSS_D43 GENOA_SP5-SOCKET6096_13568-001,SMLF,IO,DGA^6000030     I1 @T6G_MB_LIB.T6G(SCH_1):PAGE58
   U26  D44 VSS_D44 GENOA_SP5-SOCKET6096_13568-001,SMLF,IO,DGA^6000030     I1 @T6G_MB_LIB.T6G(SCH_1):PAGE58
   U26  D45 VSS_D45 GENOA_SP5-SOCKET6096_13568-001,SMLF,IO,DGA^6000030     I1 @T6G_MB_LIB.T6G(SCH_1):PAGE58
   U26  D46 VSS_D46 GENOA_SP5-SOCKET6096_13568-001,SMLF,IO,DGA^6000030     I1 @T6G_MB_LIB.T6G(SCH_1):PAGE58
   U26  D47 VSS_D47 GENOA_SP5-SOCKET6096_13568-001,SMLF,IO,DGA^6000030     I1 @T6G_MB_LIB.T6G(SCH_1):PAGE58
   U26  D48 VSS_D48 GENOA_SP5-SOCKET6096_13568-001,SMLF,IO,DGA^6000030     I1 @T6G_MB_LIB.T6G(SCH_1):PAGE58
   U26  D49 VSS_D49 GENOA_SP5-SOCKET6096_13568-001,SMLF,IO,DGA^6000030     I1 @T6G_MB_LIB.T6G(SCH_1):PAGE58
   U26  D50 VSS_D50 GENOA_SP5-SOCKET6096_13568-001,SMLF,IO,DGA^6000030     I1 @T6G_MB_LIB.T6G(SCH_1):PAGE58
   U26  D51 VSS_D51 GENOA_SP5-SOCKET6096_13568-001,SMLF,IO,DGA^6000030     I1 @T6G_MB_LIB.T6G(SCH_1):PAGE58
   U26  D52 VSS_D52 GENOA_SP5-SOCKET6096_13568-001,SMLF,IO,DGA^6000030     I1 @T6G_MB_LIB.T6G(SCH_1):PAGE58
   U26  D53 VSS_D53 GENOA_SP5-SOCKET6096_13568-001,SMLF,IO,DGA^6000030     I1 @T6G_MB_LIB.T6G(SCH_1):PAGE58
   U26  D54 VSS_D54 GENOA_SP5-SOCKET6096_13568-001,SMLF,IO,DGA^6000030     I1 @T6G_MB_LIB.T6G(SCH_1):PAGE58
   U26  D57 VSS_D57 GENOA_SP5-SOCKET6096_13568-001,SMLF,IO,DGA^6000030     I1 @T6G_MB_LIB.T6G(SCH_1):PAGE58
   U26  D59 VSS_D59 GENOA_SP5-SOCKET6096_13568-001,SMLF,IO,DGA^6000030     I1 @T6G_MB_LIB.T6G(SCH_1):PAGE58
   U26  D60 VSS_D60 GENOA_SP5-SOCKET6096_13568-001,SMLF,IO,DGA^6000030     I1 @T6G_MB_LIB.T6G(SCH_1):PAGE58
   U26  D61 VSS_D61 GENOA_SP5-SOCKET6096_13568-001,SMLF,IO,DGA^6000030     I1 @T6G_MB_LIB.T6G(SCH_1):PAGE58
   U26  D63 VSS_D63 GENOA_SP5-SOCKET6096_13568-001,SMLF,IO,DGA^6000030     I1 @T6G_MB_LIB.T6G(SCH_1):PAGE58
   U26  D64 VSS_D64 GENOA_SP5-SOCKET6096_13568-001,SMLF,IO,DGA^6000030     I1 @T6G_MB_LIB.T6G(SCH_1):PAGE58
   U26  D66 VSS_D66 GENOA_SP5-SOCKET6096_13568-001,SMLF,IO,DGA^6000030     I1 @T6G_MB_LIB.T6G(SCH_1):PAGE58
   U26  D67 VSS_D67 GENOA_SP5-SOCKET6096_13568-001,SMLF,IO,DGA^6000030     I1 @T6G_MB_LIB.T6G(SCH_1):PAGE58
   U26  D70 VSS_D70 GENOA_SP5-SOCKET6096_13568-001,SMLF,IO,DGA^6000030     I1 @T6G_MB_LIB.T6G(SCH_1):PAGE58
   U26  D71 VSS_D71 GENOA_SP5-SOCKET6096_13568-001,SMLF,IO,DGA^6000030     I1 @T6G_MB_LIB.T6G(SCH_1):PAGE58
   U26  D73 VSS_D73 GENOA_SP5-SOCKET6096_13568-001,SMLF,IO,DGA^6000030     I1 @T6G_MB_LIB.T6G(SCH_1):PAGE58
   U26  D74 VSS_D74 GENOA_SP5-SOCKET6096_13568-001,SMLF,IO,DGA^6000030     I1 @T6G_MB_LIB.T6G(SCH_1):PAGE58
   U26   E1 VSS_E1 GENOA_SP5-SOCKET6096_13568-001,SMLF,IO,DGA^6000030     I1 @T6G_MB_LIB.T6G(SCH_1):PAGE58
   U26   E3 VSS_E3 GENOA_SP5-SOCKET6096_13568-001,SMLF,IO,DGA^6000030     I1 @T6G_MB_LIB.T6G(SCH_1):PAGE58
   U26   E6 VSS_E6 GENOA_SP5-SOCKET6096_13568-001,SMLF,IO,DGA^6000030     I1 @T6G_MB_LIB.T6G(SCH_1):PAGE58
   U26   E7 VSS_E7 GENOA_SP5-SOCKET6096_13568-001,SMLF,IO,DGA^6000030     I1 @T6G_MB_LIB.T6G(SCH_1):PAGE58
   U26   E8 VSS_E8 GENOA_SP5-SOCKET6096_13568-001,SMLF,IO,DGA^6000030     I1 @T6G_MB_LIB.T6G(SCH_1):PAGE58
   U26  E10 VSS_E10 GENOA_SP5-SOCKET6096_13568-001,SMLF,IO,DGA^6000030     I1 @T6G_MB_LIB.T6G(SCH_1):PAGE58
   U26  E13 VSS_E13 GENOA_SP5-SOCKET6096_13568-001,SMLF,IO,DGA^6000030     I1 @T6G_MB_LIB.T6G(SCH_1):PAGE58
   U26  E14 VSS_E14 GENOA_SP5-SOCKET6096_13568-001,SMLF,IO,DGA^6000030     I1 @T6G_MB_LIB.T6G(SCH_1):PAGE58
   U26  E15 VSS_E15 GENOA_SP5-SOCKET6096_13568-001,SMLF,IO,DGA^6000030     I1 @T6G_MB_LIB.T6G(SCH_1):PAGE58
   U26  E17 VSS_E17 GENOA_SP5-SOCKET6096_13568-001,SMLF,IO,DGA^6000030     I1 @T6G_MB_LIB.T6G(SCH_1):PAGE58
   U26  E18 VSS_E18 GENOA_SP5-SOCKET6096_13568-001,SMLF,IO,DGA^6000030     I1 @T6G_MB_LIB.T6G(SCH_1):PAGE58
   U26  E20 VSS_E20 GENOA_SP5-SOCKET6096_13568-001,SMLF,IO,DGA^6000030     I1 @T6G_MB_LIB.T6G(SCH_1):PAGE58
   U26  E21 VSS_E21 GENOA_SP5-SOCKET6096_13568-001,SMLF,IO,DGA^6000030     I1 @T6G_MB_LIB.T6G(SCH_1):PAGE58
   U26  E52 VSS_E52 GENOA_SP5-SOCKET6096_13568-001,SMLF,IO,DGA^6000030     I1 @T6G_MB_LIB.T6G(SCH_1):PAGE58
   U26  E53 VSS_E53 GENOA_SP5-SOCKET6096_13568-001,SMLF,IO,DGA^6000030     I1 @T6G_MB_LIB.T6G(SCH_1):PAGE58
   U26  E55 VSS_E55 GENOA_SP5-SOCKET6096_13568-001,SMLF,IO,DGA^6000030     I1 @T6G_MB_LIB.T6G(SCH_1):PAGE58
   U26  E56 VSS_E56 GENOA_SP5-SOCKET6096_13568-001,SMLF,IO,DGA^6000030     I1 @T6G_MB_LIB.T6G(SCH_1):PAGE58
   U26  E58 VSS_E58 GENOA_SP5-SOCKET6096_13568-001,SMLF,IO,DGA^6000030     I1 @T6G_MB_LIB.T6G(SCH_1):PAGE58
   U26  E59 VSS_E59 GENOA_SP5-SOCKET6096_13568-001,SMLF,IO,DGA^6000030     I1 @T6G_MB_LIB.T6G(SCH_1):PAGE58
   U26  E61 VSS_E61 GENOA_SP5-SOCKET6096_13568-001,SMLF,IO,DGA^6000030     I1 @T6G_MB_LIB.T6G(SCH_1):PAGE58
   U26  E62 VSS_E62 GENOA_SP5-SOCKET6096_13568-001,SMLF,IO,DGA^6000030     I1 @T6G_MB_LIB.T6G(SCH_1):PAGE58
   U26  E63 VSS_E63 GENOA_SP5-SOCKET6096_13568-001,SMLF,IO,DGA^6000030     I1 @T6G_MB_LIB.T6G(SCH_1):PAGE58
   U26  E65 VSS_E65 GENOA_SP5-SOCKET6096_13568-001,SMLF,IO,DGA^6000030     I1 @T6G_MB_LIB.T6G(SCH_1):PAGE58
   U26  E66 VSS_E66 GENOA_SP5-SOCKET6096_13568-001,SMLF,IO,DGA^6000030     I1 @T6G_MB_LIB.T6G(SCH_1):PAGE58
   U26  E68 VSS_E68 GENOA_SP5-SOCKET6096_13568-001,SMLF,IO,DGA^6000030     I1 @T6G_MB_LIB.T6G(SCH_1):PAGE58
   U26  E69 VSS_E69 GENOA_SP5-SOCKET6096_13568-001,SMLF,IO,DGA^6000030     I1 @T6G_MB_LIB.T6G(SCH_1):PAGE58
   U26  E70 VSS_E70 GENOA_SP5-SOCKET6096_13568-001,SMLF,IO,DGA^6000030     I1 @T6G_MB_LIB.T6G(SCH_1):PAGE58
   U26  E72 VSS_E72 GENOA_SP5-SOCKET6096_13568-001,SMLF,IO,DGA^6000030     I1 @T6G_MB_LIB.T6G(SCH_1):PAGE58
   U26  E73 VSS_E73 GENOA_SP5-SOCKET6096_13568-001,SMLF,IO,DGA^6000030     I1 @T6G_MB_LIB.T6G(SCH_1):PAGE58
   U26  E75 VSS_E75 GENOA_SP5-SOCKET6096_13568-001,SMLF,IO,DGA^6000030     I1 @T6G_MB_LIB.T6G(SCH_1):PAGE58
   U26   F3 VSS_F3 GENOA_SP5-SOCKET6096_13568-001,SMLF,IO,DGA^6000030     I1 @T6G_MB_LIB.T6G(SCH_1):PAGE58
   U26   F5 VSS_F5 GENOA_SP5-SOCKET6096_13568-001,SMLF,IO,DGA^6000030     I1 @T6G_MB_LIB.T6G(SCH_1):PAGE58
   U26   F8 VSS_F8 GENOA_SP5-SOCKET6096_13568-001,SMLF,IO,DGA^6000030     I1 @T6G_MB_LIB.T6G(SCH_1):PAGE58
   U26  F10 VSS_F10 GENOA_SP5-SOCKET6096_13568-001,SMLF,IO,DGA^6000030     I1 @T6G_MB_LIB.T6G(SCH_1):PAGE58
   U26  F12 VSS_F12 GENOA_SP5-SOCKET6096_13568-001,SMLF,IO,DGA^6000030     I1 @T6G_MB_LIB.T6G(SCH_1):PAGE58
   U26  F15 VSS_F15 GENOA_SP5-SOCKET6096_13568-001,SMLF,IO,DGA^6000030     I1 @T6G_MB_LIB.T6G(SCH_1):PAGE58
   U26  F17 VSS_F17 GENOA_SP5-SOCKET6096_13568-001,SMLF,IO,DGA^6000030     I1 @T6G_MB_LIB.T6G(SCH_1):PAGE58
   U26  F19 VSS_F19 GENOA_SP5-SOCKET6096_13568-001,SMLF,IO,DGA^6000030     I1 @T6G_MB_LIB.T6G(SCH_1):PAGE58
   U26  F23 VSS_F23 GENOA_SP5-SOCKET6096_13568-001,SMLF,IO,DGA^6000030     I1 @T6G_MB_LIB.T6G(SCH_1):PAGE58
   U26  F24 VSS_F24 GENOA_SP5-SOCKET6096_13568-001,SMLF,IO,DGA^6000030     I1 @T6G_MB_LIB.T6G(SCH_1):PAGE58
   U26  F26 VSS_F26 GENOA_SP5-SOCKET6096_13568-001,SMLF,IO,DGA^6000030     I1 @T6G_MB_LIB.T6G(SCH_1):PAGE58
   U26  F27 VSS_F27 GENOA_SP5-SOCKET6096_13568-001,SMLF,IO,DGA^6000030     I1 @T6G_MB_LIB.T6G(SCH_1):PAGE58
   U26  F29 VSS_F29 GENOA_SP5-SOCKET6096_13568-001,SMLF,IO,DGA^6000030     I1 @T6G_MB_LIB.T6G(SCH_1):PAGE58
   U26  F30 VSS_F30 GENOA_SP5-SOCKET6096_13568-001,SMLF,IO,DGA^6000030     I1 @T6G_MB_LIB.T6G(SCH_1):PAGE58
   U26  F32 VSS_F32 GENOA_SP5-SOCKET6096_13568-001,SMLF,IO,DGA^6000030     I1 @T6G_MB_LIB.T6G(SCH_1):PAGE58
   U26  F33 VSS_F33 GENOA_SP5-SOCKET6096_13568-001,SMLF,IO,DGA^6000030     I1 @T6G_MB_LIB.T6G(SCH_1):PAGE58
   U26  F35 VSS_F35 GENOA_SP5-SOCKET6096_13568-001,SMLF,IO,DGA^6000030     I1 @T6G_MB_LIB.T6G(SCH_1):PAGE58
   U26  F36 VSS_F36 GENOA_SP5-SOCKET6096_13568-001,SMLF,IO,DGA^6000030     I1 @T6G_MB_LIB.T6G(SCH_1):PAGE58
   U26  F37 VSS_F37 GENOA_SP5-SOCKET6096_13568-001,SMLF,IO,DGA^6000030     I1 @T6G_MB_LIB.T6G(SCH_1):PAGE58
   U26  F39 VSS_F39 GENOA_SP5-SOCKET6096_13568-001,SMLF,IO,DGA^6000030     I1 @T6G_MB_LIB.T6G(SCH_1):PAGE58
   U26  F40 VSS_F40 GENOA_SP5-SOCKET6096_13568-001,SMLF,IO,DGA^6000030     I1 @T6G_MB_LIB.T6G(SCH_1):PAGE58
   U26  F41 VSS_F41 GENOA_SP5-SOCKET6096_13568-001,SMLF,IO,DGA^6000030     I1 @T6G_MB_LIB.T6G(SCH_1):PAGE58
   U26  F43 VSS_F43 GENOA_SP5-SOCKET6096_13568-001,SMLF,IO,DGA^6000030     I1 @T6G_MB_LIB.T6G(SCH_1):PAGE58
   U26  F44 VSS_F44 GENOA_SP5-SOCKET6096_13568-001,SMLF,IO,DGA^6000030     I1 @T6G_MB_LIB.T6G(SCH_1):PAGE58
   U26  F46 VSS_F46 GENOA_SP5-SOCKET6096_13568-001,SMLF,IO,DGA^6000030     I1 @T6G_MB_LIB.T6G(SCH_1):PAGE58
   U26  F47 VSS_F47 GENOA_SP5-SOCKET6096_13568-001,SMLF,IO,DGA^6000030     I1 @T6G_MB_LIB.T6G(SCH_1):PAGE58
   U26  F49 VSS_F49 GENOA_SP5-SOCKET6096_13568-001,SMLF,IO,DGA^6000030     I1 @T6G_MB_LIB.T6G(SCH_1):PAGE58
   U26  F50 VSS_F50 GENOA_SP5-SOCKET6096_13568-001,SMLF,IO,DGA^6000030     I1 @T6G_MB_LIB.T6G(SCH_1):PAGE58
   U26  F52 VSS_F52 GENOA_SP5-SOCKET6096_13568-001,SMLF,IO,DGA^6000030     I1 @T6G_MB_LIB.T6G(SCH_1):PAGE58
   U26  F53 VSS_F53 GENOA_SP5-SOCKET6096_13568-001,SMLF,IO,DGA^6000030     I1 @T6G_MB_LIB.T6G(SCH_1):PAGE58
   U26  F57 VSS_F57 GENOA_SP5-SOCKET6096_13568-001,SMLF,IO,DGA^6000030     I1 @T6G_MB_LIB.T6G(SCH_1):PAGE58
   U26  F59 VSS_F59 GENOA_SP5-SOCKET6096_13568-001,SMLF,IO,DGA^6000030     I1 @T6G_MB_LIB.T6G(SCH_1):PAGE58
   U26  F61 VSS_F61 GENOA_SP5-SOCKET6096_13568-001,SMLF,IO,DGA^6000030     I1 @T6G_MB_LIB.T6G(SCH_1):PAGE58
   U26  F64 VSS_F64 GENOA_SP5-SOCKET6096_13568-001,SMLF,IO,DGA^6000030     I1 @T6G_MB_LIB.T6G(SCH_1):PAGE58
   U26  F66 VSS_F66 GENOA_SP5-SOCKET6096_13568-001,SMLF,IO,DGA^6000030     I1 @T6G_MB_LIB.T6G(SCH_1):PAGE58
   U26  F68 VSS_F68 GENOA_SP5-SOCKET6096_13568-001,SMLF,IO,DGA^6000030     I1 @T6G_MB_LIB.T6G(SCH_1):PAGE58
   U26  F71 VSS_F71 GENOA_SP5-SOCKET6096_13568-001,SMLF,IO,DGA^6000030     I1 @T6G_MB_LIB.T6G(SCH_1):PAGE58
   U26  F73 VSS_F73 GENOA_SP5-SOCKET6096_13568-001,SMLF,IO,DGA^6000030     I1 @T6G_MB_LIB.T6G(SCH_1):PAGE58
   U26   G1 VSS_G1 GENOA_SP5-SOCKET6096_13568-001,SMLF,IO,DGA^6000030     I1 @T6G_MB_LIB.T6G(SCH_1):PAGE58
   U26   G4 VSS_G4 GENOA_SP5-SOCKET6096_13568-001,SMLF,IO,DGA^6000030     I1 @T6G_MB_LIB.T6G(SCH_1):PAGE58
   U26   G6 VSS_G6 GENOA_SP5-SOCKET6096_13568-001,SMLF,IO,DGA^6000030     I1 @T6G_MB_LIB.T6G(SCH_1):PAGE58
   U26   G8 VSS_G8 GENOA_SP5-SOCKET6096_13568-001,SMLF,IO,DGA^6000030     I1 @T6G_MB_LIB.T6G(SCH_1):PAGE58
   U26  G11 VSS_G11 GENOA_SP5-SOCKET6096_13568-001,SMLF,IO,DGA^6000030     I1 @T6G_MB_LIB.T6G(SCH_1):PAGE58
   U26  G13 VSS_G13 GENOA_SP5-SOCKET6096_13568-001,SMLF,IO,DGA^6000030     I1 @T6G_MB_LIB.T6G(SCH_1):PAGE58
   U26  G15 VSS_G15 GENOA_SP5-SOCKET6096_13568-001,SMLF,IO,DGA^6000030     I1 @T6G_MB_LIB.T6G(SCH_1):PAGE58
   U26  G18 VSS_G18 GENOA_SP5-SOCKET6096_13568-001,SMLF,IO,DGA^6000030     I1 @T6G_MB_LIB.T6G(SCH_1):PAGE58
   U26  G20 VSS_G20 GENOA_SP5-SOCKET6096_13568-001,SMLF,IO,DGA^6000030     I1 @T6G_MB_LIB.T6G(SCH_1):PAGE58
   U26  G22 VSS_G22 GENOA_SP5-SOCKET6096_13568-001,SMLF,IO,DGA^6000030     I1 @T6G_MB_LIB.T6G(SCH_1):PAGE58
   U26  G25 VSS_G25 GENOA_SP5-SOCKET6096_13568-001,SMLF,IO,DGA^6000030     I1 @T6G_MB_LIB.T6G(SCH_1):PAGE58
   U26  G28 VSS_G28 GENOA_SP5-SOCKET6096_13568-001,SMLF,IO,DGA^6000030     I1 @T6G_MB_LIB.T6G(SCH_1):PAGE58
   U26  G31 VSS_G31 GENOA_SP5-SOCKET6096_13568-001,SMLF,IO,DGA^6000030     I1 @T6G_MB_LIB.T6G(SCH_1):PAGE58
   U26  G34 VSS_G34 GENOA_SP5-SOCKET6096_13568-001,SMLF,IO,DGA^6000030     I1 @T6G_MB_LIB.T6G(SCH_1):PAGE58
   U26  G42 VSS_G42 GENOA_SP5-SOCKET6096_13568-001,SMLF,IO,DGA^6000030     I1 @T6G_MB_LIB.T6G(SCH_1):PAGE58
   U26  G45 VSS_G45 GENOA_SP5-SOCKET6096_13568-001,SMLF,IO,DGA^6000030     I1 @T6G_MB_LIB.T6G(SCH_1):PAGE58
   U26  G48 VSS_G48 GENOA_SP5-SOCKET6096_13568-001,SMLF,IO,DGA^6000030     I1 @T6G_MB_LIB.T6G(SCH_1):PAGE58
   U26  G51 VSS_G51 GENOA_SP5-SOCKET6096_13568-001,SMLF,IO,DGA^6000030     I1 @T6G_MB_LIB.T6G(SCH_1):PAGE58
   U26  G54 VSS_G54 GENOA_SP5-SOCKET6096_13568-001,SMLF,IO,DGA^6000030     I1 @T6G_MB_LIB.T6G(SCH_1):PAGE58
   U26  G56 VSS_G56 GENOA_SP5-SOCKET6096_13568-001,SMLF,IO,DGA^6000030     I1 @T6G_MB_LIB.T6G(SCH_1):PAGE58
   U26  G58 VSS_G58 GENOA_SP5-SOCKET6096_13568-001,SMLF,IO,DGA^6000030     I1 @T6G_MB_LIB.T6G(SCH_1):PAGE58
   U26  G61 VSS_G61 GENOA_SP5-SOCKET6096_13568-001,SMLF,IO,DGA^6000030     I1 @T6G_MB_LIB.T6G(SCH_1):PAGE58
   U26  G63 VSS_G63 GENOA_SP5-SOCKET6096_13568-001,SMLF,IO,DGA^6000030     I1 @T6G_MB_LIB.T6G(SCH_1):PAGE58
   U26  G65 VSS_G65 GENOA_SP5-SOCKET6096_13568-001,SMLF,IO,DGA^6000030     I1 @T6G_MB_LIB.T6G(SCH_1):PAGE58
   U26  G68 VSS_G68 GENOA_SP5-SOCKET6096_13568-001,SMLF,IO,DGA^6000030     I1 @T6G_MB_LIB.T6G(SCH_1):PAGE58
   U26  G70 VSS_G70 GENOA_SP5-SOCKET6096_13568-001,SMLF,IO,DGA^6000030     I1 @T6G_MB_LIB.T6G(SCH_1):PAGE58
   U26  G72 VSS_G72 GENOA_SP5-SOCKET6096_13568-001,SMLF,IO,DGA^6000030     I1 @T6G_MB_LIB.T6G(SCH_1):PAGE58
   U26  G75 VSS_G75 GENOA_SP5-SOCKET6096_13568-001,SMLF,IO,DGA^6000030     I1 @T6G_MB_LIB.T6G(SCH_1):PAGE58
   U26   H3 VSS_H3 GENOA_SP5-SOCKET6096_13568-001,SMLF,IO,DGA^6000030     I1 @T6G_MB_LIB.T6G(SCH_1):PAGE58
   U26   H8 VSS_H8 GENOA_SP5-SOCKET6096_13568-001,SMLF,IO,DGA^6000030     I1 @T6G_MB_LIB.T6G(SCH_1):PAGE58
   U26  H10 VSS_H10 GENOA_SP5-SOCKET6096_13568-001,SMLF,IO,DGA^6000030     I1 @T6G_MB_LIB.T6G(SCH_1):PAGE58
   U26  H15 VSS_H15 GENOA_SP5-SOCKET6096_13568-001,SMLF,IO,DGA^6000030     I1 @T6G_MB_LIB.T6G(SCH_1):PAGE58
   U26  H17 VSS_H17 GENOA_SP5-SOCKET6096_13568-001,SMLF,IO,DGA^6000030     I1 @T6G_MB_LIB.T6G(SCH_1):PAGE58
   U26  H22 VSS_H22 GENOA_SP5-SOCKET6096_13568-001,SMLF,IO,DGA^6000030     I1 @T6G_MB_LIB.T6G(SCH_1):PAGE58
   U26  H25 VSS_H25 GENOA_SP5-SOCKET6096_13568-001,SMLF,IO,DGA^6000030     I1 @T6G_MB_LIB.T6G(SCH_1):PAGE58
   U26  H28 VSS_H28 GENOA_SP5-SOCKET6096_13568-001,SMLF,IO,DGA^6000030     I1 @T6G_MB_LIB.T6G(SCH_1):PAGE58
   U26  H31 VSS_H31 GENOA_SP5-SOCKET6096_13568-001,SMLF,IO,DGA^6000030     I1 @T6G_MB_LIB.T6G(SCH_1):PAGE58
   U26  H34 VSS_H34 GENOA_SP5-SOCKET6096_13568-001,SMLF,IO,DGA^6000030     I1 @T6G_MB_LIB.T6G(SCH_1):PAGE58
   U26  H37 VSS_H37 GENOA_SP5-SOCKET6096_13568-001,SMLF,IO,DGA^6000030     I1 @T6G_MB_LIB.T6G(SCH_1):PAGE58
   U26  H39 VSS_H39 GENOA_SP5-SOCKET6096_13568-001,SMLF,IO,DGA^6000030     I1 @T6G_MB_LIB.T6G(SCH_1):PAGE58
   U26  H42 VSS_H42 GENOA_SP5-SOCKET6096_13568-001,SMLF,IO,DGA^6000030     I1 @T6G_MB_LIB.T6G(SCH_1):PAGE58
   U26  H45 VSS_H45 GENOA_SP5-SOCKET6096_13568-001,SMLF,IO,DGA^6000030     I1 @T6G_MB_LIB.T6G(SCH_1):PAGE58
   U26  H48 VSS_H48 GENOA_SP5-SOCKET6096_13568-001,SMLF,IO,DGA^6000030     I1 @T6G_MB_LIB.T6G(SCH_1):PAGE58
   U26  H51 VSS_H51 GENOA_SP5-SOCKET6096_13568-001,SMLF,IO,DGA^6000030     I1 @T6G_MB_LIB.T6G(SCH_1):PAGE58
   U26  H54 VSS_H54 GENOA_SP5-SOCKET6096_13568-001,SMLF,IO,DGA^6000030     I1 @T6G_MB_LIB.T6G(SCH_1):PAGE58
   U26  H59 VSS_H59 GENOA_SP5-SOCKET6096_13568-001,SMLF,IO,DGA^6000030     I1 @T6G_MB_LIB.T6G(SCH_1):PAGE58
   U26  H61 VSS_H61 GENOA_SP5-SOCKET6096_13568-001,SMLF,IO,DGA^6000030     I1 @T6G_MB_LIB.T6G(SCH_1):PAGE58
   U26  H66 VSS_H66 GENOA_SP5-SOCKET6096_13568-001,SMLF,IO,DGA^6000030     I1 @T6G_MB_LIB.T6G(SCH_1):PAGE58
   U26  H68 VSS_H68 GENOA_SP5-SOCKET6096_13568-001,SMLF,IO,DGA^6000030     I1 @T6G_MB_LIB.T6G(SCH_1):PAGE58
   U26  H73 VSS_H73 GENOA_SP5-SOCKET6096_13568-001,SMLF,IO,DGA^6000030     I1 @T6G_MB_LIB.T6G(SCH_1):PAGE58
   U26   J1 VSS_J1 GENOA_SP5-SOCKET6096_13568-001,SMLF,IO,DGA^6000030     I1 @T6G_MB_LIB.T6G(SCH_1):PAGE58
   U26   J4 VSS_J4 GENOA_SP5-SOCKET6096_13568-001,SMLF,IO,DGA^6000030     I1 @T6G_MB_LIB.T6G(SCH_1):PAGE58
   U26   J6 VSS_J6 GENOA_SP5-SOCKET6096_13568-001,SMLF,IO,DGA^6000030     I1 @T6G_MB_LIB.T6G(SCH_1):PAGE58
   U26   J8 VSS_J8 GENOA_SP5-SOCKET6096_13568-001,SMLF,IO,DGA^6000030     I1 @T6G_MB_LIB.T6G(SCH_1):PAGE58
   U26  J11 VSS_J11 GENOA_SP5-SOCKET6096_13568-001,SMLF,IO,DGA^6000030     I1 @T6G_MB_LIB.T6G(SCH_1):PAGE58
   U26  J13 VSS_J13 GENOA_SP5-SOCKET6096_13568-001,SMLF,IO,DGA^6000030     I1 @T6G_MB_LIB.T6G(SCH_1):PAGE58
   U26 AW63 VSS_AW63 GENOA_SP5-SOCKET6096_13568-001,SMLF,IO,DGA^6000030     I3 @T6G_MB_LIB.T6G(SCH_1):PAGE58
   U26 AW65 VSS_AW65 GENOA_SP5-SOCKET6096_13568-001,SMLF,IO,DGA^6000030     I3 @T6G_MB_LIB.T6G(SCH_1):PAGE58
   U26 AW68 VSS_AW68 GENOA_SP5-SOCKET6096_13568-001,SMLF,IO,DGA^6000030     I3 @T6G_MB_LIB.T6G(SCH_1):PAGE58
   U26 AW70 VSS_AW70 GENOA_SP5-SOCKET6096_13568-001,SMLF,IO,DGA^6000030     I3 @T6G_MB_LIB.T6G(SCH_1):PAGE58
   U26 AW72 VSS_AW72 GENOA_SP5-SOCKET6096_13568-001,SMLF,IO,DGA^6000030     I3 @T6G_MB_LIB.T6G(SCH_1):PAGE58
   U26 AW75 VSS_AW75 GENOA_SP5-SOCKET6096_13568-001,SMLF,IO,DGA^6000030     I3 @T6G_MB_LIB.T6G(SCH_1):PAGE58
   U26  AY3 VSS_AY3 GENOA_SP5-SOCKET6096_13568-001,SMLF,IO,DGA^6000030     I3 @T6G_MB_LIB.T6G(SCH_1):PAGE58
   U26  AY5 VSS_AY5 GENOA_SP5-SOCKET6096_13568-001,SMLF,IO,DGA^6000030     I3 @T6G_MB_LIB.T6G(SCH_1):PAGE58
   U26  AY8 VSS_AY8 GENOA_SP5-SOCKET6096_13568-001,SMLF,IO,DGA^6000030     I3 @T6G_MB_LIB.T6G(SCH_1):PAGE58
   U26 AY10 VSS_AY10 GENOA_SP5-SOCKET6096_13568-001,SMLF,IO,DGA^6000030     I3 @T6G_MB_LIB.T6G(SCH_1):PAGE58
   U26 AY12 VSS_AY12 GENOA_SP5-SOCKET6096_13568-001,SMLF,IO,DGA^6000030     I3 @T6G_MB_LIB.T6G(SCH_1):PAGE58
   U26 AY15 VSS_AY15 GENOA_SP5-SOCKET6096_13568-001,SMLF,IO,DGA^6000030     I3 @T6G_MB_LIB.T6G(SCH_1):PAGE58
   U26 AY17 VSS_AY17 GENOA_SP5-SOCKET6096_13568-001,SMLF,IO,DGA^6000030     I3 @T6G_MB_LIB.T6G(SCH_1):PAGE58
   U26 AY19 VSS_AY19 GENOA_SP5-SOCKET6096_13568-001,SMLF,IO,DGA^6000030     I3 @T6G_MB_LIB.T6G(SCH_1):PAGE58
   U26 AY23 VSS_AY23 GENOA_SP5-SOCKET6096_13568-001,SMLF,IO,DGA^6000030     I3 @T6G_MB_LIB.T6G(SCH_1):PAGE58
   U26 AY25 VSS_AY25 GENOA_SP5-SOCKET6096_13568-001,SMLF,IO,DGA^6000030     I3 @T6G_MB_LIB.T6G(SCH_1):PAGE58
   U26 AY27 VSS_AY27 GENOA_SP5-SOCKET6096_13568-001,SMLF,IO,DGA^6000030     I3 @T6G_MB_LIB.T6G(SCH_1):PAGE58
   U26 AY48 VSS_AY48 GENOA_SP5-SOCKET6096_13568-001,SMLF,IO,DGA^6000030     I3 @T6G_MB_LIB.T6G(SCH_1):PAGE58
   U26 AY50 VSS_AY50 GENOA_SP5-SOCKET6096_13568-001,SMLF,IO,DGA^6000030     I3 @T6G_MB_LIB.T6G(SCH_1):PAGE58
   U26 AY52 VSS_AY52 GENOA_SP5-SOCKET6096_13568-001,SMLF,IO,DGA^6000030     I3 @T6G_MB_LIB.T6G(SCH_1):PAGE58
   U26 AY54 VSS_AY54 GENOA_SP5-SOCKET6096_13568-001,SMLF,IO,DGA^6000030     I3 @T6G_MB_LIB.T6G(SCH_1):PAGE58
   U26 AY57 VSS_AY57 GENOA_SP5-SOCKET6096_13568-001,SMLF,IO,DGA^6000030     I3 @T6G_MB_LIB.T6G(SCH_1):PAGE58
   U26 AY59 VSS_AY59 GENOA_SP5-SOCKET6096_13568-001,SMLF,IO,DGA^6000030     I3 @T6G_MB_LIB.T6G(SCH_1):PAGE58
   U26 AY61 VSS_AY61 GENOA_SP5-SOCKET6096_13568-001,SMLF,IO,DGA^6000030     I3 @T6G_MB_LIB.T6G(SCH_1):PAGE58
   U26 AY64 VSS_AY64 GENOA_SP5-SOCKET6096_13568-001,SMLF,IO,DGA^6000030     I3 @T6G_MB_LIB.T6G(SCH_1):PAGE58
   U26 AY66 VSS_AY66 GENOA_SP5-SOCKET6096_13568-001,SMLF,IO,DGA^6000030     I3 @T6G_MB_LIB.T6G(SCH_1):PAGE58
   U26 AY68 VSS_AY68 GENOA_SP5-SOCKET6096_13568-001,SMLF,IO,DGA^6000030     I3 @T6G_MB_LIB.T6G(SCH_1):PAGE58
   U26 AY71 VSS_AY71 GENOA_SP5-SOCKET6096_13568-001,SMLF,IO,DGA^6000030     I3 @T6G_MB_LIB.T6G(SCH_1):PAGE58
   U26 AY73 VSS_AY73 GENOA_SP5-SOCKET6096_13568-001,SMLF,IO,DGA^6000030     I3 @T6G_MB_LIB.T6G(SCH_1):PAGE58
   U26  BA1 VSS_BA1 GENOA_SP5-SOCKET6096_13568-001,SMLF,IO,DGA^6000030     I3 @T6G_MB_LIB.T6G(SCH_1):PAGE58
   U26  BA6 VSS_BA6 GENOA_SP5-SOCKET6096_13568-001,SMLF,IO,DGA^6000030     I3 @T6G_MB_LIB.T6G(SCH_1):PAGE58
   U26  BA8 VSS_BA8 GENOA_SP5-SOCKET6096_13568-001,SMLF,IO,DGA^6000030     I3 @T6G_MB_LIB.T6G(SCH_1):PAGE58
   U26 BA13 VSS_BA13 GENOA_SP5-SOCKET6096_13568-001,SMLF,IO,DGA^6000030     I3 @T6G_MB_LIB.T6G(SCH_1):PAGE58
   U26 BA15 VSS_BA15 GENOA_SP5-SOCKET6096_13568-001,SMLF,IO,DGA^6000030     I3 @T6G_MB_LIB.T6G(SCH_1):PAGE58
   U26 BA20 VSS_BA20 GENOA_SP5-SOCKET6096_13568-001,SMLF,IO,DGA^6000030     I3 @T6G_MB_LIB.T6G(SCH_1):PAGE58
   U26 BA22 VSS_BA22 GENOA_SP5-SOCKET6096_13568-001,SMLF,IO,DGA^6000030     I3 @T6G_MB_LIB.T6G(SCH_1):PAGE58
   U26 BA24 VSS_BA24 GENOA_SP5-SOCKET6096_13568-001,SMLF,IO,DGA^6000030     I3 @T6G_MB_LIB.T6G(SCH_1):PAGE58
   U26 BA26 VSS_BA26 GENOA_SP5-SOCKET6096_13568-001,SMLF,IO,DGA^6000030     I3 @T6G_MB_LIB.T6G(SCH_1):PAGE58
   U26 BA28 VSS_BA28 GENOA_SP5-SOCKET6096_13568-001,SMLF,IO,DGA^6000030     I3 @T6G_MB_LIB.T6G(SCH_1):PAGE58
   U26 BA49 VSS_BA49 GENOA_SP5-SOCKET6096_13568-001,SMLF,IO,DGA^6000030     I3 @T6G_MB_LIB.T6G(SCH_1):PAGE58
   U26 BA51 VSS_BA51 GENOA_SP5-SOCKET6096_13568-001,SMLF,IO,DGA^6000030     I3 @T6G_MB_LIB.T6G(SCH_1):PAGE58
   U26 BA53 VSS_BA53 GENOA_SP5-SOCKET6096_13568-001,SMLF,IO,DGA^6000030     I3 @T6G_MB_LIB.T6G(SCH_1):PAGE58
   U26 BA56 VSS_BA56 GENOA_SP5-SOCKET6096_13568-001,SMLF,IO,DGA^6000030     I3 @T6G_MB_LIB.T6G(SCH_1):PAGE58
   U26 BA61 VSS_BA61 GENOA_SP5-SOCKET6096_13568-001,SMLF,IO,DGA^6000030     I3 @T6G_MB_LIB.T6G(SCH_1):PAGE58
   U26 BA63 VSS_BA63 GENOA_SP5-SOCKET6096_13568-001,SMLF,IO,DGA^6000030     I3 @T6G_MB_LIB.T6G(SCH_1):PAGE58
   U26 BA68 VSS_BA68 GENOA_SP5-SOCKET6096_13568-001,SMLF,IO,DGA^6000030     I3 @T6G_MB_LIB.T6G(SCH_1):PAGE58
   U26 BA70 VSS_BA70 GENOA_SP5-SOCKET6096_13568-001,SMLF,IO,DGA^6000030     I3 @T6G_MB_LIB.T6G(SCH_1):PAGE58
   U26 BA75 VSS_BA75 GENOA_SP5-SOCKET6096_13568-001,SMLF,IO,DGA^6000030     I3 @T6G_MB_LIB.T6G(SCH_1):PAGE58
   U26  BB3 VSS_BB3 GENOA_SP5-SOCKET6096_13568-001,SMLF,IO,DGA^6000030     I3 @T6G_MB_LIB.T6G(SCH_1):PAGE58
   U26  BB5 VSS_BB5 GENOA_SP5-SOCKET6096_13568-001,SMLF,IO,DGA^6000030     I3 @T6G_MB_LIB.T6G(SCH_1):PAGE58
   U26  BB8 VSS_BB8 GENOA_SP5-SOCKET6096_13568-001,SMLF,IO,DGA^6000030     I3 @T6G_MB_LIB.T6G(SCH_1):PAGE58
   U26 BB10 VSS_BB10 GENOA_SP5-SOCKET6096_13568-001,SMLF,IO,DGA^6000030     I3 @T6G_MB_LIB.T6G(SCH_1):PAGE58
   U26 BB12 VSS_BB12 GENOA_SP5-SOCKET6096_13568-001,SMLF,IO,DGA^6000030     I3 @T6G_MB_LIB.T6G(SCH_1):PAGE58
   U26 BB15 VSS_BB15 GENOA_SP5-SOCKET6096_13568-001,SMLF,IO,DGA^6000030     I3 @T6G_MB_LIB.T6G(SCH_1):PAGE58
   U26 BB17 VSS_BB17 GENOA_SP5-SOCKET6096_13568-001,SMLF,IO,DGA^6000030     I3 @T6G_MB_LIB.T6G(SCH_1):PAGE58
   U26 BB19 VSS_BB19 GENOA_SP5-SOCKET6096_13568-001,SMLF,IO,DGA^6000030     I3 @T6G_MB_LIB.T6G(SCH_1):PAGE58
   U26 BB23 VSS_BB23 GENOA_SP5-SOCKET6096_13568-001,SMLF,IO,DGA^6000030     I3 @T6G_MB_LIB.T6G(SCH_1):PAGE58
   U26 BB25 VSS_BB25 GENOA_SP5-SOCKET6096_13568-001,SMLF,IO,DGA^6000030     I3 @T6G_MB_LIB.T6G(SCH_1):PAGE58
   U26 BB27 VSS_BB27 GENOA_SP5-SOCKET6096_13568-001,SMLF,IO,DGA^6000030     I3 @T6G_MB_LIB.T6G(SCH_1):PAGE58
   U26 BB48 VSS_BB48 GENOA_SP5-SOCKET6096_13568-001,SMLF,IO,DGA^6000030     I3 @T6G_MB_LIB.T6G(SCH_1):PAGE58
   U26 BB50 VSS_BB50 GENOA_SP5-SOCKET6096_13568-001,SMLF,IO,DGA^6000030     I3 @T6G_MB_LIB.T6G(SCH_1):PAGE58
   U26 BB52 VSS_BB52 GENOA_SP5-SOCKET6096_13568-001,SMLF,IO,DGA^6000030     I3 @T6G_MB_LIB.T6G(SCH_1):PAGE58
   U26 BB54 VSS_BB54 GENOA_SP5-SOCKET6096_13568-001,SMLF,IO,DGA^6000030     I3 @T6G_MB_LIB.T6G(SCH_1):PAGE58
   U26 BB57 VSS_BB57 GENOA_SP5-SOCKET6096_13568-001,SMLF,IO,DGA^6000030     I3 @T6G_MB_LIB.T6G(SCH_1):PAGE58
   U26 BB59 VSS_BB59 GENOA_SP5-SOCKET6096_13568-001,SMLF,IO,DGA^6000030     I3 @T6G_MB_LIB.T6G(SCH_1):PAGE58
   U26 BB61 VSS_BB61 GENOA_SP5-SOCKET6096_13568-001,SMLF,IO,DGA^6000030     I3 @T6G_MB_LIB.T6G(SCH_1):PAGE58
   U26 BB64 VSS_BB64 GENOA_SP5-SOCKET6096_13568-001,SMLF,IO,DGA^6000030     I3 @T6G_MB_LIB.T6G(SCH_1):PAGE58
   U26 BB66 VSS_BB66 GENOA_SP5-SOCKET6096_13568-001,SMLF,IO,DGA^6000030     I3 @T6G_MB_LIB.T6G(SCH_1):PAGE58
   U26 BB68 VSS_BB68 GENOA_SP5-SOCKET6096_13568-001,SMLF,IO,DGA^6000030     I3 @T6G_MB_LIB.T6G(SCH_1):PAGE58
   U26 BB71 VSS_BB71 GENOA_SP5-SOCKET6096_13568-001,SMLF,IO,DGA^6000030     I3 @T6G_MB_LIB.T6G(SCH_1):PAGE58
   U26 BB73 VSS_BB73 GENOA_SP5-SOCKET6096_13568-001,SMLF,IO,DGA^6000030     I3 @T6G_MB_LIB.T6G(SCH_1):PAGE58
   U26  BC1 VSS_BC1 GENOA_SP5-SOCKET6096_13568-001,SMLF,IO,DGA^6000030     I3 @T6G_MB_LIB.T6G(SCH_1):PAGE58
   U26  BC4 VSS_BC4 GENOA_SP5-SOCKET6096_13568-001,SMLF,IO,DGA^6000030     I3 @T6G_MB_LIB.T6G(SCH_1):PAGE58
   U26  BC6 VSS_BC6 GENOA_SP5-SOCKET6096_13568-001,SMLF,IO,DGA^6000030     I3 @T6G_MB_LIB.T6G(SCH_1):PAGE58
   U26  BC8 VSS_BC8 GENOA_SP5-SOCKET6096_13568-001,SMLF,IO,DGA^6000030     I3 @T6G_MB_LIB.T6G(SCH_1):PAGE58
   U26 BC11 VSS_BC11 GENOA_SP5-SOCKET6096_13568-001,SMLF,IO,DGA^6000030     I3 @T6G_MB_LIB.T6G(SCH_1):PAGE58
   U26 BC13 VSS_BC13 GENOA_SP5-SOCKET6096_13568-001,SMLF,IO,DGA^6000030     I3 @T6G_MB_LIB.T6G(SCH_1):PAGE58
   U26 BC15 VSS_BC15 GENOA_SP5-SOCKET6096_13568-001,SMLF,IO,DGA^6000030     I3 @T6G_MB_LIB.T6G(SCH_1):PAGE58
   U26 BC18 VSS_BC18 GENOA_SP5-SOCKET6096_13568-001,SMLF,IO,DGA^6000030     I3 @T6G_MB_LIB.T6G(SCH_1):PAGE58
   U26 BC20 VSS_BC20 GENOA_SP5-SOCKET6096_13568-001,SMLF,IO,DGA^6000030     I3 @T6G_MB_LIB.T6G(SCH_1):PAGE58
   U26 BC22 VSS_BC22 GENOA_SP5-SOCKET6096_13568-001,SMLF,IO,DGA^6000030     I3 @T6G_MB_LIB.T6G(SCH_1):PAGE58
   U26 BC24 VSS_BC24 GENOA_SP5-SOCKET6096_13568-001,SMLF,IO,DGA^6000030     I3 @T6G_MB_LIB.T6G(SCH_1):PAGE58
   U26 BC26 VSS_BC26 GENOA_SP5-SOCKET6096_13568-001,SMLF,IO,DGA^6000030     I3 @T6G_MB_LIB.T6G(SCH_1):PAGE58
   U26 BC28 VSS_BC28 GENOA_SP5-SOCKET6096_13568-001,SMLF,IO,DGA^6000030     I3 @T6G_MB_LIB.T6G(SCH_1):PAGE58
   U26 BC49 VSS_BC49 GENOA_SP5-SOCKET6096_13568-001,SMLF,IO,DGA^6000030     I3 @T6G_MB_LIB.T6G(SCH_1):PAGE58
   U26 BC50 VSS_BC50 GENOA_SP5-SOCKET6096_13568-001,SMLF,IO,DGA^6000030     I3 @T6G_MB_LIB.T6G(SCH_1):PAGE58
   U26 BC51 VSS_BC51 GENOA_SP5-SOCKET6096_13568-001,SMLF,IO,DGA^6000030     I3 @T6G_MB_LIB.T6G(SCH_1):PAGE58
   U26 BC53 VSS_BC53 GENOA_SP5-SOCKET6096_13568-001,SMLF,IO,DGA^6000030     I3 @T6G_MB_LIB.T6G(SCH_1):PAGE58
   U26 BC56 VSS_BC56 GENOA_SP5-SOCKET6096_13568-001,SMLF,IO,DGA^6000030     I3 @T6G_MB_LIB.T6G(SCH_1):PAGE58
   U26 BC58 VSS_BC58 GENOA_SP5-SOCKET6096_13568-001,SMLF,IO,DGA^6000030     I3 @T6G_MB_LIB.T6G(SCH_1):PAGE58
   U26 BC61 VSS_BC61 GENOA_SP5-SOCKET6096_13568-001,SMLF,IO,DGA^6000030     I3 @T6G_MB_LIB.T6G(SCH_1):PAGE58
   U26 BC63 VSS_BC63 GENOA_SP5-SOCKET6096_13568-001,SMLF,IO,DGA^6000030     I3 @T6G_MB_LIB.T6G(SCH_1):PAGE58
   U26 BC65 VSS_BC65 GENOA_SP5-SOCKET6096_13568-001,SMLF,IO,DGA^6000030     I3 @T6G_MB_LIB.T6G(SCH_1):PAGE58
   U26 BC68 VSS_BC68 GENOA_SP5-SOCKET6096_13568-001,SMLF,IO,DGA^6000030     I3 @T6G_MB_LIB.T6G(SCH_1):PAGE58
   U26 BC70 VSS_BC70 GENOA_SP5-SOCKET6096_13568-001,SMLF,IO,DGA^6000030     I3 @T6G_MB_LIB.T6G(SCH_1):PAGE58
   U26 BC72 VSS_BC72 GENOA_SP5-SOCKET6096_13568-001,SMLF,IO,DGA^6000030     I3 @T6G_MB_LIB.T6G(SCH_1):PAGE58
   U26 BC75 VSS_BC75 GENOA_SP5-SOCKET6096_13568-001,SMLF,IO,DGA^6000030     I3 @T6G_MB_LIB.T6G(SCH_1):PAGE58
   U26  BD3 VSS_BD3 GENOA_SP5-SOCKET6096_13568-001,SMLF,IO,DGA^6000030     I3 @T6G_MB_LIB.T6G(SCH_1):PAGE58
   U26  BD8 VSS_BD8 GENOA_SP5-SOCKET6096_13568-001,SMLF,IO,DGA^6000030     I3 @T6G_MB_LIB.T6G(SCH_1):PAGE58
   U26 BD10 VSS_BD10 GENOA_SP5-SOCKET6096_13568-001,SMLF,IO,DGA^6000030     I3 @T6G_MB_LIB.T6G(SCH_1):PAGE58
   U26 BD15 VSS_BD15 GENOA_SP5-SOCKET6096_13568-001,SMLF,IO,DGA^6000030     I3 @T6G_MB_LIB.T6G(SCH_1):PAGE58
   U26 BD17 VSS_BD17 GENOA_SP5-SOCKET6096_13568-001,SMLF,IO,DGA^6000030     I3 @T6G_MB_LIB.T6G(SCH_1):PAGE58
   U26 BD23 VSS_BD23 GENOA_SP5-SOCKET6096_13568-001,SMLF,IO,DGA^6000030     I3 @T6G_MB_LIB.T6G(SCH_1):PAGE58
   U26 BD25 VSS_BD25 GENOA_SP5-SOCKET6096_13568-001,SMLF,IO,DGA^6000030     I3 @T6G_MB_LIB.T6G(SCH_1):PAGE58
   U26 BD27 VSS_BD27 GENOA_SP5-SOCKET6096_13568-001,SMLF,IO,DGA^6000030     I3 @T6G_MB_LIB.T6G(SCH_1):PAGE58
   U26 BD49 VSS_BD49 GENOA_SP5-SOCKET6096_13568-001,SMLF,IO,DGA^6000030     I3 @T6G_MB_LIB.T6G(SCH_1):PAGE58
   U26 BD51 VSS_BD51 GENOA_SP5-SOCKET6096_13568-001,SMLF,IO,DGA^6000030     I3 @T6G_MB_LIB.T6G(SCH_1):PAGE58
   U26 BD53 VSS_BD53 GENOA_SP5-SOCKET6096_13568-001,SMLF,IO,DGA^6000030     I3 @T6G_MB_LIB.T6G(SCH_1):PAGE58
   U26 BD57 VSS_BD57 GENOA_SP5-SOCKET6096_13568-001,SMLF,IO,DGA^6000030     I3 @T6G_MB_LIB.T6G(SCH_1):PAGE58
   U26 BD59 VSS_BD59 GENOA_SP5-SOCKET6096_13568-001,SMLF,IO,DGA^6000030     I3 @T6G_MB_LIB.T6G(SCH_1):PAGE58
   U26 BD61 VSS_BD61 GENOA_SP5-SOCKET6096_13568-001,SMLF,IO,DGA^6000030     I3 @T6G_MB_LIB.T6G(SCH_1):PAGE58
   U26 BD64 VSS_BD64 GENOA_SP5-SOCKET6096_13568-001,SMLF,IO,DGA^6000030     I3 @T6G_MB_LIB.T6G(SCH_1):PAGE58
   U26 BD66 VSS_BD66 GENOA_SP5-SOCKET6096_13568-001,SMLF,IO,DGA^6000030     I3 @T6G_MB_LIB.T6G(SCH_1):PAGE58
   U26 BD68 VSS_BD68 GENOA_SP5-SOCKET6096_13568-001,SMLF,IO,DGA^6000030     I3 @T6G_MB_LIB.T6G(SCH_1):PAGE58
   U26 BD71 VSS_BD71 GENOA_SP5-SOCKET6096_13568-001,SMLF,IO,DGA^6000030     I3 @T6G_MB_LIB.T6G(SCH_1):PAGE58
   U26 BD73 VSS_BD73 GENOA_SP5-SOCKET6096_13568-001,SMLF,IO,DGA^6000030     I3 @T6G_MB_LIB.T6G(SCH_1):PAGE58
   U26  BF3 VSS_BF3 GENOA_SP5-SOCKET6096_13568-001,SMLF,IO,DGA^6000030     I3 @T6G_MB_LIB.T6G(SCH_1):PAGE58
   U26  BF5 VSS_BF5 GENOA_SP5-SOCKET6096_13568-001,SMLF,IO,DGA^6000030     I3 @T6G_MB_LIB.T6G(SCH_1):PAGE58
   U26  BF8 VSS_BF8 GENOA_SP5-SOCKET6096_13568-001,SMLF,IO,DGA^6000030     I3 @T6G_MB_LIB.T6G(SCH_1):PAGE58
   U26 BF10 VSS_BF10 GENOA_SP5-SOCKET6096_13568-001,SMLF,IO,DGA^6000030     I3 @T6G_MB_LIB.T6G(SCH_1):PAGE58
   U26 BF12 VSS_BF12 GENOA_SP5-SOCKET6096_13568-001,SMLF,IO,DGA^6000030     I3 @T6G_MB_LIB.T6G(SCH_1):PAGE58
   U26 BF15 VSS_BF15 GENOA_SP5-SOCKET6096_13568-001,SMLF,IO,DGA^6000030     I3 @T6G_MB_LIB.T6G(SCH_1):PAGE58
   U26 BF17 VSS_BF17 GENOA_SP5-SOCKET6096_13568-001,SMLF,IO,DGA^6000030     I3 @T6G_MB_LIB.T6G(SCH_1):PAGE58
   U26 BF19 VSS_BF19 GENOA_SP5-SOCKET6096_13568-001,SMLF,IO,DGA^6000030     I3 @T6G_MB_LIB.T6G(SCH_1):PAGE58
   U26 BF22 VSS_BF22 GENOA_SP5-SOCKET6096_13568-001,SMLF,IO,DGA^6000030     I3 @T6G_MB_LIB.T6G(SCH_1):PAGE58
   U26 BF24 VSS_BF24 GENOA_SP5-SOCKET6096_13568-001,SMLF,IO,DGA^6000030     I3 @T6G_MB_LIB.T6G(SCH_1):PAGE58
   U26 BF26 VSS_BF26 GENOA_SP5-SOCKET6096_13568-001,SMLF,IO,DGA^6000030     I3 @T6G_MB_LIB.T6G(SCH_1):PAGE58
   U26 BF28 VSS_BF28 GENOA_SP5-SOCKET6096_13568-001,SMLF,IO,DGA^6000030     I3 @T6G_MB_LIB.T6G(SCH_1):PAGE58
   U26 BF49 VSS_BF49 GENOA_SP5-SOCKET6096_13568-001,SMLF,IO,DGA^6000030     I3 @T6G_MB_LIB.T6G(SCH_1):PAGE58
   U26 BF50 VSS_BF50 GENOA_SP5-SOCKET6096_13568-001,SMLF,IO,DGA^6000030     I3 @T6G_MB_LIB.T6G(SCH_1):PAGE58
   U26 BF52 VSS_BF52 GENOA_SP5-SOCKET6096_13568-001,SMLF,IO,DGA^6000030     I3 @T6G_MB_LIB.T6G(SCH_1):PAGE58
   U26 BF54 VSS_BF54 GENOA_SP5-SOCKET6096_13568-001,SMLF,IO,DGA^6000030     I3 @T6G_MB_LIB.T6G(SCH_1):PAGE58
   U26 BF59 VSS_BF59 GENOA_SP5-SOCKET6096_13568-001,SMLF,IO,DGA^6000030     I3 @T6G_MB_LIB.T6G(SCH_1):PAGE58
   U26 BF61 VSS_BF61 GENOA_SP5-SOCKET6096_13568-001,SMLF,IO,DGA^6000030     I3 @T6G_MB_LIB.T6G(SCH_1):PAGE58
   U26 BF66 VSS_BF66 GENOA_SP5-SOCKET6096_13568-001,SMLF,IO,DGA^6000030     I3 @T6G_MB_LIB.T6G(SCH_1):PAGE58
   U26 BF68 VSS_BF68 GENOA_SP5-SOCKET6096_13568-001,SMLF,IO,DGA^6000030     I3 @T6G_MB_LIB.T6G(SCH_1):PAGE58
   U26 BF73 VSS_BF73 GENOA_SP5-SOCKET6096_13568-001,SMLF,IO,DGA^6000030     I3 @T6G_MB_LIB.T6G(SCH_1):PAGE58
   U26  BG1 VSS_BG1 GENOA_SP5-SOCKET6096_13568-001,SMLF,IO,DGA^6000030     I3 @T6G_MB_LIB.T6G(SCH_1):PAGE58
   U26  BG4 VSS_BG4 GENOA_SP5-SOCKET6096_13568-001,SMLF,IO,DGA^6000030     I3 @T6G_MB_LIB.T6G(SCH_1):PAGE58
   U26  BG6 VSS_BG6 GENOA_SP5-SOCKET6096_13568-001,SMLF,IO,DGA^6000030     I3 @T6G_MB_LIB.T6G(SCH_1):PAGE58
   U26  BG8 VSS_BG8 GENOA_SP5-SOCKET6096_13568-001,SMLF,IO,DGA^6000030     I3 @T6G_MB_LIB.T6G(SCH_1):PAGE58
   U26 BG11 VSS_BG11 GENOA_SP5-SOCKET6096_13568-001,SMLF,IO,DGA^6000030     I3 @T6G_MB_LIB.T6G(SCH_1):PAGE58
   U26 BG13 VSS_BG13 GENOA_SP5-SOCKET6096_13568-001,SMLF,IO,DGA^6000030     I3 @T6G_MB_LIB.T6G(SCH_1):PAGE58
   U26 BG15 VSS_BG15 GENOA_SP5-SOCKET6096_13568-001,SMLF,IO,DGA^6000030     I3 @T6G_MB_LIB.T6G(SCH_1):PAGE58
   U26 BG18 VSS_BG18 GENOA_SP5-SOCKET6096_13568-001,SMLF,IO,DGA^6000030     I3 @T6G_MB_LIB.T6G(SCH_1):PAGE58
   U26 BG20 VSS_BG20 GENOA_SP5-SOCKET6096_13568-001,SMLF,IO,DGA^6000030     I3 @T6G_MB_LIB.T6G(SCH_1):PAGE58
   U26 BG23 VSS_BG23 GENOA_SP5-SOCKET6096_13568-001,SMLF,IO,DGA^6000030     I3 @T6G_MB_LIB.T6G(SCH_1):PAGE58
   U26 BG25 VSS_BG25 GENOA_SP5-SOCKET6096_13568-001,SMLF,IO,DGA^6000030     I3 @T6G_MB_LIB.T6G(SCH_1):PAGE58
   U26 BG27 VSS_BG27 GENOA_SP5-SOCKET6096_13568-001,SMLF,IO,DGA^6000030     I3 @T6G_MB_LIB.T6G(SCH_1):PAGE58
   U26 BG49 VSS_BG49 GENOA_SP5-SOCKET6096_13568-001,SMLF,IO,DGA^6000030     I3 @T6G_MB_LIB.T6G(SCH_1):PAGE58
   U26 BG51 VSS_BG51 GENOA_SP5-SOCKET6096_13568-001,SMLF,IO,DGA^6000030     I3 @T6G_MB_LIB.T6G(SCH_1):PAGE58
   U26 BG53 VSS_BG53 GENOA_SP5-SOCKET6096_13568-001,SMLF,IO,DGA^6000030     I3 @T6G_MB_LIB.T6G(SCH_1):PAGE58
   U26 BG56 VSS_BG56 GENOA_SP5-SOCKET6096_13568-001,SMLF,IO,DGA^6000030     I3 @T6G_MB_LIB.T6G(SCH_1):PAGE58
   U26 BG58 VSS_BG58 GENOA_SP5-SOCKET6096_13568-001,SMLF,IO,DGA^6000030     I3 @T6G_MB_LIB.T6G(SCH_1):PAGE58
   U26 BG61 VSS_BG61 GENOA_SP5-SOCKET6096_13568-001,SMLF,IO,DGA^6000030     I3 @T6G_MB_LIB.T6G(SCH_1):PAGE58
   U26 BG63 VSS_BG63 GENOA_SP5-SOCKET6096_13568-001,SMLF,IO,DGA^6000030     I3 @T6G_MB_LIB.T6G(SCH_1):PAGE58
   U26 BG65 VSS_BG65 GENOA_SP5-SOCKET6096_13568-001,SMLF,IO,DGA^6000030     I3 @T6G_MB_LIB.T6G(SCH_1):PAGE58
   U26 BG68 VSS_BG68 GENOA_SP5-SOCKET6096_13568-001,SMLF,IO,DGA^6000030     I3 @T6G_MB_LIB.T6G(SCH_1):PAGE58
   U26 BG70 VSS_BG70 GENOA_SP5-SOCKET6096_13568-001,SMLF,IO,DGA^6000030     I3 @T6G_MB_LIB.T6G(SCH_1):PAGE58
   U26 BG72 VSS_BG72 GENOA_SP5-SOCKET6096_13568-001,SMLF,IO,DGA^6000030     I3 @T6G_MB_LIB.T6G(SCH_1):PAGE58
   U26 BG75 VSS_BG75 GENOA_SP5-SOCKET6096_13568-001,SMLF,IO,DGA^6000030     I3 @T6G_MB_LIB.T6G(SCH_1):PAGE58
   U26  BH3 VSS_BH3 GENOA_SP5-SOCKET6096_13568-001,SMLF,IO,DGA^6000030     I3 @T6G_MB_LIB.T6G(SCH_1):PAGE58
   U26  BH5 VSS_BH5 GENOA_SP5-SOCKET6096_13568-001,SMLF,IO,DGA^6000030     I3 @T6G_MB_LIB.T6G(SCH_1):PAGE58
   U26  BH8 VSS_BH8 GENOA_SP5-SOCKET6096_13568-001,SMLF,IO,DGA^6000030     I3 @T6G_MB_LIB.T6G(SCH_1):PAGE58
   U26 BH10 VSS_BH10 GENOA_SP5-SOCKET6096_13568-001,SMLF,IO,DGA^6000030     I3 @T6G_MB_LIB.T6G(SCH_1):PAGE58
   U26 BH12 VSS_BH12 GENOA_SP5-SOCKET6096_13568-001,SMLF,IO,DGA^6000030     I3 @T6G_MB_LIB.T6G(SCH_1):PAGE58
   U26 BH15 VSS_BH15 GENOA_SP5-SOCKET6096_13568-001,SMLF,IO,DGA^6000030     I3 @T6G_MB_LIB.T6G(SCH_1):PAGE58
   U26 BH17 VSS_BH17 GENOA_SP5-SOCKET6096_13568-001,SMLF,IO,DGA^6000030     I3 @T6G_MB_LIB.T6G(SCH_1):PAGE58
   U26 BH19 VSS_BH19 GENOA_SP5-SOCKET6096_13568-001,SMLF,IO,DGA^6000030     I3 @T6G_MB_LIB.T6G(SCH_1):PAGE58
   U26 BH22 VSS_BH22 GENOA_SP5-SOCKET6096_13568-001,SMLF,IO,DGA^6000030     I3 @T6G_MB_LIB.T6G(SCH_1):PAGE58
   U26 BH24 VSS_BH24 GENOA_SP5-SOCKET6096_13568-001,SMLF,IO,DGA^6000030     I3 @T6G_MB_LIB.T6G(SCH_1):PAGE58
   U26 BH26 VSS_BH26 GENOA_SP5-SOCKET6096_13568-001,SMLF,IO,DGA^6000030     I3 @T6G_MB_LIB.T6G(SCH_1):PAGE58
   U26 BH28 VSS_BH28 GENOA_SP5-SOCKET6096_13568-001,SMLF,IO,DGA^6000030     I3 @T6G_MB_LIB.T6G(SCH_1):PAGE58
   U26 BH49 VSS_BH49 GENOA_SP5-SOCKET6096_13568-001,SMLF,IO,DGA^6000030     I3 @T6G_MB_LIB.T6G(SCH_1):PAGE58
   U26 BH50 VSS_BH50 GENOA_SP5-SOCKET6096_13568-001,SMLF,IO,DGA^6000030     I3 @T6G_MB_LIB.T6G(SCH_1):PAGE58
   U26 BH52 VSS_BH52 GENOA_SP5-SOCKET6096_13568-001,SMLF,IO,DGA^6000030     I3 @T6G_MB_LIB.T6G(SCH_1):PAGE58
   U26 BH54 VSS_BH54 GENOA_SP5-SOCKET6096_13568-001,SMLF,IO,DGA^6000030     I3 @T6G_MB_LIB.T6G(SCH_1):PAGE58
   U26 BH57 VSS_BH57 GENOA_SP5-SOCKET6096_13568-001,SMLF,IO,DGA^6000030     I3 @T6G_MB_LIB.T6G(SCH_1):PAGE58
   U26 BH59 VSS_BH59 GENOA_SP5-SOCKET6096_13568-001,SMLF,IO,DGA^6000030     I3 @T6G_MB_LIB.T6G(SCH_1):PAGE58
   U26 BH61 VSS_BH61 GENOA_SP5-SOCKET6096_13568-001,SMLF,IO,DGA^6000030     I3 @T6G_MB_LIB.T6G(SCH_1):PAGE58
   U26 BH64 VSS_BH64 GENOA_SP5-SOCKET6096_13568-001,SMLF,IO,DGA^6000030     I3 @T6G_MB_LIB.T6G(SCH_1):PAGE58
   U26 BH66 VSS_BH66 GENOA_SP5-SOCKET6096_13568-001,SMLF,IO,DGA^6000030     I3 @T6G_MB_LIB.T6G(SCH_1):PAGE58
   U26 BH68 VSS_BH68 GENOA_SP5-SOCKET6096_13568-001,SMLF,IO,DGA^6000030     I3 @T6G_MB_LIB.T6G(SCH_1):PAGE58
   U26 BH71 VSS_BH71 GENOA_SP5-SOCKET6096_13568-001,SMLF,IO,DGA^6000030     I3 @T6G_MB_LIB.T6G(SCH_1):PAGE58
   U26 BH73 VSS_BH73 GENOA_SP5-SOCKET6096_13568-001,SMLF,IO,DGA^6000030     I3 @T6G_MB_LIB.T6G(SCH_1):PAGE58
   U26  BJ1 VSS_BJ1 GENOA_SP5-SOCKET6096_13568-001,SMLF,IO,DGA^6000030     I3 @T6G_MB_LIB.T6G(SCH_1):PAGE58
   U26  BJ6 VSS_BJ6 GENOA_SP5-SOCKET6096_13568-001,SMLF,IO,DGA^6000030     I3 @T6G_MB_LIB.T6G(SCH_1):PAGE58
   U26  BJ8 VSS_BJ8 GENOA_SP5-SOCKET6096_13568-001,SMLF,IO,DGA^6000030     I3 @T6G_MB_LIB.T6G(SCH_1):PAGE58
   U26 BJ13 VSS_BJ13 GENOA_SP5-SOCKET6096_13568-001,SMLF,IO,DGA^6000030     I3 @T6G_MB_LIB.T6G(SCH_1):PAGE58
   U26 BJ15 VSS_BJ15 GENOA_SP5-SOCKET6096_13568-001,SMLF,IO,DGA^6000030     I3 @T6G_MB_LIB.T6G(SCH_1):PAGE58
   U26 BJ20 VSS_BJ20 GENOA_SP5-SOCKET6096_13568-001,SMLF,IO,DGA^6000030     I3 @T6G_MB_LIB.T6G(SCH_1):PAGE58
   U26 BJ22 VSS_BJ22 GENOA_SP5-SOCKET6096_13568-001,SMLF,IO,DGA^6000030     I3 @T6G_MB_LIB.T6G(SCH_1):PAGE58
   U26 BJ24 VSS_BJ24 GENOA_SP5-SOCKET6096_13568-001,SMLF,IO,DGA^6000030     I3 @T6G_MB_LIB.T6G(SCH_1):PAGE58
   U26 BJ26 VSS_BJ26 GENOA_SP5-SOCKET6096_13568-001,SMLF,IO,DGA^6000030     I3 @T6G_MB_LIB.T6G(SCH_1):PAGE58
   U26 BJ28 VSS_BJ28 GENOA_SP5-SOCKET6096_13568-001,SMLF,IO,DGA^6000030     I3 @T6G_MB_LIB.T6G(SCH_1):PAGE58
   U26 BJ49 VSS_BJ49 GENOA_SP5-SOCKET6096_13568-001,SMLF,IO,DGA^6000030     I3 @T6G_MB_LIB.T6G(SCH_1):PAGE58
   U26 BJ51 VSS_BJ51 GENOA_SP5-SOCKET6096_13568-001,SMLF,IO,DGA^6000030     I3 @T6G_MB_LIB.T6G(SCH_1):PAGE58
   U26 BJ53 VSS_BJ53 GENOA_SP5-SOCKET6096_13568-001,SMLF,IO,DGA^6000030     I3 @T6G_MB_LIB.T6G(SCH_1):PAGE58
   U26 BJ56 VSS_BJ56 GENOA_SP5-SOCKET6096_13568-001,SMLF,IO,DGA^6000030     I3 @T6G_MB_LIB.T6G(SCH_1):PAGE58
   U26 BJ61 VSS_BJ61 GENOA_SP5-SOCKET6096_13568-001,SMLF,IO,DGA^6000030     I3 @T6G_MB_LIB.T6G(SCH_1):PAGE58
   U26 BJ63 VSS_BJ63 GENOA_SP5-SOCKET6096_13568-001,SMLF,IO,DGA^6000030     I3 @T6G_MB_LIB.T6G(SCH_1):PAGE58
   U26 BJ68 VSS_BJ68 GENOA_SP5-SOCKET6096_13568-001,SMLF,IO,DGA^6000030     I3 @T6G_MB_LIB.T6G(SCH_1):PAGE58
   U26 BJ70 VSS_BJ70 GENOA_SP5-SOCKET6096_13568-001,SMLF,IO,DGA^6000030     I3 @T6G_MB_LIB.T6G(SCH_1):PAGE58
   U26 BJ75 VSS_BJ75 GENOA_SP5-SOCKET6096_13568-001,SMLF,IO,DGA^6000030     I3 @T6G_MB_LIB.T6G(SCH_1):PAGE58
   U26  BK3 VSS_BK3 GENOA_SP5-SOCKET6096_13568-001,SMLF,IO,DGA^6000030     I3 @T6G_MB_LIB.T6G(SCH_1):PAGE58
   U26  BK5 VSS_BK5 GENOA_SP5-SOCKET6096_13568-001,SMLF,IO,DGA^6000030     I3 @T6G_MB_LIB.T6G(SCH_1):PAGE58
   U26  BK8 VSS_BK8 GENOA_SP5-SOCKET6096_13568-001,SMLF,IO,DGA^6000030     I3 @T6G_MB_LIB.T6G(SCH_1):PAGE58
   U26 BK10 VSS_BK10 GENOA_SP5-SOCKET6096_13568-001,SMLF,IO,DGA^6000030     I3 @T6G_MB_LIB.T6G(SCH_1):PAGE58
   U26 BK12 VSS_BK12 GENOA_SP5-SOCKET6096_13568-001,SMLF,IO,DGA^6000030     I3 @T6G_MB_LIB.T6G(SCH_1):PAGE58
   U26 BK15 VSS_BK15 GENOA_SP5-SOCKET6096_13568-001,SMLF,IO,DGA^6000030     I3 @T6G_MB_LIB.T6G(SCH_1):PAGE58
   U26 BK17 VSS_BK17 GENOA_SP5-SOCKET6096_13568-001,SMLF,IO,DGA^6000030     I3 @T6G_MB_LIB.T6G(SCH_1):PAGE58
   U26 BK19 VSS_BK19 GENOA_SP5-SOCKET6096_13568-001,SMLF,IO,DGA^6000030     I3 @T6G_MB_LIB.T6G(SCH_1):PAGE58
   U26 BK23 VSS_BK23 GENOA_SP5-SOCKET6096_13568-001,SMLF,IO,DGA^6000030     I3 @T6G_MB_LIB.T6G(SCH_1):PAGE58
   U26 BK25 VSS_BK25 GENOA_SP5-SOCKET6096_13568-001,SMLF,IO,DGA^6000030     I3 @T6G_MB_LIB.T6G(SCH_1):PAGE58
   U26 BK27 VSS_BK27 GENOA_SP5-SOCKET6096_13568-001,SMLF,IO,DGA^6000030     I3 @T6G_MB_LIB.T6G(SCH_1):PAGE58
   U26 BK48 VSS_BK48 GENOA_SP5-SOCKET6096_13568-001,SMLF,IO,DGA^6000030     I3 @T6G_MB_LIB.T6G(SCH_1):PAGE58
   U26 BK50 VSS_BK50 GENOA_SP5-SOCKET6096_13568-001,SMLF,IO,DGA^6000030     I3 @T6G_MB_LIB.T6G(SCH_1):PAGE58
   U26 BK52 VSS_BK52 GENOA_SP5-SOCKET6096_13568-001,SMLF,IO,DGA^6000030     I3 @T6G_MB_LIB.T6G(SCH_1):PAGE58
   U26 BK54 VSS_BK54 GENOA_SP5-SOCKET6096_13568-001,SMLF,IO,DGA^6000030     I3 @T6G_MB_LIB.T6G(SCH_1):PAGE58
   U26 BK57 VSS_BK57 GENOA_SP5-SOCKET6096_13568-001,SMLF,IO,DGA^6000030     I3 @T6G_MB_LIB.T6G(SCH_1):PAGE58
   U26 BK59 VSS_BK59 GENOA_SP5-SOCKET6096_13568-001,SMLF,IO,DGA^6000030     I3 @T6G_MB_LIB.T6G(SCH_1):PAGE58
   U26 BK61 VSS_BK61 GENOA_SP5-SOCKET6096_13568-001,SMLF,IO,DGA^6000030     I3 @T6G_MB_LIB.T6G(SCH_1):PAGE58
   U26 BK64 VSS_BK64 GENOA_SP5-SOCKET6096_13568-001,SMLF,IO,DGA^6000030     I3 @T6G_MB_LIB.T6G(SCH_1):PAGE58
   U26 BK66 VSS_BK66 GENOA_SP5-SOCKET6096_13568-001,SMLF,IO,DGA^6000030     I3 @T6G_MB_LIB.T6G(SCH_1):PAGE58
   U26 BK68 VSS_BK68 GENOA_SP5-SOCKET6096_13568-001,SMLF,IO,DGA^6000030     I3 @T6G_MB_LIB.T6G(SCH_1):PAGE58
   U26 BK71 VSS_BK71 GENOA_SP5-SOCKET6096_13568-001,SMLF,IO,DGA^6000030     I3 @T6G_MB_LIB.T6G(SCH_1):PAGE58
   U26 BK73 VSS_BK73 GENOA_SP5-SOCKET6096_13568-001,SMLF,IO,DGA^6000030     I3 @T6G_MB_LIB.T6G(SCH_1):PAGE58
   U26  BL1 VSS_BL1 GENOA_SP5-SOCKET6096_13568-001,SMLF,IO,DGA^6000030     I3 @T6G_MB_LIB.T6G(SCH_1):PAGE58
   U26  BL4 VSS_BL4 GENOA_SP5-SOCKET6096_13568-001,SMLF,IO,DGA^6000030     I3 @T6G_MB_LIB.T6G(SCH_1):PAGE58
   U26  BL6 VSS_BL6 GENOA_SP5-SOCKET6096_13568-001,SMLF,IO,DGA^6000030     I3 @T6G_MB_LIB.T6G(SCH_1):PAGE58
   U26  BL8 VSS_BL8 GENOA_SP5-SOCKET6096_13568-001,SMLF,IO,DGA^6000030     I3 @T6G_MB_LIB.T6G(SCH_1):PAGE58
   U26 BL11 VSS_BL11 GENOA_SP5-SOCKET6096_13568-001,SMLF,IO,DGA^6000030     I3 @T6G_MB_LIB.T6G(SCH_1):PAGE58
   U26 BL13 VSS_BL13 GENOA_SP5-SOCKET6096_13568-001,SMLF,IO,DGA^6000030     I3 @T6G_MB_LIB.T6G(SCH_1):PAGE58
   U26 BL15 VSS_BL15 GENOA_SP5-SOCKET6096_13568-001,SMLF,IO,DGA^6000030     I3 @T6G_MB_LIB.T6G(SCH_1):PAGE58
   U26 BL18 VSS_BL18 GENOA_SP5-SOCKET6096_13568-001,SMLF,IO,DGA^6000030     I3 @T6G_MB_LIB.T6G(SCH_1):PAGE58
   U26 BL20 VSS_BL20 GENOA_SP5-SOCKET6096_13568-001,SMLF,IO,DGA^6000030     I3 @T6G_MB_LIB.T6G(SCH_1):PAGE58
   U26 BL22 VSS_BL22 GENOA_SP5-SOCKET6096_13568-001,SMLF,IO,DGA^6000030     I3 @T6G_MB_LIB.T6G(SCH_1):PAGE58
   U26 BL24 VSS_BL24 GENOA_SP5-SOCKET6096_13568-001,SMLF,IO,DGA^6000030     I3 @T6G_MB_LIB.T6G(SCH_1):PAGE58
   U26 AM42 VSS_AM42 GENOA_SP5-SOCKET6096_13568-001,SMLF,IO,DGA^6000030     I6 @T6G_MB_LIB.T6G(SCH_1):PAGE58
   U26 AM43 VSS_AM43 GENOA_SP5-SOCKET6096_13568-001,SMLF,IO,DGA^6000030     I6 @T6G_MB_LIB.T6G(SCH_1):PAGE58
   U26 AM44 VSS_AM44 GENOA_SP5-SOCKET6096_13568-001,SMLF,IO,DGA^6000030     I6 @T6G_MB_LIB.T6G(SCH_1):PAGE58
   U26 AM45 VSS_AM45 GENOA_SP5-SOCKET6096_13568-001,SMLF,IO,DGA^6000030     I6 @T6G_MB_LIB.T6G(SCH_1):PAGE58
   U26 AM46 VSS_AM46 GENOA_SP5-SOCKET6096_13568-001,SMLF,IO,DGA^6000030     I6 @T6G_MB_LIB.T6G(SCH_1):PAGE58
   U26 AM47 VSS_AM47 GENOA_SP5-SOCKET6096_13568-001,SMLF,IO,DGA^6000030     I6 @T6G_MB_LIB.T6G(SCH_1):PAGE58
   U26 AM48 VSS_AM48 GENOA_SP5-SOCKET6096_13568-001,SMLF,IO,DGA^6000030     I6 @T6G_MB_LIB.T6G(SCH_1):PAGE58
   U26 AM49 VSS_AM49 GENOA_SP5-SOCKET6096_13568-001,SMLF,IO,DGA^6000030     I6 @T6G_MB_LIB.T6G(SCH_1):PAGE58
   U26 AM50 VSS_AM50 GENOA_SP5-SOCKET6096_13568-001,SMLF,IO,DGA^6000030     I6 @T6G_MB_LIB.T6G(SCH_1):PAGE58
   U26 AM51 VSS_AM51 GENOA_SP5-SOCKET6096_13568-001,SMLF,IO,DGA^6000030     I6 @T6G_MB_LIB.T6G(SCH_1):PAGE58
   U26 AM52 VSS_AM52 GENOA_SP5-SOCKET6096_13568-001,SMLF,IO,DGA^6000030     I6 @T6G_MB_LIB.T6G(SCH_1):PAGE58
   U26 AM53 VSS_AM53 GENOA_SP5-SOCKET6096_13568-001,SMLF,IO,DGA^6000030     I6 @T6G_MB_LIB.T6G(SCH_1):PAGE58
   U26 AM59 VSS_AM59 GENOA_SP5-SOCKET6096_13568-001,SMLF,IO,DGA^6000030     I6 @T6G_MB_LIB.T6G(SCH_1):PAGE58
   U26 AM61 VSS_AM61 GENOA_SP5-SOCKET6096_13568-001,SMLF,IO,DGA^6000030     I6 @T6G_MB_LIB.T6G(SCH_1):PAGE58
   U26 AM66 VSS_AM66 GENOA_SP5-SOCKET6096_13568-001,SMLF,IO,DGA^6000030     I6 @T6G_MB_LIB.T6G(SCH_1):PAGE58
   U26 AM68 VSS_AM68 GENOA_SP5-SOCKET6096_13568-001,SMLF,IO,DGA^6000030     I6 @T6G_MB_LIB.T6G(SCH_1):PAGE58
   U26 AM73 VSS_AM73 GENOA_SP5-SOCKET6096_13568-001,SMLF,IO,DGA^6000030     I6 @T6G_MB_LIB.T6G(SCH_1):PAGE58
   U26  AN1 VSS_AN1 GENOA_SP5-SOCKET6096_13568-001,SMLF,IO,DGA^6000030     I6 @T6G_MB_LIB.T6G(SCH_1):PAGE58
   U26  AN4 VSS_AN4 GENOA_SP5-SOCKET6096_13568-001,SMLF,IO,DGA^6000030     I6 @T6G_MB_LIB.T6G(SCH_1):PAGE58
   U26  AN6 VSS_AN6 GENOA_SP5-SOCKET6096_13568-001,SMLF,IO,DGA^6000030     I6 @T6G_MB_LIB.T6G(SCH_1):PAGE58
   U26  AN8 VSS_AN8 GENOA_SP5-SOCKET6096_13568-001,SMLF,IO,DGA^6000030     I6 @T6G_MB_LIB.T6G(SCH_1):PAGE58
   U26 AN11 VSS_AN11 GENOA_SP5-SOCKET6096_13568-001,SMLF,IO,DGA^6000030     I6 @T6G_MB_LIB.T6G(SCH_1):PAGE58
   U26 AN13 VSS_AN13 GENOA_SP5-SOCKET6096_13568-001,SMLF,IO,DGA^6000030     I6 @T6G_MB_LIB.T6G(SCH_1):PAGE58
   U26 AN15 VSS_AN15 GENOA_SP5-SOCKET6096_13568-001,SMLF,IO,DGA^6000030     I6 @T6G_MB_LIB.T6G(SCH_1):PAGE58
   U26 AN18 VSS_AN18 GENOA_SP5-SOCKET6096_13568-001,SMLF,IO,DGA^6000030     I6 @T6G_MB_LIB.T6G(SCH_1):PAGE58
   U26 AN22 VSS_AN22 GENOA_SP5-SOCKET6096_13568-001,SMLF,IO,DGA^6000030     I6 @T6G_MB_LIB.T6G(SCH_1):PAGE58
   U26 AN25 VSS_AN25 GENOA_SP5-SOCKET6096_13568-001,SMLF,IO,DGA^6000030     I6 @T6G_MB_LIB.T6G(SCH_1):PAGE58
   U26 AN28 VSS_AN28 GENOA_SP5-SOCKET6096_13568-001,SMLF,IO,DGA^6000030     I6 @T6G_MB_LIB.T6G(SCH_1):PAGE58
   U26 AN31 VSS_AN31 GENOA_SP5-SOCKET6096_13568-001,SMLF,IO,DGA^6000030     I6 @T6G_MB_LIB.T6G(SCH_1):PAGE58
   U26 AN34 VSS_AN34 GENOA_SP5-SOCKET6096_13568-001,SMLF,IO,DGA^6000030     I6 @T6G_MB_LIB.T6G(SCH_1):PAGE58
   U26 AN35 VSS_AN35 GENOA_SP5-SOCKET6096_13568-001,SMLF,IO,DGA^6000030     I6 @T6G_MB_LIB.T6G(SCH_1):PAGE58
   U26 AN36 VSS_AN36 GENOA_SP5-SOCKET6096_13568-001,SMLF,IO,DGA^6000030     I6 @T6G_MB_LIB.T6G(SCH_1):PAGE58
   U26 AN40 VSS_AN40 GENOA_SP5-SOCKET6096_13568-001,SMLF,IO,DGA^6000030     I6 @T6G_MB_LIB.T6G(SCH_1):PAGE58
   U26 AN41 VSS_AN41 GENOA_SP5-SOCKET6096_13568-001,SMLF,IO,DGA^6000030     I6 @T6G_MB_LIB.T6G(SCH_1):PAGE58
   U26 AN42 VSS_AN42 GENOA_SP5-SOCKET6096_13568-001,SMLF,IO,DGA^6000030     I6 @T6G_MB_LIB.T6G(SCH_1):PAGE58
   U26 AN45 VSS_AN45 GENOA_SP5-SOCKET6096_13568-001,SMLF,IO,DGA^6000030     I6 @T6G_MB_LIB.T6G(SCH_1):PAGE58
   U26 AN48 VSS_AN48 GENOA_SP5-SOCKET6096_13568-001,SMLF,IO,DGA^6000030     I6 @T6G_MB_LIB.T6G(SCH_1):PAGE58
   U26 AN51 VSS_AN51 GENOA_SP5-SOCKET6096_13568-001,SMLF,IO,DGA^6000030     I6 @T6G_MB_LIB.T6G(SCH_1):PAGE58
   U26 AN54 VSS_AN54 GENOA_SP5-SOCKET6096_13568-001,SMLF,IO,DGA^6000030     I6 @T6G_MB_LIB.T6G(SCH_1):PAGE58
   U26 AN56 VSS_AN56 GENOA_SP5-SOCKET6096_13568-001,SMLF,IO,DGA^6000030     I6 @T6G_MB_LIB.T6G(SCH_1):PAGE58
   U26 AN58 VSS_AN58 GENOA_SP5-SOCKET6096_13568-001,SMLF,IO,DGA^6000030     I6 @T6G_MB_LIB.T6G(SCH_1):PAGE58
   U26 AN61 VSS_AN61 GENOA_SP5-SOCKET6096_13568-001,SMLF,IO,DGA^6000030     I6 @T6G_MB_LIB.T6G(SCH_1):PAGE58
   U26 AN63 VSS_AN63 GENOA_SP5-SOCKET6096_13568-001,SMLF,IO,DGA^6000030     I6 @T6G_MB_LIB.T6G(SCH_1):PAGE58
   U26 AN65 VSS_AN65 GENOA_SP5-SOCKET6096_13568-001,SMLF,IO,DGA^6000030     I6 @T6G_MB_LIB.T6G(SCH_1):PAGE58
   U26 AN68 VSS_AN68 GENOA_SP5-SOCKET6096_13568-001,SMLF,IO,DGA^6000030     I6 @T6G_MB_LIB.T6G(SCH_1):PAGE58
   U26 AN70 VSS_AN70 GENOA_SP5-SOCKET6096_13568-001,SMLF,IO,DGA^6000030     I6 @T6G_MB_LIB.T6G(SCH_1):PAGE58
   U26 AN72 VSS_AN72 GENOA_SP5-SOCKET6096_13568-001,SMLF,IO,DGA^6000030     I6 @T6G_MB_LIB.T6G(SCH_1):PAGE58
   U26 AN75 VSS_AN75 GENOA_SP5-SOCKET6096_13568-001,SMLF,IO,DGA^6000030     I6 @T6G_MB_LIB.T6G(SCH_1):PAGE58
   U26  AP3 VSS_AP3 GENOA_SP5-SOCKET6096_13568-001,SMLF,IO,DGA^6000030     I6 @T6G_MB_LIB.T6G(SCH_1):PAGE58
   U26  AP5 VSS_AP5 GENOA_SP5-SOCKET6096_13568-001,SMLF,IO,DGA^6000030     I6 @T6G_MB_LIB.T6G(SCH_1):PAGE58
   U26  AP8 VSS_AP8 GENOA_SP5-SOCKET6096_13568-001,SMLF,IO,DGA^6000030     I6 @T6G_MB_LIB.T6G(SCH_1):PAGE58
   U26 AP10 VSS_AP10 GENOA_SP5-SOCKET6096_13568-001,SMLF,IO,DGA^6000030     I6 @T6G_MB_LIB.T6G(SCH_1):PAGE58
   U26 AP12 VSS_AP12 GENOA_SP5-SOCKET6096_13568-001,SMLF,IO,DGA^6000030     I6 @T6G_MB_LIB.T6G(SCH_1):PAGE58
   U26 AP15 VSS_AP15 GENOA_SP5-SOCKET6096_13568-001,SMLF,IO,DGA^6000030     I6 @T6G_MB_LIB.T6G(SCH_1):PAGE58
   U26 AP17 VSS_AP17 GENOA_SP5-SOCKET6096_13568-001,SMLF,IO,DGA^6000030     I6 @T6G_MB_LIB.T6G(SCH_1):PAGE58
   U26 AP19 VSS_AP19 GENOA_SP5-SOCKET6096_13568-001,SMLF,IO,DGA^6000030     I6 @T6G_MB_LIB.T6G(SCH_1):PAGE58
   U26 AP22 VSS_AP22 GENOA_SP5-SOCKET6096_13568-001,SMLF,IO,DGA^6000030     I6 @T6G_MB_LIB.T6G(SCH_1):PAGE58
   U26 AP25 VSS_AP25 GENOA_SP5-SOCKET6096_13568-001,SMLF,IO,DGA^6000030     I6 @T6G_MB_LIB.T6G(SCH_1):PAGE58
   U26 AP28 VSS_AP28 GENOA_SP5-SOCKET6096_13568-001,SMLF,IO,DGA^6000030     I6 @T6G_MB_LIB.T6G(SCH_1):PAGE58
   U26 AP31 VSS_AP31 GENOA_SP5-SOCKET6096_13568-001,SMLF,IO,DGA^6000030     I6 @T6G_MB_LIB.T6G(SCH_1):PAGE58
   U26 AP34 VSS_AP34 GENOA_SP5-SOCKET6096_13568-001,SMLF,IO,DGA^6000030     I6 @T6G_MB_LIB.T6G(SCH_1):PAGE58
   U26 AP37 VSS_AP37 GENOA_SP5-SOCKET6096_13568-001,SMLF,IO,DGA^6000030     I6 @T6G_MB_LIB.T6G(SCH_1):PAGE58
   U26 AP39 VSS_AP39 GENOA_SP5-SOCKET6096_13568-001,SMLF,IO,DGA^6000030     I6 @T6G_MB_LIB.T6G(SCH_1):PAGE58
   U26 AP42 VSS_AP42 GENOA_SP5-SOCKET6096_13568-001,SMLF,IO,DGA^6000030     I6 @T6G_MB_LIB.T6G(SCH_1):PAGE58
   U26 AP45 VSS_AP45 GENOA_SP5-SOCKET6096_13568-001,SMLF,IO,DGA^6000030     I6 @T6G_MB_LIB.T6G(SCH_1):PAGE58
   U26 AP48 VSS_AP48 GENOA_SP5-SOCKET6096_13568-001,SMLF,IO,DGA^6000030     I6 @T6G_MB_LIB.T6G(SCH_1):PAGE58
   U26 AP51 VSS_AP51 GENOA_SP5-SOCKET6096_13568-001,SMLF,IO,DGA^6000030     I6 @T6G_MB_LIB.T6G(SCH_1):PAGE58
   U26 AP54 VSS_AP54 GENOA_SP5-SOCKET6096_13568-001,SMLF,IO,DGA^6000030     I6 @T6G_MB_LIB.T6G(SCH_1):PAGE58
   U26 AP57 VSS_AP57 GENOA_SP5-SOCKET6096_13568-001,SMLF,IO,DGA^6000030     I6 @T6G_MB_LIB.T6G(SCH_1):PAGE58
   U26 AP59 VSS_AP59 GENOA_SP5-SOCKET6096_13568-001,SMLF,IO,DGA^6000030     I6 @T6G_MB_LIB.T6G(SCH_1):PAGE58
   U26 AP61 VSS_AP61 GENOA_SP5-SOCKET6096_13568-001,SMLF,IO,DGA^6000030     I6 @T6G_MB_LIB.T6G(SCH_1):PAGE58
   U26 AP64 VSS_AP64 GENOA_SP5-SOCKET6096_13568-001,SMLF,IO,DGA^6000030     I6 @T6G_MB_LIB.T6G(SCH_1):PAGE58
   U26 AP66 VSS_AP66 GENOA_SP5-SOCKET6096_13568-001,SMLF,IO,DGA^6000030     I6 @T6G_MB_LIB.T6G(SCH_1):PAGE58
   U26 AP68 VSS_AP68 GENOA_SP5-SOCKET6096_13568-001,SMLF,IO,DGA^6000030     I6 @T6G_MB_LIB.T6G(SCH_1):PAGE58
   U26 AP71 VSS_AP71 GENOA_SP5-SOCKET6096_13568-001,SMLF,IO,DGA^6000030     I6 @T6G_MB_LIB.T6G(SCH_1):PAGE58
   U26 AP73 VSS_AP73 GENOA_SP5-SOCKET6096_13568-001,SMLF,IO,DGA^6000030     I6 @T6G_MB_LIB.T6G(SCH_1):PAGE58
   U26  AR1 VSS_AR1 GENOA_SP5-SOCKET6096_13568-001,SMLF,IO,DGA^6000030     I6 @T6G_MB_LIB.T6G(SCH_1):PAGE58
   U26  AR5 VSS_AR5 GENOA_SP5-SOCKET6096_13568-001,SMLF,IO,DGA^6000030     I6 @T6G_MB_LIB.T6G(SCH_1):PAGE58
   U26  AR6 VSS_AR6 GENOA_SP5-SOCKET6096_13568-001,SMLF,IO,DGA^6000030     I6 @T6G_MB_LIB.T6G(SCH_1):PAGE58
   U26  AR8 VSS_AR8 GENOA_SP5-SOCKET6096_13568-001,SMLF,IO,DGA^6000030     I6 @T6G_MB_LIB.T6G(SCH_1):PAGE58
   U26  AR9 VSS_AR9 GENOA_SP5-SOCKET6096_13568-001,SMLF,IO,DGA^6000030     I6 @T6G_MB_LIB.T6G(SCH_1):PAGE58
   U26 AR12 VSS_AR12 GENOA_SP5-SOCKET6096_13568-001,SMLF,IO,DGA^6000030     I6 @T6G_MB_LIB.T6G(SCH_1):PAGE58
   U26 AR13 VSS_AR13 GENOA_SP5-SOCKET6096_13568-001,SMLF,IO,DGA^6000030     I6 @T6G_MB_LIB.T6G(SCH_1):PAGE58
   U26 AR15 VSS_AR15 GENOA_SP5-SOCKET6096_13568-001,SMLF,IO,DGA^6000030     I6 @T6G_MB_LIB.T6G(SCH_1):PAGE58
   U26 AR16 VSS_AR16 GENOA_SP5-SOCKET6096_13568-001,SMLF,IO,DGA^6000030     I6 @T6G_MB_LIB.T6G(SCH_1):PAGE58
   U26 AR19 VSS_AR19 GENOA_SP5-SOCKET6096_13568-001,SMLF,IO,DGA^6000030     I6 @T6G_MB_LIB.T6G(SCH_1):PAGE58
   U26 AR20 VSS_AR20 GENOA_SP5-SOCKET6096_13568-001,SMLF,IO,DGA^6000030     I6 @T6G_MB_LIB.T6G(SCH_1):PAGE58
   U26 AR22 VSS_AR22 GENOA_SP5-SOCKET6096_13568-001,SMLF,IO,DGA^6000030     I6 @T6G_MB_LIB.T6G(SCH_1):PAGE58
   U26 AR24 VSS_AR24 GENOA_SP5-SOCKET6096_13568-001,SMLF,IO,DGA^6000030     I6 @T6G_MB_LIB.T6G(SCH_1):PAGE58
   U26 AR26 VSS_AR26 GENOA_SP5-SOCKET6096_13568-001,SMLF,IO,DGA^6000030     I6 @T6G_MB_LIB.T6G(SCH_1):PAGE58
   U26 AR28 VSS_AR28 GENOA_SP5-SOCKET6096_13568-001,SMLF,IO,DGA^6000030     I6 @T6G_MB_LIB.T6G(SCH_1):PAGE58
   U26 AR30 VSS_AR30 GENOA_SP5-SOCKET6096_13568-001,SMLF,IO,DGA^6000030     I6 @T6G_MB_LIB.T6G(SCH_1):PAGE58
   U26 AR32 VSS_AR32 GENOA_SP5-SOCKET6096_13568-001,SMLF,IO,DGA^6000030     I6 @T6G_MB_LIB.T6G(SCH_1):PAGE58
   U26 AR34 VSS_AR34 GENOA_SP5-SOCKET6096_13568-001,SMLF,IO,DGA^6000030     I6 @T6G_MB_LIB.T6G(SCH_1):PAGE58
   U26 AR36 VSS_AR36 GENOA_SP5-SOCKET6096_13568-001,SMLF,IO,DGA^6000030     I6 @T6G_MB_LIB.T6G(SCH_1):PAGE58
   U26 AR41 VSS_AR41 GENOA_SP5-SOCKET6096_13568-001,SMLF,IO,DGA^6000030     I6 @T6G_MB_LIB.T6G(SCH_1):PAGE58
   U26 AR43 VSS_AR43 GENOA_SP5-SOCKET6096_13568-001,SMLF,IO,DGA^6000030     I6 @T6G_MB_LIB.T6G(SCH_1):PAGE58
   U26 AR45 VSS_AR45 GENOA_SP5-SOCKET6096_13568-001,SMLF,IO,DGA^6000030     I6 @T6G_MB_LIB.T6G(SCH_1):PAGE58
   U26 AR47 VSS_AR47 GENOA_SP5-SOCKET6096_13568-001,SMLF,IO,DGA^6000030     I6 @T6G_MB_LIB.T6G(SCH_1):PAGE58
   U26 AR49 VSS_AR49 GENOA_SP5-SOCKET6096_13568-001,SMLF,IO,DGA^6000030     I6 @T6G_MB_LIB.T6G(SCH_1):PAGE58
   U26 AR51 VSS_AR51 GENOA_SP5-SOCKET6096_13568-001,SMLF,IO,DGA^6000030     I6 @T6G_MB_LIB.T6G(SCH_1):PAGE58
   U26 AR53 VSS_AR53 GENOA_SP5-SOCKET6096_13568-001,SMLF,IO,DGA^6000030     I6 @T6G_MB_LIB.T6G(SCH_1):PAGE58
   U26 AR56 VSS_AR56 GENOA_SP5-SOCKET6096_13568-001,SMLF,IO,DGA^6000030     I6 @T6G_MB_LIB.T6G(SCH_1):PAGE58
   U26 AR57 VSS_AR57 GENOA_SP5-SOCKET6096_13568-001,SMLF,IO,DGA^6000030     I6 @T6G_MB_LIB.T6G(SCH_1):PAGE58
   U26 AR60 VSS_AR60 GENOA_SP5-SOCKET6096_13568-001,SMLF,IO,DGA^6000030     I6 @T6G_MB_LIB.T6G(SCH_1):PAGE58
   U26 AR61 VSS_AR61 GENOA_SP5-SOCKET6096_13568-001,SMLF,IO,DGA^6000030     I6 @T6G_MB_LIB.T6G(SCH_1):PAGE58
   U26 AR63 VSS_AR63 GENOA_SP5-SOCKET6096_13568-001,SMLF,IO,DGA^6000030     I6 @T6G_MB_LIB.T6G(SCH_1):PAGE58
   U26 AR64 VSS_AR64 GENOA_SP5-SOCKET6096_13568-001,SMLF,IO,DGA^6000030     I6 @T6G_MB_LIB.T6G(SCH_1):PAGE58
   U26 AR67 VSS_AR67 GENOA_SP5-SOCKET6096_13568-001,SMLF,IO,DGA^6000030     I6 @T6G_MB_LIB.T6G(SCH_1):PAGE58
   U26 AR68 VSS_AR68 GENOA_SP5-SOCKET6096_13568-001,SMLF,IO,DGA^6000030     I6 @T6G_MB_LIB.T6G(SCH_1):PAGE58
   U26 AR70 VSS_AR70 GENOA_SP5-SOCKET6096_13568-001,SMLF,IO,DGA^6000030     I6 @T6G_MB_LIB.T6G(SCH_1):PAGE58
   U26 AR71 VSS_AR71 GENOA_SP5-SOCKET6096_13568-001,SMLF,IO,DGA^6000030     I6 @T6G_MB_LIB.T6G(SCH_1):PAGE58
   U26 AR75 VSS_AR75 GENOA_SP5-SOCKET6096_13568-001,SMLF,IO,DGA^6000030     I6 @T6G_MB_LIB.T6G(SCH_1):PAGE58
   U26  AT3 VSS_AT3 GENOA_SP5-SOCKET6096_13568-001,SMLF,IO,DGA^6000030     I6 @T6G_MB_LIB.T6G(SCH_1):PAGE58
   U26  AT4 VSS_AT4 GENOA_SP5-SOCKET6096_13568-001,SMLF,IO,DGA^6000030     I6 @T6G_MB_LIB.T6G(SCH_1):PAGE58
   U26  AT5 VSS_AT5 GENOA_SP5-SOCKET6096_13568-001,SMLF,IO,DGA^6000030     I6 @T6G_MB_LIB.T6G(SCH_1):PAGE58
   U26  AT6 VSS_AT6 GENOA_SP5-SOCKET6096_13568-001,SMLF,IO,DGA^6000030     I6 @T6G_MB_LIB.T6G(SCH_1):PAGE58
   U26  AT8 VSS_AT8 GENOA_SP5-SOCKET6096_13568-001,SMLF,IO,DGA^6000030     I6 @T6G_MB_LIB.T6G(SCH_1):PAGE58
   U26  AT9 VSS_AT9 GENOA_SP5-SOCKET6096_13568-001,SMLF,IO,DGA^6000030     I6 @T6G_MB_LIB.T6G(SCH_1):PAGE58
   U26 AT10 VSS_AT10 GENOA_SP5-SOCKET6096_13568-001,SMLF,IO,DGA^6000030     I6 @T6G_MB_LIB.T6G(SCH_1):PAGE58
   U26 AT12 VSS_AT12 GENOA_SP5-SOCKET6096_13568-001,SMLF,IO,DGA^6000030     I6 @T6G_MB_LIB.T6G(SCH_1):PAGE58
   U26 AT13 VSS_AT13 GENOA_SP5-SOCKET6096_13568-001,SMLF,IO,DGA^6000030     I6 @T6G_MB_LIB.T6G(SCH_1):PAGE58
   U26 AT15 VSS_AT15 GENOA_SP5-SOCKET6096_13568-001,SMLF,IO,DGA^6000030     I6 @T6G_MB_LIB.T6G(SCH_1):PAGE58
   U26 AT16 VSS_AT16 GENOA_SP5-SOCKET6096_13568-001,SMLF,IO,DGA^6000030     I6 @T6G_MB_LIB.T6G(SCH_1):PAGE58
   U26 AT17 VSS_AT17 GENOA_SP5-SOCKET6096_13568-001,SMLF,IO,DGA^6000030     I6 @T6G_MB_LIB.T6G(SCH_1):PAGE58
   U26 AT19 VSS_AT19 GENOA_SP5-SOCKET6096_13568-001,SMLF,IO,DGA^6000030     I6 @T6G_MB_LIB.T6G(SCH_1):PAGE58
   U26 AT20 VSS_AT20 GENOA_SP5-SOCKET6096_13568-001,SMLF,IO,DGA^6000030     I6 @T6G_MB_LIB.T6G(SCH_1):PAGE58
   U26 AT23 VSS_AT23 GENOA_SP5-SOCKET6096_13568-001,SMLF,IO,DGA^6000030     I6 @T6G_MB_LIB.T6G(SCH_1):PAGE58
   U26 AT25 VSS_AT25 GENOA_SP5-SOCKET6096_13568-001,SMLF,IO,DGA^6000030     I6 @T6G_MB_LIB.T6G(SCH_1):PAGE58
   U26 AT27 VSS_AT27 GENOA_SP5-SOCKET6096_13568-001,SMLF,IO,DGA^6000030     I6 @T6G_MB_LIB.T6G(SCH_1):PAGE58
   U26 AT29 VSS_AT29 GENOA_SP5-SOCKET6096_13568-001,SMLF,IO,DGA^6000030     I6 @T6G_MB_LIB.T6G(SCH_1):PAGE58
   U26 AT31 VSS_AT31 GENOA_SP5-SOCKET6096_13568-001,SMLF,IO,DGA^6000030     I6 @T6G_MB_LIB.T6G(SCH_1):PAGE58
   U26 AT33 VSS_AT33 GENOA_SP5-SOCKET6096_13568-001,SMLF,IO,DGA^6000030     I6 @T6G_MB_LIB.T6G(SCH_1):PAGE58
   U26 AT35 VSS_AT35 GENOA_SP5-SOCKET6096_13568-001,SMLF,IO,DGA^6000030     I6 @T6G_MB_LIB.T6G(SCH_1):PAGE58
   U26 AT37 VSS_AT37 GENOA_SP5-SOCKET6096_13568-001,SMLF,IO,DGA^6000030     I6 @T6G_MB_LIB.T6G(SCH_1):PAGE58
   U26 AT40 VSS_AT40 GENOA_SP5-SOCKET6096_13568-001,SMLF,IO,DGA^6000030     I6 @T6G_MB_LIB.T6G(SCH_1):PAGE58
   U26 AT42 VSS_AT42 GENOA_SP5-SOCKET6096_13568-001,SMLF,IO,DGA^6000030     I6 @T6G_MB_LIB.T6G(SCH_1):PAGE58
   U26 AT44 VSS_AT44 GENOA_SP5-SOCKET6096_13568-001,SMLF,IO,DGA^6000030     I6 @T6G_MB_LIB.T6G(SCH_1):PAGE58
   U26 AT46 VSS_AT46 GENOA_SP5-SOCKET6096_13568-001,SMLF,IO,DGA^6000030     I6 @T6G_MB_LIB.T6G(SCH_1):PAGE58
   U26 AT48 VSS_AT48 GENOA_SP5-SOCKET6096_13568-001,SMLF,IO,DGA^6000030     I6 @T6G_MB_LIB.T6G(SCH_1):PAGE58
   U26 AT50 VSS_AT50 GENOA_SP5-SOCKET6096_13568-001,SMLF,IO,DGA^6000030     I6 @T6G_MB_LIB.T6G(SCH_1):PAGE58
   U26 AT52 VSS_AT52 GENOA_SP5-SOCKET6096_13568-001,SMLF,IO,DGA^6000030     I6 @T6G_MB_LIB.T6G(SCH_1):PAGE58
   U26 AT54 VSS_AT54 GENOA_SP5-SOCKET6096_13568-001,SMLF,IO,DGA^6000030     I6 @T6G_MB_LIB.T6G(SCH_1):PAGE58
   U26 AT56 VSS_AT56 GENOA_SP5-SOCKET6096_13568-001,SMLF,IO,DGA^6000030     I6 @T6G_MB_LIB.T6G(SCH_1):PAGE58
   U26 AT57 VSS_AT57 GENOA_SP5-SOCKET6096_13568-001,SMLF,IO,DGA^6000030     I6 @T6G_MB_LIB.T6G(SCH_1):PAGE58
   U26 AT59 VSS_AT59 GENOA_SP5-SOCKET6096_13568-001,SMLF,IO,DGA^6000030     I6 @T6G_MB_LIB.T6G(SCH_1):PAGE58
   U26 AT60 VSS_AT60 GENOA_SP5-SOCKET6096_13568-001,SMLF,IO,DGA^6000030     I6 @T6G_MB_LIB.T6G(SCH_1):PAGE58
   U26 AT61 VSS_AT61 GENOA_SP5-SOCKET6096_13568-001,SMLF,IO,DGA^6000030     I6 @T6G_MB_LIB.T6G(SCH_1):PAGE58
   U26 AT63 VSS_AT63 GENOA_SP5-SOCKET6096_13568-001,SMLF,IO,DGA^6000030     I6 @T6G_MB_LIB.T6G(SCH_1):PAGE58
   U26 AT64 VSS_AT64 GENOA_SP5-SOCKET6096_13568-001,SMLF,IO,DGA^6000030     I6 @T6G_MB_LIB.T6G(SCH_1):PAGE58
   U26 AT66 VSS_AT66 GENOA_SP5-SOCKET6096_13568-001,SMLF,IO,DGA^6000030     I6 @T6G_MB_LIB.T6G(SCH_1):PAGE58
   U26 AT67 VSS_AT67 GENOA_SP5-SOCKET6096_13568-001,SMLF,IO,DGA^6000030     I6 @T6G_MB_LIB.T6G(SCH_1):PAGE58
   U26 AT68 VSS_AT68 GENOA_SP5-SOCKET6096_13568-001,SMLF,IO,DGA^6000030     I6 @T6G_MB_LIB.T6G(SCH_1):PAGE58
   U26 AT70 VSS_AT70 GENOA_SP5-SOCKET6096_13568-001,SMLF,IO,DGA^6000030     I6 @T6G_MB_LIB.T6G(SCH_1):PAGE58
   U26 AT71 VSS_AT71 GENOA_SP5-SOCKET6096_13568-001,SMLF,IO,DGA^6000030     I6 @T6G_MB_LIB.T6G(SCH_1):PAGE58
   U26 AT72 VSS_AT72 GENOA_SP5-SOCKET6096_13568-001,SMLF,IO,DGA^6000030     I6 @T6G_MB_LIB.T6G(SCH_1):PAGE58
   U26 AT73 VSS_AT73 GENOA_SP5-SOCKET6096_13568-001,SMLF,IO,DGA^6000030     I6 @T6G_MB_LIB.T6G(SCH_1):PAGE58
   U26  AU1 VSS_AU1 GENOA_SP5-SOCKET6096_13568-001,SMLF,IO,DGA^6000030     I6 @T6G_MB_LIB.T6G(SCH_1):PAGE58
   U26  AU3 VSS_AU3 GENOA_SP5-SOCKET6096_13568-001,SMLF,IO,DGA^6000030     I6 @T6G_MB_LIB.T6G(SCH_1):PAGE58
   U26  AU4 VSS_AU4 GENOA_SP5-SOCKET6096_13568-001,SMLF,IO,DGA^6000030     I6 @T6G_MB_LIB.T6G(SCH_1):PAGE58
   U26  AU6 VSS_AU6 GENOA_SP5-SOCKET6096_13568-001,SMLF,IO,DGA^6000030     I6 @T6G_MB_LIB.T6G(SCH_1):PAGE58
   U26  AU8 VSS_AU8 GENOA_SP5-SOCKET6096_13568-001,SMLF,IO,DGA^6000030     I6 @T6G_MB_LIB.T6G(SCH_1):PAGE58
   U26 AU11 VSS_AU11 GENOA_SP5-SOCKET6096_13568-001,SMLF,IO,DGA^6000030     I6 @T6G_MB_LIB.T6G(SCH_1):PAGE58
   U26 AU13 VSS_AU13 GENOA_SP5-SOCKET6096_13568-001,SMLF,IO,DGA^6000030     I6 @T6G_MB_LIB.T6G(SCH_1):PAGE58
   U26 AU15 VSS_AU15 GENOA_SP5-SOCKET6096_13568-001,SMLF,IO,DGA^6000030     I6 @T6G_MB_LIB.T6G(SCH_1):PAGE58
   U26 AU18 VSS_AU18 GENOA_SP5-SOCKET6096_13568-001,SMLF,IO,DGA^6000030     I6 @T6G_MB_LIB.T6G(SCH_1):PAGE58
   U26 AU20 VSS_AU20 GENOA_SP5-SOCKET6096_13568-001,SMLF,IO,DGA^6000030     I6 @T6G_MB_LIB.T6G(SCH_1):PAGE58
   U26 AU22 VSS_AU22 GENOA_SP5-SOCKET6096_13568-001,SMLF,IO,DGA^6000030     I6 @T6G_MB_LIB.T6G(SCH_1):PAGE58
   U26 AU24 VSS_AU24 GENOA_SP5-SOCKET6096_13568-001,SMLF,IO,DGA^6000030     I6 @T6G_MB_LIB.T6G(SCH_1):PAGE58
   U26 AU26 VSS_AU26 GENOA_SP5-SOCKET6096_13568-001,SMLF,IO,DGA^6000030     I6 @T6G_MB_LIB.T6G(SCH_1):PAGE58
   U26 AU28 VSS_AU28 GENOA_SP5-SOCKET6096_13568-001,SMLF,IO,DGA^6000030     I6 @T6G_MB_LIB.T6G(SCH_1):PAGE58
   U26 AU30 VSS_AU30 GENOA_SP5-SOCKET6096_13568-001,SMLF,IO,DGA^6000030     I6 @T6G_MB_LIB.T6G(SCH_1):PAGE58
   U26 AU32 VSS_AU32 GENOA_SP5-SOCKET6096_13568-001,SMLF,IO,DGA^6000030     I6 @T6G_MB_LIB.T6G(SCH_1):PAGE58
   U26 AU34 VSS_AU34 GENOA_SP5-SOCKET6096_13568-001,SMLF,IO,DGA^6000030     I6 @T6G_MB_LIB.T6G(SCH_1):PAGE58
   U26 AU36 VSS_AU36 GENOA_SP5-SOCKET6096_13568-001,SMLF,IO,DGA^6000030     I6 @T6G_MB_LIB.T6G(SCH_1):PAGE58
   U26 AU41 VSS_AU41 GENOA_SP5-SOCKET6096_13568-001,SMLF,IO,DGA^6000030     I6 @T6G_MB_LIB.T6G(SCH_1):PAGE58
   U26 AU43 VSS_AU43 GENOA_SP5-SOCKET6096_13568-001,SMLF,IO,DGA^6000030     I6 @T6G_MB_LIB.T6G(SCH_1):PAGE58
   U26 AU45 VSS_AU45 GENOA_SP5-SOCKET6096_13568-001,SMLF,IO,DGA^6000030     I6 @T6G_MB_LIB.T6G(SCH_1):PAGE58
   U26 AU47 VSS_AU47 GENOA_SP5-SOCKET6096_13568-001,SMLF,IO,DGA^6000030     I6 @T6G_MB_LIB.T6G(SCH_1):PAGE58
   U26 AU49 VSS_AU49 GENOA_SP5-SOCKET6096_13568-001,SMLF,IO,DGA^6000030     I6 @T6G_MB_LIB.T6G(SCH_1):PAGE58
   U26 AU51 VSS_AU51 GENOA_SP5-SOCKET6096_13568-001,SMLF,IO,DGA^6000030     I6 @T6G_MB_LIB.T6G(SCH_1):PAGE58
   U26 AU53 VSS_AU53 GENOA_SP5-SOCKET6096_13568-001,SMLF,IO,DGA^6000030     I6 @T6G_MB_LIB.T6G(SCH_1):PAGE58
   U26 AU56 VSS_AU56 GENOA_SP5-SOCKET6096_13568-001,SMLF,IO,DGA^6000030     I6 @T6G_MB_LIB.T6G(SCH_1):PAGE58
   U26 AU58 VSS_AU58 GENOA_SP5-SOCKET6096_13568-001,SMLF,IO,DGA^6000030     I6 @T6G_MB_LIB.T6G(SCH_1):PAGE58
   U26 AU61 VSS_AU61 GENOA_SP5-SOCKET6096_13568-001,SMLF,IO,DGA^6000030     I6 @T6G_MB_LIB.T6G(SCH_1):PAGE58
   U26 AU63 VSS_AU63 GENOA_SP5-SOCKET6096_13568-001,SMLF,IO,DGA^6000030     I6 @T6G_MB_LIB.T6G(SCH_1):PAGE58
   U26 AU65 VSS_AU65 GENOA_SP5-SOCKET6096_13568-001,SMLF,IO,DGA^6000030     I6 @T6G_MB_LIB.T6G(SCH_1):PAGE58
   U26 AU68 VSS_AU68 GENOA_SP5-SOCKET6096_13568-001,SMLF,IO,DGA^6000030     I6 @T6G_MB_LIB.T6G(SCH_1):PAGE58
   U26 AU70 VSS_AU70 GENOA_SP5-SOCKET6096_13568-001,SMLF,IO,DGA^6000030     I6 @T6G_MB_LIB.T6G(SCH_1):PAGE58
   U26 AU72 VSS_AU72 GENOA_SP5-SOCKET6096_13568-001,SMLF,IO,DGA^6000030     I6 @T6G_MB_LIB.T6G(SCH_1):PAGE58
   U26 AU73 VSS_AU73 GENOA_SP5-SOCKET6096_13568-001,SMLF,IO,DGA^6000030     I6 @T6G_MB_LIB.T6G(SCH_1):PAGE58
   U26 AU75 VSS_AU75 GENOA_SP5-SOCKET6096_13568-001,SMLF,IO,DGA^6000030     I6 @T6G_MB_LIB.T6G(SCH_1):PAGE58
   U26  AV3 VSS_AV3 GENOA_SP5-SOCKET6096_13568-001,SMLF,IO,DGA^6000030     I6 @T6G_MB_LIB.T6G(SCH_1):PAGE58
   U26  AV8 VSS_AV8 GENOA_SP5-SOCKET6096_13568-001,SMLF,IO,DGA^6000030     I6 @T6G_MB_LIB.T6G(SCH_1):PAGE58
   U26 AV10 VSS_AV10 GENOA_SP5-SOCKET6096_13568-001,SMLF,IO,DGA^6000030     I6 @T6G_MB_LIB.T6G(SCH_1):PAGE58
   U26 AV15 VSS_AV15 GENOA_SP5-SOCKET6096_13568-001,SMLF,IO,DGA^6000030     I6 @T6G_MB_LIB.T6G(SCH_1):PAGE58
   U26 AV17 VSS_AV17 GENOA_SP5-SOCKET6096_13568-001,SMLF,IO,DGA^6000030     I6 @T6G_MB_LIB.T6G(SCH_1):PAGE58
   U26 AV23 VSS_AV23 GENOA_SP5-SOCKET6096_13568-001,SMLF,IO,DGA^6000030     I6 @T6G_MB_LIB.T6G(SCH_1):PAGE58
   U26 AV25 VSS_AV25 GENOA_SP5-SOCKET6096_13568-001,SMLF,IO,DGA^6000030     I6 @T6G_MB_LIB.T6G(SCH_1):PAGE58
   U26 AV27 VSS_AV27 GENOA_SP5-SOCKET6096_13568-001,SMLF,IO,DGA^6000030     I6 @T6G_MB_LIB.T6G(SCH_1):PAGE58
   U26 AV29 VSS_AV29 GENOA_SP5-SOCKET6096_13568-001,SMLF,IO,DGA^6000030     I6 @T6G_MB_LIB.T6G(SCH_1):PAGE58
   U26 AV31 VSS_AV31 GENOA_SP5-SOCKET6096_13568-001,SMLF,IO,DGA^6000030     I6 @T6G_MB_LIB.T6G(SCH_1):PAGE58
   U26 AV33 VSS_AV33 GENOA_SP5-SOCKET6096_13568-001,SMLF,IO,DGA^6000030     I6 @T6G_MB_LIB.T6G(SCH_1):PAGE58
   U26 AV35 VSS_AV35 GENOA_SP5-SOCKET6096_13568-001,SMLF,IO,DGA^6000030     I6 @T6G_MB_LIB.T6G(SCH_1):PAGE58
   U26 AV37 VSS_AV37 GENOA_SP5-SOCKET6096_13568-001,SMLF,IO,DGA^6000030     I6 @T6G_MB_LIB.T6G(SCH_1):PAGE58
   U26 AV40 VSS_AV40 GENOA_SP5-SOCKET6096_13568-001,SMLF,IO,DGA^6000030     I6 @T6G_MB_LIB.T6G(SCH_1):PAGE58
   U26 AV42 VSS_AV42 GENOA_SP5-SOCKET6096_13568-001,SMLF,IO,DGA^6000030     I6 @T6G_MB_LIB.T6G(SCH_1):PAGE58
   U26 AV44 VSS_AV44 GENOA_SP5-SOCKET6096_13568-001,SMLF,IO,DGA^6000030     I6 @T6G_MB_LIB.T6G(SCH_1):PAGE58
   U26 AV46 VSS_AV46 GENOA_SP5-SOCKET6096_13568-001,SMLF,IO,DGA^6000030     I6 @T6G_MB_LIB.T6G(SCH_1):PAGE58
   U26 AV48 VSS_AV48 GENOA_SP5-SOCKET6096_13568-001,SMLF,IO,DGA^6000030     I6 @T6G_MB_LIB.T6G(SCH_1):PAGE58
   U26 AV50 VSS_AV50 GENOA_SP5-SOCKET6096_13568-001,SMLF,IO,DGA^6000030     I6 @T6G_MB_LIB.T6G(SCH_1):PAGE58
   U26 AV52 VSS_AV52 GENOA_SP5-SOCKET6096_13568-001,SMLF,IO,DGA^6000030     I6 @T6G_MB_LIB.T6G(SCH_1):PAGE58
   U26 AV54 VSS_AV54 GENOA_SP5-SOCKET6096_13568-001,SMLF,IO,DGA^6000030     I6 @T6G_MB_LIB.T6G(SCH_1):PAGE58
   U26 AV59 VSS_AV59 GENOA_SP5-SOCKET6096_13568-001,SMLF,IO,DGA^6000030     I6 @T6G_MB_LIB.T6G(SCH_1):PAGE58
   U26 AV61 VSS_AV61 GENOA_SP5-SOCKET6096_13568-001,SMLF,IO,DGA^6000030     I6 @T6G_MB_LIB.T6G(SCH_1):PAGE58
   U26 AV66 VSS_AV66 GENOA_SP5-SOCKET6096_13568-001,SMLF,IO,DGA^6000030     I6 @T6G_MB_LIB.T6G(SCH_1):PAGE58
   U26 AV68 VSS_AV68 GENOA_SP5-SOCKET6096_13568-001,SMLF,IO,DGA^6000030     I6 @T6G_MB_LIB.T6G(SCH_1):PAGE58
   U26 AV73 VSS_AV73 GENOA_SP5-SOCKET6096_13568-001,SMLF,IO,DGA^6000030     I6 @T6G_MB_LIB.T6G(SCH_1):PAGE58
   U26  AW1 VSS_AW1 GENOA_SP5-SOCKET6096_13568-001,SMLF,IO,DGA^6000030     I6 @T6G_MB_LIB.T6G(SCH_1):PAGE58
   U26  AW4 VSS_AW4 GENOA_SP5-SOCKET6096_13568-001,SMLF,IO,DGA^6000030     I6 @T6G_MB_LIB.T6G(SCH_1):PAGE58
   U26  AW6 VSS_AW6 GENOA_SP5-SOCKET6096_13568-001,SMLF,IO,DGA^6000030     I6 @T6G_MB_LIB.T6G(SCH_1):PAGE58
   U26  AW8 VSS_AW8 GENOA_SP5-SOCKET6096_13568-001,SMLF,IO,DGA^6000030     I6 @T6G_MB_LIB.T6G(SCH_1):PAGE58
   U26 AW11 VSS_AW11 GENOA_SP5-SOCKET6096_13568-001,SMLF,IO,DGA^6000030     I6 @T6G_MB_LIB.T6G(SCH_1):PAGE58
   U26 AW13 VSS_AW13 GENOA_SP5-SOCKET6096_13568-001,SMLF,IO,DGA^6000030     I6 @T6G_MB_LIB.T6G(SCH_1):PAGE58
   U26 AW15 VSS_AW15 GENOA_SP5-SOCKET6096_13568-001,SMLF,IO,DGA^6000030     I6 @T6G_MB_LIB.T6G(SCH_1):PAGE58
   U26 AW18 VSS_AW18 GENOA_SP5-SOCKET6096_13568-001,SMLF,IO,DGA^6000030     I6 @T6G_MB_LIB.T6G(SCH_1):PAGE58
   U26 AW20 VSS_AW20 GENOA_SP5-SOCKET6096_13568-001,SMLF,IO,DGA^6000030     I6 @T6G_MB_LIB.T6G(SCH_1):PAGE58
   U26 AW22 VSS_AW22 GENOA_SP5-SOCKET6096_13568-001,SMLF,IO,DGA^6000030     I6 @T6G_MB_LIB.T6G(SCH_1):PAGE58
   U26 AW24 VSS_AW24 GENOA_SP5-SOCKET6096_13568-001,SMLF,IO,DGA^6000030     I6 @T6G_MB_LIB.T6G(SCH_1):PAGE58
   U26 AW26 VSS_AW26 GENOA_SP5-SOCKET6096_13568-001,SMLF,IO,DGA^6000030     I6 @T6G_MB_LIB.T6G(SCH_1):PAGE58
   U26 AW28 VSS_AW28 GENOA_SP5-SOCKET6096_13568-001,SMLF,IO,DGA^6000030     I6 @T6G_MB_LIB.T6G(SCH_1):PAGE58
   U26 AW49 VSS_AW49 GENOA_SP5-SOCKET6096_13568-001,SMLF,IO,DGA^6000030     I6 @T6G_MB_LIB.T6G(SCH_1):PAGE58
   U26 AW51 VSS_AW51 GENOA_SP5-SOCKET6096_13568-001,SMLF,IO,DGA^6000030     I6 @T6G_MB_LIB.T6G(SCH_1):PAGE58
   U26 AW53 VSS_AW53 GENOA_SP5-SOCKET6096_13568-001,SMLF,IO,DGA^6000030     I6 @T6G_MB_LIB.T6G(SCH_1):PAGE58
   U26 AW56 VSS_AW56 GENOA_SP5-SOCKET6096_13568-001,SMLF,IO,DGA^6000030     I6 @T6G_MB_LIB.T6G(SCH_1):PAGE58
   U26 AW58 VSS_AW58 GENOA_SP5-SOCKET6096_13568-001,SMLF,IO,DGA^6000030     I6 @T6G_MB_LIB.T6G(SCH_1):PAGE58
   U26 AW61 VSS_AW61 GENOA_SP5-SOCKET6096_13568-001,SMLF,IO,DGA^6000030     I6 @T6G_MB_LIB.T6G(SCH_1):PAGE58
   U26 AD49 VSS_AD49 GENOA_SP5-SOCKET6096_13568-001,SMLF,IO,DGA^6000030     I9 @T6G_MB_LIB.T6G(SCH_1):PAGE58
   U26 AD50 VSS_AD50 GENOA_SP5-SOCKET6096_13568-001,SMLF,IO,DGA^6000030     I9 @T6G_MB_LIB.T6G(SCH_1):PAGE58
   U26 AD51 VSS_AD51 GENOA_SP5-SOCKET6096_13568-001,SMLF,IO,DGA^6000030     I9 @T6G_MB_LIB.T6G(SCH_1):PAGE58
   U26 AD52 VSS_AD52 GENOA_SP5-SOCKET6096_13568-001,SMLF,IO,DGA^6000030     I9 @T6G_MB_LIB.T6G(SCH_1):PAGE58
   U26 AD53 VSS_AD53 GENOA_SP5-SOCKET6096_13568-001,SMLF,IO,DGA^6000030     I9 @T6G_MB_LIB.T6G(SCH_1):PAGE58
   U26 AD57 VSS_AD57 GENOA_SP5-SOCKET6096_13568-001,SMLF,IO,DGA^6000030     I9 @T6G_MB_LIB.T6G(SCH_1):PAGE58
   U26 AD59 VSS_AD59 GENOA_SP5-SOCKET6096_13568-001,SMLF,IO,DGA^6000030     I9 @T6G_MB_LIB.T6G(SCH_1):PAGE58
   U26 AD61 VSS_AD61 GENOA_SP5-SOCKET6096_13568-001,SMLF,IO,DGA^6000030     I9 @T6G_MB_LIB.T6G(SCH_1):PAGE58
   U26 AD64 VSS_AD64 GENOA_SP5-SOCKET6096_13568-001,SMLF,IO,DGA^6000030     I9 @T6G_MB_LIB.T6G(SCH_1):PAGE58
   U26 AD66 VSS_AD66 GENOA_SP5-SOCKET6096_13568-001,SMLF,IO,DGA^6000030     I9 @T6G_MB_LIB.T6G(SCH_1):PAGE58
   U26 AD68 VSS_AD68 GENOA_SP5-SOCKET6096_13568-001,SMLF,IO,DGA^6000030     I9 @T6G_MB_LIB.T6G(SCH_1):PAGE58
   U26 AD71 VSS_AD71 GENOA_SP5-SOCKET6096_13568-001,SMLF,IO,DGA^6000030     I9 @T6G_MB_LIB.T6G(SCH_1):PAGE58
   U26 AD73 VSS_AD73 GENOA_SP5-SOCKET6096_13568-001,SMLF,IO,DGA^6000030     I9 @T6G_MB_LIB.T6G(SCH_1):PAGE58
   U26  AE1 VSS_AE1 GENOA_SP5-SOCKET6096_13568-001,SMLF,IO,DGA^6000030     I9 @T6G_MB_LIB.T6G(SCH_1):PAGE58
   U26  AE6 VSS_AE6 GENOA_SP5-SOCKET6096_13568-001,SMLF,IO,DGA^6000030     I9 @T6G_MB_LIB.T6G(SCH_1):PAGE58
   U26  AE8 VSS_AE8 GENOA_SP5-SOCKET6096_13568-001,SMLF,IO,DGA^6000030     I9 @T6G_MB_LIB.T6G(SCH_1):PAGE58
   U26 AE11 VSS_AE11 GENOA_SP5-SOCKET6096_13568-001,SMLF,IO,DGA^6000030     I9 @T6G_MB_LIB.T6G(SCH_1):PAGE58
   U26 AE13 VSS_AE13 GENOA_SP5-SOCKET6096_13568-001,SMLF,IO,DGA^6000030     I9 @T6G_MB_LIB.T6G(SCH_1):PAGE58
   U26 AE15 VSS_AE15 GENOA_SP5-SOCKET6096_13568-001,SMLF,IO,DGA^6000030     I9 @T6G_MB_LIB.T6G(SCH_1):PAGE58
   U26 AE18 VSS_AE18 GENOA_SP5-SOCKET6096_13568-001,SMLF,IO,DGA^6000030     I9 @T6G_MB_LIB.T6G(SCH_1):PAGE58
   U26 AE20 VSS_AE20 GENOA_SP5-SOCKET6096_13568-001,SMLF,IO,DGA^6000030     I9 @T6G_MB_LIB.T6G(SCH_1):PAGE58
   U26 AE22 VSS_AE22 GENOA_SP5-SOCKET6096_13568-001,SMLF,IO,DGA^6000030     I9 @T6G_MB_LIB.T6G(SCH_1):PAGE58
   U26 AE25 VSS_AE25 GENOA_SP5-SOCKET6096_13568-001,SMLF,IO,DGA^6000030     I9 @T6G_MB_LIB.T6G(SCH_1):PAGE58
   U26 AE28 VSS_AE28 GENOA_SP5-SOCKET6096_13568-001,SMLF,IO,DGA^6000030     I9 @T6G_MB_LIB.T6G(SCH_1):PAGE58
   U26 AE31 VSS_AE31 GENOA_SP5-SOCKET6096_13568-001,SMLF,IO,DGA^6000030     I9 @T6G_MB_LIB.T6G(SCH_1):PAGE58
   U26 AE34 VSS_AE34 GENOA_SP5-SOCKET6096_13568-001,SMLF,IO,DGA^6000030     I9 @T6G_MB_LIB.T6G(SCH_1):PAGE58
   U26 AE35 VSS_AE35 GENOA_SP5-SOCKET6096_13568-001,SMLF,IO,DGA^6000030     I9 @T6G_MB_LIB.T6G(SCH_1):PAGE58
   U26 AE36 VSS_AE36 GENOA_SP5-SOCKET6096_13568-001,SMLF,IO,DGA^6000030     I9 @T6G_MB_LIB.T6G(SCH_1):PAGE58
   U26 AE40 VSS_AE40 GENOA_SP5-SOCKET6096_13568-001,SMLF,IO,DGA^6000030     I9 @T6G_MB_LIB.T6G(SCH_1):PAGE58
   U26 AE41 VSS_AE41 GENOA_SP5-SOCKET6096_13568-001,SMLF,IO,DGA^6000030     I9 @T6G_MB_LIB.T6G(SCH_1):PAGE58
   U26 AE42 VSS_AE42 GENOA_SP5-SOCKET6096_13568-001,SMLF,IO,DGA^6000030     I9 @T6G_MB_LIB.T6G(SCH_1):PAGE58
   U26 AE45 VSS_AE45 GENOA_SP5-SOCKET6096_13568-001,SMLF,IO,DGA^6000030     I9 @T6G_MB_LIB.T6G(SCH_1):PAGE58
   U26 AE48 VSS_AE48 GENOA_SP5-SOCKET6096_13568-001,SMLF,IO,DGA^6000030     I9 @T6G_MB_LIB.T6G(SCH_1):PAGE58
   U26 AE51 VSS_AE51 GENOA_SP5-SOCKET6096_13568-001,SMLF,IO,DGA^6000030     I9 @T6G_MB_LIB.T6G(SCH_1):PAGE58
   U26 AE54 VSS_AE54 GENOA_SP5-SOCKET6096_13568-001,SMLF,IO,DGA^6000030     I9 @T6G_MB_LIB.T6G(SCH_1):PAGE58
   U26 AE56 VSS_AE56 GENOA_SP5-SOCKET6096_13568-001,SMLF,IO,DGA^6000030     I9 @T6G_MB_LIB.T6G(SCH_1):PAGE58
   U26 AE58 VSS_AE58 GENOA_SP5-SOCKET6096_13568-001,SMLF,IO,DGA^6000030     I9 @T6G_MB_LIB.T6G(SCH_1):PAGE58
   U26 AE61 VSS_AE61 GENOA_SP5-SOCKET6096_13568-001,SMLF,IO,DGA^6000030     I9 @T6G_MB_LIB.T6G(SCH_1):PAGE58
   U26 AE63 VSS_AE63 GENOA_SP5-SOCKET6096_13568-001,SMLF,IO,DGA^6000030     I9 @T6G_MB_LIB.T6G(SCH_1):PAGE58
   U26 AE65 VSS_AE65 GENOA_SP5-SOCKET6096_13568-001,SMLF,IO,DGA^6000030     I9 @T6G_MB_LIB.T6G(SCH_1):PAGE58
   U26 AE68 VSS_AE68 GENOA_SP5-SOCKET6096_13568-001,SMLF,IO,DGA^6000030     I9 @T6G_MB_LIB.T6G(SCH_1):PAGE58
   U26 AE70 VSS_AE70 GENOA_SP5-SOCKET6096_13568-001,SMLF,IO,DGA^6000030     I9 @T6G_MB_LIB.T6G(SCH_1):PAGE58
   U26 AE72 VSS_AE72 GENOA_SP5-SOCKET6096_13568-001,SMLF,IO,DGA^6000030     I9 @T6G_MB_LIB.T6G(SCH_1):PAGE58
   U26 AE75 VSS_AE75 GENOA_SP5-SOCKET6096_13568-001,SMLF,IO,DGA^6000030     I9 @T6G_MB_LIB.T6G(SCH_1):PAGE58
   U26  AF3 VSS_AF3 GENOA_SP5-SOCKET6096_13568-001,SMLF,IO,DGA^6000030     I9 @T6G_MB_LIB.T6G(SCH_1):PAGE58
   U26  AF8 VSS_AF8 GENOA_SP5-SOCKET6096_13568-001,SMLF,IO,DGA^6000030     I9 @T6G_MB_LIB.T6G(SCH_1):PAGE58
   U26 AF10 VSS_AF10 GENOA_SP5-SOCKET6096_13568-001,SMLF,IO,DGA^6000030     I9 @T6G_MB_LIB.T6G(SCH_1):PAGE58
   U26 AF15 VSS_AF15 GENOA_SP5-SOCKET6096_13568-001,SMLF,IO,DGA^6000030     I9 @T6G_MB_LIB.T6G(SCH_1):PAGE58
   U26 AF17 VSS_AF17 GENOA_SP5-SOCKET6096_13568-001,SMLF,IO,DGA^6000030     I9 @T6G_MB_LIB.T6G(SCH_1):PAGE58
   U26 AF22 VSS_AF22 GENOA_SP5-SOCKET6096_13568-001,SMLF,IO,DGA^6000030     I9 @T6G_MB_LIB.T6G(SCH_1):PAGE58
   U26 AF25 VSS_AF25 GENOA_SP5-SOCKET6096_13568-001,SMLF,IO,DGA^6000030     I9 @T6G_MB_LIB.T6G(SCH_1):PAGE58
   U26 AF28 VSS_AF28 GENOA_SP5-SOCKET6096_13568-001,SMLF,IO,DGA^6000030     I9 @T6G_MB_LIB.T6G(SCH_1):PAGE58
   U26 AF31 VSS_AF31 GENOA_SP5-SOCKET6096_13568-001,SMLF,IO,DGA^6000030     I9 @T6G_MB_LIB.T6G(SCH_1):PAGE58
   U26 AF34 VSS_AF34 GENOA_SP5-SOCKET6096_13568-001,SMLF,IO,DGA^6000030     I9 @T6G_MB_LIB.T6G(SCH_1):PAGE58
   U26 AF37 VSS_AF37 GENOA_SP5-SOCKET6096_13568-001,SMLF,IO,DGA^6000030     I9 @T6G_MB_LIB.T6G(SCH_1):PAGE58
   U26 AF39 VSS_AF39 GENOA_SP5-SOCKET6096_13568-001,SMLF,IO,DGA^6000030     I9 @T6G_MB_LIB.T6G(SCH_1):PAGE58
   U26 AF42 VSS_AF42 GENOA_SP5-SOCKET6096_13568-001,SMLF,IO,DGA^6000030     I9 @T6G_MB_LIB.T6G(SCH_1):PAGE58
   U26 AF45 VSS_AF45 GENOA_SP5-SOCKET6096_13568-001,SMLF,IO,DGA^6000030     I9 @T6G_MB_LIB.T6G(SCH_1):PAGE58
   U26 AF48 VSS_AF48 GENOA_SP5-SOCKET6096_13568-001,SMLF,IO,DGA^6000030     I9 @T6G_MB_LIB.T6G(SCH_1):PAGE58
   U26 AF51 VSS_AF51 GENOA_SP5-SOCKET6096_13568-001,SMLF,IO,DGA^6000030     I9 @T6G_MB_LIB.T6G(SCH_1):PAGE58
   U26 AF54 VSS_AF54 GENOA_SP5-SOCKET6096_13568-001,SMLF,IO,DGA^6000030     I9 @T6G_MB_LIB.T6G(SCH_1):PAGE58
   U26 AF59 VSS_AF59 GENOA_SP5-SOCKET6096_13568-001,SMLF,IO,DGA^6000030     I9 @T6G_MB_LIB.T6G(SCH_1):PAGE58
   U26 AF61 VSS_AF61 GENOA_SP5-SOCKET6096_13568-001,SMLF,IO,DGA^6000030     I9 @T6G_MB_LIB.T6G(SCH_1):PAGE58
   U26 AF66 VSS_AF66 GENOA_SP5-SOCKET6096_13568-001,SMLF,IO,DGA^6000030     I9 @T6G_MB_LIB.T6G(SCH_1):PAGE58
   U26 AF68 VSS_AF68 GENOA_SP5-SOCKET6096_13568-001,SMLF,IO,DGA^6000030     I9 @T6G_MB_LIB.T6G(SCH_1):PAGE58
   U26 AF73 VSS_AF73 GENOA_SP5-SOCKET6096_13568-001,SMLF,IO,DGA^6000030     I9 @T6G_MB_LIB.T6G(SCH_1):PAGE58
   U26  AG1 VSS_AG1 GENOA_SP5-SOCKET6096_13568-001,SMLF,IO,DGA^6000030     I9 @T6G_MB_LIB.T6G(SCH_1):PAGE58
   U26  AG4 VSS_AG4 GENOA_SP5-SOCKET6096_13568-001,SMLF,IO,DGA^6000030     I9 @T6G_MB_LIB.T6G(SCH_1):PAGE58
   U26  AG6 VSS_AG6 GENOA_SP5-SOCKET6096_13568-001,SMLF,IO,DGA^6000030     I9 @T6G_MB_LIB.T6G(SCH_1):PAGE58
   U26  AG8 VSS_AG8 GENOA_SP5-SOCKET6096_13568-001,SMLF,IO,DGA^6000030     I9 @T6G_MB_LIB.T6G(SCH_1):PAGE58
   U26 AG11 VSS_AG11 GENOA_SP5-SOCKET6096_13568-001,SMLF,IO,DGA^6000030     I9 @T6G_MB_LIB.T6G(SCH_1):PAGE58
   U26 AG13 VSS_AG13 GENOA_SP5-SOCKET6096_13568-001,SMLF,IO,DGA^6000030     I9 @T6G_MB_LIB.T6G(SCH_1):PAGE58
   U26 AG15 VSS_AG15 GENOA_SP5-SOCKET6096_13568-001,SMLF,IO,DGA^6000030     I9 @T6G_MB_LIB.T6G(SCH_1):PAGE58
   U26 AG18 VSS_AG18 GENOA_SP5-SOCKET6096_13568-001,SMLF,IO,DGA^6000030     I9 @T6G_MB_LIB.T6G(SCH_1):PAGE58
   U26 AG20 VSS_AG20 GENOA_SP5-SOCKET6096_13568-001,SMLF,IO,DGA^6000030     I9 @T6G_MB_LIB.T6G(SCH_1):PAGE58
   U26 AG22 VSS_AG22 GENOA_SP5-SOCKET6096_13568-001,SMLF,IO,DGA^6000030     I9 @T6G_MB_LIB.T6G(SCH_1):PAGE58
   U26 AG25 VSS_AG25 GENOA_SP5-SOCKET6096_13568-001,SMLF,IO,DGA^6000030     I9 @T6G_MB_LIB.T6G(SCH_1):PAGE58
   U26 AG28 VSS_AG28 GENOA_SP5-SOCKET6096_13568-001,SMLF,IO,DGA^6000030     I9 @T6G_MB_LIB.T6G(SCH_1):PAGE58
   U26 AG31 VSS_AG31 GENOA_SP5-SOCKET6096_13568-001,SMLF,IO,DGA^6000030     I9 @T6G_MB_LIB.T6G(SCH_1):PAGE58
   U26 AG34 VSS_AG34 GENOA_SP5-SOCKET6096_13568-001,SMLF,IO,DGA^6000030     I9 @T6G_MB_LIB.T6G(SCH_1):PAGE58
   U26 AG42 VSS_AG42 GENOA_SP5-SOCKET6096_13568-001,SMLF,IO,DGA^6000030     I9 @T6G_MB_LIB.T6G(SCH_1):PAGE58
   U26 AG45 VSS_AG45 GENOA_SP5-SOCKET6096_13568-001,SMLF,IO,DGA^6000030     I9 @T6G_MB_LIB.T6G(SCH_1):PAGE58
   U26 AG48 VSS_AG48 GENOA_SP5-SOCKET6096_13568-001,SMLF,IO,DGA^6000030     I9 @T6G_MB_LIB.T6G(SCH_1):PAGE58
   U26 AG51 VSS_AG51 GENOA_SP5-SOCKET6096_13568-001,SMLF,IO,DGA^6000030     I9 @T6G_MB_LIB.T6G(SCH_1):PAGE58
   U26 AG54 VSS_AG54 GENOA_SP5-SOCKET6096_13568-001,SMLF,IO,DGA^6000030     I9 @T6G_MB_LIB.T6G(SCH_1):PAGE58
   U26 AG56 VSS_AG56 GENOA_SP5-SOCKET6096_13568-001,SMLF,IO,DGA^6000030     I9 @T6G_MB_LIB.T6G(SCH_1):PAGE58
   U26 AG58 VSS_AG58 GENOA_SP5-SOCKET6096_13568-001,SMLF,IO,DGA^6000030     I9 @T6G_MB_LIB.T6G(SCH_1):PAGE58
   U26 AG61 VSS_AG61 GENOA_SP5-SOCKET6096_13568-001,SMLF,IO,DGA^6000030     I9 @T6G_MB_LIB.T6G(SCH_1):PAGE58
   U26 AG63 VSS_AG63 GENOA_SP5-SOCKET6096_13568-001,SMLF,IO,DGA^6000030     I9 @T6G_MB_LIB.T6G(SCH_1):PAGE58
   U26 AG65 VSS_AG65 GENOA_SP5-SOCKET6096_13568-001,SMLF,IO,DGA^6000030     I9 @T6G_MB_LIB.T6G(SCH_1):PAGE58
   U26 AG68 VSS_AG68 GENOA_SP5-SOCKET6096_13568-001,SMLF,IO,DGA^6000030     I9 @T6G_MB_LIB.T6G(SCH_1):PAGE58
   U26 AG70 VSS_AG70 GENOA_SP5-SOCKET6096_13568-001,SMLF,IO,DGA^6000030     I9 @T6G_MB_LIB.T6G(SCH_1):PAGE58
   U26 AG72 VSS_AG72 GENOA_SP5-SOCKET6096_13568-001,SMLF,IO,DGA^6000030     I9 @T6G_MB_LIB.T6G(SCH_1):PAGE58
   U26 AG75 VSS_AG75 GENOA_SP5-SOCKET6096_13568-001,SMLF,IO,DGA^6000030     I9 @T6G_MB_LIB.T6G(SCH_1):PAGE58
   U26  AH3 VSS_AH3 GENOA_SP5-SOCKET6096_13568-001,SMLF,IO,DGA^6000030     I9 @T6G_MB_LIB.T6G(SCH_1):PAGE58
   U26  AH5 VSS_AH5 GENOA_SP5-SOCKET6096_13568-001,SMLF,IO,DGA^6000030     I9 @T6G_MB_LIB.T6G(SCH_1):PAGE58
   U26  AH8 VSS_AH8 GENOA_SP5-SOCKET6096_13568-001,SMLF,IO,DGA^6000030     I9 @T6G_MB_LIB.T6G(SCH_1):PAGE58
   U26 AH10 VSS_AH10 GENOA_SP5-SOCKET6096_13568-001,SMLF,IO,DGA^6000030     I9 @T6G_MB_LIB.T6G(SCH_1):PAGE58
   U26 AH12 VSS_AH12 GENOA_SP5-SOCKET6096_13568-001,SMLF,IO,DGA^6000030     I9 @T6G_MB_LIB.T6G(SCH_1):PAGE58
   U26 AH15 VSS_AH15 GENOA_SP5-SOCKET6096_13568-001,SMLF,IO,DGA^6000030     I9 @T6G_MB_LIB.T6G(SCH_1):PAGE58
   U26 AH17 VSS_AH17 GENOA_SP5-SOCKET6096_13568-001,SMLF,IO,DGA^6000030     I9 @T6G_MB_LIB.T6G(SCH_1):PAGE58
   U26 AH19 VSS_AH19 GENOA_SP5-SOCKET6096_13568-001,SMLF,IO,DGA^6000030     I9 @T6G_MB_LIB.T6G(SCH_1):PAGE58
   U26 AH23 VSS_AH23 GENOA_SP5-SOCKET6096_13568-001,SMLF,IO,DGA^6000030     I9 @T6G_MB_LIB.T6G(SCH_1):PAGE58
   U26 AH24 VSS_AH24 GENOA_SP5-SOCKET6096_13568-001,SMLF,IO,DGA^6000030     I9 @T6G_MB_LIB.T6G(SCH_1):PAGE58
   U26 AH25 VSS_AH25 GENOA_SP5-SOCKET6096_13568-001,SMLF,IO,DGA^6000030     I9 @T6G_MB_LIB.T6G(SCH_1):PAGE58
   U26 AH26 VSS_AH26 GENOA_SP5-SOCKET6096_13568-001,SMLF,IO,DGA^6000030     I9 @T6G_MB_LIB.T6G(SCH_1):PAGE58
   U26 AH27 VSS_AH27 GENOA_SP5-SOCKET6096_13568-001,SMLF,IO,DGA^6000030     I9 @T6G_MB_LIB.T6G(SCH_1):PAGE58
   U26 AH28 VSS_AH28 GENOA_SP5-SOCKET6096_13568-001,SMLF,IO,DGA^6000030     I9 @T6G_MB_LIB.T6G(SCH_1):PAGE58
   U26 AH29 VSS_AH29 GENOA_SP5-SOCKET6096_13568-001,SMLF,IO,DGA^6000030     I9 @T6G_MB_LIB.T6G(SCH_1):PAGE58
   U26 AH30 VSS_AH30 GENOA_SP5-SOCKET6096_13568-001,SMLF,IO,DGA^6000030     I9 @T6G_MB_LIB.T6G(SCH_1):PAGE58
   U26 AH31 VSS_AH31 GENOA_SP5-SOCKET6096_13568-001,SMLF,IO,DGA^6000030     I9 @T6G_MB_LIB.T6G(SCH_1):PAGE58
   U26 AH32 VSS_AH32 GENOA_SP5-SOCKET6096_13568-001,SMLF,IO,DGA^6000030     I9 @T6G_MB_LIB.T6G(SCH_1):PAGE58
   U26 AH34 VSS_AH34 GENOA_SP5-SOCKET6096_13568-001,SMLF,IO,DGA^6000030     I9 @T6G_MB_LIB.T6G(SCH_1):PAGE58
   U26 AH37 VSS_AH37 GENOA_SP5-SOCKET6096_13568-001,SMLF,IO,DGA^6000030     I9 @T6G_MB_LIB.T6G(SCH_1):PAGE58
   U26 AH39 VSS_AH39 GENOA_SP5-SOCKET6096_13568-001,SMLF,IO,DGA^6000030     I9 @T6G_MB_LIB.T6G(SCH_1):PAGE58
   U26 AH42 VSS_AH42 GENOA_SP5-SOCKET6096_13568-001,SMLF,IO,DGA^6000030     I9 @T6G_MB_LIB.T6G(SCH_1):PAGE58
   U26 AH43 VSS_AH43 GENOA_SP5-SOCKET6096_13568-001,SMLF,IO,DGA^6000030     I9 @T6G_MB_LIB.T6G(SCH_1):PAGE58
   U26 AH44 VSS_AH44 GENOA_SP5-SOCKET6096_13568-001,SMLF,IO,DGA^6000030     I9 @T6G_MB_LIB.T6G(SCH_1):PAGE58
   U26 AH45 VSS_AH45 GENOA_SP5-SOCKET6096_13568-001,SMLF,IO,DGA^6000030     I9 @T6G_MB_LIB.T6G(SCH_1):PAGE58
   U26 AH46 VSS_AH46 GENOA_SP5-SOCKET6096_13568-001,SMLF,IO,DGA^6000030     I9 @T6G_MB_LIB.T6G(SCH_1):PAGE58
   U26 AH47 VSS_AH47 GENOA_SP5-SOCKET6096_13568-001,SMLF,IO,DGA^6000030     I9 @T6G_MB_LIB.T6G(SCH_1):PAGE58
   U26 AH48 VSS_AH48 GENOA_SP5-SOCKET6096_13568-001,SMLF,IO,DGA^6000030     I9 @T6G_MB_LIB.T6G(SCH_1):PAGE58
   U26 AH49 VSS_AH49 GENOA_SP5-SOCKET6096_13568-001,SMLF,IO,DGA^6000030     I9 @T6G_MB_LIB.T6G(SCH_1):PAGE58
   U26 AH50 VSS_AH50 GENOA_SP5-SOCKET6096_13568-001,SMLF,IO,DGA^6000030     I9 @T6G_MB_LIB.T6G(SCH_1):PAGE58
   U26 AH51 VSS_AH51 GENOA_SP5-SOCKET6096_13568-001,SMLF,IO,DGA^6000030     I9 @T6G_MB_LIB.T6G(SCH_1):PAGE58
   U26 AH52 VSS_AH52 GENOA_SP5-SOCKET6096_13568-001,SMLF,IO,DGA^6000030     I9 @T6G_MB_LIB.T6G(SCH_1):PAGE58
   U26 AH53 VSS_AH53 GENOA_SP5-SOCKET6096_13568-001,SMLF,IO,DGA^6000030     I9 @T6G_MB_LIB.T6G(SCH_1):PAGE58
   U26 AH57 VSS_AH57 GENOA_SP5-SOCKET6096_13568-001,SMLF,IO,DGA^6000030     I9 @T6G_MB_LIB.T6G(SCH_1):PAGE58
   U26 AH59 VSS_AH59 GENOA_SP5-SOCKET6096_13568-001,SMLF,IO,DGA^6000030     I9 @T6G_MB_LIB.T6G(SCH_1):PAGE58
   U26 AH61 VSS_AH61 GENOA_SP5-SOCKET6096_13568-001,SMLF,IO,DGA^6000030     I9 @T6G_MB_LIB.T6G(SCH_1):PAGE58
   U26 AH64 VSS_AH64 GENOA_SP5-SOCKET6096_13568-001,SMLF,IO,DGA^6000030     I9 @T6G_MB_LIB.T6G(SCH_1):PAGE58
   U26 AH66 VSS_AH66 GENOA_SP5-SOCKET6096_13568-001,SMLF,IO,DGA^6000030     I9 @T6G_MB_LIB.T6G(SCH_1):PAGE58
   U26 AH68 VSS_AH68 GENOA_SP5-SOCKET6096_13568-001,SMLF,IO,DGA^6000030     I9 @T6G_MB_LIB.T6G(SCH_1):PAGE58
   U26 AH71 VSS_AH71 GENOA_SP5-SOCKET6096_13568-001,SMLF,IO,DGA^6000030     I9 @T6G_MB_LIB.T6G(SCH_1):PAGE58
   U26 AH73 VSS_AH73 GENOA_SP5-SOCKET6096_13568-001,SMLF,IO,DGA^6000030     I9 @T6G_MB_LIB.T6G(SCH_1):PAGE58
   U26  AJ1 VSS_AJ1 GENOA_SP5-SOCKET6096_13568-001,SMLF,IO,DGA^6000030     I9 @T6G_MB_LIB.T6G(SCH_1):PAGE58
   U26  AJ6 VSS_AJ6 GENOA_SP5-SOCKET6096_13568-001,SMLF,IO,DGA^6000030     I9 @T6G_MB_LIB.T6G(SCH_1):PAGE58
   U26  AJ8 VSS_AJ8 GENOA_SP5-SOCKET6096_13568-001,SMLF,IO,DGA^6000030     I9 @T6G_MB_LIB.T6G(SCH_1):PAGE58
   U26 AJ15 VSS_AJ15 GENOA_SP5-SOCKET6096_13568-001,SMLF,IO,DGA^6000030     I9 @T6G_MB_LIB.T6G(SCH_1):PAGE58
   U26 AJ20 VSS_AJ20 GENOA_SP5-SOCKET6096_13568-001,SMLF,IO,DGA^6000030     I9 @T6G_MB_LIB.T6G(SCH_1):PAGE58
   U26 AJ22 VSS_AJ22 GENOA_SP5-SOCKET6096_13568-001,SMLF,IO,DGA^6000030     I9 @T6G_MB_LIB.T6G(SCH_1):PAGE58
   U26 AJ25 VSS_AJ25 GENOA_SP5-SOCKET6096_13568-001,SMLF,IO,DGA^6000030     I9 @T6G_MB_LIB.T6G(SCH_1):PAGE58
   U26 AJ28 VSS_AJ28 GENOA_SP5-SOCKET6096_13568-001,SMLF,IO,DGA^6000030     I9 @T6G_MB_LIB.T6G(SCH_1):PAGE58
   U26 AJ31 VSS_AJ31 GENOA_SP5-SOCKET6096_13568-001,SMLF,IO,DGA^6000030     I9 @T6G_MB_LIB.T6G(SCH_1):PAGE58
   U26 AJ34 VSS_AJ34 GENOA_SP5-SOCKET6096_13568-001,SMLF,IO,DGA^6000030     I9 @T6G_MB_LIB.T6G(SCH_1):PAGE58
   U26 AJ35 VSS_AJ35 GENOA_SP5-SOCKET6096_13568-001,SMLF,IO,DGA^6000030     I9 @T6G_MB_LIB.T6G(SCH_1):PAGE58
   U26 AJ36 VSS_AJ36 GENOA_SP5-SOCKET6096_13568-001,SMLF,IO,DGA^6000030     I9 @T6G_MB_LIB.T6G(SCH_1):PAGE58
   U26 AJ40 VSS_AJ40 GENOA_SP5-SOCKET6096_13568-001,SMLF,IO,DGA^6000030     I9 @T6G_MB_LIB.T6G(SCH_1):PAGE58
   U26 AJ41 VSS_AJ41 GENOA_SP5-SOCKET6096_13568-001,SMLF,IO,DGA^6000030     I9 @T6G_MB_LIB.T6G(SCH_1):PAGE58
   U26 AJ42 VSS_AJ42 GENOA_SP5-SOCKET6096_13568-001,SMLF,IO,DGA^6000030     I9 @T6G_MB_LIB.T6G(SCH_1):PAGE58
   U26 AJ45 VSS_AJ45 GENOA_SP5-SOCKET6096_13568-001,SMLF,IO,DGA^6000030     I9 @T6G_MB_LIB.T6G(SCH_1):PAGE58
   U26 AJ48 VSS_AJ48 GENOA_SP5-SOCKET6096_13568-001,SMLF,IO,DGA^6000030     I9 @T6G_MB_LIB.T6G(SCH_1):PAGE58
   U26 AJ51 VSS_AJ51 GENOA_SP5-SOCKET6096_13568-001,SMLF,IO,DGA^6000030     I9 @T6G_MB_LIB.T6G(SCH_1):PAGE58
   U26 AJ54 VSS_AJ54 GENOA_SP5-SOCKET6096_13568-001,SMLF,IO,DGA^6000030     I9 @T6G_MB_LIB.T6G(SCH_1):PAGE58
   U26 AJ56 VSS_AJ56 GENOA_SP5-SOCKET6096_13568-001,SMLF,IO,DGA^6000030     I9 @T6G_MB_LIB.T6G(SCH_1):PAGE58
   U26 AJ61 VSS_AJ61 GENOA_SP5-SOCKET6096_13568-001,SMLF,IO,DGA^6000030     I9 @T6G_MB_LIB.T6G(SCH_1):PAGE58
   U26 AJ63 VSS_AJ63 GENOA_SP5-SOCKET6096_13568-001,SMLF,IO,DGA^6000030     I9 @T6G_MB_LIB.T6G(SCH_1):PAGE58
   U26 AJ68 VSS_AJ68 GENOA_SP5-SOCKET6096_13568-001,SMLF,IO,DGA^6000030     I9 @T6G_MB_LIB.T6G(SCH_1):PAGE58
   U26 AJ70 VSS_AJ70 GENOA_SP5-SOCKET6096_13568-001,SMLF,IO,DGA^6000030     I9 @T6G_MB_LIB.T6G(SCH_1):PAGE58
   U26 AJ75 VSS_AJ75 GENOA_SP5-SOCKET6096_13568-001,SMLF,IO,DGA^6000030     I9 @T6G_MB_LIB.T6G(SCH_1):PAGE58
   U26  AK3 VSS_AK3 GENOA_SP5-SOCKET6096_13568-001,SMLF,IO,DGA^6000030     I9 @T6G_MB_LIB.T6G(SCH_1):PAGE58
   U26  AK5 VSS_AK5 GENOA_SP5-SOCKET6096_13568-001,SMLF,IO,DGA^6000030     I9 @T6G_MB_LIB.T6G(SCH_1):PAGE58
   U26  AK8 VSS_AK8 GENOA_SP5-SOCKET6096_13568-001,SMLF,IO,DGA^6000030     I9 @T6G_MB_LIB.T6G(SCH_1):PAGE58
   U26 AK10 VSS_AK10 GENOA_SP5-SOCKET6096_13568-001,SMLF,IO,DGA^6000030     I9 @T6G_MB_LIB.T6G(SCH_1):PAGE58
   U26 AK12 VSS_AK12 GENOA_SP5-SOCKET6096_13568-001,SMLF,IO,DGA^6000030     I9 @T6G_MB_LIB.T6G(SCH_1):PAGE58
   U26 AK15 VSS_AK15 GENOA_SP5-SOCKET6096_13568-001,SMLF,IO,DGA^6000030     I9 @T6G_MB_LIB.T6G(SCH_1):PAGE58
   U26 AK17 VSS_AK17 GENOA_SP5-SOCKET6096_13568-001,SMLF,IO,DGA^6000030     I9 @T6G_MB_LIB.T6G(SCH_1):PAGE58
   U26 AK19 VSS_AK19 GENOA_SP5-SOCKET6096_13568-001,SMLF,IO,DGA^6000030     I9 @T6G_MB_LIB.T6G(SCH_1):PAGE58
   U26 AK22 VSS_AK22 GENOA_SP5-SOCKET6096_13568-001,SMLF,IO,DGA^6000030     I9 @T6G_MB_LIB.T6G(SCH_1):PAGE58
   U26 AK25 VSS_AK25 GENOA_SP5-SOCKET6096_13568-001,SMLF,IO,DGA^6000030     I9 @T6G_MB_LIB.T6G(SCH_1):PAGE58
   U26 AK28 VSS_AK28 GENOA_SP5-SOCKET6096_13568-001,SMLF,IO,DGA^6000030     I9 @T6G_MB_LIB.T6G(SCH_1):PAGE58
   U26 AK31 VSS_AK31 GENOA_SP5-SOCKET6096_13568-001,SMLF,IO,DGA^6000030     I9 @T6G_MB_LIB.T6G(SCH_1):PAGE58
   U26 AK34 VSS_AK34 GENOA_SP5-SOCKET6096_13568-001,SMLF,IO,DGA^6000030     I9 @T6G_MB_LIB.T6G(SCH_1):PAGE58
   U26 AK37 VSS_AK37 GENOA_SP5-SOCKET6096_13568-001,SMLF,IO,DGA^6000030     I9 @T6G_MB_LIB.T6G(SCH_1):PAGE58
   U26 AK39 VSS_AK39 GENOA_SP5-SOCKET6096_13568-001,SMLF,IO,DGA^6000030     I9 @T6G_MB_LIB.T6G(SCH_1):PAGE58
   U26 AK42 VSS_AK42 GENOA_SP5-SOCKET6096_13568-001,SMLF,IO,DGA^6000030     I9 @T6G_MB_LIB.T6G(SCH_1):PAGE58
   U26 AK45 VSS_AK45 GENOA_SP5-SOCKET6096_13568-001,SMLF,IO,DGA^6000030     I9 @T6G_MB_LIB.T6G(SCH_1):PAGE58
   U26 AK48 VSS_AK48 GENOA_SP5-SOCKET6096_13568-001,SMLF,IO,DGA^6000030     I9 @T6G_MB_LIB.T6G(SCH_1):PAGE58
   U26 AK51 VSS_AK51 GENOA_SP5-SOCKET6096_13568-001,SMLF,IO,DGA^6000030     I9 @T6G_MB_LIB.T6G(SCH_1):PAGE58
   U26 AK54 VSS_AK54 GENOA_SP5-SOCKET6096_13568-001,SMLF,IO,DGA^6000030     I9 @T6G_MB_LIB.T6G(SCH_1):PAGE58
   U26 AK57 VSS_AK57 GENOA_SP5-SOCKET6096_13568-001,SMLF,IO,DGA^6000030     I9 @T6G_MB_LIB.T6G(SCH_1):PAGE58
   U26 AK59 VSS_AK59 GENOA_SP5-SOCKET6096_13568-001,SMLF,IO,DGA^6000030     I9 @T6G_MB_LIB.T6G(SCH_1):PAGE58
   U26 AK61 VSS_AK61 GENOA_SP5-SOCKET6096_13568-001,SMLF,IO,DGA^6000030     I9 @T6G_MB_LIB.T6G(SCH_1):PAGE58
   U26 AK64 VSS_AK64 GENOA_SP5-SOCKET6096_13568-001,SMLF,IO,DGA^6000030     I9 @T6G_MB_LIB.T6G(SCH_1):PAGE58
   U26 AK66 VSS_AK66 GENOA_SP5-SOCKET6096_13568-001,SMLF,IO,DGA^6000030     I9 @T6G_MB_LIB.T6G(SCH_1):PAGE58
   U26 AK68 VSS_AK68 GENOA_SP5-SOCKET6096_13568-001,SMLF,IO,DGA^6000030     I9 @T6G_MB_LIB.T6G(SCH_1):PAGE58
   U26 AK71 VSS_AK71 GENOA_SP5-SOCKET6096_13568-001,SMLF,IO,DGA^6000030     I9 @T6G_MB_LIB.T6G(SCH_1):PAGE58
   U26 AK73 VSS_AK73 GENOA_SP5-SOCKET6096_13568-001,SMLF,IO,DGA^6000030     I9 @T6G_MB_LIB.T6G(SCH_1):PAGE58
   U26  AL1 VSS_AL1 GENOA_SP5-SOCKET6096_13568-001,SMLF,IO,DGA^6000030     I9 @T6G_MB_LIB.T6G(SCH_1):PAGE58
   U26  AL4 VSS_AL4 GENOA_SP5-SOCKET6096_13568-001,SMLF,IO,DGA^6000030     I9 @T6G_MB_LIB.T6G(SCH_1):PAGE58
   U26  AL6 VSS_AL6 GENOA_SP5-SOCKET6096_13568-001,SMLF,IO,DGA^6000030     I9 @T6G_MB_LIB.T6G(SCH_1):PAGE58
   U26  AL8 VSS_AL8 GENOA_SP5-SOCKET6096_13568-001,SMLF,IO,DGA^6000030     I9 @T6G_MB_LIB.T6G(SCH_1):PAGE58
   U26 AL11 VSS_AL11 GENOA_SP5-SOCKET6096_13568-001,SMLF,IO,DGA^6000030     I9 @T6G_MB_LIB.T6G(SCH_1):PAGE58
   U26 AL13 VSS_AL13 GENOA_SP5-SOCKET6096_13568-001,SMLF,IO,DGA^6000030     I9 @T6G_MB_LIB.T6G(SCH_1):PAGE58
   U26 AL15 VSS_AL15 GENOA_SP5-SOCKET6096_13568-001,SMLF,IO,DGA^6000030     I9 @T6G_MB_LIB.T6G(SCH_1):PAGE58
   U26 AL18 VSS_AL18 GENOA_SP5-SOCKET6096_13568-001,SMLF,IO,DGA^6000030     I9 @T6G_MB_LIB.T6G(SCH_1):PAGE58
   U26 AL20 VSS_AL20 GENOA_SP5-SOCKET6096_13568-001,SMLF,IO,DGA^6000030     I9 @T6G_MB_LIB.T6G(SCH_1):PAGE58
   U26 AL22 VSS_AL22 GENOA_SP5-SOCKET6096_13568-001,SMLF,IO,DGA^6000030     I9 @T6G_MB_LIB.T6G(SCH_1):PAGE58
   U26 AL25 VSS_AL25 GENOA_SP5-SOCKET6096_13568-001,SMLF,IO,DGA^6000030     I9 @T6G_MB_LIB.T6G(SCH_1):PAGE58
   U26 AL28 VSS_AL28 GENOA_SP5-SOCKET6096_13568-001,SMLF,IO,DGA^6000030     I9 @T6G_MB_LIB.T6G(SCH_1):PAGE58
   U26 AL31 VSS_AL31 GENOA_SP5-SOCKET6096_13568-001,SMLF,IO,DGA^6000030     I9 @T6G_MB_LIB.T6G(SCH_1):PAGE58
   U26 AL34 VSS_AL34 GENOA_SP5-SOCKET6096_13568-001,SMLF,IO,DGA^6000030     I9 @T6G_MB_LIB.T6G(SCH_1):PAGE58
   U26 AL42 VSS_AL42 GENOA_SP5-SOCKET6096_13568-001,SMLF,IO,DGA^6000030     I9 @T6G_MB_LIB.T6G(SCH_1):PAGE58
   U26 AL45 VSS_AL45 GENOA_SP5-SOCKET6096_13568-001,SMLF,IO,DGA^6000030     I9 @T6G_MB_LIB.T6G(SCH_1):PAGE58
   U26 AL48 VSS_AL48 GENOA_SP5-SOCKET6096_13568-001,SMLF,IO,DGA^6000030     I9 @T6G_MB_LIB.T6G(SCH_1):PAGE58
   U26 AL51 VSS_AL51 GENOA_SP5-SOCKET6096_13568-001,SMLF,IO,DGA^6000030     I9 @T6G_MB_LIB.T6G(SCH_1):PAGE58
   U26 AL54 VSS_AL54 GENOA_SP5-SOCKET6096_13568-001,SMLF,IO,DGA^6000030     I9 @T6G_MB_LIB.T6G(SCH_1):PAGE58
   U26 AL56 VSS_AL56 GENOA_SP5-SOCKET6096_13568-001,SMLF,IO,DGA^6000030     I9 @T6G_MB_LIB.T6G(SCH_1):PAGE58
   U26 AL58 VSS_AL58 GENOA_SP5-SOCKET6096_13568-001,SMLF,IO,DGA^6000030     I9 @T6G_MB_LIB.T6G(SCH_1):PAGE58
   U26 AL61 VSS_AL61 GENOA_SP5-SOCKET6096_13568-001,SMLF,IO,DGA^6000030     I9 @T6G_MB_LIB.T6G(SCH_1):PAGE58
   U26 AL63 VSS_AL63 GENOA_SP5-SOCKET6096_13568-001,SMLF,IO,DGA^6000030     I9 @T6G_MB_LIB.T6G(SCH_1):PAGE58
   U26 AL65 VSS_AL65 GENOA_SP5-SOCKET6096_13568-001,SMLF,IO,DGA^6000030     I9 @T6G_MB_LIB.T6G(SCH_1):PAGE58
   U26 AL68 VSS_AL68 GENOA_SP5-SOCKET6096_13568-001,SMLF,IO,DGA^6000030     I9 @T6G_MB_LIB.T6G(SCH_1):PAGE58
   U26 AL70 VSS_AL70 GENOA_SP5-SOCKET6096_13568-001,SMLF,IO,DGA^6000030     I9 @T6G_MB_LIB.T6G(SCH_1):PAGE58
   U26 AL72 VSS_AL72 GENOA_SP5-SOCKET6096_13568-001,SMLF,IO,DGA^6000030     I9 @T6G_MB_LIB.T6G(SCH_1):PAGE58
   U26 AL75 VSS_AL75 GENOA_SP5-SOCKET6096_13568-001,SMLF,IO,DGA^6000030     I9 @T6G_MB_LIB.T6G(SCH_1):PAGE58
   U26  AM3 VSS_AM3 GENOA_SP5-SOCKET6096_13568-001,SMLF,IO,DGA^6000030     I9 @T6G_MB_LIB.T6G(SCH_1):PAGE58
   U26  AM8 VSS_AM8 GENOA_SP5-SOCKET6096_13568-001,SMLF,IO,DGA^6000030     I9 @T6G_MB_LIB.T6G(SCH_1):PAGE58
   U26 AM10 VSS_AM10 GENOA_SP5-SOCKET6096_13568-001,SMLF,IO,DGA^6000030     I9 @T6G_MB_LIB.T6G(SCH_1):PAGE58
   U26 AM15 VSS_AM15 GENOA_SP5-SOCKET6096_13568-001,SMLF,IO,DGA^6000030     I9 @T6G_MB_LIB.T6G(SCH_1):PAGE58
   U26 AM17 VSS_AM17 GENOA_SP5-SOCKET6096_13568-001,SMLF,IO,DGA^6000030     I9 @T6G_MB_LIB.T6G(SCH_1):PAGE58
   U26 AM23 VSS_AM23 GENOA_SP5-SOCKET6096_13568-001,SMLF,IO,DGA^6000030     I9 @T6G_MB_LIB.T6G(SCH_1):PAGE58
   U26 AM24 VSS_AM24 GENOA_SP5-SOCKET6096_13568-001,SMLF,IO,DGA^6000030     I9 @T6G_MB_LIB.T6G(SCH_1):PAGE58
   U26 AM25 VSS_AM25 GENOA_SP5-SOCKET6096_13568-001,SMLF,IO,DGA^6000030     I9 @T6G_MB_LIB.T6G(SCH_1):PAGE58
   U26 AM26 VSS_AM26 GENOA_SP5-SOCKET6096_13568-001,SMLF,IO,DGA^6000030     I9 @T6G_MB_LIB.T6G(SCH_1):PAGE58
   U26 AM27 VSS_AM27 GENOA_SP5-SOCKET6096_13568-001,SMLF,IO,DGA^6000030     I9 @T6G_MB_LIB.T6G(SCH_1):PAGE58
   U26 AM28 VSS_AM28 GENOA_SP5-SOCKET6096_13568-001,SMLF,IO,DGA^6000030     I9 @T6G_MB_LIB.T6G(SCH_1):PAGE58
   U26 AM29 VSS_AM29 GENOA_SP5-SOCKET6096_13568-001,SMLF,IO,DGA^6000030     I9 @T6G_MB_LIB.T6G(SCH_1):PAGE58
   U26 AM30 VSS_AM30 GENOA_SP5-SOCKET6096_13568-001,SMLF,IO,DGA^6000030     I9 @T6G_MB_LIB.T6G(SCH_1):PAGE58
   U26 AM31 VSS_AM31 GENOA_SP5-SOCKET6096_13568-001,SMLF,IO,DGA^6000030     I9 @T6G_MB_LIB.T6G(SCH_1):PAGE58
   U26 AM32 VSS_AM32 GENOA_SP5-SOCKET6096_13568-001,SMLF,IO,DGA^6000030     I9 @T6G_MB_LIB.T6G(SCH_1):PAGE58
   U26 AM33 VSS_AM33 GENOA_SP5-SOCKET6096_13568-001,SMLF,IO,DGA^6000030     I9 @T6G_MB_LIB.T6G(SCH_1):PAGE58
   U26 AM34 VSS_AM34 GENOA_SP5-SOCKET6096_13568-001,SMLF,IO,DGA^6000030     I9 @T6G_MB_LIB.T6G(SCH_1):PAGE58
   U26 AM39 VSS_AM39 GENOA_SP5-SOCKET6096_13568-001,SMLF,IO,DGA^6000030     I9 @T6G_MB_LIB.T6G(SCH_1):PAGE58
   U26  AA1 VSS_AA1 GENOA_SP5-SOCKET6096_13568-001,SMLF,IO,DGA^6000030    I12 @T6G_MB_LIB.T6G(SCH_1):PAGE58
   U26  AA4 VSS_AA4 GENOA_SP5-SOCKET6096_13568-001,SMLF,IO,DGA^6000030    I12 @T6G_MB_LIB.T6G(SCH_1):PAGE58
   U26  AA6 VSS_AA6 GENOA_SP5-SOCKET6096_13568-001,SMLF,IO,DGA^6000030    I12 @T6G_MB_LIB.T6G(SCH_1):PAGE58
   U26  AA8 VSS_AA8 GENOA_SP5-SOCKET6096_13568-001,SMLF,IO,DGA^6000030    I12 @T6G_MB_LIB.T6G(SCH_1):PAGE58
   U26 AA11 VSS_AA11 GENOA_SP5-SOCKET6096_13568-001,SMLF,IO,DGA^6000030    I12 @T6G_MB_LIB.T6G(SCH_1):PAGE58
   U26 AA13 VSS_AA13 GENOA_SP5-SOCKET6096_13568-001,SMLF,IO,DGA^6000030    I12 @T6G_MB_LIB.T6G(SCH_1):PAGE58
   U26 AA15 VSS_AA15 GENOA_SP5-SOCKET6096_13568-001,SMLF,IO,DGA^6000030    I12 @T6G_MB_LIB.T6G(SCH_1):PAGE58
   U26 AA18 VSS_AA18 GENOA_SP5-SOCKET6096_13568-001,SMLF,IO,DGA^6000030    I12 @T6G_MB_LIB.T6G(SCH_1):PAGE58
   U26 AA20 VSS_AA20 GENOA_SP5-SOCKET6096_13568-001,SMLF,IO,DGA^6000030    I12 @T6G_MB_LIB.T6G(SCH_1):PAGE58
   U26 AA31 VSS_AA31 GENOA_SP5-SOCKET6096_13568-001,SMLF,IO,DGA^6000030    I12 @T6G_MB_LIB.T6G(SCH_1):PAGE58
   U26 AA34 VSS_AA34 GENOA_SP5-SOCKET6096_13568-001,SMLF,IO,DGA^6000030    I12 @T6G_MB_LIB.T6G(SCH_1):PAGE58
   U26 AA35 VSS_AA35 GENOA_SP5-SOCKET6096_13568-001,SMLF,IO,DGA^6000030    I12 @T6G_MB_LIB.T6G(SCH_1):PAGE58
   U26 AA36 VSS_AA36 GENOA_SP5-SOCKET6096_13568-001,SMLF,IO,DGA^6000030    I12 @T6G_MB_LIB.T6G(SCH_1):PAGE58
   U26 AA40 VSS_AA40 GENOA_SP5-SOCKET6096_13568-001,SMLF,IO,DGA^6000030    I12 @T6G_MB_LIB.T6G(SCH_1):PAGE58
   U26 AA41 VSS_AA41 GENOA_SP5-SOCKET6096_13568-001,SMLF,IO,DGA^6000030    I12 @T6G_MB_LIB.T6G(SCH_1):PAGE58
   U26 AA45 VSS_AA45 GENOA_SP5-SOCKET6096_13568-001,SMLF,IO,DGA^6000030    I12 @T6G_MB_LIB.T6G(SCH_1):PAGE58
   U26 AA56 VSS_AA56 GENOA_SP5-SOCKET6096_13568-001,SMLF,IO,DGA^6000030    I12 @T6G_MB_LIB.T6G(SCH_1):PAGE58
   U26 AA58 VSS_AA58 GENOA_SP5-SOCKET6096_13568-001,SMLF,IO,DGA^6000030    I12 @T6G_MB_LIB.T6G(SCH_1):PAGE58
   U26 AA61 VSS_AA61 GENOA_SP5-SOCKET6096_13568-001,SMLF,IO,DGA^6000030    I12 @T6G_MB_LIB.T6G(SCH_1):PAGE58
   U26 AA63 VSS_AA63 GENOA_SP5-SOCKET6096_13568-001,SMLF,IO,DGA^6000030    I12 @T6G_MB_LIB.T6G(SCH_1):PAGE58
   U26 AA65 VSS_AA65 GENOA_SP5-SOCKET6096_13568-001,SMLF,IO,DGA^6000030    I12 @T6G_MB_LIB.T6G(SCH_1):PAGE58
   U26 AA68 VSS_AA68 GENOA_SP5-SOCKET6096_13568-001,SMLF,IO,DGA^6000030    I12 @T6G_MB_LIB.T6G(SCH_1):PAGE58
   U26 AA70 VSS_AA70 GENOA_SP5-SOCKET6096_13568-001,SMLF,IO,DGA^6000030    I12 @T6G_MB_LIB.T6G(SCH_1):PAGE58
   U26 AA75 VSS_AA75 GENOA_SP5-SOCKET6096_13568-001,SMLF,IO,DGA^6000030    I12 @T6G_MB_LIB.T6G(SCH_1):PAGE58
   U26  AB3 VSS_AB3 GENOA_SP5-SOCKET6096_13568-001,SMLF,IO,DGA^6000030    I12 @T6G_MB_LIB.T6G(SCH_1):PAGE58
   U26  AB5 VSS_AB5 GENOA_SP5-SOCKET6096_13568-001,SMLF,IO,DGA^6000030    I12 @T6G_MB_LIB.T6G(SCH_1):PAGE58
   U26  AB8 VSS_AB8 GENOA_SP5-SOCKET6096_13568-001,SMLF,IO,DGA^6000030    I12 @T6G_MB_LIB.T6G(SCH_1):PAGE58
   U26 AB10 VSS_AB10 GENOA_SP5-SOCKET6096_13568-001,SMLF,IO,DGA^6000030    I12 @T6G_MB_LIB.T6G(SCH_1):PAGE58
   U26 AB12 VSS_AB12 GENOA_SP5-SOCKET6096_13568-001,SMLF,IO,DGA^6000030    I12 @T6G_MB_LIB.T6G(SCH_1):PAGE58
   U26 AB15 VSS_AB15 GENOA_SP5-SOCKET6096_13568-001,SMLF,IO,DGA^6000030    I12 @T6G_MB_LIB.T6G(SCH_1):PAGE58
   U26 AB17 VSS_AB17 GENOA_SP5-SOCKET6096_13568-001,SMLF,IO,DGA^6000030    I12 @T6G_MB_LIB.T6G(SCH_1):PAGE58
   U26 AB19 VSS_AB19 GENOA_SP5-SOCKET6096_13568-001,SMLF,IO,DGA^6000030    I12 @T6G_MB_LIB.T6G(SCH_1):PAGE58
   U26 AB22 VSS_AB22 GENOA_SP5-SOCKET6096_13568-001,SMLF,IO,DGA^6000030    I12 @T6G_MB_LIB.T6G(SCH_1):PAGE58
   U26 AB25 VSS_AB25 GENOA_SP5-SOCKET6096_13568-001,SMLF,IO,DGA^6000030    I12 @T6G_MB_LIB.T6G(SCH_1):PAGE58
   U26 AB28 VSS_AB28 GENOA_SP5-SOCKET6096_13568-001,SMLF,IO,DGA^6000030    I12 @T6G_MB_LIB.T6G(SCH_1):PAGE58
   U26 AB31 VSS_AB31 GENOA_SP5-SOCKET6096_13568-001,SMLF,IO,DGA^6000030    I12 @T6G_MB_LIB.T6G(SCH_1):PAGE58
   U26 AB34 VSS_AB34 GENOA_SP5-SOCKET6096_13568-001,SMLF,IO,DGA^6000030    I12 @T6G_MB_LIB.T6G(SCH_1):PAGE58
   U26 AB37 VSS_AB37 GENOA_SP5-SOCKET6096_13568-001,SMLF,IO,DGA^6000030    I12 @T6G_MB_LIB.T6G(SCH_1):PAGE58
   U26 AB39 VSS_AB39 GENOA_SP5-SOCKET6096_13568-001,SMLF,IO,DGA^6000030    I12 @T6G_MB_LIB.T6G(SCH_1):PAGE58
   U26 AB42 VSS_AB42 GENOA_SP5-SOCKET6096_13568-001,SMLF,IO,DGA^6000030    I12 @T6G_MB_LIB.T6G(SCH_1):PAGE58
   U26 AB45 VSS_AB45 GENOA_SP5-SOCKET6096_13568-001,SMLF,IO,DGA^6000030    I12 @T6G_MB_LIB.T6G(SCH_1):PAGE58
   U26 AB48 VSS_AB48 GENOA_SP5-SOCKET6096_13568-001,SMLF,IO,DGA^6000030    I12 @T6G_MB_LIB.T6G(SCH_1):PAGE58
   U26 AB51 VSS_AB51 GENOA_SP5-SOCKET6096_13568-001,SMLF,IO,DGA^6000030    I12 @T6G_MB_LIB.T6G(SCH_1):PAGE58
   U26 AB54 VSS_AB54 GENOA_SP5-SOCKET6096_13568-001,SMLF,IO,DGA^6000030    I12 @T6G_MB_LIB.T6G(SCH_1):PAGE58
   U26 AB57 VSS_AB57 GENOA_SP5-SOCKET6096_13568-001,SMLF,IO,DGA^6000030    I12 @T6G_MB_LIB.T6G(SCH_1):PAGE58
   U26 AB59 VSS_AB59 GENOA_SP5-SOCKET6096_13568-001,SMLF,IO,DGA^6000030    I12 @T6G_MB_LIB.T6G(SCH_1):PAGE58
   U26 AB61 VSS_AB61 GENOA_SP5-SOCKET6096_13568-001,SMLF,IO,DGA^6000030    I12 @T6G_MB_LIB.T6G(SCH_1):PAGE58
   U26 AB64 VSS_AB64 GENOA_SP5-SOCKET6096_13568-001,SMLF,IO,DGA^6000030    I12 @T6G_MB_LIB.T6G(SCH_1):PAGE58
   U26 AB66 VSS_AB66 GENOA_SP5-SOCKET6096_13568-001,SMLF,IO,DGA^6000030    I12 @T6G_MB_LIB.T6G(SCH_1):PAGE58
   U26 AB68 VSS_AB68 GENOA_SP5-SOCKET6096_13568-001,SMLF,IO,DGA^6000030    I12 @T6G_MB_LIB.T6G(SCH_1):PAGE58
   U26 AB71 VSS_AB71 GENOA_SP5-SOCKET6096_13568-001,SMLF,IO,DGA^6000030    I12 @T6G_MB_LIB.T6G(SCH_1):PAGE58
   U26 AB73 VSS_AB73 GENOA_SP5-SOCKET6096_13568-001,SMLF,IO,DGA^6000030    I12 @T6G_MB_LIB.T6G(SCH_1):PAGE58
   U26  AC1 VSS_AC1 GENOA_SP5-SOCKET6096_13568-001,SMLF,IO,DGA^6000030    I12 @T6G_MB_LIB.T6G(SCH_1):PAGE58
   U26  AC6 VSS_AC6 GENOA_SP5-SOCKET6096_13568-001,SMLF,IO,DGA^6000030    I12 @T6G_MB_LIB.T6G(SCH_1):PAGE58
   U26  AC8 VSS_AC8 GENOA_SP5-SOCKET6096_13568-001,SMLF,IO,DGA^6000030    I12 @T6G_MB_LIB.T6G(SCH_1):PAGE58
   U26 AC13 VSS_AC13 GENOA_SP5-SOCKET6096_13568-001,SMLF,IO,DGA^6000030    I12 @T6G_MB_LIB.T6G(SCH_1):PAGE58
   U26 AC15 VSS_AC15 GENOA_SP5-SOCKET6096_13568-001,SMLF,IO,DGA^6000030    I12 @T6G_MB_LIB.T6G(SCH_1):PAGE58
   U26 AC20 VSS_AC20 GENOA_SP5-SOCKET6096_13568-001,SMLF,IO,DGA^6000030    I12 @T6G_MB_LIB.T6G(SCH_1):PAGE58
   U26 AC22 VSS_AC22 GENOA_SP5-SOCKET6096_13568-001,SMLF,IO,DGA^6000030    I12 @T6G_MB_LIB.T6G(SCH_1):PAGE58
   U26 AC25 VSS_AC25 GENOA_SP5-SOCKET6096_13568-001,SMLF,IO,DGA^6000030    I12 @T6G_MB_LIB.T6G(SCH_1):PAGE58
   U26 AC28 VSS_AC28 GENOA_SP5-SOCKET6096_13568-001,SMLF,IO,DGA^6000030    I12 @T6G_MB_LIB.T6G(SCH_1):PAGE58
   U26 AC31 VSS_AC31 GENOA_SP5-SOCKET6096_13568-001,SMLF,IO,DGA^6000030    I12 @T6G_MB_LIB.T6G(SCH_1):PAGE58
   U26 AC34 VSS_AC34 GENOA_SP5-SOCKET6096_13568-001,SMLF,IO,DGA^6000030    I12 @T6G_MB_LIB.T6G(SCH_1):PAGE58
   U26 AC42 VSS_AC42 GENOA_SP5-SOCKET6096_13568-001,SMLF,IO,DGA^6000030    I12 @T6G_MB_LIB.T6G(SCH_1):PAGE58
   U26 AC45 VSS_AC45 GENOA_SP5-SOCKET6096_13568-001,SMLF,IO,DGA^6000030    I12 @T6G_MB_LIB.T6G(SCH_1):PAGE58
   U26 AC48 VSS_AC48 GENOA_SP5-SOCKET6096_13568-001,SMLF,IO,DGA^6000030    I12 @T6G_MB_LIB.T6G(SCH_1):PAGE58
   U26 AC51 VSS_AC51 GENOA_SP5-SOCKET6096_13568-001,SMLF,IO,DGA^6000030    I12 @T6G_MB_LIB.T6G(SCH_1):PAGE58
   U26 AC54 VSS_AC54 GENOA_SP5-SOCKET6096_13568-001,SMLF,IO,DGA^6000030    I12 @T6G_MB_LIB.T6G(SCH_1):PAGE58
   U26 AC56 VSS_AC56 GENOA_SP5-SOCKET6096_13568-001,SMLF,IO,DGA^6000030    I12 @T6G_MB_LIB.T6G(SCH_1):PAGE58
   U26 AC61 VSS_AC61 GENOA_SP5-SOCKET6096_13568-001,SMLF,IO,DGA^6000030    I12 @T6G_MB_LIB.T6G(SCH_1):PAGE58
   U26 AC63 VSS_AC63 GENOA_SP5-SOCKET6096_13568-001,SMLF,IO,DGA^6000030    I12 @T6G_MB_LIB.T6G(SCH_1):PAGE58
   U26 AC68 VSS_AC68 GENOA_SP5-SOCKET6096_13568-001,SMLF,IO,DGA^6000030    I12 @T6G_MB_LIB.T6G(SCH_1):PAGE58
   U26 AC70 VSS_AC70 GENOA_SP5-SOCKET6096_13568-001,SMLF,IO,DGA^6000030    I12 @T6G_MB_LIB.T6G(SCH_1):PAGE58
   U26 AC75 VSS_AC75 GENOA_SP5-SOCKET6096_13568-001,SMLF,IO,DGA^6000030    I12 @T6G_MB_LIB.T6G(SCH_1):PAGE58
   U26  AD3 VSS_AD3 GENOA_SP5-SOCKET6096_13568-001,SMLF,IO,DGA^6000030    I12 @T6G_MB_LIB.T6G(SCH_1):PAGE58
   U26  AD5 VSS_AD5 GENOA_SP5-SOCKET6096_13568-001,SMLF,IO,DGA^6000030    I12 @T6G_MB_LIB.T6G(SCH_1):PAGE58
   U26  AD8 VSS_AD8 GENOA_SP5-SOCKET6096_13568-001,SMLF,IO,DGA^6000030    I12 @T6G_MB_LIB.T6G(SCH_1):PAGE58
   U26 AD10 VSS_AD10 GENOA_SP5-SOCKET6096_13568-001,SMLF,IO,DGA^6000030    I12 @T6G_MB_LIB.T6G(SCH_1):PAGE58
   U26 AD12 VSS_AD12 GENOA_SP5-SOCKET6096_13568-001,SMLF,IO,DGA^6000030    I12 @T6G_MB_LIB.T6G(SCH_1):PAGE58
   U26 AD15 VSS_AD15 GENOA_SP5-SOCKET6096_13568-001,SMLF,IO,DGA^6000030    I12 @T6G_MB_LIB.T6G(SCH_1):PAGE58
   U26 AD17 VSS_AD17 GENOA_SP5-SOCKET6096_13568-001,SMLF,IO,DGA^6000030    I12 @T6G_MB_LIB.T6G(SCH_1):PAGE58
   U26 AD19 VSS_AD19 GENOA_SP5-SOCKET6096_13568-001,SMLF,IO,DGA^6000030    I12 @T6G_MB_LIB.T6G(SCH_1):PAGE58
   U26 AD23 VSS_AD23 GENOA_SP5-SOCKET6096_13568-001,SMLF,IO,DGA^6000030    I12 @T6G_MB_LIB.T6G(SCH_1):PAGE58
   U26 AD24 VSS_AD24 GENOA_SP5-SOCKET6096_13568-001,SMLF,IO,DGA^6000030    I12 @T6G_MB_LIB.T6G(SCH_1):PAGE58
   U26 AD25 VSS_AD25 GENOA_SP5-SOCKET6096_13568-001,SMLF,IO,DGA^6000030    I12 @T6G_MB_LIB.T6G(SCH_1):PAGE58
   U26 AD26 VSS_AD26 GENOA_SP5-SOCKET6096_13568-001,SMLF,IO,DGA^6000030    I12 @T6G_MB_LIB.T6G(SCH_1):PAGE58
   U26 AD27 VSS_AD27 GENOA_SP5-SOCKET6096_13568-001,SMLF,IO,DGA^6000030    I12 @T6G_MB_LIB.T6G(SCH_1):PAGE58
   U26 AD28 VSS_AD28 GENOA_SP5-SOCKET6096_13568-001,SMLF,IO,DGA^6000030    I12 @T6G_MB_LIB.T6G(SCH_1):PAGE58
   U26 AD29 VSS_AD29 GENOA_SP5-SOCKET6096_13568-001,SMLF,IO,DGA^6000030    I12 @T6G_MB_LIB.T6G(SCH_1):PAGE58
   U26 AD30 VSS_AD30 GENOA_SP5-SOCKET6096_13568-001,SMLF,IO,DGA^6000030    I12 @T6G_MB_LIB.T6G(SCH_1):PAGE58
   U26 AD32 VSS_AD32 GENOA_SP5-SOCKET6096_13568-001,SMLF,IO,DGA^6000030    I12 @T6G_MB_LIB.T6G(SCH_1):PAGE58
   U26 AD33 VSS_AD33 GENOA_SP5-SOCKET6096_13568-001,SMLF,IO,DGA^6000030    I12 @T6G_MB_LIB.T6G(SCH_1):PAGE58
   U26 AD34 VSS_AD34 GENOA_SP5-SOCKET6096_13568-001,SMLF,IO,DGA^6000030    I12 @T6G_MB_LIB.T6G(SCH_1):PAGE58
   U26 AD37 VSS_AD37 GENOA_SP5-SOCKET6096_13568-001,SMLF,IO,DGA^6000030    I12 @T6G_MB_LIB.T6G(SCH_1):PAGE58
   U26 AD39 VSS_AD39 GENOA_SP5-SOCKET6096_13568-001,SMLF,IO,DGA^6000030    I12 @T6G_MB_LIB.T6G(SCH_1):PAGE58
   U26 AD42 VSS_AD42 GENOA_SP5-SOCKET6096_13568-001,SMLF,IO,DGA^6000030    I12 @T6G_MB_LIB.T6G(SCH_1):PAGE58
   U26 AD43 VSS_AD43 GENOA_SP5-SOCKET6096_13568-001,SMLF,IO,DGA^6000030    I12 @T6G_MB_LIB.T6G(SCH_1):PAGE58
   U26 AD44 VSS_AD44 GENOA_SP5-SOCKET6096_13568-001,SMLF,IO,DGA^6000030    I12 @T6G_MB_LIB.T6G(SCH_1):PAGE58
   U26 AD45 VSS_AD45 GENOA_SP5-SOCKET6096_13568-001,SMLF,IO,DGA^6000030    I12 @T6G_MB_LIB.T6G(SCH_1):PAGE58
   U26 AD46 VSS_AD46 GENOA_SP5-SOCKET6096_13568-001,SMLF,IO,DGA^6000030    I12 @T6G_MB_LIB.T6G(SCH_1):PAGE58
   U26 AD47 VSS_AD47 GENOA_SP5-SOCKET6096_13568-001,SMLF,IO,DGA^6000030    I12 @T6G_MB_LIB.T6G(SCH_1):PAGE58
   U26 AD48 VSS_AD48 GENOA_SP5-SOCKET6096_13568-001,SMLF,IO,DGA^6000030    I12 @T6G_MB_LIB.T6G(SCH_1):PAGE58
   U26  T66 VSS_T66 GENOA_SP5-SOCKET6096_13568-001,SMLF,IO,DGA^6000030    I12 @T6G_MB_LIB.T6G(SCH_1):PAGE58
   U26  T68 VSS_T68 GENOA_SP5-SOCKET6096_13568-001,SMLF,IO,DGA^6000030    I12 @T6G_MB_LIB.T6G(SCH_1):PAGE58
   U26  T71 VSS_T71 GENOA_SP5-SOCKET6096_13568-001,SMLF,IO,DGA^6000030    I12 @T6G_MB_LIB.T6G(SCH_1):PAGE58
   U26  T73 VSS_T73 GENOA_SP5-SOCKET6096_13568-001,SMLF,IO,DGA^6000030    I12 @T6G_MB_LIB.T6G(SCH_1):PAGE58
   U26   U1 VSS_U1 GENOA_SP5-SOCKET6096_13568-001,SMLF,IO,DGA^6000030    I12 @T6G_MB_LIB.T6G(SCH_1):PAGE58
   U26   U6 VSS_U6 GENOA_SP5-SOCKET6096_13568-001,SMLF,IO,DGA^6000030    I12 @T6G_MB_LIB.T6G(SCH_1):PAGE58
   U26   U8 VSS_U8 GENOA_SP5-SOCKET6096_13568-001,SMLF,IO,DGA^6000030    I12 @T6G_MB_LIB.T6G(SCH_1):PAGE58
   U26  U13 VSS_U13 GENOA_SP5-SOCKET6096_13568-001,SMLF,IO,DGA^6000030    I12 @T6G_MB_LIB.T6G(SCH_1):PAGE58
   U26  U15 VSS_U15 GENOA_SP5-SOCKET6096_13568-001,SMLF,IO,DGA^6000030    I12 @T6G_MB_LIB.T6G(SCH_1):PAGE58
   U26  U20 VSS_U20 GENOA_SP5-SOCKET6096_13568-001,SMLF,IO,DGA^6000030    I12 @T6G_MB_LIB.T6G(SCH_1):PAGE58
   U26  U22 VSS_U22 GENOA_SP5-SOCKET6096_13568-001,SMLF,IO,DGA^6000030    I12 @T6G_MB_LIB.T6G(SCH_1):PAGE58
   U26  U25 VSS_U25 GENOA_SP5-SOCKET6096_13568-001,SMLF,IO,DGA^6000030    I12 @T6G_MB_LIB.T6G(SCH_1):PAGE58
   U26  U28 VSS_U28 GENOA_SP5-SOCKET6096_13568-001,SMLF,IO,DGA^6000030    I12 @T6G_MB_LIB.T6G(SCH_1):PAGE58
   U26  U31 VSS_U31 GENOA_SP5-SOCKET6096_13568-001,SMLF,IO,DGA^6000030    I12 @T6G_MB_LIB.T6G(SCH_1):PAGE58
   U26  U34 VSS_U34 GENOA_SP5-SOCKET6096_13568-001,SMLF,IO,DGA^6000030    I12 @T6G_MB_LIB.T6G(SCH_1):PAGE58
   U26  U42 VSS_U42 GENOA_SP5-SOCKET6096_13568-001,SMLF,IO,DGA^6000030    I12 @T6G_MB_LIB.T6G(SCH_1):PAGE58
   U26  U45 VSS_U45 GENOA_SP5-SOCKET6096_13568-001,SMLF,IO,DGA^6000030    I12 @T6G_MB_LIB.T6G(SCH_1):PAGE58
   U26  U48 VSS_U48 GENOA_SP5-SOCKET6096_13568-001,SMLF,IO,DGA^6000030    I12 @T6G_MB_LIB.T6G(SCH_1):PAGE58
   U26  U51 VSS_U51 GENOA_SP5-SOCKET6096_13568-001,SMLF,IO,DGA^6000030    I12 @T6G_MB_LIB.T6G(SCH_1):PAGE58
   U26  U54 VSS_U54 GENOA_SP5-SOCKET6096_13568-001,SMLF,IO,DGA^6000030    I12 @T6G_MB_LIB.T6G(SCH_1):PAGE58
   U26  U56 VSS_U56 GENOA_SP5-SOCKET6096_13568-001,SMLF,IO,DGA^6000030    I12 @T6G_MB_LIB.T6G(SCH_1):PAGE58
   U26  U61 VSS_U61 GENOA_SP5-SOCKET6096_13568-001,SMLF,IO,DGA^6000030    I12 @T6G_MB_LIB.T6G(SCH_1):PAGE58
   U26  U63 VSS_U63 GENOA_SP5-SOCKET6096_13568-001,SMLF,IO,DGA^6000030    I12 @T6G_MB_LIB.T6G(SCH_1):PAGE58
   U26  U68 VSS_U68 GENOA_SP5-SOCKET6096_13568-001,SMLF,IO,DGA^6000030    I12 @T6G_MB_LIB.T6G(SCH_1):PAGE58
   U26  U70 VSS_U70 GENOA_SP5-SOCKET6096_13568-001,SMLF,IO,DGA^6000030    I12 @T6G_MB_LIB.T6G(SCH_1):PAGE58
   U26  U75 VSS_U75 GENOA_SP5-SOCKET6096_13568-001,SMLF,IO,DGA^6000030    I12 @T6G_MB_LIB.T6G(SCH_1):PAGE58
   U26   V3 VSS_V3 GENOA_SP5-SOCKET6096_13568-001,SMLF,IO,DGA^6000030    I12 @T6G_MB_LIB.T6G(SCH_1):PAGE58
   U26   V5 VSS_V5 GENOA_SP5-SOCKET6096_13568-001,SMLF,IO,DGA^6000030    I12 @T6G_MB_LIB.T6G(SCH_1):PAGE58
   U26   V8 VSS_V8 GENOA_SP5-SOCKET6096_13568-001,SMLF,IO,DGA^6000030    I12 @T6G_MB_LIB.T6G(SCH_1):PAGE58
   U26  V10 VSS_V10 GENOA_SP5-SOCKET6096_13568-001,SMLF,IO,DGA^6000030    I12 @T6G_MB_LIB.T6G(SCH_1):PAGE58
   U26  V12 VSS_V12 GENOA_SP5-SOCKET6096_13568-001,SMLF,IO,DGA^6000030    I12 @T6G_MB_LIB.T6G(SCH_1):PAGE58
   U26  V15 VSS_V15 GENOA_SP5-SOCKET6096_13568-001,SMLF,IO,DGA^6000030    I12 @T6G_MB_LIB.T6G(SCH_1):PAGE58
   U26  V17 VSS_V17 GENOA_SP5-SOCKET6096_13568-001,SMLF,IO,DGA^6000030    I12 @T6G_MB_LIB.T6G(SCH_1):PAGE58
   U26  V19 VSS_V19 GENOA_SP5-SOCKET6096_13568-001,SMLF,IO,DGA^6000030    I12 @T6G_MB_LIB.T6G(SCH_1):PAGE58
   U26  V23 VSS_V23 GENOA_SP5-SOCKET6096_13568-001,SMLF,IO,DGA^6000030    I12 @T6G_MB_LIB.T6G(SCH_1):PAGE58
   U26  V24 VSS_V24 GENOA_SP5-SOCKET6096_13568-001,SMLF,IO,DGA^6000030    I12 @T6G_MB_LIB.T6G(SCH_1):PAGE58
   U26  V25 VSS_V25 GENOA_SP5-SOCKET6096_13568-001,SMLF,IO,DGA^6000030    I12 @T6G_MB_LIB.T6G(SCH_1):PAGE58
   U26  V26 VSS_V26 GENOA_SP5-SOCKET6096_13568-001,SMLF,IO,DGA^6000030    I12 @T6G_MB_LIB.T6G(SCH_1):PAGE58
   U26  V28 VSS_V28 GENOA_SP5-SOCKET6096_13568-001,SMLF,IO,DGA^6000030    I12 @T6G_MB_LIB.T6G(SCH_1):PAGE58
   U26  V29 VSS_V29 GENOA_SP5-SOCKET6096_13568-001,SMLF,IO,DGA^6000030    I12 @T6G_MB_LIB.T6G(SCH_1):PAGE58
   U26  V30 VSS_V30 GENOA_SP5-SOCKET6096_13568-001,SMLF,IO,DGA^6000030    I12 @T6G_MB_LIB.T6G(SCH_1):PAGE58
   U26  V31 VSS_V31 GENOA_SP5-SOCKET6096_13568-001,SMLF,IO,DGA^6000030    I12 @T6G_MB_LIB.T6G(SCH_1):PAGE58
   U26  V32 VSS_V32 GENOA_SP5-SOCKET6096_13568-001,SMLF,IO,DGA^6000030    I12 @T6G_MB_LIB.T6G(SCH_1):PAGE58
   U26  V33 VSS_V33 GENOA_SP5-SOCKET6096_13568-001,SMLF,IO,DGA^6000030    I12 @T6G_MB_LIB.T6G(SCH_1):PAGE58
   U26  V34 VSS_V34 GENOA_SP5-SOCKET6096_13568-001,SMLF,IO,DGA^6000030    I12 @T6G_MB_LIB.T6G(SCH_1):PAGE58
   U26  V37 VSS_V37 GENOA_SP5-SOCKET6096_13568-001,SMLF,IO,DGA^6000030    I12 @T6G_MB_LIB.T6G(SCH_1):PAGE58
   U26  V39 VSS_V39 GENOA_SP5-SOCKET6096_13568-001,SMLF,IO,DGA^6000030    I12 @T6G_MB_LIB.T6G(SCH_1):PAGE58
   U26  V42 VSS_V42 GENOA_SP5-SOCKET6096_13568-001,SMLF,IO,DGA^6000030    I12 @T6G_MB_LIB.T6G(SCH_1):PAGE58
   U26  V43 VSS_V43 GENOA_SP5-SOCKET6096_13568-001,SMLF,IO,DGA^6000030    I12 @T6G_MB_LIB.T6G(SCH_1):PAGE58
   U26  V44 VSS_V44 GENOA_SP5-SOCKET6096_13568-001,SMLF,IO,DGA^6000030    I12 @T6G_MB_LIB.T6G(SCH_1):PAGE58
   U26  V45 VSS_V45 GENOA_SP5-SOCKET6096_13568-001,SMLF,IO,DGA^6000030    I12 @T6G_MB_LIB.T6G(SCH_1):PAGE58
   U26  V46 VSS_V46 GENOA_SP5-SOCKET6096_13568-001,SMLF,IO,DGA^6000030    I12 @T6G_MB_LIB.T6G(SCH_1):PAGE58
   U26  V47 VSS_V47 GENOA_SP5-SOCKET6096_13568-001,SMLF,IO,DGA^6000030    I12 @T6G_MB_LIB.T6G(SCH_1):PAGE58
   U26  V48 VSS_V48 GENOA_SP5-SOCKET6096_13568-001,SMLF,IO,DGA^6000030    I12 @T6G_MB_LIB.T6G(SCH_1):PAGE58
   U26  V49 VSS_V49 GENOA_SP5-SOCKET6096_13568-001,SMLF,IO,DGA^6000030    I12 @T6G_MB_LIB.T6G(SCH_1):PAGE58
   U26  V50 VSS_V50 GENOA_SP5-SOCKET6096_13568-001,SMLF,IO,DGA^6000030    I12 @T6G_MB_LIB.T6G(SCH_1):PAGE58
   U26  V51 VSS_V51 GENOA_SP5-SOCKET6096_13568-001,SMLF,IO,DGA^6000030    I12 @T6G_MB_LIB.T6G(SCH_1):PAGE58
   U26  V52 VSS_V52 GENOA_SP5-SOCKET6096_13568-001,SMLF,IO,DGA^6000030    I12 @T6G_MB_LIB.T6G(SCH_1):PAGE58
   U26  V53 VSS_V53 GENOA_SP5-SOCKET6096_13568-001,SMLF,IO,DGA^6000030    I12 @T6G_MB_LIB.T6G(SCH_1):PAGE58
   U26  V57 VSS_V57 GENOA_SP5-SOCKET6096_13568-001,SMLF,IO,DGA^6000030    I12 @T6G_MB_LIB.T6G(SCH_1):PAGE58
   U26  V59 VSS_V59 GENOA_SP5-SOCKET6096_13568-001,SMLF,IO,DGA^6000030    I12 @T6G_MB_LIB.T6G(SCH_1):PAGE58
   U26  V61 VSS_V61 GENOA_SP5-SOCKET6096_13568-001,SMLF,IO,DGA^6000030    I12 @T6G_MB_LIB.T6G(SCH_1):PAGE58
   U26  V64 VSS_V64 GENOA_SP5-SOCKET6096_13568-001,SMLF,IO,DGA^6000030    I12 @T6G_MB_LIB.T6G(SCH_1):PAGE58
   U26  V66 VSS_V66 GENOA_SP5-SOCKET6096_13568-001,SMLF,IO,DGA^6000030    I12 @T6G_MB_LIB.T6G(SCH_1):PAGE58
   U26  V71 VSS_V71 GENOA_SP5-SOCKET6096_13568-001,SMLF,IO,DGA^6000030    I12 @T6G_MB_LIB.T6G(SCH_1):PAGE58
   U26  V73 VSS_V73 GENOA_SP5-SOCKET6096_13568-001,SMLF,IO,DGA^6000030    I12 @T6G_MB_LIB.T6G(SCH_1):PAGE58
   U26   W1 VSS_W1 GENOA_SP5-SOCKET6096_13568-001,SMLF,IO,DGA^6000030    I12 @T6G_MB_LIB.T6G(SCH_1):PAGE58
   U26   W4 VSS_W4 GENOA_SP5-SOCKET6096_13568-001,SMLF,IO,DGA^6000030    I12 @T6G_MB_LIB.T6G(SCH_1):PAGE58
   U26   W6 VSS_W6 GENOA_SP5-SOCKET6096_13568-001,SMLF,IO,DGA^6000030    I12 @T6G_MB_LIB.T6G(SCH_1):PAGE58
   U26   W8 VSS_W8 GENOA_SP5-SOCKET6096_13568-001,SMLF,IO,DGA^6000030    I12 @T6G_MB_LIB.T6G(SCH_1):PAGE58
   U26  W11 VSS_W11 GENOA_SP5-SOCKET6096_13568-001,SMLF,IO,DGA^6000030    I12 @T6G_MB_LIB.T6G(SCH_1):PAGE58
   U26  W13 VSS_W13 GENOA_SP5-SOCKET6096_13568-001,SMLF,IO,DGA^6000030    I12 @T6G_MB_LIB.T6G(SCH_1):PAGE58
   U26  W15 VSS_W15 GENOA_SP5-SOCKET6096_13568-001,SMLF,IO,DGA^6000030    I12 @T6G_MB_LIB.T6G(SCH_1):PAGE58
   U26  W18 VSS_W18 GENOA_SP5-SOCKET6096_13568-001,SMLF,IO,DGA^6000030    I12 @T6G_MB_LIB.T6G(SCH_1):PAGE58
   U26  W20 VSS_W20 GENOA_SP5-SOCKET6096_13568-001,SMLF,IO,DGA^6000030    I12 @T6G_MB_LIB.T6G(SCH_1):PAGE58
   U26  W22 VSS_W22 GENOA_SP5-SOCKET6096_13568-001,SMLF,IO,DGA^6000030    I12 @T6G_MB_LIB.T6G(SCH_1):PAGE58
   U26  W25 VSS_W25 GENOA_SP5-SOCKET6096_13568-001,SMLF,IO,DGA^6000030    I12 @T6G_MB_LIB.T6G(SCH_1):PAGE58
   U26  W28 VSS_W28 GENOA_SP5-SOCKET6096_13568-001,SMLF,IO,DGA^6000030    I12 @T6G_MB_LIB.T6G(SCH_1):PAGE58
   U26  W34 VSS_W34 GENOA_SP5-SOCKET6096_13568-001,SMLF,IO,DGA^6000030    I12 @T6G_MB_LIB.T6G(SCH_1):PAGE58
   U26  W35 VSS_W35 GENOA_SP5-SOCKET6096_13568-001,SMLF,IO,DGA^6000030    I12 @T6G_MB_LIB.T6G(SCH_1):PAGE58
   U26  W36 VSS_W36 GENOA_SP5-SOCKET6096_13568-001,SMLF,IO,DGA^6000030    I12 @T6G_MB_LIB.T6G(SCH_1):PAGE58
   U26  W40 VSS_W40 GENOA_SP5-SOCKET6096_13568-001,SMLF,IO,DGA^6000030    I12 @T6G_MB_LIB.T6G(SCH_1):PAGE58
   U26  W41 VSS_W41 GENOA_SP5-SOCKET6096_13568-001,SMLF,IO,DGA^6000030    I12 @T6G_MB_LIB.T6G(SCH_1):PAGE58
   U26  W42 VSS_W42 GENOA_SP5-SOCKET6096_13568-001,SMLF,IO,DGA^6000030    I12 @T6G_MB_LIB.T6G(SCH_1):PAGE58
   U26  W45 VSS_W45 GENOA_SP5-SOCKET6096_13568-001,SMLF,IO,DGA^6000030    I12 @T6G_MB_LIB.T6G(SCH_1):PAGE58
   U26  W48 VSS_W48 GENOA_SP5-SOCKET6096_13568-001,SMLF,IO,DGA^6000030    I12 @T6G_MB_LIB.T6G(SCH_1):PAGE58
   U26  W51 VSS_W51 GENOA_SP5-SOCKET6096_13568-001,SMLF,IO,DGA^6000030    I12 @T6G_MB_LIB.T6G(SCH_1):PAGE58
   U26  W54 VSS_W54 GENOA_SP5-SOCKET6096_13568-001,SMLF,IO,DGA^6000030    I12 @T6G_MB_LIB.T6G(SCH_1):PAGE58
   U26  W56 VSS_W56 GENOA_SP5-SOCKET6096_13568-001,SMLF,IO,DGA^6000030    I12 @T6G_MB_LIB.T6G(SCH_1):PAGE58
   U26  W58 VSS_W58 GENOA_SP5-SOCKET6096_13568-001,SMLF,IO,DGA^6000030    I12 @T6G_MB_LIB.T6G(SCH_1):PAGE58
   U26  W61 VSS_W61 GENOA_SP5-SOCKET6096_13568-001,SMLF,IO,DGA^6000030    I12 @T6G_MB_LIB.T6G(SCH_1):PAGE58
   U26  W63 VSS_W63 GENOA_SP5-SOCKET6096_13568-001,SMLF,IO,DGA^6000030    I12 @T6G_MB_LIB.T6G(SCH_1):PAGE58
   U26  W65 VSS_W65 GENOA_SP5-SOCKET6096_13568-001,SMLF,IO,DGA^6000030    I12 @T6G_MB_LIB.T6G(SCH_1):PAGE58
   U26  W68 VSS_W68 GENOA_SP5-SOCKET6096_13568-001,SMLF,IO,DGA^6000030    I12 @T6G_MB_LIB.T6G(SCH_1):PAGE58
   U26  W70 VSS_W70 GENOA_SP5-SOCKET6096_13568-001,SMLF,IO,DGA^6000030    I12 @T6G_MB_LIB.T6G(SCH_1):PAGE58
   U26  W72 VSS_W72 GENOA_SP5-SOCKET6096_13568-001,SMLF,IO,DGA^6000030    I12 @T6G_MB_LIB.T6G(SCH_1):PAGE58
   U26  W75 VSS_W75 GENOA_SP5-SOCKET6096_13568-001,SMLF,IO,DGA^6000030    I12 @T6G_MB_LIB.T6G(SCH_1):PAGE58
   U26   Y3 VSS_Y3 GENOA_SP5-SOCKET6096_13568-001,SMLF,IO,DGA^6000030    I12 @T6G_MB_LIB.T6G(SCH_1):PAGE58
   U26   Y8 VSS_Y8 GENOA_SP5-SOCKET6096_13568-001,SMLF,IO,DGA^6000030    I12 @T6G_MB_LIB.T6G(SCH_1):PAGE58
   U26  Y10 VSS_Y10 GENOA_SP5-SOCKET6096_13568-001,SMLF,IO,DGA^6000030    I12 @T6G_MB_LIB.T6G(SCH_1):PAGE58
   U26  Y15 VSS_Y15 GENOA_SP5-SOCKET6096_13568-001,SMLF,IO,DGA^6000030    I12 @T6G_MB_LIB.T6G(SCH_1):PAGE58
   U26  Y17 VSS_Y17 GENOA_SP5-SOCKET6096_13568-001,SMLF,IO,DGA^6000030    I12 @T6G_MB_LIB.T6G(SCH_1):PAGE58
   U26  Y22 VSS_Y22 GENOA_SP5-SOCKET6096_13568-001,SMLF,IO,DGA^6000030    I12 @T6G_MB_LIB.T6G(SCH_1):PAGE58
   U26  Y23 VSS_Y23 GENOA_SP5-SOCKET6096_13568-001,SMLF,IO,DGA^6000030    I12 @T6G_MB_LIB.T6G(SCH_1):PAGE58
   U26  Y24 VSS_Y24 GENOA_SP5-SOCKET6096_13568-001,SMLF,IO,DGA^6000030    I12 @T6G_MB_LIB.T6G(SCH_1):PAGE58
   U26  Y25 VSS_Y25 GENOA_SP5-SOCKET6096_13568-001,SMLF,IO,DGA^6000030    I12 @T6G_MB_LIB.T6G(SCH_1):PAGE58
   U26  Y26 VSS_Y26 GENOA_SP5-SOCKET6096_13568-001,SMLF,IO,DGA^6000030    I12 @T6G_MB_LIB.T6G(SCH_1):PAGE58
   U26  Y27 VSS_Y27 GENOA_SP5-SOCKET6096_13568-001,SMLF,IO,DGA^6000030    I12 @T6G_MB_LIB.T6G(SCH_1):PAGE58
   U26  Y28 VSS_Y28 GENOA_SP5-SOCKET6096_13568-001,SMLF,IO,DGA^6000030    I12 @T6G_MB_LIB.T6G(SCH_1):PAGE58
   U26  Y31 VSS_Y31 GENOA_SP5-SOCKET6096_13568-001,SMLF,IO,DGA^6000030    I12 @T6G_MB_LIB.T6G(SCH_1):PAGE58
   U26  Y32 VSS_Y32 GENOA_SP5-SOCKET6096_13568-001,SMLF,IO,DGA^6000030    I12 @T6G_MB_LIB.T6G(SCH_1):PAGE58
   U26  Y33 VSS_Y33 GENOA_SP5-SOCKET6096_13568-001,SMLF,IO,DGA^6000030    I12 @T6G_MB_LIB.T6G(SCH_1):PAGE58
   U26  Y34 VSS_Y34 GENOA_SP5-SOCKET6096_13568-001,SMLF,IO,DGA^6000030    I12 @T6G_MB_LIB.T6G(SCH_1):PAGE58
   U26  Y37 VSS_Y37 GENOA_SP5-SOCKET6096_13568-001,SMLF,IO,DGA^6000030    I12 @T6G_MB_LIB.T6G(SCH_1):PAGE58
   U26  Y39 VSS_Y39 GENOA_SP5-SOCKET6096_13568-001,SMLF,IO,DGA^6000030    I12 @T6G_MB_LIB.T6G(SCH_1):PAGE58
   U26  Y42 VSS_Y42 GENOA_SP5-SOCKET6096_13568-001,SMLF,IO,DGA^6000030    I12 @T6G_MB_LIB.T6G(SCH_1):PAGE58
   U26  Y43 VSS_Y43 GENOA_SP5-SOCKET6096_13568-001,SMLF,IO,DGA^6000030    I12 @T6G_MB_LIB.T6G(SCH_1):PAGE58
   U26  Y44 VSS_Y44 GENOA_SP5-SOCKET6096_13568-001,SMLF,IO,DGA^6000030    I12 @T6G_MB_LIB.T6G(SCH_1):PAGE58
   U26  Y45 VSS_Y45 GENOA_SP5-SOCKET6096_13568-001,SMLF,IO,DGA^6000030    I12 @T6G_MB_LIB.T6G(SCH_1):PAGE58
   U26  Y48 VSS_Y48 GENOA_SP5-SOCKET6096_13568-001,SMLF,IO,DGA^6000030    I12 @T6G_MB_LIB.T6G(SCH_1):PAGE58
   U26  Y49 VSS_Y49 GENOA_SP5-SOCKET6096_13568-001,SMLF,IO,DGA^6000030    I12 @T6G_MB_LIB.T6G(SCH_1):PAGE58
   U26  Y50 VSS_Y50 GENOA_SP5-SOCKET6096_13568-001,SMLF,IO,DGA^6000030    I12 @T6G_MB_LIB.T6G(SCH_1):PAGE58
   U26  Y51 VSS_Y51 GENOA_SP5-SOCKET6096_13568-001,SMLF,IO,DGA^6000030    I12 @T6G_MB_LIB.T6G(SCH_1):PAGE58
   U26  Y52 VSS_Y52 GENOA_SP5-SOCKET6096_13568-001,SMLF,IO,DGA^6000030    I12 @T6G_MB_LIB.T6G(SCH_1):PAGE58
   U26  Y53 VSS_Y53 GENOA_SP5-SOCKET6096_13568-001,SMLF,IO,DGA^6000030    I12 @T6G_MB_LIB.T6G(SCH_1):PAGE58
   U26  Y54 VSS_Y54 GENOA_SP5-SOCKET6096_13568-001,SMLF,IO,DGA^6000030    I12 @T6G_MB_LIB.T6G(SCH_1):PAGE58
   U26  Y59 VSS_Y59 GENOA_SP5-SOCKET6096_13568-001,SMLF,IO,DGA^6000030    I12 @T6G_MB_LIB.T6G(SCH_1):PAGE58
   U26  Y61 VSS_Y61 GENOA_SP5-SOCKET6096_13568-001,SMLF,IO,DGA^6000030    I12 @T6G_MB_LIB.T6G(SCH_1):PAGE58
   U26  Y66 VSS_Y66 GENOA_SP5-SOCKET6096_13568-001,SMLF,IO,DGA^6000030    I12 @T6G_MB_LIB.T6G(SCH_1):PAGE58
   U26  Y68 VSS_Y68 GENOA_SP5-SOCKET6096_13568-001,SMLF,IO,DGA^6000030    I12 @T6G_MB_LIB.T6G(SCH_1):PAGE58
   U26  Y73 VSS_Y73 GENOA_SP5-SOCKET6096_13568-001,SMLF,IO,DGA^6000030    I12 @T6G_MB_LIB.T6G(SCH_1):PAGE58
   U26  J15 VSS_J15 GENOA_SP5-SOCKET6096_13568-001,SMLF,IO,DGA^6000030    I15 @T6G_MB_LIB.T6G(SCH_1):PAGE58
   U26  J18 VSS_J18 GENOA_SP5-SOCKET6096_13568-001,SMLF,IO,DGA^6000030    I15 @T6G_MB_LIB.T6G(SCH_1):PAGE58
   U26  J20 VSS_J20 GENOA_SP5-SOCKET6096_13568-001,SMLF,IO,DGA^6000030    I15 @T6G_MB_LIB.T6G(SCH_1):PAGE58
   U26  J22 VSS_J22 GENOA_SP5-SOCKET6096_13568-001,SMLF,IO,DGA^6000030    I15 @T6G_MB_LIB.T6G(SCH_1):PAGE58
   U26  J25 VSS_J25 GENOA_SP5-SOCKET6096_13568-001,SMLF,IO,DGA^6000030    I15 @T6G_MB_LIB.T6G(SCH_1):PAGE58
   U26  J28 VSS_J28 GENOA_SP5-SOCKET6096_13568-001,SMLF,IO,DGA^6000030    I15 @T6G_MB_LIB.T6G(SCH_1):PAGE58
   U26  J31 VSS_J31 GENOA_SP5-SOCKET6096_13568-001,SMLF,IO,DGA^6000030    I15 @T6G_MB_LIB.T6G(SCH_1):PAGE58
   U26  J34 VSS_J34 GENOA_SP5-SOCKET6096_13568-001,SMLF,IO,DGA^6000030    I15 @T6G_MB_LIB.T6G(SCH_1):PAGE58
   U26  J42 VSS_J42 GENOA_SP5-SOCKET6096_13568-001,SMLF,IO,DGA^6000030    I15 @T6G_MB_LIB.T6G(SCH_1):PAGE58
   U26  J45 VSS_J45 GENOA_SP5-SOCKET6096_13568-001,SMLF,IO,DGA^6000030    I15 @T6G_MB_LIB.T6G(SCH_1):PAGE58
   U26  J48 VSS_J48 GENOA_SP5-SOCKET6096_13568-001,SMLF,IO,DGA^6000030    I15 @T6G_MB_LIB.T6G(SCH_1):PAGE58
   U26  J51 VSS_J51 GENOA_SP5-SOCKET6096_13568-001,SMLF,IO,DGA^6000030    I15 @T6G_MB_LIB.T6G(SCH_1):PAGE58
   U26  J54 VSS_J54 GENOA_SP5-SOCKET6096_13568-001,SMLF,IO,DGA^6000030    I15 @T6G_MB_LIB.T6G(SCH_1):PAGE58
   U26  J56 VSS_J56 GENOA_SP5-SOCKET6096_13568-001,SMLF,IO,DGA^6000030    I15 @T6G_MB_LIB.T6G(SCH_1):PAGE58
   U26  J58 VSS_J58 GENOA_SP5-SOCKET6096_13568-001,SMLF,IO,DGA^6000030    I15 @T6G_MB_LIB.T6G(SCH_1):PAGE58
   U26  J61 VSS_J61 GENOA_SP5-SOCKET6096_13568-001,SMLF,IO,DGA^6000030    I15 @T6G_MB_LIB.T6G(SCH_1):PAGE58
   U26  J63 VSS_J63 GENOA_SP5-SOCKET6096_13568-001,SMLF,IO,DGA^6000030    I15 @T6G_MB_LIB.T6G(SCH_1):PAGE58
   U26  J65 VSS_J65 GENOA_SP5-SOCKET6096_13568-001,SMLF,IO,DGA^6000030    I15 @T6G_MB_LIB.T6G(SCH_1):PAGE58
   U26  J68 VSS_J68 GENOA_SP5-SOCKET6096_13568-001,SMLF,IO,DGA^6000030    I15 @T6G_MB_LIB.T6G(SCH_1):PAGE58
   U26  J70 VSS_J70 GENOA_SP5-SOCKET6096_13568-001,SMLF,IO,DGA^6000030    I15 @T6G_MB_LIB.T6G(SCH_1):PAGE58
   U26  J72 VSS_J72 GENOA_SP5-SOCKET6096_13568-001,SMLF,IO,DGA^6000030    I15 @T6G_MB_LIB.T6G(SCH_1):PAGE58
   U26  J75 VSS_J75 GENOA_SP5-SOCKET6096_13568-001,SMLF,IO,DGA^6000030    I15 @T6G_MB_LIB.T6G(SCH_1):PAGE58
   U26   K3 VSS_K3 GENOA_SP5-SOCKET6096_13568-001,SMLF,IO,DGA^6000030    I15 @T6G_MB_LIB.T6G(SCH_1):PAGE58
   U26   K5 VSS_K5 GENOA_SP5-SOCKET6096_13568-001,SMLF,IO,DGA^6000030    I15 @T6G_MB_LIB.T6G(SCH_1):PAGE58
   U26   K8 VSS_K8 GENOA_SP5-SOCKET6096_13568-001,SMLF,IO,DGA^6000030    I15 @T6G_MB_LIB.T6G(SCH_1):PAGE58
   U26  K10 VSS_K10 GENOA_SP5-SOCKET6096_13568-001,SMLF,IO,DGA^6000030    I15 @T6G_MB_LIB.T6G(SCH_1):PAGE58
   U26  K12 VSS_K12 GENOA_SP5-SOCKET6096_13568-001,SMLF,IO,DGA^6000030    I15 @T6G_MB_LIB.T6G(SCH_1):PAGE58
   U26  K15 VSS_K15 GENOA_SP5-SOCKET6096_13568-001,SMLF,IO,DGA^6000030    I15 @T6G_MB_LIB.T6G(SCH_1):PAGE58
   U26  K17 VSS_K17 GENOA_SP5-SOCKET6096_13568-001,SMLF,IO,DGA^6000030    I15 @T6G_MB_LIB.T6G(SCH_1):PAGE58
   U26  K19 VSS_K19 GENOA_SP5-SOCKET6096_13568-001,SMLF,IO,DGA^6000030    I15 @T6G_MB_LIB.T6G(SCH_1):PAGE58
   U26  K24 VSS_K24 GENOA_SP5-SOCKET6096_13568-001,SMLF,IO,DGA^6000030    I15 @T6G_MB_LIB.T6G(SCH_1):PAGE58
   U26  K25 VSS_K25 GENOA_SP5-SOCKET6096_13568-001,SMLF,IO,DGA^6000030    I15 @T6G_MB_LIB.T6G(SCH_1):PAGE58
   U26  K26 VSS_K26 GENOA_SP5-SOCKET6096_13568-001,SMLF,IO,DGA^6000030    I15 @T6G_MB_LIB.T6G(SCH_1):PAGE58
   U26  K27 VSS_K27 GENOA_SP5-SOCKET6096_13568-001,SMLF,IO,DGA^6000030    I15 @T6G_MB_LIB.T6G(SCH_1):PAGE58
   U26  K28 VSS_K28 GENOA_SP5-SOCKET6096_13568-001,SMLF,IO,DGA^6000030    I15 @T6G_MB_LIB.T6G(SCH_1):PAGE58
   U26  K29 VSS_K29 GENOA_SP5-SOCKET6096_13568-001,SMLF,IO,DGA^6000030    I15 @T6G_MB_LIB.T6G(SCH_1):PAGE58
   U26  K30 VSS_K30 GENOA_SP5-SOCKET6096_13568-001,SMLF,IO,DGA^6000030    I15 @T6G_MB_LIB.T6G(SCH_1):PAGE58
   U26  K31 VSS_K31 GENOA_SP5-SOCKET6096_13568-001,SMLF,IO,DGA^6000030    I15 @T6G_MB_LIB.T6G(SCH_1):PAGE58
   U26  K32 VSS_K32 GENOA_SP5-SOCKET6096_13568-001,SMLF,IO,DGA^6000030    I15 @T6G_MB_LIB.T6G(SCH_1):PAGE58
   U26  K33 VSS_K33 GENOA_SP5-SOCKET6096_13568-001,SMLF,IO,DGA^6000030    I15 @T6G_MB_LIB.T6G(SCH_1):PAGE58
   U26  K34 VSS_K34 GENOA_SP5-SOCKET6096_13568-001,SMLF,IO,DGA^6000030    I15 @T6G_MB_LIB.T6G(SCH_1):PAGE58
   U26  K37 VSS_K37 GENOA_SP5-SOCKET6096_13568-001,SMLF,IO,DGA^6000030    I15 @T6G_MB_LIB.T6G(SCH_1):PAGE58
   U26  K39 VSS_K39 GENOA_SP5-SOCKET6096_13568-001,SMLF,IO,DGA^6000030    I15 @T6G_MB_LIB.T6G(SCH_1):PAGE58
   U26  K42 VSS_K42 GENOA_SP5-SOCKET6096_13568-001,SMLF,IO,DGA^6000030    I15 @T6G_MB_LIB.T6G(SCH_1):PAGE58
   U26  K43 VSS_K43 GENOA_SP5-SOCKET6096_13568-001,SMLF,IO,DGA^6000030    I15 @T6G_MB_LIB.T6G(SCH_1):PAGE58
   U26  K44 VSS_K44 GENOA_SP5-SOCKET6096_13568-001,SMLF,IO,DGA^6000030    I15 @T6G_MB_LIB.T6G(SCH_1):PAGE58
   U26  K45 VSS_K45 GENOA_SP5-SOCKET6096_13568-001,SMLF,IO,DGA^6000030    I15 @T6G_MB_LIB.T6G(SCH_1):PAGE58
   U26  K46 VSS_K46 GENOA_SP5-SOCKET6096_13568-001,SMLF,IO,DGA^6000030    I15 @T6G_MB_LIB.T6G(SCH_1):PAGE58
   U26  K47 VSS_K47 GENOA_SP5-SOCKET6096_13568-001,SMLF,IO,DGA^6000030    I15 @T6G_MB_LIB.T6G(SCH_1):PAGE58
   U26  K48 VSS_K48 GENOA_SP5-SOCKET6096_13568-001,SMLF,IO,DGA^6000030    I15 @T6G_MB_LIB.T6G(SCH_1):PAGE58
   U26  K49 VSS_K49 GENOA_SP5-SOCKET6096_13568-001,SMLF,IO,DGA^6000030    I15 @T6G_MB_LIB.T6G(SCH_1):PAGE58
   U26  K50 VSS_K50 GENOA_SP5-SOCKET6096_13568-001,SMLF,IO,DGA^6000030    I15 @T6G_MB_LIB.T6G(SCH_1):PAGE58
   U26  K51 VSS_K51 GENOA_SP5-SOCKET6096_13568-001,SMLF,IO,DGA^6000030    I15 @T6G_MB_LIB.T6G(SCH_1):PAGE58
   U26  K52 VSS_K52 GENOA_SP5-SOCKET6096_13568-001,SMLF,IO,DGA^6000030    I15 @T6G_MB_LIB.T6G(SCH_1):PAGE58
   U26  K53 VSS_K53 GENOA_SP5-SOCKET6096_13568-001,SMLF,IO,DGA^6000030    I15 @T6G_MB_LIB.T6G(SCH_1):PAGE58
   U26  K57 VSS_K57 GENOA_SP5-SOCKET6096_13568-001,SMLF,IO,DGA^6000030    I15 @T6G_MB_LIB.T6G(SCH_1):PAGE58
   U26  K61 VSS_K61 GENOA_SP5-SOCKET6096_13568-001,SMLF,IO,DGA^6000030    I15 @T6G_MB_LIB.T6G(SCH_1):PAGE58
   U26  K64 VSS_K64 GENOA_SP5-SOCKET6096_13568-001,SMLF,IO,DGA^6000030    I15 @T6G_MB_LIB.T6G(SCH_1):PAGE58
   U26  K66 VSS_K66 GENOA_SP5-SOCKET6096_13568-001,SMLF,IO,DGA^6000030    I15 @T6G_MB_LIB.T6G(SCH_1):PAGE58
   U26  K68 VSS_K68 GENOA_SP5-SOCKET6096_13568-001,SMLF,IO,DGA^6000030    I15 @T6G_MB_LIB.T6G(SCH_1):PAGE58
   U26  K71 VSS_K71 GENOA_SP5-SOCKET6096_13568-001,SMLF,IO,DGA^6000030    I15 @T6G_MB_LIB.T6G(SCH_1):PAGE58
   U26  K73 VSS_K73 GENOA_SP5-SOCKET6096_13568-001,SMLF,IO,DGA^6000030    I15 @T6G_MB_LIB.T6G(SCH_1):PAGE58
   U26   L1 VSS_L1 GENOA_SP5-SOCKET6096_13568-001,SMLF,IO,DGA^6000030    I15 @T6G_MB_LIB.T6G(SCH_1):PAGE58
   U26   L6 VSS_L6 GENOA_SP5-SOCKET6096_13568-001,SMLF,IO,DGA^6000030    I15 @T6G_MB_LIB.T6G(SCH_1):PAGE58
   U26   L8 VSS_L8 GENOA_SP5-SOCKET6096_13568-001,SMLF,IO,DGA^6000030    I15 @T6G_MB_LIB.T6G(SCH_1):PAGE58
   U26  L13 VSS_L13 GENOA_SP5-SOCKET6096_13568-001,SMLF,IO,DGA^6000030    I15 @T6G_MB_LIB.T6G(SCH_1):PAGE58
   U26  L15 VSS_L15 GENOA_SP5-SOCKET6096_13568-001,SMLF,IO,DGA^6000030    I15 @T6G_MB_LIB.T6G(SCH_1):PAGE58
   U26  L20 VSS_L20 GENOA_SP5-SOCKET6096_13568-001,SMLF,IO,DGA^6000030    I15 @T6G_MB_LIB.T6G(SCH_1):PAGE58
   U26  L22 VSS_L22 GENOA_SP5-SOCKET6096_13568-001,SMLF,IO,DGA^6000030    I15 @T6G_MB_LIB.T6G(SCH_1):PAGE58
   U26  L25 VSS_L25 GENOA_SP5-SOCKET6096_13568-001,SMLF,IO,DGA^6000030    I15 @T6G_MB_LIB.T6G(SCH_1):PAGE58
   U26  L28 VSS_L28 GENOA_SP5-SOCKET6096_13568-001,SMLF,IO,DGA^6000030    I15 @T6G_MB_LIB.T6G(SCH_1):PAGE58
   U26  L31 VSS_L31 GENOA_SP5-SOCKET6096_13568-001,SMLF,IO,DGA^6000030    I15 @T6G_MB_LIB.T6G(SCH_1):PAGE58
   U26  L34 VSS_L34 GENOA_SP5-SOCKET6096_13568-001,SMLF,IO,DGA^6000030    I15 @T6G_MB_LIB.T6G(SCH_1):PAGE58
   U26  L35 VSS_L35 GENOA_SP5-SOCKET6096_13568-001,SMLF,IO,DGA^6000030    I15 @T6G_MB_LIB.T6G(SCH_1):PAGE58
   U26  L36 VSS_L36 GENOA_SP5-SOCKET6096_13568-001,SMLF,IO,DGA^6000030    I15 @T6G_MB_LIB.T6G(SCH_1):PAGE58
   U26  L40 VSS_L40 GENOA_SP5-SOCKET6096_13568-001,SMLF,IO,DGA^6000030    I15 @T6G_MB_LIB.T6G(SCH_1):PAGE58
   U26  L41 VSS_L41 GENOA_SP5-SOCKET6096_13568-001,SMLF,IO,DGA^6000030    I15 @T6G_MB_LIB.T6G(SCH_1):PAGE58
   U26  L42 VSS_L42 GENOA_SP5-SOCKET6096_13568-001,SMLF,IO,DGA^6000030    I15 @T6G_MB_LIB.T6G(SCH_1):PAGE58
   U26  L45 VSS_L45 GENOA_SP5-SOCKET6096_13568-001,SMLF,IO,DGA^6000030    I15 @T6G_MB_LIB.T6G(SCH_1):PAGE58
   U26  L48 VSS_L48 GENOA_SP5-SOCKET6096_13568-001,SMLF,IO,DGA^6000030    I15 @T6G_MB_LIB.T6G(SCH_1):PAGE58
   U26  L51 VSS_L51 GENOA_SP5-SOCKET6096_13568-001,SMLF,IO,DGA^6000030    I15 @T6G_MB_LIB.T6G(SCH_1):PAGE58
   U26  L54 VSS_L54 GENOA_SP5-SOCKET6096_13568-001,SMLF,IO,DGA^6000030    I15 @T6G_MB_LIB.T6G(SCH_1):PAGE58
   U26  L56 VSS_L56 GENOA_SP5-SOCKET6096_13568-001,SMLF,IO,DGA^6000030    I15 @T6G_MB_LIB.T6G(SCH_1):PAGE58
   U26  L61 VSS_L61 GENOA_SP5-SOCKET6096_13568-001,SMLF,IO,DGA^6000030    I15 @T6G_MB_LIB.T6G(SCH_1):PAGE58
   U26  L63 VSS_L63 GENOA_SP5-SOCKET6096_13568-001,SMLF,IO,DGA^6000030    I15 @T6G_MB_LIB.T6G(SCH_1):PAGE58
   U26  L68 VSS_L68 GENOA_SP5-SOCKET6096_13568-001,SMLF,IO,DGA^6000030    I15 @T6G_MB_LIB.T6G(SCH_1):PAGE58
   U26  L70 VSS_L70 GENOA_SP5-SOCKET6096_13568-001,SMLF,IO,DGA^6000030    I15 @T6G_MB_LIB.T6G(SCH_1):PAGE58
   U26  L75 VSS_L75 GENOA_SP5-SOCKET6096_13568-001,SMLF,IO,DGA^6000030    I15 @T6G_MB_LIB.T6G(SCH_1):PAGE58
   U26   M3 VSS_M3 GENOA_SP5-SOCKET6096_13568-001,SMLF,IO,DGA^6000030    I15 @T6G_MB_LIB.T6G(SCH_1):PAGE58
   U26   M5 VSS_M5 GENOA_SP5-SOCKET6096_13568-001,SMLF,IO,DGA^6000030    I15 @T6G_MB_LIB.T6G(SCH_1):PAGE58
   U26   M8 VSS_M8 GENOA_SP5-SOCKET6096_13568-001,SMLF,IO,DGA^6000030    I15 @T6G_MB_LIB.T6G(SCH_1):PAGE58
   U26  M10 VSS_M10 GENOA_SP5-SOCKET6096_13568-001,SMLF,IO,DGA^6000030    I15 @T6G_MB_LIB.T6G(SCH_1):PAGE58
   U26  M12 VSS_M12 GENOA_SP5-SOCKET6096_13568-001,SMLF,IO,DGA^6000030    I15 @T6G_MB_LIB.T6G(SCH_1):PAGE58
   U26  M15 VSS_M15 GENOA_SP5-SOCKET6096_13568-001,SMLF,IO,DGA^6000030    I15 @T6G_MB_LIB.T6G(SCH_1):PAGE58
   U26  M17 VSS_M17 GENOA_SP5-SOCKET6096_13568-001,SMLF,IO,DGA^6000030    I15 @T6G_MB_LIB.T6G(SCH_1):PAGE58
   U26  M19 VSS_M19 GENOA_SP5-SOCKET6096_13568-001,SMLF,IO,DGA^6000030    I15 @T6G_MB_LIB.T6G(SCH_1):PAGE58
   U26  M22 VSS_M22 GENOA_SP5-SOCKET6096_13568-001,SMLF,IO,DGA^6000030    I15 @T6G_MB_LIB.T6G(SCH_1):PAGE58
   U26  M25 VSS_M25 GENOA_SP5-SOCKET6096_13568-001,SMLF,IO,DGA^6000030    I15 @T6G_MB_LIB.T6G(SCH_1):PAGE58
   U26  M28 VSS_M28 GENOA_SP5-SOCKET6096_13568-001,SMLF,IO,DGA^6000030    I15 @T6G_MB_LIB.T6G(SCH_1):PAGE58
   U26  M31 VSS_M31 GENOA_SP5-SOCKET6096_13568-001,SMLF,IO,DGA^6000030    I15 @T6G_MB_LIB.T6G(SCH_1):PAGE58
   U26  M34 VSS_M34 GENOA_SP5-SOCKET6096_13568-001,SMLF,IO,DGA^6000030    I15 @T6G_MB_LIB.T6G(SCH_1):PAGE58
   U26  M37 VSS_M37 GENOA_SP5-SOCKET6096_13568-001,SMLF,IO,DGA^6000030    I15 @T6G_MB_LIB.T6G(SCH_1):PAGE58
   U26  M39 VSS_M39 GENOA_SP5-SOCKET6096_13568-001,SMLF,IO,DGA^6000030    I15 @T6G_MB_LIB.T6G(SCH_1):PAGE58
   U26  M42 VSS_M42 GENOA_SP5-SOCKET6096_13568-001,SMLF,IO,DGA^6000030    I15 @T6G_MB_LIB.T6G(SCH_1):PAGE58
   U26  M45 VSS_M45 GENOA_SP5-SOCKET6096_13568-001,SMLF,IO,DGA^6000030    I15 @T6G_MB_LIB.T6G(SCH_1):PAGE58
   U26  M48 VSS_M48 GENOA_SP5-SOCKET6096_13568-001,SMLF,IO,DGA^6000030    I15 @T6G_MB_LIB.T6G(SCH_1):PAGE58
   U26  M51 VSS_M51 GENOA_SP5-SOCKET6096_13568-001,SMLF,IO,DGA^6000030    I15 @T6G_MB_LIB.T6G(SCH_1):PAGE58
   U26  M54 VSS_M54 GENOA_SP5-SOCKET6096_13568-001,SMLF,IO,DGA^6000030    I15 @T6G_MB_LIB.T6G(SCH_1):PAGE58
   U26  M57 VSS_M57 GENOA_SP5-SOCKET6096_13568-001,SMLF,IO,DGA^6000030    I15 @T6G_MB_LIB.T6G(SCH_1):PAGE58
   U26  M59 VSS_M59 GENOA_SP5-SOCKET6096_13568-001,SMLF,IO,DGA^6000030    I15 @T6G_MB_LIB.T6G(SCH_1):PAGE58
   U26  M61 VSS_M61 GENOA_SP5-SOCKET6096_13568-001,SMLF,IO,DGA^6000030    I15 @T6G_MB_LIB.T6G(SCH_1):PAGE58
   U26  M64 VSS_M64 GENOA_SP5-SOCKET6096_13568-001,SMLF,IO,DGA^6000030    I15 @T6G_MB_LIB.T6G(SCH_1):PAGE58
   U26  M66 VSS_M66 GENOA_SP5-SOCKET6096_13568-001,SMLF,IO,DGA^6000030    I15 @T6G_MB_LIB.T6G(SCH_1):PAGE58
   U26  M68 VSS_M68 GENOA_SP5-SOCKET6096_13568-001,SMLF,IO,DGA^6000030    I15 @T6G_MB_LIB.T6G(SCH_1):PAGE58
   U26  M71 VSS_M71 GENOA_SP5-SOCKET6096_13568-001,SMLF,IO,DGA^6000030    I15 @T6G_MB_LIB.T6G(SCH_1):PAGE58
   U26  M73 VSS_M73 GENOA_SP5-SOCKET6096_13568-001,SMLF,IO,DGA^6000030    I15 @T6G_MB_LIB.T6G(SCH_1):PAGE58
   U26   N1 VSS_N1 GENOA_SP5-SOCKET6096_13568-001,SMLF,IO,DGA^6000030    I15 @T6G_MB_LIB.T6G(SCH_1):PAGE58
   U26   N4 VSS_N4 GENOA_SP5-SOCKET6096_13568-001,SMLF,IO,DGA^6000030    I15 @T6G_MB_LIB.T6G(SCH_1):PAGE58
   U26   N6 VSS_N6 GENOA_SP5-SOCKET6096_13568-001,SMLF,IO,DGA^6000030    I15 @T6G_MB_LIB.T6G(SCH_1):PAGE58
   U26   N8 VSS_N8 GENOA_SP5-SOCKET6096_13568-001,SMLF,IO,DGA^6000030    I15 @T6G_MB_LIB.T6G(SCH_1):PAGE58
   U26  N11 VSS_N11 GENOA_SP5-SOCKET6096_13568-001,SMLF,IO,DGA^6000030    I15 @T6G_MB_LIB.T6G(SCH_1):PAGE58
   U26  N13 VSS_N13 GENOA_SP5-SOCKET6096_13568-001,SMLF,IO,DGA^6000030    I15 @T6G_MB_LIB.T6G(SCH_1):PAGE58
   U26  N15 VSS_N15 GENOA_SP5-SOCKET6096_13568-001,SMLF,IO,DGA^6000030    I15 @T6G_MB_LIB.T6G(SCH_1):PAGE58
   U26  N18 VSS_N18 GENOA_SP5-SOCKET6096_13568-001,SMLF,IO,DGA^6000030    I15 @T6G_MB_LIB.T6G(SCH_1):PAGE58
   U26  N20 VSS_N20 GENOA_SP5-SOCKET6096_13568-001,SMLF,IO,DGA^6000030    I15 @T6G_MB_LIB.T6G(SCH_1):PAGE58
   U26  N22 VSS_N22 GENOA_SP5-SOCKET6096_13568-001,SMLF,IO,DGA^6000030    I15 @T6G_MB_LIB.T6G(SCH_1):PAGE58
   U26  N25 VSS_N25 GENOA_SP5-SOCKET6096_13568-001,SMLF,IO,DGA^6000030    I15 @T6G_MB_LIB.T6G(SCH_1):PAGE58
   U26  N28 VSS_N28 GENOA_SP5-SOCKET6096_13568-001,SMLF,IO,DGA^6000030    I15 @T6G_MB_LIB.T6G(SCH_1):PAGE58
   U26  N31 VSS_N31 GENOA_SP5-SOCKET6096_13568-001,SMLF,IO,DGA^6000030    I15 @T6G_MB_LIB.T6G(SCH_1):PAGE58
   U26  N34 VSS_N34 GENOA_SP5-SOCKET6096_13568-001,SMLF,IO,DGA^6000030    I15 @T6G_MB_LIB.T6G(SCH_1):PAGE58
   U26  N42 VSS_N42 GENOA_SP5-SOCKET6096_13568-001,SMLF,IO,DGA^6000030    I15 @T6G_MB_LIB.T6G(SCH_1):PAGE58
   U26  N45 VSS_N45 GENOA_SP5-SOCKET6096_13568-001,SMLF,IO,DGA^6000030    I15 @T6G_MB_LIB.T6G(SCH_1):PAGE58
   U26  N48 VSS_N48 GENOA_SP5-SOCKET6096_13568-001,SMLF,IO,DGA^6000030    I15 @T6G_MB_LIB.T6G(SCH_1):PAGE58
   U26  N51 VSS_N51 GENOA_SP5-SOCKET6096_13568-001,SMLF,IO,DGA^6000030    I15 @T6G_MB_LIB.T6G(SCH_1):PAGE58
   U26  N54 VSS_N54 GENOA_SP5-SOCKET6096_13568-001,SMLF,IO,DGA^6000030    I15 @T6G_MB_LIB.T6G(SCH_1):PAGE58
   U26  N56 VSS_N56 GENOA_SP5-SOCKET6096_13568-001,SMLF,IO,DGA^6000030    I15 @T6G_MB_LIB.T6G(SCH_1):PAGE58
   U26  N58 VSS_N58 GENOA_SP5-SOCKET6096_13568-001,SMLF,IO,DGA^6000030    I15 @T6G_MB_LIB.T6G(SCH_1):PAGE58
   U26  N61 VSS_N61 GENOA_SP5-SOCKET6096_13568-001,SMLF,IO,DGA^6000030    I15 @T6G_MB_LIB.T6G(SCH_1):PAGE58
   U26  N63 VSS_N63 GENOA_SP5-SOCKET6096_13568-001,SMLF,IO,DGA^6000030    I15 @T6G_MB_LIB.T6G(SCH_1):PAGE58
   U26  N65 VSS_N65 GENOA_SP5-SOCKET6096_13568-001,SMLF,IO,DGA^6000030    I15 @T6G_MB_LIB.T6G(SCH_1):PAGE58
   U26  N68 VSS_N68 GENOA_SP5-SOCKET6096_13568-001,SMLF,IO,DGA^6000030    I15 @T6G_MB_LIB.T6G(SCH_1):PAGE58
   U26  N70 VSS_N70 GENOA_SP5-SOCKET6096_13568-001,SMLF,IO,DGA^6000030    I15 @T6G_MB_LIB.T6G(SCH_1):PAGE58
   U26  N72 VSS_N72 GENOA_SP5-SOCKET6096_13568-001,SMLF,IO,DGA^6000030    I15 @T6G_MB_LIB.T6G(SCH_1):PAGE58
   U26  N75 VSS_N75 GENOA_SP5-SOCKET6096_13568-001,SMLF,IO,DGA^6000030    I15 @T6G_MB_LIB.T6G(SCH_1):PAGE58
   U26   P3 VSS_P3 GENOA_SP5-SOCKET6096_13568-001,SMLF,IO,DGA^6000030    I15 @T6G_MB_LIB.T6G(SCH_1):PAGE58
   U26   P8 VSS_P8 GENOA_SP5-SOCKET6096_13568-001,SMLF,IO,DGA^6000030    I15 @T6G_MB_LIB.T6G(SCH_1):PAGE58
   U26  P10 VSS_P10 GENOA_SP5-SOCKET6096_13568-001,SMLF,IO,DGA^6000030    I15 @T6G_MB_LIB.T6G(SCH_1):PAGE58
   U26  P15 VSS_P15 GENOA_SP5-SOCKET6096_13568-001,SMLF,IO,DGA^6000030    I15 @T6G_MB_LIB.T6G(SCH_1):PAGE58
   U26  P17 VSS_P17 GENOA_SP5-SOCKET6096_13568-001,SMLF,IO,DGA^6000030    I15 @T6G_MB_LIB.T6G(SCH_1):PAGE58
   U26  P23 VSS_P23 GENOA_SP5-SOCKET6096_13568-001,SMLF,IO,DGA^6000030    I15 @T6G_MB_LIB.T6G(SCH_1):PAGE58
   U26  P24 VSS_P24 GENOA_SP5-SOCKET6096_13568-001,SMLF,IO,DGA^6000030    I15 @T6G_MB_LIB.T6G(SCH_1):PAGE58
   U26  P26 VSS_P26 GENOA_SP5-SOCKET6096_13568-001,SMLF,IO,DGA^6000030    I15 @T6G_MB_LIB.T6G(SCH_1):PAGE58
   U26  P27 VSS_P27 GENOA_SP5-SOCKET6096_13568-001,SMLF,IO,DGA^6000030    I15 @T6G_MB_LIB.T6G(SCH_1):PAGE58
   U26  P28 VSS_P28 GENOA_SP5-SOCKET6096_13568-001,SMLF,IO,DGA^6000030    I15 @T6G_MB_LIB.T6G(SCH_1):PAGE58
   U26  P29 VSS_P29 GENOA_SP5-SOCKET6096_13568-001,SMLF,IO,DGA^6000030    I15 @T6G_MB_LIB.T6G(SCH_1):PAGE58
   U26  P30 VSS_P30 GENOA_SP5-SOCKET6096_13568-001,SMLF,IO,DGA^6000030    I15 @T6G_MB_LIB.T6G(SCH_1):PAGE58
   U26  P31 VSS_P31 GENOA_SP5-SOCKET6096_13568-001,SMLF,IO,DGA^6000030    I15 @T6G_MB_LIB.T6G(SCH_1):PAGE58
   U26  P32 VSS_P32 GENOA_SP5-SOCKET6096_13568-001,SMLF,IO,DGA^6000030    I15 @T6G_MB_LIB.T6G(SCH_1):PAGE58
   U26  P33 VSS_P33 GENOA_SP5-SOCKET6096_13568-001,SMLF,IO,DGA^6000030    I15 @T6G_MB_LIB.T6G(SCH_1):PAGE58
   U26  P34 VSS_P34 GENOA_SP5-SOCKET6096_13568-001,SMLF,IO,DGA^6000030    I15 @T6G_MB_LIB.T6G(SCH_1):PAGE58
   U26  P37 VSS_P37 GENOA_SP5-SOCKET6096_13568-001,SMLF,IO,DGA^6000030    I15 @T6G_MB_LIB.T6G(SCH_1):PAGE58
   U26  P39 VSS_P39 GENOA_SP5-SOCKET6096_13568-001,SMLF,IO,DGA^6000030    I15 @T6G_MB_LIB.T6G(SCH_1):PAGE58
   U26  P42 VSS_P42 GENOA_SP5-SOCKET6096_13568-001,SMLF,IO,DGA^6000030    I15 @T6G_MB_LIB.T6G(SCH_1):PAGE58
   U26  P43 VSS_P43 GENOA_SP5-SOCKET6096_13568-001,SMLF,IO,DGA^6000030    I15 @T6G_MB_LIB.T6G(SCH_1):PAGE58
   U26  P44 VSS_P44 GENOA_SP5-SOCKET6096_13568-001,SMLF,IO,DGA^6000030    I15 @T6G_MB_LIB.T6G(SCH_1):PAGE58
   U26  P45 VSS_P45 GENOA_SP5-SOCKET6096_13568-001,SMLF,IO,DGA^6000030    I15 @T6G_MB_LIB.T6G(SCH_1):PAGE58
   U26  P46 VSS_P46 GENOA_SP5-SOCKET6096_13568-001,SMLF,IO,DGA^6000030    I15 @T6G_MB_LIB.T6G(SCH_1):PAGE58
   U26  P47 VSS_P47 GENOA_SP5-SOCKET6096_13568-001,SMLF,IO,DGA^6000030    I15 @T6G_MB_LIB.T6G(SCH_1):PAGE58
   U26  P48 VSS_P48 GENOA_SP5-SOCKET6096_13568-001,SMLF,IO,DGA^6000030    I15 @T6G_MB_LIB.T6G(SCH_1):PAGE58
   U26  P49 VSS_P49 GENOA_SP5-SOCKET6096_13568-001,SMLF,IO,DGA^6000030    I15 @T6G_MB_LIB.T6G(SCH_1):PAGE58
   U26  P50 VSS_P50 GENOA_SP5-SOCKET6096_13568-001,SMLF,IO,DGA^6000030    I15 @T6G_MB_LIB.T6G(SCH_1):PAGE58
   U26  P51 VSS_P51 GENOA_SP5-SOCKET6096_13568-001,SMLF,IO,DGA^6000030    I15 @T6G_MB_LIB.T6G(SCH_1):PAGE58
   U26  P52 VSS_P52 GENOA_SP5-SOCKET6096_13568-001,SMLF,IO,DGA^6000030    I15 @T6G_MB_LIB.T6G(SCH_1):PAGE58
   U26  P53 VSS_P53 GENOA_SP5-SOCKET6096_13568-001,SMLF,IO,DGA^6000030    I15 @T6G_MB_LIB.T6G(SCH_1):PAGE58
   U26  P59 VSS_P59 GENOA_SP5-SOCKET6096_13568-001,SMLF,IO,DGA^6000030    I15 @T6G_MB_LIB.T6G(SCH_1):PAGE58
   U26  P61 VSS_P61 GENOA_SP5-SOCKET6096_13568-001,SMLF,IO,DGA^6000030    I15 @T6G_MB_LIB.T6G(SCH_1):PAGE58
   U26  P66 VSS_P66 GENOA_SP5-SOCKET6096_13568-001,SMLF,IO,DGA^6000030    I15 @T6G_MB_LIB.T6G(SCH_1):PAGE58
   U26  P73 VSS_P73 GENOA_SP5-SOCKET6096_13568-001,SMLF,IO,DGA^6000030    I15 @T6G_MB_LIB.T6G(SCH_1):PAGE58
   U26   R1 VSS_R1 GENOA_SP5-SOCKET6096_13568-001,SMLF,IO,DGA^6000030    I15 @T6G_MB_LIB.T6G(SCH_1):PAGE58
   U26   R4 VSS_R4 GENOA_SP5-SOCKET6096_13568-001,SMLF,IO,DGA^6000030    I15 @T6G_MB_LIB.T6G(SCH_1):PAGE58
   U26   R6 VSS_R6 GENOA_SP5-SOCKET6096_13568-001,SMLF,IO,DGA^6000030    I15 @T6G_MB_LIB.T6G(SCH_1):PAGE58
   U26   R8 VSS_R8 GENOA_SP5-SOCKET6096_13568-001,SMLF,IO,DGA^6000030    I15 @T6G_MB_LIB.T6G(SCH_1):PAGE58
   U26  R11 VSS_R11 GENOA_SP5-SOCKET6096_13568-001,SMLF,IO,DGA^6000030    I15 @T6G_MB_LIB.T6G(SCH_1):PAGE58
   U26  R13 VSS_R13 GENOA_SP5-SOCKET6096_13568-001,SMLF,IO,DGA^6000030    I15 @T6G_MB_LIB.T6G(SCH_1):PAGE58
   U26  R15 VSS_R15 GENOA_SP5-SOCKET6096_13568-001,SMLF,IO,DGA^6000030    I15 @T6G_MB_LIB.T6G(SCH_1):PAGE58
   U26  R18 VSS_R18 GENOA_SP5-SOCKET6096_13568-001,SMLF,IO,DGA^6000030    I15 @T6G_MB_LIB.T6G(SCH_1):PAGE58
   U26  R20 VSS_R20 GENOA_SP5-SOCKET6096_13568-001,SMLF,IO,DGA^6000030    I15 @T6G_MB_LIB.T6G(SCH_1):PAGE58
   U26  R22 VSS_R22 GENOA_SP5-SOCKET6096_13568-001,SMLF,IO,DGA^6000030    I15 @T6G_MB_LIB.T6G(SCH_1):PAGE58
   U26  R25 VSS_R25 GENOA_SP5-SOCKET6096_13568-001,SMLF,IO,DGA^6000030    I15 @T6G_MB_LIB.T6G(SCH_1):PAGE58
   U26  R28 VSS_R28 GENOA_SP5-SOCKET6096_13568-001,SMLF,IO,DGA^6000030    I15 @T6G_MB_LIB.T6G(SCH_1):PAGE58
   U26  R31 VSS_R31 GENOA_SP5-SOCKET6096_13568-001,SMLF,IO,DGA^6000030    I15 @T6G_MB_LIB.T6G(SCH_1):PAGE58
   U26  R34 VSS_R34 GENOA_SP5-SOCKET6096_13568-001,SMLF,IO,DGA^6000030    I15 @T6G_MB_LIB.T6G(SCH_1):PAGE58
   U26  R35 VSS_R35 GENOA_SP5-SOCKET6096_13568-001,SMLF,IO,DGA^6000030    I15 @T6G_MB_LIB.T6G(SCH_1):PAGE58
   U26  R36 VSS_R36 GENOA_SP5-SOCKET6096_13568-001,SMLF,IO,DGA^6000030    I15 @T6G_MB_LIB.T6G(SCH_1):PAGE58
   U26  R40 VSS_R40 GENOA_SP5-SOCKET6096_13568-001,SMLF,IO,DGA^6000030    I15 @T6G_MB_LIB.T6G(SCH_1):PAGE58
   U26  R41 VSS_R41 GENOA_SP5-SOCKET6096_13568-001,SMLF,IO,DGA^6000030    I15 @T6G_MB_LIB.T6G(SCH_1):PAGE58
   U26  R42 VSS_R42 GENOA_SP5-SOCKET6096_13568-001,SMLF,IO,DGA^6000030    I15 @T6G_MB_LIB.T6G(SCH_1):PAGE58
   U26  R45 VSS_R45 GENOA_SP5-SOCKET6096_13568-001,SMLF,IO,DGA^6000030    I15 @T6G_MB_LIB.T6G(SCH_1):PAGE58
   U26  R48 VSS_R48 GENOA_SP5-SOCKET6096_13568-001,SMLF,IO,DGA^6000030    I15 @T6G_MB_LIB.T6G(SCH_1):PAGE58
   U26  R51 VSS_R51 GENOA_SP5-SOCKET6096_13568-001,SMLF,IO,DGA^6000030    I15 @T6G_MB_LIB.T6G(SCH_1):PAGE58
   U26  R54 VSS_R54 GENOA_SP5-SOCKET6096_13568-001,SMLF,IO,DGA^6000030    I15 @T6G_MB_LIB.T6G(SCH_1):PAGE58
   U26  R56 VSS_R56 GENOA_SP5-SOCKET6096_13568-001,SMLF,IO,DGA^6000030    I15 @T6G_MB_LIB.T6G(SCH_1):PAGE58
   U26  R58 VSS_R58 GENOA_SP5-SOCKET6096_13568-001,SMLF,IO,DGA^6000030    I15 @T6G_MB_LIB.T6G(SCH_1):PAGE58
   U26  R61 VSS_R61 GENOA_SP5-SOCKET6096_13568-001,SMLF,IO,DGA^6000030    I15 @T6G_MB_LIB.T6G(SCH_1):PAGE58
   U26  R63 VSS_R63 GENOA_SP5-SOCKET6096_13568-001,SMLF,IO,DGA^6000030    I15 @T6G_MB_LIB.T6G(SCH_1):PAGE58
   U26  R65 VSS_R65 GENOA_SP5-SOCKET6096_13568-001,SMLF,IO,DGA^6000030    I15 @T6G_MB_LIB.T6G(SCH_1):PAGE58
   U26  R68 VSS_R68 GENOA_SP5-SOCKET6096_13568-001,SMLF,IO,DGA^6000030    I15 @T6G_MB_LIB.T6G(SCH_1):PAGE58
   U26  R70 VSS_R70 GENOA_SP5-SOCKET6096_13568-001,SMLF,IO,DGA^6000030    I15 @T6G_MB_LIB.T6G(SCH_1):PAGE58
   U26  R72 VSS_R72 GENOA_SP5-SOCKET6096_13568-001,SMLF,IO,DGA^6000030    I15 @T6G_MB_LIB.T6G(SCH_1):PAGE58
   U26  R75 VSS_R75 GENOA_SP5-SOCKET6096_13568-001,SMLF,IO,DGA^6000030    I15 @T6G_MB_LIB.T6G(SCH_1):PAGE58
   U26   T3 VSS_T3 GENOA_SP5-SOCKET6096_13568-001,SMLF,IO,DGA^6000030    I15 @T6G_MB_LIB.T6G(SCH_1):PAGE58
   U26   T5 VSS_T5 GENOA_SP5-SOCKET6096_13568-001,SMLF,IO,DGA^6000030    I15 @T6G_MB_LIB.T6G(SCH_1):PAGE58
   U26   T8 VSS_T8 GENOA_SP5-SOCKET6096_13568-001,SMLF,IO,DGA^6000030    I15 @T6G_MB_LIB.T6G(SCH_1):PAGE58
   U26  T10 VSS_T10 GENOA_SP5-SOCKET6096_13568-001,SMLF,IO,DGA^6000030    I15 @T6G_MB_LIB.T6G(SCH_1):PAGE58
   U26  T12 VSS_T12 GENOA_SP5-SOCKET6096_13568-001,SMLF,IO,DGA^6000030    I15 @T6G_MB_LIB.T6G(SCH_1):PAGE58
   U26  T15 VSS_T15 GENOA_SP5-SOCKET6096_13568-001,SMLF,IO,DGA^6000030    I15 @T6G_MB_LIB.T6G(SCH_1):PAGE58
   U26  T17 VSS_T17 GENOA_SP5-SOCKET6096_13568-001,SMLF,IO,DGA^6000030    I15 @T6G_MB_LIB.T6G(SCH_1):PAGE58
   U26  T19 VSS_T19 GENOA_SP5-SOCKET6096_13568-001,SMLF,IO,DGA^6000030    I15 @T6G_MB_LIB.T6G(SCH_1):PAGE58
   U26  T22 VSS_T22 GENOA_SP5-SOCKET6096_13568-001,SMLF,IO,DGA^6000030    I15 @T6G_MB_LIB.T6G(SCH_1):PAGE58
   U26  T25 VSS_T25 GENOA_SP5-SOCKET6096_13568-001,SMLF,IO,DGA^6000030    I15 @T6G_MB_LIB.T6G(SCH_1):PAGE58
   U26  T28 VSS_T28 GENOA_SP5-SOCKET6096_13568-001,SMLF,IO,DGA^6000030    I15 @T6G_MB_LIB.T6G(SCH_1):PAGE58
   U26  T31 VSS_T31 GENOA_SP5-SOCKET6096_13568-001,SMLF,IO,DGA^6000030    I15 @T6G_MB_LIB.T6G(SCH_1):PAGE58
   U26  T34 VSS_T34 GENOA_SP5-SOCKET6096_13568-001,SMLF,IO,DGA^6000030    I15 @T6G_MB_LIB.T6G(SCH_1):PAGE58
   U26  T37 VSS_T37 GENOA_SP5-SOCKET6096_13568-001,SMLF,IO,DGA^6000030    I15 @T6G_MB_LIB.T6G(SCH_1):PAGE58
   U26  T39 VSS_T39 GENOA_SP5-SOCKET6096_13568-001,SMLF,IO,DGA^6000030    I15 @T6G_MB_LIB.T6G(SCH_1):PAGE58
   U26  T42 VSS_T42 GENOA_SP5-SOCKET6096_13568-001,SMLF,IO,DGA^6000030    I15 @T6G_MB_LIB.T6G(SCH_1):PAGE58
   U26  T45 VSS_T45 GENOA_SP5-SOCKET6096_13568-001,SMLF,IO,DGA^6000030    I15 @T6G_MB_LIB.T6G(SCH_1):PAGE58
   U26  T48 VSS_T48 GENOA_SP5-SOCKET6096_13568-001,SMLF,IO,DGA^6000030    I15 @T6G_MB_LIB.T6G(SCH_1):PAGE58
   U26  T51 VSS_T51 GENOA_SP5-SOCKET6096_13568-001,SMLF,IO,DGA^6000030    I15 @T6G_MB_LIB.T6G(SCH_1):PAGE58
   U26  T54 VSS_T54 GENOA_SP5-SOCKET6096_13568-001,SMLF,IO,DGA^6000030    I15 @T6G_MB_LIB.T6G(SCH_1):PAGE58
   U26  T57 VSS_T57 GENOA_SP5-SOCKET6096_13568-001,SMLF,IO,DGA^6000030    I15 @T6G_MB_LIB.T6G(SCH_1):PAGE58
   U26  T59 VSS_T59 GENOA_SP5-SOCKET6096_13568-001,SMLF,IO,DGA^6000030    I15 @T6G_MB_LIB.T6G(SCH_1):PAGE58
   U26  T61 VSS_T61 GENOA_SP5-SOCKET6096_13568-001,SMLF,IO,DGA^6000030    I15 @T6G_MB_LIB.T6G(SCH_1):PAGE58
   U26  T64 VSS_T64 GENOA_SP5-SOCKET6096_13568-001,SMLF,IO,DGA^6000030    I15 @T6G_MB_LIB.T6G(SCH_1):PAGE58
   U26 BL26 VSS_BL26 GENOA_SP5-SOCKET6096_13568-001,SMLF,IO,DGA^6000030     I1 @T6G_MB_LIB.T6G(SCH_1):PAGE59
   U26 BL28 VSS_BL28 GENOA_SP5-SOCKET6096_13568-001,SMLF,IO,DGA^6000030     I1 @T6G_MB_LIB.T6G(SCH_1):PAGE59
   U26 BL49 VSS_BL49 GENOA_SP5-SOCKET6096_13568-001,SMLF,IO,DGA^6000030     I1 @T6G_MB_LIB.T6G(SCH_1):PAGE59
   U26 BL51 VSS_BL51 GENOA_SP5-SOCKET6096_13568-001,SMLF,IO,DGA^6000030     I1 @T6G_MB_LIB.T6G(SCH_1):PAGE59
   U26 BL53 VSS_BL53 GENOA_SP5-SOCKET6096_13568-001,SMLF,IO,DGA^6000030     I1 @T6G_MB_LIB.T6G(SCH_1):PAGE59
   U26 BL56 VSS_BL56 GENOA_SP5-SOCKET6096_13568-001,SMLF,IO,DGA^6000030     I1 @T6G_MB_LIB.T6G(SCH_1):PAGE59
   U26 BL58 VSS_BL58 GENOA_SP5-SOCKET6096_13568-001,SMLF,IO,DGA^6000030     I1 @T6G_MB_LIB.T6G(SCH_1):PAGE59
   U26 BL61 VSS_BL61 GENOA_SP5-SOCKET6096_13568-001,SMLF,IO,DGA^6000030     I1 @T6G_MB_LIB.T6G(SCH_1):PAGE59
   U26 BL63 VSS_BL63 GENOA_SP5-SOCKET6096_13568-001,SMLF,IO,DGA^6000030     I1 @T6G_MB_LIB.T6G(SCH_1):PAGE59
   U26 BL65 VSS_BL65 GENOA_SP5-SOCKET6096_13568-001,SMLF,IO,DGA^6000030     I1 @T6G_MB_LIB.T6G(SCH_1):PAGE59
   U26 BL68 VSS_BL68 GENOA_SP5-SOCKET6096_13568-001,SMLF,IO,DGA^6000030     I1 @T6G_MB_LIB.T6G(SCH_1):PAGE59
   U26 BL70 VSS_BL70 GENOA_SP5-SOCKET6096_13568-001,SMLF,IO,DGA^6000030     I1 @T6G_MB_LIB.T6G(SCH_1):PAGE59
   U26 BL72 VSS_BL72 GENOA_SP5-SOCKET6096_13568-001,SMLF,IO,DGA^6000030     I1 @T6G_MB_LIB.T6G(SCH_1):PAGE59
   U26 BL75 VSS_BL75 GENOA_SP5-SOCKET6096_13568-001,SMLF,IO,DGA^6000030     I1 @T6G_MB_LIB.T6G(SCH_1):PAGE59
   U26  BM3 VSS_BM3 GENOA_SP5-SOCKET6096_13568-001,SMLF,IO,DGA^6000030     I1 @T6G_MB_LIB.T6G(SCH_1):PAGE59
   U26  BM8 VSS_BM8 GENOA_SP5-SOCKET6096_13568-001,SMLF,IO,DGA^6000030     I1 @T6G_MB_LIB.T6G(SCH_1):PAGE59
   U26 BM10 VSS_BM10 GENOA_SP5-SOCKET6096_13568-001,SMLF,IO,DGA^6000030     I1 @T6G_MB_LIB.T6G(SCH_1):PAGE59
   U26 BM15 VSS_BM15 GENOA_SP5-SOCKET6096_13568-001,SMLF,IO,DGA^6000030     I1 @T6G_MB_LIB.T6G(SCH_1):PAGE59
   U26 BM17 VSS_BM17 GENOA_SP5-SOCKET6096_13568-001,SMLF,IO,DGA^6000030     I1 @T6G_MB_LIB.T6G(SCH_1):PAGE59
   U26 BM23 VSS_BM23 GENOA_SP5-SOCKET6096_13568-001,SMLF,IO,DGA^6000030     I1 @T6G_MB_LIB.T6G(SCH_1):PAGE59
   U26 BM25 VSS_BM25 GENOA_SP5-SOCKET6096_13568-001,SMLF,IO,DGA^6000030     I1 @T6G_MB_LIB.T6G(SCH_1):PAGE59
   U26 BM27 VSS_BM27 GENOA_SP5-SOCKET6096_13568-001,SMLF,IO,DGA^6000030     I1 @T6G_MB_LIB.T6G(SCH_1):PAGE59
   U26 BM29 VSS_BM29 GENOA_SP5-SOCKET6096_13568-001,SMLF,IO,DGA^6000030     I1 @T6G_MB_LIB.T6G(SCH_1):PAGE59
   U26 BM31 VSS_BM31 GENOA_SP5-SOCKET6096_13568-001,SMLF,IO,DGA^6000030     I1 @T6G_MB_LIB.T6G(SCH_1):PAGE59
   U26 BM33 VSS_BM33 GENOA_SP5-SOCKET6096_13568-001,SMLF,IO,DGA^6000030     I1 @T6G_MB_LIB.T6G(SCH_1):PAGE59
   U26 BM35 VSS_BM35 GENOA_SP5-SOCKET6096_13568-001,SMLF,IO,DGA^6000030     I1 @T6G_MB_LIB.T6G(SCH_1):PAGE59
   U26 BM37 VSS_BM37 GENOA_SP5-SOCKET6096_13568-001,SMLF,IO,DGA^6000030     I1 @T6G_MB_LIB.T6G(SCH_1):PAGE59
   U26 BM40 VSS_BM40 GENOA_SP5-SOCKET6096_13568-001,SMLF,IO,DGA^6000030     I1 @T6G_MB_LIB.T6G(SCH_1):PAGE59
   U26 BM42 VSS_BM42 GENOA_SP5-SOCKET6096_13568-001,SMLF,IO,DGA^6000030     I1 @T6G_MB_LIB.T6G(SCH_1):PAGE59
   U26 BM44 VSS_BM44 GENOA_SP5-SOCKET6096_13568-001,SMLF,IO,DGA^6000030     I1 @T6G_MB_LIB.T6G(SCH_1):PAGE59
   U26 BM46 VSS_BM46 GENOA_SP5-SOCKET6096_13568-001,SMLF,IO,DGA^6000030     I1 @T6G_MB_LIB.T6G(SCH_1):PAGE59
   U26 BM48 VSS_BM48 GENOA_SP5-SOCKET6096_13568-001,SMLF,IO,DGA^6000030     I1 @T6G_MB_LIB.T6G(SCH_1):PAGE59
   U26 BM50 VSS_BM50 GENOA_SP5-SOCKET6096_13568-001,SMLF,IO,DGA^6000030     I1 @T6G_MB_LIB.T6G(SCH_1):PAGE59
   U26 BM52 VSS_BM52 GENOA_SP5-SOCKET6096_13568-001,SMLF,IO,DGA^6000030     I1 @T6G_MB_LIB.T6G(SCH_1):PAGE59
   U26 BM54 VSS_BM54 GENOA_SP5-SOCKET6096_13568-001,SMLF,IO,DGA^6000030     I1 @T6G_MB_LIB.T6G(SCH_1):PAGE59
   U26 BM59 VSS_BM59 GENOA_SP5-SOCKET6096_13568-001,SMLF,IO,DGA^6000030     I1 @T6G_MB_LIB.T6G(SCH_1):PAGE59
   U26 BM61 VSS_BM61 GENOA_SP5-SOCKET6096_13568-001,SMLF,IO,DGA^6000030     I1 @T6G_MB_LIB.T6G(SCH_1):PAGE59
   U26 BM66 VSS_BM66 GENOA_SP5-SOCKET6096_13568-001,SMLF,IO,DGA^6000030     I1 @T6G_MB_LIB.T6G(SCH_1):PAGE59
   U26 BM68 VSS_BM68 GENOA_SP5-SOCKET6096_13568-001,SMLF,IO,DGA^6000030     I1 @T6G_MB_LIB.T6G(SCH_1):PAGE59
   U26 BM73 VSS_BM73 GENOA_SP5-SOCKET6096_13568-001,SMLF,IO,DGA^6000030     I1 @T6G_MB_LIB.T6G(SCH_1):PAGE59
   U26  BN1 VSS_BN1 GENOA_SP5-SOCKET6096_13568-001,SMLF,IO,DGA^6000030     I1 @T6G_MB_LIB.T6G(SCH_1):PAGE59
   U26  BN4 VSS_BN4 GENOA_SP5-SOCKET6096_13568-001,SMLF,IO,DGA^6000030     I1 @T6G_MB_LIB.T6G(SCH_1):PAGE59
   U26  BN6 VSS_BN6 GENOA_SP5-SOCKET6096_13568-001,SMLF,IO,DGA^6000030     I1 @T6G_MB_LIB.T6G(SCH_1):PAGE59
   U26  BN8 VSS_BN8 GENOA_SP5-SOCKET6096_13568-001,SMLF,IO,DGA^6000030     I1 @T6G_MB_LIB.T6G(SCH_1):PAGE59
   U26 BN11 VSS_BN11 GENOA_SP5-SOCKET6096_13568-001,SMLF,IO,DGA^6000030     I1 @T6G_MB_LIB.T6G(SCH_1):PAGE59
   U26 BN13 VSS_BN13 GENOA_SP5-SOCKET6096_13568-001,SMLF,IO,DGA^6000030     I1 @T6G_MB_LIB.T6G(SCH_1):PAGE59
   U26 BN15 VSS_BN15 GENOA_SP5-SOCKET6096_13568-001,SMLF,IO,DGA^6000030     I1 @T6G_MB_LIB.T6G(SCH_1):PAGE59
   U26 BN18 VSS_BN18 GENOA_SP5-SOCKET6096_13568-001,SMLF,IO,DGA^6000030     I1 @T6G_MB_LIB.T6G(SCH_1):PAGE59
   U26 BN20 VSS_BN20 GENOA_SP5-SOCKET6096_13568-001,SMLF,IO,DGA^6000030     I1 @T6G_MB_LIB.T6G(SCH_1):PAGE59
   U26 BN22 VSS_BN22 GENOA_SP5-SOCKET6096_13568-001,SMLF,IO,DGA^6000030     I1 @T6G_MB_LIB.T6G(SCH_1):PAGE59
   U26 BN24 VSS_BN24 GENOA_SP5-SOCKET6096_13568-001,SMLF,IO,DGA^6000030     I1 @T6G_MB_LIB.T6G(SCH_1):PAGE59
   U26 BN26 VSS_BN26 GENOA_SP5-SOCKET6096_13568-001,SMLF,IO,DGA^6000030     I1 @T6G_MB_LIB.T6G(SCH_1):PAGE59
   U26 BN28 VSS_BN28 GENOA_SP5-SOCKET6096_13568-001,SMLF,IO,DGA^6000030     I1 @T6G_MB_LIB.T6G(SCH_1):PAGE59
   U26 BN30 VSS_BN30 GENOA_SP5-SOCKET6096_13568-001,SMLF,IO,DGA^6000030     I1 @T6G_MB_LIB.T6G(SCH_1):PAGE59
   U26 BN32 VSS_BN32 GENOA_SP5-SOCKET6096_13568-001,SMLF,IO,DGA^6000030     I1 @T6G_MB_LIB.T6G(SCH_1):PAGE59
   U26 BN34 VSS_BN34 GENOA_SP5-SOCKET6096_13568-001,SMLF,IO,DGA^6000030     I1 @T6G_MB_LIB.T6G(SCH_1):PAGE59
   U26 BN36 VSS_BN36 GENOA_SP5-SOCKET6096_13568-001,SMLF,IO,DGA^6000030     I1 @T6G_MB_LIB.T6G(SCH_1):PAGE59
   U26 BN41 VSS_BN41 GENOA_SP5-SOCKET6096_13568-001,SMLF,IO,DGA^6000030     I1 @T6G_MB_LIB.T6G(SCH_1):PAGE59
   U26 BN43 VSS_BN43 GENOA_SP5-SOCKET6096_13568-001,SMLF,IO,DGA^6000030     I1 @T6G_MB_LIB.T6G(SCH_1):PAGE59
   U26 BN45 VSS_BN45 GENOA_SP5-SOCKET6096_13568-001,SMLF,IO,DGA^6000030     I1 @T6G_MB_LIB.T6G(SCH_1):PAGE59
   U26 BN47 VSS_BN47 GENOA_SP5-SOCKET6096_13568-001,SMLF,IO,DGA^6000030     I1 @T6G_MB_LIB.T6G(SCH_1):PAGE59
   U26 BN49 VSS_BN49 GENOA_SP5-SOCKET6096_13568-001,SMLF,IO,DGA^6000030     I1 @T6G_MB_LIB.T6G(SCH_1):PAGE59
   U26 BN51 VSS_BN51 GENOA_SP5-SOCKET6096_13568-001,SMLF,IO,DGA^6000030     I1 @T6G_MB_LIB.T6G(SCH_1):PAGE59
   U26 BN53 VSS_BN53 GENOA_SP5-SOCKET6096_13568-001,SMLF,IO,DGA^6000030     I1 @T6G_MB_LIB.T6G(SCH_1):PAGE59
   U26 BN56 VSS_BN56 GENOA_SP5-SOCKET6096_13568-001,SMLF,IO,DGA^6000030     I1 @T6G_MB_LIB.T6G(SCH_1):PAGE59
   U26 BN58 VSS_BN58 GENOA_SP5-SOCKET6096_13568-001,SMLF,IO,DGA^6000030     I1 @T6G_MB_LIB.T6G(SCH_1):PAGE59
   U26 BN61 VSS_BN61 GENOA_SP5-SOCKET6096_13568-001,SMLF,IO,DGA^6000030     I1 @T6G_MB_LIB.T6G(SCH_1):PAGE59
   U26 BN63 VSS_BN63 GENOA_SP5-SOCKET6096_13568-001,SMLF,IO,DGA^6000030     I1 @T6G_MB_LIB.T6G(SCH_1):PAGE59
   U26 BN65 VSS_BN65 GENOA_SP5-SOCKET6096_13568-001,SMLF,IO,DGA^6000030     I1 @T6G_MB_LIB.T6G(SCH_1):PAGE59
   U26 BN68 VSS_BN68 GENOA_SP5-SOCKET6096_13568-001,SMLF,IO,DGA^6000030     I1 @T6G_MB_LIB.T6G(SCH_1):PAGE59
   U26 BN70 VSS_BN70 GENOA_SP5-SOCKET6096_13568-001,SMLF,IO,DGA^6000030     I1 @T6G_MB_LIB.T6G(SCH_1):PAGE59
   U26 BN72 VSS_BN72 GENOA_SP5-SOCKET6096_13568-001,SMLF,IO,DGA^6000030     I1 @T6G_MB_LIB.T6G(SCH_1):PAGE59
   U26 BN75 VSS_BN75 GENOA_SP5-SOCKET6096_13568-001,SMLF,IO,DGA^6000030     I1 @T6G_MB_LIB.T6G(SCH_1):PAGE59
   U26  BP3 VSS_BP3 GENOA_SP5-SOCKET6096_13568-001,SMLF,IO,DGA^6000030     I1 @T6G_MB_LIB.T6G(SCH_1):PAGE59
   U26  BP5 VSS_BP5 GENOA_SP5-SOCKET6096_13568-001,SMLF,IO,DGA^6000030     I1 @T6G_MB_LIB.T6G(SCH_1):PAGE59
   U26  BP8 VSS_BP8 GENOA_SP5-SOCKET6096_13568-001,SMLF,IO,DGA^6000030     I1 @T6G_MB_LIB.T6G(SCH_1):PAGE59
   U26 BP10 VSS_BP10 GENOA_SP5-SOCKET6096_13568-001,SMLF,IO,DGA^6000030     I1 @T6G_MB_LIB.T6G(SCH_1):PAGE59
   U26 BP12 VSS_BP12 GENOA_SP5-SOCKET6096_13568-001,SMLF,IO,DGA^6000030     I1 @T6G_MB_LIB.T6G(SCH_1):PAGE59
   U26 BP15 VSS_BP15 GENOA_SP5-SOCKET6096_13568-001,SMLF,IO,DGA^6000030     I1 @T6G_MB_LIB.T6G(SCH_1):PAGE59
   U26 BP17 VSS_BP17 GENOA_SP5-SOCKET6096_13568-001,SMLF,IO,DGA^6000030     I1 @T6G_MB_LIB.T6G(SCH_1):PAGE59
   U26 BP19 VSS_BP19 GENOA_SP5-SOCKET6096_13568-001,SMLF,IO,DGA^6000030     I1 @T6G_MB_LIB.T6G(SCH_1):PAGE59
   U26 BP23 VSS_BP23 GENOA_SP5-SOCKET6096_13568-001,SMLF,IO,DGA^6000030     I1 @T6G_MB_LIB.T6G(SCH_1):PAGE59
   U26 BP25 VSS_BP25 GENOA_SP5-SOCKET6096_13568-001,SMLF,IO,DGA^6000030     I1 @T6G_MB_LIB.T6G(SCH_1):PAGE59
   U26 BP27 VSS_BP27 GENOA_SP5-SOCKET6096_13568-001,SMLF,IO,DGA^6000030     I1 @T6G_MB_LIB.T6G(SCH_1):PAGE59
   U26 BP29 VSS_BP29 GENOA_SP5-SOCKET6096_13568-001,SMLF,IO,DGA^6000030     I1 @T6G_MB_LIB.T6G(SCH_1):PAGE59
   U26 BP31 VSS_BP31 GENOA_SP5-SOCKET6096_13568-001,SMLF,IO,DGA^6000030     I1 @T6G_MB_LIB.T6G(SCH_1):PAGE59
   U26 BP33 VSS_BP33 GENOA_SP5-SOCKET6096_13568-001,SMLF,IO,DGA^6000030     I1 @T6G_MB_LIB.T6G(SCH_1):PAGE59
   U26 BP35 VSS_BP35 GENOA_SP5-SOCKET6096_13568-001,SMLF,IO,DGA^6000030     I1 @T6G_MB_LIB.T6G(SCH_1):PAGE59
   U26 BP37 VSS_BP37 GENOA_SP5-SOCKET6096_13568-001,SMLF,IO,DGA^6000030     I1 @T6G_MB_LIB.T6G(SCH_1):PAGE59
   U26 BP40 VSS_BP40 GENOA_SP5-SOCKET6096_13568-001,SMLF,IO,DGA^6000030     I1 @T6G_MB_LIB.T6G(SCH_1):PAGE59
   U26 BP42 VSS_BP42 GENOA_SP5-SOCKET6096_13568-001,SMLF,IO,DGA^6000030     I1 @T6G_MB_LIB.T6G(SCH_1):PAGE59
   U26 BP44 VSS_BP44 GENOA_SP5-SOCKET6096_13568-001,SMLF,IO,DGA^6000030     I1 @T6G_MB_LIB.T6G(SCH_1):PAGE59
   U26 BP46 VSS_BP46 GENOA_SP5-SOCKET6096_13568-001,SMLF,IO,DGA^6000030     I1 @T6G_MB_LIB.T6G(SCH_1):PAGE59
   U26 BP48 VSS_BP48 GENOA_SP5-SOCKET6096_13568-001,SMLF,IO,DGA^6000030     I1 @T6G_MB_LIB.T6G(SCH_1):PAGE59
   U26 BP50 VSS_BP50 GENOA_SP5-SOCKET6096_13568-001,SMLF,IO,DGA^6000030     I1 @T6G_MB_LIB.T6G(SCH_1):PAGE59
   U26 BP52 VSS_BP52 GENOA_SP5-SOCKET6096_13568-001,SMLF,IO,DGA^6000030     I1 @T6G_MB_LIB.T6G(SCH_1):PAGE59
   U26 BP54 VSS_BP54 GENOA_SP5-SOCKET6096_13568-001,SMLF,IO,DGA^6000030     I1 @T6G_MB_LIB.T6G(SCH_1):PAGE59
   U26 BP57 VSS_BP57 GENOA_SP5-SOCKET6096_13568-001,SMLF,IO,DGA^6000030     I1 @T6G_MB_LIB.T6G(SCH_1):PAGE59
   U26 BP59 VSS_BP59 GENOA_SP5-SOCKET6096_13568-001,SMLF,IO,DGA^6000030     I1 @T6G_MB_LIB.T6G(SCH_1):PAGE59
   U26 BP61 VSS_BP61 GENOA_SP5-SOCKET6096_13568-001,SMLF,IO,DGA^6000030     I1 @T6G_MB_LIB.T6G(SCH_1):PAGE59
   U26 BP64 VSS_BP64 GENOA_SP5-SOCKET6096_13568-001,SMLF,IO,DGA^6000030     I1 @T6G_MB_LIB.T6G(SCH_1):PAGE59
   U26 BP66 VSS_BP66 GENOA_SP5-SOCKET6096_13568-001,SMLF,IO,DGA^6000030     I1 @T6G_MB_LIB.T6G(SCH_1):PAGE59
   U26 BP68 VSS_BP68 GENOA_SP5-SOCKET6096_13568-001,SMLF,IO,DGA^6000030     I1 @T6G_MB_LIB.T6G(SCH_1):PAGE59
   U26 BP71 VSS_BP71 GENOA_SP5-SOCKET6096_13568-001,SMLF,IO,DGA^6000030     I1 @T6G_MB_LIB.T6G(SCH_1):PAGE59
   U26 BP73 VSS_BP73 GENOA_SP5-SOCKET6096_13568-001,SMLF,IO,DGA^6000030     I1 @T6G_MB_LIB.T6G(SCH_1):PAGE59
   U26  BR1 VSS_BR1 GENOA_SP5-SOCKET6096_13568-001,SMLF,IO,DGA^6000030     I1 @T6G_MB_LIB.T6G(SCH_1):PAGE59
   U26  BR3 VSS_BR3 GENOA_SP5-SOCKET6096_13568-001,SMLF,IO,DGA^6000030     I1 @T6G_MB_LIB.T6G(SCH_1):PAGE59
   U26  BR6 VSS_BR6 GENOA_SP5-SOCKET6096_13568-001,SMLF,IO,DGA^6000030     I1 @T6G_MB_LIB.T6G(SCH_1):PAGE59
   U26  BR7 VSS_BR7 GENOA_SP5-SOCKET6096_13568-001,SMLF,IO,DGA^6000030     I1 @T6G_MB_LIB.T6G(SCH_1):PAGE59
   U26  BR8 VSS_BR8 GENOA_SP5-SOCKET6096_13568-001,SMLF,IO,DGA^6000030     I1 @T6G_MB_LIB.T6G(SCH_1):PAGE59
   U26 BR10 VSS_BR10 GENOA_SP5-SOCKET6096_13568-001,SMLF,IO,DGA^6000030     I1 @T6G_MB_LIB.T6G(SCH_1):PAGE59
   U26 BR13 VSS_BR13 GENOA_SP5-SOCKET6096_13568-001,SMLF,IO,DGA^6000030     I1 @T6G_MB_LIB.T6G(SCH_1):PAGE59
   U26 BR14 VSS_BR14 GENOA_SP5-SOCKET6096_13568-001,SMLF,IO,DGA^6000030     I1 @T6G_MB_LIB.T6G(SCH_1):PAGE59
   U26 BR15 VSS_BR15 GENOA_SP5-SOCKET6096_13568-001,SMLF,IO,DGA^6000030     I1 @T6G_MB_LIB.T6G(SCH_1):PAGE59
   U26 BR17 VSS_BR17 GENOA_SP5-SOCKET6096_13568-001,SMLF,IO,DGA^6000030     I1 @T6G_MB_LIB.T6G(SCH_1):PAGE59
   U26 BR20 VSS_BR20 GENOA_SP5-SOCKET6096_13568-001,SMLF,IO,DGA^6000030     I1 @T6G_MB_LIB.T6G(SCH_1):PAGE59
   U26 BR21 VSS_BR21 GENOA_SP5-SOCKET6096_13568-001,SMLF,IO,DGA^6000030     I1 @T6G_MB_LIB.T6G(SCH_1):PAGE59
   U26 BR22 VSS_BR22 GENOA_SP5-SOCKET6096_13568-001,SMLF,IO,DGA^6000030     I1 @T6G_MB_LIB.T6G(SCH_1):PAGE59
   U26 BR24 VSS_BR24 GENOA_SP5-SOCKET6096_13568-001,SMLF,IO,DGA^6000030     I1 @T6G_MB_LIB.T6G(SCH_1):PAGE59
   U26 BR26 VSS_BR26 GENOA_SP5-SOCKET6096_13568-001,SMLF,IO,DGA^6000030     I1 @T6G_MB_LIB.T6G(SCH_1):PAGE59
   U26 BR28 VSS_BR28 GENOA_SP5-SOCKET6096_13568-001,SMLF,IO,DGA^6000030     I1 @T6G_MB_LIB.T6G(SCH_1):PAGE59
   U26 BR30 VSS_BR30 GENOA_SP5-SOCKET6096_13568-001,SMLF,IO,DGA^6000030     I1 @T6G_MB_LIB.T6G(SCH_1):PAGE59
   U26 BR32 VSS_BR32 GENOA_SP5-SOCKET6096_13568-001,SMLF,IO,DGA^6000030     I1 @T6G_MB_LIB.T6G(SCH_1):PAGE59
   U26 BR34 VSS_BR34 GENOA_SP5-SOCKET6096_13568-001,SMLF,IO,DGA^6000030     I1 @T6G_MB_LIB.T6G(SCH_1):PAGE59
   U26 BR36 VSS_BR36 GENOA_SP5-SOCKET6096_13568-001,SMLF,IO,DGA^6000030     I1 @T6G_MB_LIB.T6G(SCH_1):PAGE59
   U26 BR41 VSS_BR41 GENOA_SP5-SOCKET6096_13568-001,SMLF,IO,DGA^6000030     I1 @T6G_MB_LIB.T6G(SCH_1):PAGE59
   U26 BR43 VSS_BR43 GENOA_SP5-SOCKET6096_13568-001,SMLF,IO,DGA^6000030     I1 @T6G_MB_LIB.T6G(SCH_1):PAGE59
   U26 BR45 VSS_BR45 GENOA_SP5-SOCKET6096_13568-001,SMLF,IO,DGA^6000030     I1 @T6G_MB_LIB.T6G(SCH_1):PAGE59
   U26 BR47 VSS_BR47 GENOA_SP5-SOCKET6096_13568-001,SMLF,IO,DGA^6000030     I1 @T6G_MB_LIB.T6G(SCH_1):PAGE59
   U26 BR49 VSS_BR49 GENOA_SP5-SOCKET6096_13568-001,SMLF,IO,DGA^6000030     I1 @T6G_MB_LIB.T6G(SCH_1):PAGE59
   U26 BR51 VSS_BR51 GENOA_SP5-SOCKET6096_13568-001,SMLF,IO,DGA^6000030     I1 @T6G_MB_LIB.T6G(SCH_1):PAGE59
   U26 BR55 VSS_BR55 GENOA_SP5-SOCKET6096_13568-001,SMLF,IO,DGA^6000030     I1 @T6G_MB_LIB.T6G(SCH_1):PAGE59
   U26 BR56 VSS_BR56 GENOA_SP5-SOCKET6096_13568-001,SMLF,IO,DGA^6000030     I1 @T6G_MB_LIB.T6G(SCH_1):PAGE59
   U26 BR59 VSS_BR59 GENOA_SP5-SOCKET6096_13568-001,SMLF,IO,DGA^6000030     I1 @T6G_MB_LIB.T6G(SCH_1):PAGE59
   U26 BR61 VSS_BR61 GENOA_SP5-SOCKET6096_13568-001,SMLF,IO,DGA^6000030     I1 @T6G_MB_LIB.T6G(SCH_1):PAGE59
   U26 BR62 VSS_BR62 GENOA_SP5-SOCKET6096_13568-001,SMLF,IO,DGA^6000030     I1 @T6G_MB_LIB.T6G(SCH_1):PAGE59
   U26 BR63 VSS_BR63 GENOA_SP5-SOCKET6096_13568-001,SMLF,IO,DGA^6000030     I1 @T6G_MB_LIB.T6G(SCH_1):PAGE59
   U26 BR66 VSS_BR66 GENOA_SP5-SOCKET6096_13568-001,SMLF,IO,DGA^6000030     I1 @T6G_MB_LIB.T6G(SCH_1):PAGE59
   U26 BR68 VSS_BR68 GENOA_SP5-SOCKET6096_13568-001,SMLF,IO,DGA^6000030     I1 @T6G_MB_LIB.T6G(SCH_1):PAGE59
   U26 BR69 VSS_BR69 GENOA_SP5-SOCKET6096_13568-001,SMLF,IO,DGA^6000030     I1 @T6G_MB_LIB.T6G(SCH_1):PAGE59
   U26 BR70 VSS_BR70 GENOA_SP5-SOCKET6096_13568-001,SMLF,IO,DGA^6000030     I1 @T6G_MB_LIB.T6G(SCH_1):PAGE59
   U26 BR73 VSS_BR73 GENOA_SP5-SOCKET6096_13568-001,SMLF,IO,DGA^6000030     I1 @T6G_MB_LIB.T6G(SCH_1):PAGE59
   U26 BR75 VSS_BR75 GENOA_SP5-SOCKET6096_13568-001,SMLF,IO,DGA^6000030     I1 @T6G_MB_LIB.T6G(SCH_1):PAGE59
   U26  BT3 VSS_BT3 GENOA_SP5-SOCKET6096_13568-001,SMLF,IO,DGA^6000030     I1 @T6G_MB_LIB.T6G(SCH_1):PAGE59
   U26  BT4 VSS_BT4 GENOA_SP5-SOCKET6096_13568-001,SMLF,IO,DGA^6000030     I1 @T6G_MB_LIB.T6G(SCH_1):PAGE59
   U26  BT5 VSS_BT5 GENOA_SP5-SOCKET6096_13568-001,SMLF,IO,DGA^6000030     I1 @T6G_MB_LIB.T6G(SCH_1):PAGE59
   U26  BT7 VSS_BT7 GENOA_SP5-SOCKET6096_13568-001,SMLF,IO,DGA^6000030     I1 @T6G_MB_LIB.T6G(SCH_1):PAGE59
   U26  BT8 VSS_BT8 GENOA_SP5-SOCKET6096_13568-001,SMLF,IO,DGA^6000030     I1 @T6G_MB_LIB.T6G(SCH_1):PAGE59
   U26 BT10 VSS_BT10 GENOA_SP5-SOCKET6096_13568-001,SMLF,IO,DGA^6000030     I1 @T6G_MB_LIB.T6G(SCH_1):PAGE59
   U26 BT11 VSS_BT11 GENOA_SP5-SOCKET6096_13568-001,SMLF,IO,DGA^6000030     I1 @T6G_MB_LIB.T6G(SCH_1):PAGE59
   U26 BT12 VSS_BT12 GENOA_SP5-SOCKET6096_13568-001,SMLF,IO,DGA^6000030     I1 @T6G_MB_LIB.T6G(SCH_1):PAGE59
   U26 BT14 VSS_BT14 GENOA_SP5-SOCKET6096_13568-001,SMLF,IO,DGA^6000030     I1 @T6G_MB_LIB.T6G(SCH_1):PAGE59
   U26 BT15 VSS_BT15 GENOA_SP5-SOCKET6096_13568-001,SMLF,IO,DGA^6000030     I1 @T6G_MB_LIB.T6G(SCH_1):PAGE59
   U26 BT17 VSS_BT17 GENOA_SP5-SOCKET6096_13568-001,SMLF,IO,DGA^6000030     I1 @T6G_MB_LIB.T6G(SCH_1):PAGE59
   U26 BT18 VSS_BT18 GENOA_SP5-SOCKET6096_13568-001,SMLF,IO,DGA^6000030     I1 @T6G_MB_LIB.T6G(SCH_1):PAGE59
   U26 BT19 VSS_BT19 GENOA_SP5-SOCKET6096_13568-001,SMLF,IO,DGA^6000030     I1 @T6G_MB_LIB.T6G(SCH_1):PAGE59
   U26 BT21 VSS_BT21 GENOA_SP5-SOCKET6096_13568-001,SMLF,IO,DGA^6000030     I1 @T6G_MB_LIB.T6G(SCH_1):PAGE59
   U26 BT22 VSS_BT22 GENOA_SP5-SOCKET6096_13568-001,SMLF,IO,DGA^6000030     I1 @T6G_MB_LIB.T6G(SCH_1):PAGE59
   U26 BT25 VSS_BT25 GENOA_SP5-SOCKET6096_13568-001,SMLF,IO,DGA^6000030     I1 @T6G_MB_LIB.T6G(SCH_1):PAGE59
   U26 BT28 VSS_BT28 GENOA_SP5-SOCKET6096_13568-001,SMLF,IO,DGA^6000030     I1 @T6G_MB_LIB.T6G(SCH_1):PAGE59
   U26 BT31 VSS_BT31 GENOA_SP5-SOCKET6096_13568-001,SMLF,IO,DGA^6000030     I1 @T6G_MB_LIB.T6G(SCH_1):PAGE59
   U26 BT34 VSS_BT34 GENOA_SP5-SOCKET6096_13568-001,SMLF,IO,DGA^6000030     I1 @T6G_MB_LIB.T6G(SCH_1):PAGE59
   U26 BT37 VSS_BT37 GENOA_SP5-SOCKET6096_13568-001,SMLF,IO,DGA^6000030     I1 @T6G_MB_LIB.T6G(SCH_1):PAGE59
   U26 BT39 VSS_BT39 GENOA_SP5-SOCKET6096_13568-001,SMLF,IO,DGA^6000030     I1 @T6G_MB_LIB.T6G(SCH_1):PAGE59
   U26 BT42 VSS_BT42 GENOA_SP5-SOCKET6096_13568-001,SMLF,IO,DGA^6000030     I1 @T6G_MB_LIB.T6G(SCH_1):PAGE59
   U26 BT45 VSS_BT45 GENOA_SP5-SOCKET6096_13568-001,SMLF,IO,DGA^6000030     I1 @T6G_MB_LIB.T6G(SCH_1):PAGE59
   U26 BT48 VSS_BT48 GENOA_SP5-SOCKET6096_13568-001,SMLF,IO,DGA^6000030     I1 @T6G_MB_LIB.T6G(SCH_1):PAGE59
   U26 BT51 VSS_BT51 GENOA_SP5-SOCKET6096_13568-001,SMLF,IO,DGA^6000030     I1 @T6G_MB_LIB.T6G(SCH_1):PAGE59
   U26 BT54 VSS_BT54 GENOA_SP5-SOCKET6096_13568-001,SMLF,IO,DGA^6000030     I1 @T6G_MB_LIB.T6G(SCH_1):PAGE59
   U26 BT55 VSS_BT55 GENOA_SP5-SOCKET6096_13568-001,SMLF,IO,DGA^6000030     I1 @T6G_MB_LIB.T6G(SCH_1):PAGE59
   U26 BT57 VSS_BT57 GENOA_SP5-SOCKET6096_13568-001,SMLF,IO,DGA^6000030     I1 @T6G_MB_LIB.T6G(SCH_1):PAGE59
   U26 BT58 VSS_BT58 GENOA_SP5-SOCKET6096_13568-001,SMLF,IO,DGA^6000030     I1 @T6G_MB_LIB.T6G(SCH_1):PAGE59
   U26 BT59 VSS_BT59 GENOA_SP5-SOCKET6096_13568-001,SMLF,IO,DGA^6000030     I1 @T6G_MB_LIB.T6G(SCH_1):PAGE59
   U26 BT61 VSS_BT61 GENOA_SP5-SOCKET6096_13568-001,SMLF,IO,DGA^6000030     I1 @T6G_MB_LIB.T6G(SCH_1):PAGE59
   U26 BT62 VSS_BT62 GENOA_SP5-SOCKET6096_13568-001,SMLF,IO,DGA^6000030     I1 @T6G_MB_LIB.T6G(SCH_1):PAGE59
   U26 BT64 VSS_BT64 GENOA_SP5-SOCKET6096_13568-001,SMLF,IO,DGA^6000030     I1 @T6G_MB_LIB.T6G(SCH_1):PAGE59
   U26 BT65 VSS_BT65 GENOA_SP5-SOCKET6096_13568-001,SMLF,IO,DGA^6000030     I1 @T6G_MB_LIB.T6G(SCH_1):PAGE59
   U26 BT66 VSS_BT66 GENOA_SP5-SOCKET6096_13568-001,SMLF,IO,DGA^6000030     I1 @T6G_MB_LIB.T6G(SCH_1):PAGE59
   U26 BT68 VSS_BT68 GENOA_SP5-SOCKET6096_13568-001,SMLF,IO,DGA^6000030     I1 @T6G_MB_LIB.T6G(SCH_1):PAGE59
   U26 BT69 VSS_BT69 GENOA_SP5-SOCKET6096_13568-001,SMLF,IO,DGA^6000030     I1 @T6G_MB_LIB.T6G(SCH_1):PAGE59
   U26 BT71 VSS_BT71 GENOA_SP5-SOCKET6096_13568-001,SMLF,IO,DGA^6000030     I1 @T6G_MB_LIB.T6G(SCH_1):PAGE59
   U26 BT72 VSS_BT72 GENOA_SP5-SOCKET6096_13568-001,SMLF,IO,DGA^6000030     I1 @T6G_MB_LIB.T6G(SCH_1):PAGE59
   U26 BT73 VSS_BT73 GENOA_SP5-SOCKET6096_13568-001,SMLF,IO,DGA^6000030     I1 @T6G_MB_LIB.T6G(SCH_1):PAGE59
   U26  BU1 VSS_BU1 GENOA_SP5-SOCKET6096_13568-001,SMLF,IO,DGA^6000030     I1 @T6G_MB_LIB.T6G(SCH_1):PAGE59
   U26  BU4 VSS_BU4 GENOA_SP5-SOCKET6096_13568-001,SMLF,IO,DGA^6000030     I1 @T6G_MB_LIB.T6G(SCH_1):PAGE59
   U26  BU6 VSS_BU6 GENOA_SP5-SOCKET6096_13568-001,SMLF,IO,DGA^6000030     I1 @T6G_MB_LIB.T6G(SCH_1):PAGE59
   U26  BU8 VSS_BU8 GENOA_SP5-SOCKET6096_13568-001,SMLF,IO,DGA^6000030     I1 @T6G_MB_LIB.T6G(SCH_1):PAGE59
   U26 BU11 VSS_BU11 GENOA_SP5-SOCKET6096_13568-001,SMLF,IO,DGA^6000030     I1 @T6G_MB_LIB.T6G(SCH_1):PAGE59
   U26 BU13 VSS_BU13 GENOA_SP5-SOCKET6096_13568-001,SMLF,IO,DGA^6000030     I1 @T6G_MB_LIB.T6G(SCH_1):PAGE59
   U26 BU15 VSS_BU15 GENOA_SP5-SOCKET6096_13568-001,SMLF,IO,DGA^6000030     I1 @T6G_MB_LIB.T6G(SCH_1):PAGE59
   U26 BU18 VSS_BU18 GENOA_SP5-SOCKET6096_13568-001,SMLF,IO,DGA^6000030     I1 @T6G_MB_LIB.T6G(SCH_1):PAGE59
   U26 BU20 VSS_BU20 GENOA_SP5-SOCKET6096_13568-001,SMLF,IO,DGA^6000030     I1 @T6G_MB_LIB.T6G(SCH_1):PAGE59
   U26 BU22 VSS_BU22 GENOA_SP5-SOCKET6096_13568-001,SMLF,IO,DGA^6000030     I1 @T6G_MB_LIB.T6G(SCH_1):PAGE59
   U26 BU25 VSS_BU25 GENOA_SP5-SOCKET6096_13568-001,SMLF,IO,DGA^6000030     I1 @T6G_MB_LIB.T6G(SCH_1):PAGE59
   U26 BU28 VSS_BU28 GENOA_SP5-SOCKET6096_13568-001,SMLF,IO,DGA^6000030     I1 @T6G_MB_LIB.T6G(SCH_1):PAGE59
   U26 BU31 VSS_BU31 GENOA_SP5-SOCKET6096_13568-001,SMLF,IO,DGA^6000030     I1 @T6G_MB_LIB.T6G(SCH_1):PAGE59
   U26 BU34 VSS_BU34 GENOA_SP5-SOCKET6096_13568-001,SMLF,IO,DGA^6000030     I1 @T6G_MB_LIB.T6G(SCH_1):PAGE59
   U26 BU35 VSS_BU35 GENOA_SP5-SOCKET6096_13568-001,SMLF,IO,DGA^6000030     I1 @T6G_MB_LIB.T6G(SCH_1):PAGE59
   U26 BU36 VSS_BU36 GENOA_SP5-SOCKET6096_13568-001,SMLF,IO,DGA^6000030     I1 @T6G_MB_LIB.T6G(SCH_1):PAGE59
   U26 BU40 VSS_BU40 GENOA_SP5-SOCKET6096_13568-001,SMLF,IO,DGA^6000030     I1 @T6G_MB_LIB.T6G(SCH_1):PAGE59
   U26 BU41 VSS_BU41 GENOA_SP5-SOCKET6096_13568-001,SMLF,IO,DGA^6000030     I1 @T6G_MB_LIB.T6G(SCH_1):PAGE59
   U26 BU42 VSS_BU42 GENOA_SP5-SOCKET6096_13568-001,SMLF,IO,DGA^6000030     I1 @T6G_MB_LIB.T6G(SCH_1):PAGE59
   U26 BU45 VSS_BU45 GENOA_SP5-SOCKET6096_13568-001,SMLF,IO,DGA^6000030     I1 @T6G_MB_LIB.T6G(SCH_1):PAGE59
   U26 BU48 VSS_BU48 GENOA_SP5-SOCKET6096_13568-001,SMLF,IO,DGA^6000030     I1 @T6G_MB_LIB.T6G(SCH_1):PAGE59
   U26 BU51 VSS_BU51 GENOA_SP5-SOCKET6096_13568-001,SMLF,IO,DGA^6000030     I1 @T6G_MB_LIB.T6G(SCH_1):PAGE59
   U26 BU54 VSS_BU54 GENOA_SP5-SOCKET6096_13568-001,SMLF,IO,DGA^6000030     I1 @T6G_MB_LIB.T6G(SCH_1):PAGE59
   U26 BU56 VSS_BU56 GENOA_SP5-SOCKET6096_13568-001,SMLF,IO,DGA^6000030     I1 @T6G_MB_LIB.T6G(SCH_1):PAGE59
   U26 BU58 VSS_BU58 GENOA_SP5-SOCKET6096_13568-001,SMLF,IO,DGA^6000030     I1 @T6G_MB_LIB.T6G(SCH_1):PAGE59
   U26 BU61 VSS_BU61 GENOA_SP5-SOCKET6096_13568-001,SMLF,IO,DGA^6000030     I1 @T6G_MB_LIB.T6G(SCH_1):PAGE59
   U26 BU63 VSS_BU63 GENOA_SP5-SOCKET6096_13568-001,SMLF,IO,DGA^6000030     I1 @T6G_MB_LIB.T6G(SCH_1):PAGE59
   U26 BU65 VSS_BU65 GENOA_SP5-SOCKET6096_13568-001,SMLF,IO,DGA^6000030     I1 @T6G_MB_LIB.T6G(SCH_1):PAGE59
   U26 BU68 VSS_BU68 GENOA_SP5-SOCKET6096_13568-001,SMLF,IO,DGA^6000030     I1 @T6G_MB_LIB.T6G(SCH_1):PAGE59
   U26 BU70 VSS_BU70 GENOA_SP5-SOCKET6096_13568-001,SMLF,IO,DGA^6000030     I1 @T6G_MB_LIB.T6G(SCH_1):PAGE59
   U26 BU72 VSS_BU72 GENOA_SP5-SOCKET6096_13568-001,SMLF,IO,DGA^6000030     I1 @T6G_MB_LIB.T6G(SCH_1):PAGE59
   U26 BU75 VSS_BU75 GENOA_SP5-SOCKET6096_13568-001,SMLF,IO,DGA^6000030     I1 @T6G_MB_LIB.T6G(SCH_1):PAGE59
   U26  BV3 VSS_BV3 GENOA_SP5-SOCKET6096_13568-001,SMLF,IO,DGA^6000030     I1 @T6G_MB_LIB.T6G(SCH_1):PAGE59
   U26  BV8 VSS_BV8 GENOA_SP5-SOCKET6096_13568-001,SMLF,IO,DGA^6000030     I1 @T6G_MB_LIB.T6G(SCH_1):PAGE59
   U26 BV10 VSS_BV10 GENOA_SP5-SOCKET6096_13568-001,SMLF,IO,DGA^6000030     I1 @T6G_MB_LIB.T6G(SCH_1):PAGE59
   U26 BV15 VSS_BV15 GENOA_SP5-SOCKET6096_13568-001,SMLF,IO,DGA^6000030     I1 @T6G_MB_LIB.T6G(SCH_1):PAGE59
   U26 BV17 VSS_BV17 GENOA_SP5-SOCKET6096_13568-001,SMLF,IO,DGA^6000030     I1 @T6G_MB_LIB.T6G(SCH_1):PAGE59
   U26 BV23 VSS_BV23 GENOA_SP5-SOCKET6096_13568-001,SMLF,IO,DGA^6000030     I1 @T6G_MB_LIB.T6G(SCH_1):PAGE59
   U26 BV24 VSS_BV24 GENOA_SP5-SOCKET6096_13568-001,SMLF,IO,DGA^6000030     I1 @T6G_MB_LIB.T6G(SCH_1):PAGE59
   U26 BV25 VSS_BV25 GENOA_SP5-SOCKET6096_13568-001,SMLF,IO,DGA^6000030     I1 @T6G_MB_LIB.T6G(SCH_1):PAGE59
   U26 BV26 VSS_BV26 GENOA_SP5-SOCKET6096_13568-001,SMLF,IO,DGA^6000030     I1 @T6G_MB_LIB.T6G(SCH_1):PAGE59
   U26 BV27 VSS_BV27 GENOA_SP5-SOCKET6096_13568-001,SMLF,IO,DGA^6000030     I1 @T6G_MB_LIB.T6G(SCH_1):PAGE59
   U26 BV28 VSS_BV28 GENOA_SP5-SOCKET6096_13568-001,SMLF,IO,DGA^6000030     I1 @T6G_MB_LIB.T6G(SCH_1):PAGE59
   U26 BV29 VSS_BV29 GENOA_SP5-SOCKET6096_13568-001,SMLF,IO,DGA^6000030     I1 @T6G_MB_LIB.T6G(SCH_1):PAGE59
   U26 BV30 VSS_BV30 GENOA_SP5-SOCKET6096_13568-001,SMLF,IO,DGA^6000030     I1 @T6G_MB_LIB.T6G(SCH_1):PAGE59
   U26 BV31 VSS_BV31 GENOA_SP5-SOCKET6096_13568-001,SMLF,IO,DGA^6000030     I1 @T6G_MB_LIB.T6G(SCH_1):PAGE59
   U26 BV32 VSS_BV32 GENOA_SP5-SOCKET6096_13568-001,SMLF,IO,DGA^6000030     I1 @T6G_MB_LIB.T6G(SCH_1):PAGE59
   U26 BV33 VSS_BV33 GENOA_SP5-SOCKET6096_13568-001,SMLF,IO,DGA^6000030     I1 @T6G_MB_LIB.T6G(SCH_1):PAGE59
   U26 BV34 VSS_BV34 GENOA_SP5-SOCKET6096_13568-001,SMLF,IO,DGA^6000030     I1 @T6G_MB_LIB.T6G(SCH_1):PAGE59
   U26 BV37 VSS_BV37 GENOA_SP5-SOCKET6096_13568-001,SMLF,IO,DGA^6000030     I1 @T6G_MB_LIB.T6G(SCH_1):PAGE59
   U26 BV39 VSS_BV39 GENOA_SP5-SOCKET6096_13568-001,SMLF,IO,DGA^6000030     I1 @T6G_MB_LIB.T6G(SCH_1):PAGE59
   U26 BV43 VSS_BV43 GENOA_SP5-SOCKET6096_13568-001,SMLF,IO,DGA^6000030     I1 @T6G_MB_LIB.T6G(SCH_1):PAGE59
   U26 BV44 VSS_BV44 GENOA_SP5-SOCKET6096_13568-001,SMLF,IO,DGA^6000030     I1 @T6G_MB_LIB.T6G(SCH_1):PAGE59
   U26 BV45 VSS_BV45 GENOA_SP5-SOCKET6096_13568-001,SMLF,IO,DGA^6000030     I1 @T6G_MB_LIB.T6G(SCH_1):PAGE59
   U26 BV46 VSS_BV46 GENOA_SP5-SOCKET6096_13568-001,SMLF,IO,DGA^6000030     I2 @T6G_MB_LIB.T6G(SCH_1):PAGE59
   U26 BV47 VSS_BV47 GENOA_SP5-SOCKET6096_13568-001,SMLF,IO,DGA^6000030     I2 @T6G_MB_LIB.T6G(SCH_1):PAGE59
   U26 BV48 VSS_BV48 GENOA_SP5-SOCKET6096_13568-001,SMLF,IO,DGA^6000030     I2 @T6G_MB_LIB.T6G(SCH_1):PAGE59
   U26 BV49 VSS_BV49 GENOA_SP5-SOCKET6096_13568-001,SMLF,IO,DGA^6000030     I2 @T6G_MB_LIB.T6G(SCH_1):PAGE59
   U26 BV50 VSS_BV50 GENOA_SP5-SOCKET6096_13568-001,SMLF,IO,DGA^6000030     I2 @T6G_MB_LIB.T6G(SCH_1):PAGE59
   U26 BV51 VSS_BV51 GENOA_SP5-SOCKET6096_13568-001,SMLF,IO,DGA^6000030     I2 @T6G_MB_LIB.T6G(SCH_1):PAGE59
   U26 BV52 VSS_BV52 GENOA_SP5-SOCKET6096_13568-001,SMLF,IO,DGA^6000030     I2 @T6G_MB_LIB.T6G(SCH_1):PAGE59
   U26 BV53 VSS_BV53 GENOA_SP5-SOCKET6096_13568-001,SMLF,IO,DGA^6000030     I2 @T6G_MB_LIB.T6G(SCH_1):PAGE59
   U26 BV59 VSS_BV59 GENOA_SP5-SOCKET6096_13568-001,SMLF,IO,DGA^6000030     I2 @T6G_MB_LIB.T6G(SCH_1):PAGE59
   U26 BV61 VSS_BV61 GENOA_SP5-SOCKET6096_13568-001,SMLF,IO,DGA^6000030     I2 @T6G_MB_LIB.T6G(SCH_1):PAGE59
   U26 BV66 VSS_BV66 GENOA_SP5-SOCKET6096_13568-001,SMLF,IO,DGA^6000030     I2 @T6G_MB_LIB.T6G(SCH_1):PAGE59
   U26 BV68 VSS_BV68 GENOA_SP5-SOCKET6096_13568-001,SMLF,IO,DGA^6000030     I2 @T6G_MB_LIB.T6G(SCH_1):PAGE59
   U26 BV73 VSS_BV73 GENOA_SP5-SOCKET6096_13568-001,SMLF,IO,DGA^6000030     I2 @T6G_MB_LIB.T6G(SCH_1):PAGE59
   U26  BW1 VSS_BW1 GENOA_SP5-SOCKET6096_13568-001,SMLF,IO,DGA^6000030     I2 @T6G_MB_LIB.T6G(SCH_1):PAGE59
   U26  BW4 VSS_BW4 GENOA_SP5-SOCKET6096_13568-001,SMLF,IO,DGA^6000030     I2 @T6G_MB_LIB.T6G(SCH_1):PAGE59
   U26  BW6 VSS_BW6 GENOA_SP5-SOCKET6096_13568-001,SMLF,IO,DGA^6000030     I2 @T6G_MB_LIB.T6G(SCH_1):PAGE59
   U26  BW8 VSS_BW8 GENOA_SP5-SOCKET6096_13568-001,SMLF,IO,DGA^6000030     I2 @T6G_MB_LIB.T6G(SCH_1):PAGE59
   U26 BW11 VSS_BW11 GENOA_SP5-SOCKET6096_13568-001,SMLF,IO,DGA^6000030     I2 @T6G_MB_LIB.T6G(SCH_1):PAGE59
   U26 BW13 VSS_BW13 GENOA_SP5-SOCKET6096_13568-001,SMLF,IO,DGA^6000030     I2 @T6G_MB_LIB.T6G(SCH_1):PAGE59
   U26 BW15 VSS_BW15 GENOA_SP5-SOCKET6096_13568-001,SMLF,IO,DGA^6000030     I2 @T6G_MB_LIB.T6G(SCH_1):PAGE59
   U26 BW18 VSS_BW18 GENOA_SP5-SOCKET6096_13568-001,SMLF,IO,DGA^6000030     I2 @T6G_MB_LIB.T6G(SCH_1):PAGE59
   U26 BW20 VSS_BW20 GENOA_SP5-SOCKET6096_13568-001,SMLF,IO,DGA^6000030     I2 @T6G_MB_LIB.T6G(SCH_1):PAGE59
   U26 BW22 VSS_BW22 GENOA_SP5-SOCKET6096_13568-001,SMLF,IO,DGA^6000030     I2 @T6G_MB_LIB.T6G(SCH_1):PAGE59
   U26 BW28 VSS_BW28 GENOA_SP5-SOCKET6096_13568-001,SMLF,IO,DGA^6000030     I2 @T6G_MB_LIB.T6G(SCH_1):PAGE59
   U26 BW31 VSS_BW31 GENOA_SP5-SOCKET6096_13568-001,SMLF,IO,DGA^6000030     I2 @T6G_MB_LIB.T6G(SCH_1):PAGE59
   U26 BW34 VSS_BW34 GENOA_SP5-SOCKET6096_13568-001,SMLF,IO,DGA^6000030     I2 @T6G_MB_LIB.T6G(SCH_1):PAGE59
   U26 BW42 VSS_BW42 GENOA_SP5-SOCKET6096_13568-001,SMLF,IO,DGA^6000030     I2 @T6G_MB_LIB.T6G(SCH_1):PAGE59
   U26 BW45 VSS_BW45 GENOA_SP5-SOCKET6096_13568-001,SMLF,IO,DGA^6000030     I2 @T6G_MB_LIB.T6G(SCH_1):PAGE59
   U26 BW48 VSS_BW48 GENOA_SP5-SOCKET6096_13568-001,SMLF,IO,DGA^6000030     I2 @T6G_MB_LIB.T6G(SCH_1):PAGE59
   U26 BW51 VSS_BW51 GENOA_SP5-SOCKET6096_13568-001,SMLF,IO,DGA^6000030     I2 @T6G_MB_LIB.T6G(SCH_1):PAGE59
   U26 BW54 VSS_BW54 GENOA_SP5-SOCKET6096_13568-001,SMLF,IO,DGA^6000030     I2 @T6G_MB_LIB.T6G(SCH_1):PAGE59
   U26 BW56 VSS_BW56 GENOA_SP5-SOCKET6096_13568-001,SMLF,IO,DGA^6000030     I2 @T6G_MB_LIB.T6G(SCH_1):PAGE59
   U26 BW58 VSS_BW58 GENOA_SP5-SOCKET6096_13568-001,SMLF,IO,DGA^6000030     I2 @T6G_MB_LIB.T6G(SCH_1):PAGE59
   U26 BW61 VSS_BW61 GENOA_SP5-SOCKET6096_13568-001,SMLF,IO,DGA^6000030     I2 @T6G_MB_LIB.T6G(SCH_1):PAGE59
   U26 BW63 VSS_BW63 GENOA_SP5-SOCKET6096_13568-001,SMLF,IO,DGA^6000030     I2 @T6G_MB_LIB.T6G(SCH_1):PAGE59
   U26 BW65 VSS_BW65 GENOA_SP5-SOCKET6096_13568-001,SMLF,IO,DGA^6000030     I2 @T6G_MB_LIB.T6G(SCH_1):PAGE59
   U26 BW68 VSS_BW68 GENOA_SP5-SOCKET6096_13568-001,SMLF,IO,DGA^6000030     I2 @T6G_MB_LIB.T6G(SCH_1):PAGE59
   U26 BW70 VSS_BW70 GENOA_SP5-SOCKET6096_13568-001,SMLF,IO,DGA^6000030     I2 @T6G_MB_LIB.T6G(SCH_1):PAGE59
   U26 BW72 VSS_BW72 GENOA_SP5-SOCKET6096_13568-001,SMLF,IO,DGA^6000030     I2 @T6G_MB_LIB.T6G(SCH_1):PAGE59
   U26 BW75 VSS_BW75 GENOA_SP5-SOCKET6096_13568-001,SMLF,IO,DGA^6000030     I2 @T6G_MB_LIB.T6G(SCH_1):PAGE59
   U26  BY3 VSS_BY3 GENOA_SP5-SOCKET6096_13568-001,SMLF,IO,DGA^6000030     I2 @T6G_MB_LIB.T6G(SCH_1):PAGE59
   U26  BY5 VSS_BY5 GENOA_SP5-SOCKET6096_13568-001,SMLF,IO,DGA^6000030     I2 @T6G_MB_LIB.T6G(SCH_1):PAGE59
   U26  BY8 VSS_BY8 GENOA_SP5-SOCKET6096_13568-001,SMLF,IO,DGA^6000030     I2 @T6G_MB_LIB.T6G(SCH_1):PAGE59
   U26 BY10 VSS_BY10 GENOA_SP5-SOCKET6096_13568-001,SMLF,IO,DGA^6000030     I2 @T6G_MB_LIB.T6G(SCH_1):PAGE59
   U26 BY12 VSS_BY12 GENOA_SP5-SOCKET6096_13568-001,SMLF,IO,DGA^6000030     I2 @T6G_MB_LIB.T6G(SCH_1):PAGE59
   U26 BY15 VSS_BY15 GENOA_SP5-SOCKET6096_13568-001,SMLF,IO,DGA^6000030     I2 @T6G_MB_LIB.T6G(SCH_1):PAGE59
   U26 BY17 VSS_BY17 GENOA_SP5-SOCKET6096_13568-001,SMLF,IO,DGA^6000030     I2 @T6G_MB_LIB.T6G(SCH_1):PAGE59
   U26 BY19 VSS_BY19 GENOA_SP5-SOCKET6096_13568-001,SMLF,IO,DGA^6000030     I2 @T6G_MB_LIB.T6G(SCH_1):PAGE59
   U26 BY22 VSS_BY22 GENOA_SP5-SOCKET6096_13568-001,SMLF,IO,DGA^6000030     I2 @T6G_MB_LIB.T6G(SCH_1):PAGE59
   U26 BY25 VSS_BY25 GENOA_SP5-SOCKET6096_13568-001,SMLF,IO,DGA^6000030     I2 @T6G_MB_LIB.T6G(SCH_1):PAGE59
   U26 BY28 VSS_BY28 GENOA_SP5-SOCKET6096_13568-001,SMLF,IO,DGA^6000030     I2 @T6G_MB_LIB.T6G(SCH_1):PAGE59
   U26 BY31 VSS_BY31 GENOA_SP5-SOCKET6096_13568-001,SMLF,IO,DGA^6000030     I2 @T6G_MB_LIB.T6G(SCH_1):PAGE59
   U26 BY34 VSS_BY34 GENOA_SP5-SOCKET6096_13568-001,SMLF,IO,DGA^6000030     I2 @T6G_MB_LIB.T6G(SCH_1):PAGE59
   U26 BY37 VSS_BY37 GENOA_SP5-SOCKET6096_13568-001,SMLF,IO,DGA^6000030     I2 @T6G_MB_LIB.T6G(SCH_1):PAGE59
   U26 BY39 VSS_BY39 GENOA_SP5-SOCKET6096_13568-001,SMLF,IO,DGA^6000030     I2 @T6G_MB_LIB.T6G(SCH_1):PAGE59
   U26 BY42 VSS_BY42 GENOA_SP5-SOCKET6096_13568-001,SMLF,IO,DGA^6000030     I2 @T6G_MB_LIB.T6G(SCH_1):PAGE59
   U26 BY45 VSS_BY45 GENOA_SP5-SOCKET6096_13568-001,SMLF,IO,DGA^6000030     I2 @T6G_MB_LIB.T6G(SCH_1):PAGE59
   U26 BY48 VSS_BY48 GENOA_SP5-SOCKET6096_13568-001,SMLF,IO,DGA^6000030     I2 @T6G_MB_LIB.T6G(SCH_1):PAGE59
   U26 BY51 VSS_BY51 GENOA_SP5-SOCKET6096_13568-001,SMLF,IO,DGA^6000030     I2 @T6G_MB_LIB.T6G(SCH_1):PAGE59
   U26 BY54 VSS_BY54 GENOA_SP5-SOCKET6096_13568-001,SMLF,IO,DGA^6000030     I2 @T6G_MB_LIB.T6G(SCH_1):PAGE59
   U26 BY57 VSS_BY57 GENOA_SP5-SOCKET6096_13568-001,SMLF,IO,DGA^6000030     I2 @T6G_MB_LIB.T6G(SCH_1):PAGE59
   U26 BY59 VSS_BY59 GENOA_SP5-SOCKET6096_13568-001,SMLF,IO,DGA^6000030     I2 @T6G_MB_LIB.T6G(SCH_1):PAGE59
   U26 BY61 VSS_BY61 GENOA_SP5-SOCKET6096_13568-001,SMLF,IO,DGA^6000030     I2 @T6G_MB_LIB.T6G(SCH_1):PAGE59
   U26 BY64 VSS_BY64 GENOA_SP5-SOCKET6096_13568-001,SMLF,IO,DGA^6000030     I2 @T6G_MB_LIB.T6G(SCH_1):PAGE59
   U26 BY66 VSS_BY66 GENOA_SP5-SOCKET6096_13568-001,SMLF,IO,DGA^6000030     I2 @T6G_MB_LIB.T6G(SCH_1):PAGE59
   U26 BY68 VSS_BY68 GENOA_SP5-SOCKET6096_13568-001,SMLF,IO,DGA^6000030     I2 @T6G_MB_LIB.T6G(SCH_1):PAGE59
   U26 BY71 VSS_BY71 GENOA_SP5-SOCKET6096_13568-001,SMLF,IO,DGA^6000030     I2 @T6G_MB_LIB.T6G(SCH_1):PAGE59
   U26 BY73 VSS_BY73 GENOA_SP5-SOCKET6096_13568-001,SMLF,IO,DGA^6000030     I2 @T6G_MB_LIB.T6G(SCH_1):PAGE59
   U26  CA1 VSS_CA1 GENOA_SP5-SOCKET6096_13568-001,SMLF,IO,DGA^6000030     I2 @T6G_MB_LIB.T6G(SCH_1):PAGE59
   U26  CA6 VSS_CA6 GENOA_SP5-SOCKET6096_13568-001,SMLF,IO,DGA^6000030     I2 @T6G_MB_LIB.T6G(SCH_1):PAGE59
   U26  CA8 VSS_CA8 GENOA_SP5-SOCKET6096_13568-001,SMLF,IO,DGA^6000030     I2 @T6G_MB_LIB.T6G(SCH_1):PAGE59
   U26 CA13 VSS_CA13 GENOA_SP5-SOCKET6096_13568-001,SMLF,IO,DGA^6000030     I2 @T6G_MB_LIB.T6G(SCH_1):PAGE59
   U26 CA15 VSS_CA15 GENOA_SP5-SOCKET6096_13568-001,SMLF,IO,DGA^6000030     I2 @T6G_MB_LIB.T6G(SCH_1):PAGE59
   U26 CA20 VSS_CA20 GENOA_SP5-SOCKET6096_13568-001,SMLF,IO,DGA^6000030     I2 @T6G_MB_LIB.T6G(SCH_1):PAGE59
   U26 CA22 VSS_CA22 GENOA_SP5-SOCKET6096_13568-001,SMLF,IO,DGA^6000030     I2 @T6G_MB_LIB.T6G(SCH_1):PAGE59
   U26 CA25 VSS_CA25 GENOA_SP5-SOCKET6096_13568-001,SMLF,IO,DGA^6000030     I2 @T6G_MB_LIB.T6G(SCH_1):PAGE59
   U26 CA28 VSS_CA28 GENOA_SP5-SOCKET6096_13568-001,SMLF,IO,DGA^6000030     I2 @T6G_MB_LIB.T6G(SCH_1):PAGE59
   U26 CA31 VSS_CA31 GENOA_SP5-SOCKET6096_13568-001,SMLF,IO,DGA^6000030     I2 @T6G_MB_LIB.T6G(SCH_1):PAGE59
   U26 CA34 VSS_CA34 GENOA_SP5-SOCKET6096_13568-001,SMLF,IO,DGA^6000030     I2 @T6G_MB_LIB.T6G(SCH_1):PAGE59
   U26 CA35 VSS_CA35 GENOA_SP5-SOCKET6096_13568-001,SMLF,IO,DGA^6000030     I2 @T6G_MB_LIB.T6G(SCH_1):PAGE59
   U26 CA36 VSS_CA36 GENOA_SP5-SOCKET6096_13568-001,SMLF,IO,DGA^6000030     I2 @T6G_MB_LIB.T6G(SCH_1):PAGE59
   U26 CA40 VSS_CA40 GENOA_SP5-SOCKET6096_13568-001,SMLF,IO,DGA^6000030     I2 @T6G_MB_LIB.T6G(SCH_1):PAGE59
   U26 CA41 VSS_CA41 GENOA_SP5-SOCKET6096_13568-001,SMLF,IO,DGA^6000030     I2 @T6G_MB_LIB.T6G(SCH_1):PAGE59
   U26 CA42 VSS_CA42 GENOA_SP5-SOCKET6096_13568-001,SMLF,IO,DGA^6000030     I2 @T6G_MB_LIB.T6G(SCH_1):PAGE59
   U26 CA45 VSS_CA45 GENOA_SP5-SOCKET6096_13568-001,SMLF,IO,DGA^6000030     I2 @T6G_MB_LIB.T6G(SCH_1):PAGE59
   U26 CA48 VSS_CA48 GENOA_SP5-SOCKET6096_13568-001,SMLF,IO,DGA^6000030     I2 @T6G_MB_LIB.T6G(SCH_1):PAGE59
   U26 CA51 VSS_CA51 GENOA_SP5-SOCKET6096_13568-001,SMLF,IO,DGA^6000030     I2 @T6G_MB_LIB.T6G(SCH_1):PAGE59
   U26 CA54 VSS_CA54 GENOA_SP5-SOCKET6096_13568-001,SMLF,IO,DGA^6000030     I2 @T6G_MB_LIB.T6G(SCH_1):PAGE59
   U26 CA56 VSS_CA56 GENOA_SP5-SOCKET6096_13568-001,SMLF,IO,DGA^6000030     I2 @T6G_MB_LIB.T6G(SCH_1):PAGE59
   U26 CA61 VSS_CA61 GENOA_SP5-SOCKET6096_13568-001,SMLF,IO,DGA^6000030     I2 @T6G_MB_LIB.T6G(SCH_1):PAGE59
   U26 CA63 VSS_CA63 GENOA_SP5-SOCKET6096_13568-001,SMLF,IO,DGA^6000030     I2 @T6G_MB_LIB.T6G(SCH_1):PAGE59
   U26 CA68 VSS_CA68 GENOA_SP5-SOCKET6096_13568-001,SMLF,IO,DGA^6000030     I2 @T6G_MB_LIB.T6G(SCH_1):PAGE59
   U26 CA70 VSS_CA70 GENOA_SP5-SOCKET6096_13568-001,SMLF,IO,DGA^6000030     I2 @T6G_MB_LIB.T6G(SCH_1):PAGE59
   U26 CA75 VSS_CA75 GENOA_SP5-SOCKET6096_13568-001,SMLF,IO,DGA^6000030     I2 @T6G_MB_LIB.T6G(SCH_1):PAGE59
   U26  CB3 VSS_CB3 GENOA_SP5-SOCKET6096_13568-001,SMLF,IO,DGA^6000030     I2 @T6G_MB_LIB.T6G(SCH_1):PAGE59
   U26  CB5 VSS_CB5 GENOA_SP5-SOCKET6096_13568-001,SMLF,IO,DGA^6000030     I2 @T6G_MB_LIB.T6G(SCH_1):PAGE59
   U26  CB8 VSS_CB8 GENOA_SP5-SOCKET6096_13568-001,SMLF,IO,DGA^6000030     I2 @T6G_MB_LIB.T6G(SCH_1):PAGE59
   U26 CB10 VSS_CB10 GENOA_SP5-SOCKET6096_13568-001,SMLF,IO,DGA^6000030     I2 @T6G_MB_LIB.T6G(SCH_1):PAGE59
   U26 CB12 VSS_CB12 GENOA_SP5-SOCKET6096_13568-001,SMLF,IO,DGA^6000030     I2 @T6G_MB_LIB.T6G(SCH_1):PAGE59
   U26 CB15 VSS_CB15 GENOA_SP5-SOCKET6096_13568-001,SMLF,IO,DGA^6000030     I2 @T6G_MB_LIB.T6G(SCH_1):PAGE59
   U26 CB17 VSS_CB17 GENOA_SP5-SOCKET6096_13568-001,SMLF,IO,DGA^6000030     I2 @T6G_MB_LIB.T6G(SCH_1):PAGE59
   U26 CB19 VSS_CB19 GENOA_SP5-SOCKET6096_13568-001,SMLF,IO,DGA^6000030     I2 @T6G_MB_LIB.T6G(SCH_1):PAGE59
   U26 CB23 VSS_CB23 GENOA_SP5-SOCKET6096_13568-001,SMLF,IO,DGA^6000030     I2 @T6G_MB_LIB.T6G(SCH_1):PAGE59
   U26 CB24 VSS_CB24 GENOA_SP5-SOCKET6096_13568-001,SMLF,IO,DGA^6000030     I2 @T6G_MB_LIB.T6G(SCH_1):PAGE59
   U26 CB25 VSS_CB25 GENOA_SP5-SOCKET6096_13568-001,SMLF,IO,DGA^6000030     I2 @T6G_MB_LIB.T6G(SCH_1):PAGE59
   U26 CB26 VSS_CB26 GENOA_SP5-SOCKET6096_13568-001,SMLF,IO,DGA^6000030     I2 @T6G_MB_LIB.T6G(SCH_1):PAGE59
   U26 CB27 VSS_CB27 GENOA_SP5-SOCKET6096_13568-001,SMLF,IO,DGA^6000030     I2 @T6G_MB_LIB.T6G(SCH_1):PAGE59
   U26 CB28 VSS_CB28 GENOA_SP5-SOCKET6096_13568-001,SMLF,IO,DGA^6000030     I2 @T6G_MB_LIB.T6G(SCH_1):PAGE59
   U26 CB29 VSS_CB29 GENOA_SP5-SOCKET6096_13568-001,SMLF,IO,DGA^6000030     I2 @T6G_MB_LIB.T6G(SCH_1):PAGE59
   U26 CB30 VSS_CB30 GENOA_SP5-SOCKET6096_13568-001,SMLF,IO,DGA^6000030     I2 @T6G_MB_LIB.T6G(SCH_1):PAGE59
   U26 CB31 VSS_CB31 GENOA_SP5-SOCKET6096_13568-001,SMLF,IO,DGA^6000030     I2 @T6G_MB_LIB.T6G(SCH_1):PAGE59
   U26 CB32 VSS_CB32 GENOA_SP5-SOCKET6096_13568-001,SMLF,IO,DGA^6000030     I2 @T6G_MB_LIB.T6G(SCH_1):PAGE59
   U26 CB33 VSS_CB33 GENOA_SP5-SOCKET6096_13568-001,SMLF,IO,DGA^6000030     I2 @T6G_MB_LIB.T6G(SCH_1):PAGE59
   U26 CB34 VSS_CB34 GENOA_SP5-SOCKET6096_13568-001,SMLF,IO,DGA^6000030     I2 @T6G_MB_LIB.T6G(SCH_1):PAGE59
   U26 CB37 VSS_CB37 GENOA_SP5-SOCKET6096_13568-001,SMLF,IO,DGA^6000030     I2 @T6G_MB_LIB.T6G(SCH_1):PAGE59
   U26 CB39 VSS_CB39 GENOA_SP5-SOCKET6096_13568-001,SMLF,IO,DGA^6000030     I2 @T6G_MB_LIB.T6G(SCH_1):PAGE59
   U26 CB42 VSS_CB42 GENOA_SP5-SOCKET6096_13568-001,SMLF,IO,DGA^6000030     I2 @T6G_MB_LIB.T6G(SCH_1):PAGE59
   U26 CB43 VSS_CB43 GENOA_SP5-SOCKET6096_13568-001,SMLF,IO,DGA^6000030     I2 @T6G_MB_LIB.T6G(SCH_1):PAGE59
   U26 CB45 VSS_CB45 GENOA_SP5-SOCKET6096_13568-001,SMLF,IO,DGA^6000030     I2 @T6G_MB_LIB.T6G(SCH_1):PAGE59
   U26 CB46 VSS_CB46 GENOA_SP5-SOCKET6096_13568-001,SMLF,IO,DGA^6000030     I2 @T6G_MB_LIB.T6G(SCH_1):PAGE59
   U26 CB47 VSS_CB47 GENOA_SP5-SOCKET6096_13568-001,SMLF,IO,DGA^6000030     I2 @T6G_MB_LIB.T6G(SCH_1):PAGE59
   U26 CB48 VSS_CB48 GENOA_SP5-SOCKET6096_13568-001,SMLF,IO,DGA^6000030     I2 @T6G_MB_LIB.T6G(SCH_1):PAGE59
   U26 CB49 VSS_CB49 GENOA_SP5-SOCKET6096_13568-001,SMLF,IO,DGA^6000030     I2 @T6G_MB_LIB.T6G(SCH_1):PAGE59
   U26 CB50 VSS_CB50 GENOA_SP5-SOCKET6096_13568-001,SMLF,IO,DGA^6000030     I2 @T6G_MB_LIB.T6G(SCH_1):PAGE59
   U26 CB51 VSS_CB51 GENOA_SP5-SOCKET6096_13568-001,SMLF,IO,DGA^6000030     I2 @T6G_MB_LIB.T6G(SCH_1):PAGE59
   U26 CB52 VSS_CB52 GENOA_SP5-SOCKET6096_13568-001,SMLF,IO,DGA^6000030     I2 @T6G_MB_LIB.T6G(SCH_1):PAGE59
   U26 CB53 VSS_CB53 GENOA_SP5-SOCKET6096_13568-001,SMLF,IO,DGA^6000030     I2 @T6G_MB_LIB.T6G(SCH_1):PAGE59
   U26 CB57 VSS_CB57 GENOA_SP5-SOCKET6096_13568-001,SMLF,IO,DGA^6000030     I2 @T6G_MB_LIB.T6G(SCH_1):PAGE59
   U26 CB59 VSS_CB59 GENOA_SP5-SOCKET6096_13568-001,SMLF,IO,DGA^6000030     I2 @T6G_MB_LIB.T6G(SCH_1):PAGE59
   U26 CB61 VSS_CB61 GENOA_SP5-SOCKET6096_13568-001,SMLF,IO,DGA^6000030     I2 @T6G_MB_LIB.T6G(SCH_1):PAGE59
   U26 CB64 VSS_CB64 GENOA_SP5-SOCKET6096_13568-001,SMLF,IO,DGA^6000030     I2 @T6G_MB_LIB.T6G(SCH_1):PAGE59
   U26 CB66 VSS_CB66 GENOA_SP5-SOCKET6096_13568-001,SMLF,IO,DGA^6000030     I2 @T6G_MB_LIB.T6G(SCH_1):PAGE59
   U26 CB68 VSS_CB68 GENOA_SP5-SOCKET6096_13568-001,SMLF,IO,DGA^6000030     I2 @T6G_MB_LIB.T6G(SCH_1):PAGE59
   U26 CB71 VSS_CB71 GENOA_SP5-SOCKET6096_13568-001,SMLF,IO,DGA^6000030     I2 @T6G_MB_LIB.T6G(SCH_1):PAGE59
   U26 CB73 VSS_CB73 GENOA_SP5-SOCKET6096_13568-001,SMLF,IO,DGA^6000030     I2 @T6G_MB_LIB.T6G(SCH_1):PAGE59
   U26  CC1 VSS_CC1 GENOA_SP5-SOCKET6096_13568-001,SMLF,IO,DGA^6000030     I2 @T6G_MB_LIB.T6G(SCH_1):PAGE59
   U26  CC4 VSS_CC4 GENOA_SP5-SOCKET6096_13568-001,SMLF,IO,DGA^6000030     I2 @T6G_MB_LIB.T6G(SCH_1):PAGE59
   U26  CC6 VSS_CC6 GENOA_SP5-SOCKET6096_13568-001,SMLF,IO,DGA^6000030     I2 @T6G_MB_LIB.T6G(SCH_1):PAGE59
   U26  CC8 VSS_CC8 GENOA_SP5-SOCKET6096_13568-001,SMLF,IO,DGA^6000030     I2 @T6G_MB_LIB.T6G(SCH_1):PAGE59
   U26 CC11 VSS_CC11 GENOA_SP5-SOCKET6096_13568-001,SMLF,IO,DGA^6000030     I2 @T6G_MB_LIB.T6G(SCH_1):PAGE59
   U26 CC13 VSS_CC13 GENOA_SP5-SOCKET6096_13568-001,SMLF,IO,DGA^6000030     I2 @T6G_MB_LIB.T6G(SCH_1):PAGE59
   U26 CC15 VSS_CC15 GENOA_SP5-SOCKET6096_13568-001,SMLF,IO,DGA^6000030     I2 @T6G_MB_LIB.T6G(SCH_1):PAGE59
   U26 CC18 VSS_CC18 GENOA_SP5-SOCKET6096_13568-001,SMLF,IO,DGA^6000030     I2 @T6G_MB_LIB.T6G(SCH_1):PAGE59
   U26 CC20 VSS_CC20 GENOA_SP5-SOCKET6096_13568-001,SMLF,IO,DGA^6000030     I2 @T6G_MB_LIB.T6G(SCH_1):PAGE59
   U26 CC25 VSS_CC25 GENOA_SP5-SOCKET6096_13568-001,SMLF,IO,DGA^6000030     I2 @T6G_MB_LIB.T6G(SCH_1):PAGE59
   U26 CC28 VSS_CC28 GENOA_SP5-SOCKET6096_13568-001,SMLF,IO,DGA^6000030     I2 @T6G_MB_LIB.T6G(SCH_1):PAGE59
   U26 CC31 VSS_CC31 GENOA_SP5-SOCKET6096_13568-001,SMLF,IO,DGA^6000030     I2 @T6G_MB_LIB.T6G(SCH_1):PAGE59
   U26 CC34 VSS_CC34 GENOA_SP5-SOCKET6096_13568-001,SMLF,IO,DGA^6000030     I2 @T6G_MB_LIB.T6G(SCH_1):PAGE59
   U26 CC42 VSS_CC42 GENOA_SP5-SOCKET6096_13568-001,SMLF,IO,DGA^6000030     I2 @T6G_MB_LIB.T6G(SCH_1):PAGE59
   U26 CC45 VSS_CC45 GENOA_SP5-SOCKET6096_13568-001,SMLF,IO,DGA^6000030     I2 @T6G_MB_LIB.T6G(SCH_1):PAGE59
   U26 CC48 VSS_CC48 GENOA_SP5-SOCKET6096_13568-001,SMLF,IO,DGA^6000030     I2 @T6G_MB_LIB.T6G(SCH_1):PAGE59
   U26 CC51 VSS_CC51 GENOA_SP5-SOCKET6096_13568-001,SMLF,IO,DGA^6000030     I2 @T6G_MB_LIB.T6G(SCH_1):PAGE59
   U26 CC54 VSS_CC54 GENOA_SP5-SOCKET6096_13568-001,SMLF,IO,DGA^6000030     I2 @T6G_MB_LIB.T6G(SCH_1):PAGE59
   U26 CC56 VSS_CC56 GENOA_SP5-SOCKET6096_13568-001,SMLF,IO,DGA^6000030     I2 @T6G_MB_LIB.T6G(SCH_1):PAGE59
   U26 CC58 VSS_CC58 GENOA_SP5-SOCKET6096_13568-001,SMLF,IO,DGA^6000030     I2 @T6G_MB_LIB.T6G(SCH_1):PAGE59
   U26 CC61 VSS_CC61 GENOA_SP5-SOCKET6096_13568-001,SMLF,IO,DGA^6000030     I2 @T6G_MB_LIB.T6G(SCH_1):PAGE59
   U26 CC63 VSS_CC63 GENOA_SP5-SOCKET6096_13568-001,SMLF,IO,DGA^6000030     I2 @T6G_MB_LIB.T6G(SCH_1):PAGE59
   U26 CC65 VSS_CC65 GENOA_SP5-SOCKET6096_13568-001,SMLF,IO,DGA^6000030     I2 @T6G_MB_LIB.T6G(SCH_1):PAGE59
   U26 CC68 VSS_CC68 GENOA_SP5-SOCKET6096_13568-001,SMLF,IO,DGA^6000030     I2 @T6G_MB_LIB.T6G(SCH_1):PAGE59
   U26 CC70 VSS_CC70 GENOA_SP5-SOCKET6096_13568-001,SMLF,IO,DGA^6000030     I2 @T6G_MB_LIB.T6G(SCH_1):PAGE59
   U26 CC72 VSS_CC72 GENOA_SP5-SOCKET6096_13568-001,SMLF,IO,DGA^6000030     I2 @T6G_MB_LIB.T6G(SCH_1):PAGE59
   U26 CC75 VSS_CC75 GENOA_SP5-SOCKET6096_13568-001,SMLF,IO,DGA^6000030     I2 @T6G_MB_LIB.T6G(SCH_1):PAGE59
   U26  CD3 VSS_CD3 GENOA_SP5-SOCKET6096_13568-001,SMLF,IO,DGA^6000030     I2 @T6G_MB_LIB.T6G(SCH_1):PAGE59
   U26  CD8 VSS_CD8 GENOA_SP5-SOCKET6096_13568-001,SMLF,IO,DGA^6000030     I2 @T6G_MB_LIB.T6G(SCH_1):PAGE59
   U26 CD10 VSS_CD10 GENOA_SP5-SOCKET6096_13568-001,SMLF,IO,DGA^6000030     I2 @T6G_MB_LIB.T6G(SCH_1):PAGE59
   U26 CD15 VSS_CD15 GENOA_SP5-SOCKET6096_13568-001,SMLF,IO,DGA^6000030     I2 @T6G_MB_LIB.T6G(SCH_1):PAGE59
   U26 CD17 VSS_CD17 GENOA_SP5-SOCKET6096_13568-001,SMLF,IO,DGA^6000030     I2 @T6G_MB_LIB.T6G(SCH_1):PAGE59
   U26 CD22 VSS_CD22 GENOA_SP5-SOCKET6096_13568-001,SMLF,IO,DGA^6000030     I2 @T6G_MB_LIB.T6G(SCH_1):PAGE59
   U26 CD25 VSS_CD25 GENOA_SP5-SOCKET6096_13568-001,SMLF,IO,DGA^6000030     I2 @T6G_MB_LIB.T6G(SCH_1):PAGE59
   U26 CD28 VSS_CD28 GENOA_SP5-SOCKET6096_13568-001,SMLF,IO,DGA^6000030     I2 @T6G_MB_LIB.T6G(SCH_1):PAGE59
   U26 CD31 VSS_CD31 GENOA_SP5-SOCKET6096_13568-001,SMLF,IO,DGA^6000030     I2 @T6G_MB_LIB.T6G(SCH_1):PAGE59
   U26 CD34 VSS_CD34 GENOA_SP5-SOCKET6096_13568-001,SMLF,IO,DGA^6000030     I2 @T6G_MB_LIB.T6G(SCH_1):PAGE59
   U26 CD37 VSS_CD37 GENOA_SP5-SOCKET6096_13568-001,SMLF,IO,DGA^6000030     I2 @T6G_MB_LIB.T6G(SCH_1):PAGE59
   U26 CD39 VSS_CD39 GENOA_SP5-SOCKET6096_13568-001,SMLF,IO,DGA^6000030     I2 @T6G_MB_LIB.T6G(SCH_1):PAGE59
   U26 CD42 VSS_CD42 GENOA_SP5-SOCKET6096_13568-001,SMLF,IO,DGA^6000030     I2 @T6G_MB_LIB.T6G(SCH_1):PAGE59
   U26 CD45 VSS_CD45 GENOA_SP5-SOCKET6096_13568-001,SMLF,IO,DGA^6000030     I2 @T6G_MB_LIB.T6G(SCH_1):PAGE59
   U26 CD48 VSS_CD48 GENOA_SP5-SOCKET6096_13568-001,SMLF,IO,DGA^6000030     I2 @T6G_MB_LIB.T6G(SCH_1):PAGE59
   U26 CD51 VSS_CD51 GENOA_SP5-SOCKET6096_13568-001,SMLF,IO,DGA^6000030     I2 @T6G_MB_LIB.T6G(SCH_1):PAGE59
   U26 CD54 VSS_CD54 GENOA_SP5-SOCKET6096_13568-001,SMLF,IO,DGA^6000030     I2 @T6G_MB_LIB.T6G(SCH_1):PAGE59
   U26 CD59 VSS_CD59 GENOA_SP5-SOCKET6096_13568-001,SMLF,IO,DGA^6000030     I2 @T6G_MB_LIB.T6G(SCH_1):PAGE59
   U26 CD61 VSS_CD61 GENOA_SP5-SOCKET6096_13568-001,SMLF,IO,DGA^6000030     I2 @T6G_MB_LIB.T6G(SCH_1):PAGE59
   U26 CD66 VSS_CD66 GENOA_SP5-SOCKET6096_13568-001,SMLF,IO,DGA^6000030     I2 @T6G_MB_LIB.T6G(SCH_1):PAGE59
   U26 CD68 VSS_CD68 GENOA_SP5-SOCKET6096_13568-001,SMLF,IO,DGA^6000030     I2 @T6G_MB_LIB.T6G(SCH_1):PAGE59
   U26 CD73 VSS_CD73 GENOA_SP5-SOCKET6096_13568-001,SMLF,IO,DGA^6000030     I2 @T6G_MB_LIB.T6G(SCH_1):PAGE59
   U26  CE1 VSS_CE1 GENOA_SP5-SOCKET6096_13568-001,SMLF,IO,DGA^6000030     I2 @T6G_MB_LIB.T6G(SCH_1):PAGE59
   U26  CE4 VSS_CE4 GENOA_SP5-SOCKET6096_13568-001,SMLF,IO,DGA^6000030     I2 @T6G_MB_LIB.T6G(SCH_1):PAGE59
   U26  CE6 VSS_CE6 GENOA_SP5-SOCKET6096_13568-001,SMLF,IO,DGA^6000030     I2 @T6G_MB_LIB.T6G(SCH_1):PAGE59
   U26  CE8 VSS_CE8 GENOA_SP5-SOCKET6096_13568-001,SMLF,IO,DGA^6000030     I2 @T6G_MB_LIB.T6G(SCH_1):PAGE59
   U26 CE11 VSS_CE11 GENOA_SP5-SOCKET6096_13568-001,SMLF,IO,DGA^6000030     I2 @T6G_MB_LIB.T6G(SCH_1):PAGE59
   U26 CE13 VSS_CE13 GENOA_SP5-SOCKET6096_13568-001,SMLF,IO,DGA^6000030     I2 @T6G_MB_LIB.T6G(SCH_1):PAGE59
   U26 CE15 VSS_CE15 GENOA_SP5-SOCKET6096_13568-001,SMLF,IO,DGA^6000030     I2 @T6G_MB_LIB.T6G(SCH_1):PAGE59
   U26 CE18 VSS_CE18 GENOA_SP5-SOCKET6096_13568-001,SMLF,IO,DGA^6000030     I2 @T6G_MB_LIB.T6G(SCH_1):PAGE59
   U26 CE20 VSS_CE20 GENOA_SP5-SOCKET6096_13568-001,SMLF,IO,DGA^6000030     I2 @T6G_MB_LIB.T6G(SCH_1):PAGE59
   U26 CE22 VSS_CE22 GENOA_SP5-SOCKET6096_13568-001,SMLF,IO,DGA^6000030     I2 @T6G_MB_LIB.T6G(SCH_1):PAGE59
   U26 CE25 VSS_CE25 GENOA_SP5-SOCKET6096_13568-001,SMLF,IO,DGA^6000030     I2 @T6G_MB_LIB.T6G(SCH_1):PAGE59
   U26 CE28 VSS_CE28 GENOA_SP5-SOCKET6096_13568-001,SMLF,IO,DGA^6000030     I2 @T6G_MB_LIB.T6G(SCH_1):PAGE59
   U26 CE31 VSS_CE31 GENOA_SP5-SOCKET6096_13568-001,SMLF,IO,DGA^6000030     I2 @T6G_MB_LIB.T6G(SCH_1):PAGE59
   U26 CE34 VSS_CE34 GENOA_SP5-SOCKET6096_13568-001,SMLF,IO,DGA^6000030     I2 @T6G_MB_LIB.T6G(SCH_1):PAGE59
   U26 CE35 VSS_CE35 GENOA_SP5-SOCKET6096_13568-001,SMLF,IO,DGA^6000030     I2 @T6G_MB_LIB.T6G(SCH_1):PAGE59
   U26 CE36 VSS_CE36 GENOA_SP5-SOCKET6096_13568-001,SMLF,IO,DGA^6000030     I2 @T6G_MB_LIB.T6G(SCH_1):PAGE59
   U26 CE40 VSS_CE40 GENOA_SP5-SOCKET6096_13568-001,SMLF,IO,DGA^6000030     I2 @T6G_MB_LIB.T6G(SCH_1):PAGE59
   U26 CE41 VSS_CE41 GENOA_SP5-SOCKET6096_13568-001,SMLF,IO,DGA^6000030     I2 @T6G_MB_LIB.T6G(SCH_1):PAGE59
   U26 CE42 VSS_CE42 GENOA_SP5-SOCKET6096_13568-001,SMLF,IO,DGA^6000030     I2 @T6G_MB_LIB.T6G(SCH_1):PAGE59
   U26 CE45 VSS_CE45 GENOA_SP5-SOCKET6096_13568-001,SMLF,IO,DGA^6000030     I2 @T6G_MB_LIB.T6G(SCH_1):PAGE59
   U26 CE48 VSS_CE48 GENOA_SP5-SOCKET6096_13568-001,SMLF,IO,DGA^6000030     I2 @T6G_MB_LIB.T6G(SCH_1):PAGE59
   U26 CE51 VSS_CE51 GENOA_SP5-SOCKET6096_13568-001,SMLF,IO,DGA^6000030     I2 @T6G_MB_LIB.T6G(SCH_1):PAGE59
   U26 CE54 VSS_CE54 GENOA_SP5-SOCKET6096_13568-001,SMLF,IO,DGA^6000030     I2 @T6G_MB_LIB.T6G(SCH_1):PAGE59
   U26 CE56 VSS_CE56 GENOA_SP5-SOCKET6096_13568-001,SMLF,IO,DGA^6000030     I2 @T6G_MB_LIB.T6G(SCH_1):PAGE59
   U26 CE58 VSS_CE58 GENOA_SP5-SOCKET6096_13568-001,SMLF,IO,DGA^6000030     I2 @T6G_MB_LIB.T6G(SCH_1):PAGE59
   U26 CE61 VSS_CE61 GENOA_SP5-SOCKET6096_13568-001,SMLF,IO,DGA^6000030     I2 @T6G_MB_LIB.T6G(SCH_1):PAGE59
   U26 CE63 VSS_CE63 GENOA_SP5-SOCKET6096_13568-001,SMLF,IO,DGA^6000030     I2 @T6G_MB_LIB.T6G(SCH_1):PAGE59
   U26 CE65 VSS_CE65 GENOA_SP5-SOCKET6096_13568-001,SMLF,IO,DGA^6000030     I2 @T6G_MB_LIB.T6G(SCH_1):PAGE59
   U26 CE68 VSS_CE68 GENOA_SP5-SOCKET6096_13568-001,SMLF,IO,DGA^6000030     I2 @T6G_MB_LIB.T6G(SCH_1):PAGE59
   U26 CE70 VSS_CE70 GENOA_SP5-SOCKET6096_13568-001,SMLF,IO,DGA^6000030     I2 @T6G_MB_LIB.T6G(SCH_1):PAGE59
   U26 CE72 VSS_CE72 GENOA_SP5-SOCKET6096_13568-001,SMLF,IO,DGA^6000030     I2 @T6G_MB_LIB.T6G(SCH_1):PAGE59
   U26 CE75 VSS_CE75 GENOA_SP5-SOCKET6096_13568-001,SMLF,IO,DGA^6000030     I2 @T6G_MB_LIB.T6G(SCH_1):PAGE59
   U26  CF3 VSS_CF3 GENOA_SP5-SOCKET6096_13568-001,SMLF,IO,DGA^6000030     I2 @T6G_MB_LIB.T6G(SCH_1):PAGE59
   U26  CF5 VSS_CF5 GENOA_SP5-SOCKET6096_13568-001,SMLF,IO,DGA^6000030     I2 @T6G_MB_LIB.T6G(SCH_1):PAGE59
   U26  CF8 VSS_CF8 GENOA_SP5-SOCKET6096_13568-001,SMLF,IO,DGA^6000030     I2 @T6G_MB_LIB.T6G(SCH_1):PAGE59
   U26 CF10 VSS_CF10 GENOA_SP5-SOCKET6096_13568-001,SMLF,IO,DGA^6000030     I2 @T6G_MB_LIB.T6G(SCH_1):PAGE59
   U26 CF12 VSS_CF12 GENOA_SP5-SOCKET6096_13568-001,SMLF,IO,DGA^6000030     I2 @T6G_MB_LIB.T6G(SCH_1):PAGE59
   U26 CF15 VSS_CF15 GENOA_SP5-SOCKET6096_13568-001,SMLF,IO,DGA^6000030     I2 @T6G_MB_LIB.T6G(SCH_1):PAGE59
   U26 CF17 VSS_CF17 GENOA_SP5-SOCKET6096_13568-001,SMLF,IO,DGA^6000030     I2 @T6G_MB_LIB.T6G(SCH_1):PAGE59
   U26 CF19 VSS_CF19 GENOA_SP5-SOCKET6096_13568-001,SMLF,IO,DGA^6000030     I2 @T6G_MB_LIB.T6G(SCH_1):PAGE59
   U26 CF23 VSS_CF23 GENOA_SP5-SOCKET6096_13568-001,SMLF,IO,DGA^6000030     I2 @T6G_MB_LIB.T6G(SCH_1):PAGE59
   U26 CF24 VSS_CF24 GENOA_SP5-SOCKET6096_13568-001,SMLF,IO,DGA^6000030     I2 @T6G_MB_LIB.T6G(SCH_1):PAGE59
   U26 CF25 VSS_CF25 GENOA_SP5-SOCKET6096_13568-001,SMLF,IO,DGA^6000030     I2 @T6G_MB_LIB.T6G(SCH_1):PAGE59
   U26 CF26 VSS_CF26 GENOA_SP5-SOCKET6096_13568-001,SMLF,IO,DGA^6000030     I2 @T6G_MB_LIB.T6G(SCH_1):PAGE59
   U26 CF27 VSS_CF27 GENOA_SP5-SOCKET6096_13568-001,SMLF,IO,DGA^6000030     I2 @T6G_MB_LIB.T6G(SCH_1):PAGE59
   U26 CF28 VSS_CF28 GENOA_SP5-SOCKET6096_13568-001,SMLF,IO,DGA^6000030     I2 @T6G_MB_LIB.T6G(SCH_1):PAGE59
   U26 CF29 VSS_CF29 GENOA_SP5-SOCKET6096_13568-001,SMLF,IO,DGA^6000030     I2 @T6G_MB_LIB.T6G(SCH_1):PAGE59
   U26 CF30 VSS_CF30 GENOA_SP5-SOCKET6096_13568-001,SMLF,IO,DGA^6000030     I2 @T6G_MB_LIB.T6G(SCH_1):PAGE59
   U26 CF31 VSS_CF31 GENOA_SP5-SOCKET6096_13568-001,SMLF,IO,DGA^6000030     I2 @T6G_MB_LIB.T6G(SCH_1):PAGE59
   U26 CF32 VSS_CF32 GENOA_SP5-SOCKET6096_13568-001,SMLF,IO,DGA^6000030     I2 @T6G_MB_LIB.T6G(SCH_1):PAGE59
   U26 CF33 VSS_CF33 GENOA_SP5-SOCKET6096_13568-001,SMLF,IO,DGA^6000030     I2 @T6G_MB_LIB.T6G(SCH_1):PAGE59
   U26 CF34 VSS_CF34 GENOA_SP5-SOCKET6096_13568-001,SMLF,IO,DGA^6000030     I3 @T6G_MB_LIB.T6G(SCH_1):PAGE59
   U26 CF37 VSS_CF37 GENOA_SP5-SOCKET6096_13568-001,SMLF,IO,DGA^6000030     I3 @T6G_MB_LIB.T6G(SCH_1):PAGE59
   U26 CF39 VSS_CF39 GENOA_SP5-SOCKET6096_13568-001,SMLF,IO,DGA^6000030     I3 @T6G_MB_LIB.T6G(SCH_1):PAGE59
   U26 CF42 VSS_CF42 GENOA_SP5-SOCKET6096_13568-001,SMLF,IO,DGA^6000030     I3 @T6G_MB_LIB.T6G(SCH_1):PAGE59
   U26 CF43 VSS_CF43 GENOA_SP5-SOCKET6096_13568-001,SMLF,IO,DGA^6000030     I3 @T6G_MB_LIB.T6G(SCH_1):PAGE59
   U26 CF44 VSS_CF44 GENOA_SP5-SOCKET6096_13568-001,SMLF,IO,DGA^6000030     I3 @T6G_MB_LIB.T6G(SCH_1):PAGE59
   U26 CF45 VSS_CF45 GENOA_SP5-SOCKET6096_13568-001,SMLF,IO,DGA^6000030     I3 @T6G_MB_LIB.T6G(SCH_1):PAGE59
   U26 CF47 VSS_CF47 GENOA_SP5-SOCKET6096_13568-001,SMLF,IO,DGA^6000030     I3 @T6G_MB_LIB.T6G(SCH_1):PAGE59
   U26 CF48 VSS_CF48 GENOA_SP5-SOCKET6096_13568-001,SMLF,IO,DGA^6000030     I3 @T6G_MB_LIB.T6G(SCH_1):PAGE59
   U26 CF49 VSS_CF49 GENOA_SP5-SOCKET6096_13568-001,SMLF,IO,DGA^6000030     I3 @T6G_MB_LIB.T6G(SCH_1):PAGE59
   U26 CF50 VSS_CF50 GENOA_SP5-SOCKET6096_13568-001,SMLF,IO,DGA^6000030     I3 @T6G_MB_LIB.T6G(SCH_1):PAGE59
   U26 CF51 VSS_CF51 GENOA_SP5-SOCKET6096_13568-001,SMLF,IO,DGA^6000030     I3 @T6G_MB_LIB.T6G(SCH_1):PAGE59
   U26 CF52 VSS_CF52 GENOA_SP5-SOCKET6096_13568-001,SMLF,IO,DGA^6000030     I3 @T6G_MB_LIB.T6G(SCH_1):PAGE59
   U26 CF53 VSS_CF53 GENOA_SP5-SOCKET6096_13568-001,SMLF,IO,DGA^6000030     I3 @T6G_MB_LIB.T6G(SCH_1):PAGE59
   U26 CF57 VSS_CF57 GENOA_SP5-SOCKET6096_13568-001,SMLF,IO,DGA^6000030     I3 @T6G_MB_LIB.T6G(SCH_1):PAGE59
   U26 CF59 VSS_CF59 GENOA_SP5-SOCKET6096_13568-001,SMLF,IO,DGA^6000030     I3 @T6G_MB_LIB.T6G(SCH_1):PAGE59
   U26 CF61 VSS_CF61 GENOA_SP5-SOCKET6096_13568-001,SMLF,IO,DGA^6000030     I3 @T6G_MB_LIB.T6G(SCH_1):PAGE59
   U26 CF64 VSS_CF64 GENOA_SP5-SOCKET6096_13568-001,SMLF,IO,DGA^6000030     I3 @T6G_MB_LIB.T6G(SCH_1):PAGE59
   U26 CF66 VSS_CF66 GENOA_SP5-SOCKET6096_13568-001,SMLF,IO,DGA^6000030     I3 @T6G_MB_LIB.T6G(SCH_1):PAGE59
   U26 CF68 VSS_CF68 GENOA_SP5-SOCKET6096_13568-001,SMLF,IO,DGA^6000030     I3 @T6G_MB_LIB.T6G(SCH_1):PAGE59
   U26 CF71 VSS_CF71 GENOA_SP5-SOCKET6096_13568-001,SMLF,IO,DGA^6000030     I3 @T6G_MB_LIB.T6G(SCH_1):PAGE59
   U26 CF73 VSS_CF73 GENOA_SP5-SOCKET6096_13568-001,SMLF,IO,DGA^6000030     I3 @T6G_MB_LIB.T6G(SCH_1):PAGE59
   U26  CG1 VSS_CG1 GENOA_SP5-SOCKET6096_13568-001,SMLF,IO,DGA^6000030     I3 @T6G_MB_LIB.T6G(SCH_1):PAGE59
   U26  CG6 VSS_CG6 GENOA_SP5-SOCKET6096_13568-001,SMLF,IO,DGA^6000030     I3 @T6G_MB_LIB.T6G(SCH_1):PAGE59
   U26  CG8 VSS_CG8 GENOA_SP5-SOCKET6096_13568-001,SMLF,IO,DGA^6000030     I3 @T6G_MB_LIB.T6G(SCH_1):PAGE59
   U26 CG13 VSS_CG13 GENOA_SP5-SOCKET6096_13568-001,SMLF,IO,DGA^6000030     I3 @T6G_MB_LIB.T6G(SCH_1):PAGE59
   U26 CG15 VSS_CG15 GENOA_SP5-SOCKET6096_13568-001,SMLF,IO,DGA^6000030     I3 @T6G_MB_LIB.T6G(SCH_1):PAGE59
   U26 CG20 VSS_CG20 GENOA_SP5-SOCKET6096_13568-001,SMLF,IO,DGA^6000030     I3 @T6G_MB_LIB.T6G(SCH_1):PAGE59
   U26 CG22 VSS_CG22 GENOA_SP5-SOCKET6096_13568-001,SMLF,IO,DGA^6000030     I3 @T6G_MB_LIB.T6G(SCH_1):PAGE59
   U26 CG25 VSS_CG25 GENOA_SP5-SOCKET6096_13568-001,SMLF,IO,DGA^6000030     I3 @T6G_MB_LIB.T6G(SCH_1):PAGE59
   U26 CG28 VSS_CG28 GENOA_SP5-SOCKET6096_13568-001,SMLF,IO,DGA^6000030     I3 @T6G_MB_LIB.T6G(SCH_1):PAGE59
   U26 CG31 VSS_CG31 GENOA_SP5-SOCKET6096_13568-001,SMLF,IO,DGA^6000030     I3 @T6G_MB_LIB.T6G(SCH_1):PAGE59
   U26 CG34 VSS_CG34 GENOA_SP5-SOCKET6096_13568-001,SMLF,IO,DGA^6000030     I3 @T6G_MB_LIB.T6G(SCH_1):PAGE59
   U26 CG45 VSS_CG45 GENOA_SP5-SOCKET6096_13568-001,SMLF,IO,DGA^6000030     I3 @T6G_MB_LIB.T6G(SCH_1):PAGE59
   U26 CG48 VSS_CG48 GENOA_SP5-SOCKET6096_13568-001,SMLF,IO,DGA^6000030     I3 @T6G_MB_LIB.T6G(SCH_1):PAGE59
   U26 CG51 VSS_CG51 GENOA_SP5-SOCKET6096_13568-001,SMLF,IO,DGA^6000030     I3 @T6G_MB_LIB.T6G(SCH_1):PAGE59
   U26 CG54 VSS_CG54 GENOA_SP5-SOCKET6096_13568-001,SMLF,IO,DGA^6000030     I3 @T6G_MB_LIB.T6G(SCH_1):PAGE59
   U26 CG56 VSS_CG56 GENOA_SP5-SOCKET6096_13568-001,SMLF,IO,DGA^6000030     I3 @T6G_MB_LIB.T6G(SCH_1):PAGE59
   U26 CG61 VSS_CG61 GENOA_SP5-SOCKET6096_13568-001,SMLF,IO,DGA^6000030     I3 @T6G_MB_LIB.T6G(SCH_1):PAGE59
   U26 CG63 VSS_CG63 GENOA_SP5-SOCKET6096_13568-001,SMLF,IO,DGA^6000030     I3 @T6G_MB_LIB.T6G(SCH_1):PAGE59
   U26 CG68 VSS_CG68 GENOA_SP5-SOCKET6096_13568-001,SMLF,IO,DGA^6000030     I3 @T6G_MB_LIB.T6G(SCH_1):PAGE59
   U26 CG70 VSS_CG70 GENOA_SP5-SOCKET6096_13568-001,SMLF,IO,DGA^6000030     I3 @T6G_MB_LIB.T6G(SCH_1):PAGE59
   U26 CG75 VSS_CG75 GENOA_SP5-SOCKET6096_13568-001,SMLF,IO,DGA^6000030     I3 @T6G_MB_LIB.T6G(SCH_1):PAGE59
   U26  CH3 VSS_CH3 GENOA_SP5-SOCKET6096_13568-001,SMLF,IO,DGA^6000030     I3 @T6G_MB_LIB.T6G(SCH_1):PAGE59
   U26  CH5 VSS_CH5 GENOA_SP5-SOCKET6096_13568-001,SMLF,IO,DGA^6000030     I3 @T6G_MB_LIB.T6G(SCH_1):PAGE59
   U26  CH8 VSS_CH8 GENOA_SP5-SOCKET6096_13568-001,SMLF,IO,DGA^6000030     I3 @T6G_MB_LIB.T6G(SCH_1):PAGE59
   U26 CH10 VSS_CH10 GENOA_SP5-SOCKET6096_13568-001,SMLF,IO,DGA^6000030     I3 @T6G_MB_LIB.T6G(SCH_1):PAGE59
   U26 CH12 VSS_CH12 GENOA_SP5-SOCKET6096_13568-001,SMLF,IO,DGA^6000030     I3 @T6G_MB_LIB.T6G(SCH_1):PAGE59
   U26 CH15 VSS_CH15 GENOA_SP5-SOCKET6096_13568-001,SMLF,IO,DGA^6000030     I3 @T6G_MB_LIB.T6G(SCH_1):PAGE59
   U26 CH17 VSS_CH17 GENOA_SP5-SOCKET6096_13568-001,SMLF,IO,DGA^6000030     I3 @T6G_MB_LIB.T6G(SCH_1):PAGE59
   U26 CH19 VSS_CH19 GENOA_SP5-SOCKET6096_13568-001,SMLF,IO,DGA^6000030     I3 @T6G_MB_LIB.T6G(SCH_1):PAGE59
   U26 CH22 VSS_CH22 GENOA_SP5-SOCKET6096_13568-001,SMLF,IO,DGA^6000030     I3 @T6G_MB_LIB.T6G(SCH_1):PAGE59
   U26 CH25 VSS_CH25 GENOA_SP5-SOCKET6096_13568-001,SMLF,IO,DGA^6000030     I3 @T6G_MB_LIB.T6G(SCH_1):PAGE59
   U26 CH28 VSS_CH28 GENOA_SP5-SOCKET6096_13568-001,SMLF,IO,DGA^6000030     I3 @T6G_MB_LIB.T6G(SCH_1):PAGE59
   U26 CH31 VSS_CH31 GENOA_SP5-SOCKET6096_13568-001,SMLF,IO,DGA^6000030     I3 @T6G_MB_LIB.T6G(SCH_1):PAGE59
   U26 CH34 VSS_CH34 GENOA_SP5-SOCKET6096_13568-001,SMLF,IO,DGA^6000030     I3 @T6G_MB_LIB.T6G(SCH_1):PAGE59
   U26 CH37 VSS_CH37 GENOA_SP5-SOCKET6096_13568-001,SMLF,IO,DGA^6000030     I3 @T6G_MB_LIB.T6G(SCH_1):PAGE59
   U26 CH39 VSS_CH39 GENOA_SP5-SOCKET6096_13568-001,SMLF,IO,DGA^6000030     I3 @T6G_MB_LIB.T6G(SCH_1):PAGE59
   U26 CH42 VSS_CH42 GENOA_SP5-SOCKET6096_13568-001,SMLF,IO,DGA^6000030     I3 @T6G_MB_LIB.T6G(SCH_1):PAGE59
   U26 CH45 VSS_CH45 GENOA_SP5-SOCKET6096_13568-001,SMLF,IO,DGA^6000030     I3 @T6G_MB_LIB.T6G(SCH_1):PAGE59
   U26 CH48 VSS_CH48 GENOA_SP5-SOCKET6096_13568-001,SMLF,IO,DGA^6000030     I3 @T6G_MB_LIB.T6G(SCH_1):PAGE59
   U26 CH51 VSS_CH51 GENOA_SP5-SOCKET6096_13568-001,SMLF,IO,DGA^6000030     I3 @T6G_MB_LIB.T6G(SCH_1):PAGE59
   U26 CH54 VSS_CH54 GENOA_SP5-SOCKET6096_13568-001,SMLF,IO,DGA^6000030     I3 @T6G_MB_LIB.T6G(SCH_1):PAGE59
   U26 CH57 VSS_CH57 GENOA_SP5-SOCKET6096_13568-001,SMLF,IO,DGA^6000030     I3 @T6G_MB_LIB.T6G(SCH_1):PAGE59
   U26 CH59 VSS_CH59 GENOA_SP5-SOCKET6096_13568-001,SMLF,IO,DGA^6000030     I3 @T6G_MB_LIB.T6G(SCH_1):PAGE59
   U26 CH61 VSS_CH61 GENOA_SP5-SOCKET6096_13568-001,SMLF,IO,DGA^6000030     I3 @T6G_MB_LIB.T6G(SCH_1):PAGE59
   U26 CH64 VSS_CH64 GENOA_SP5-SOCKET6096_13568-001,SMLF,IO,DGA^6000030     I3 @T6G_MB_LIB.T6G(SCH_1):PAGE59
   U26 CH66 VSS_CH66 GENOA_SP5-SOCKET6096_13568-001,SMLF,IO,DGA^6000030     I3 @T6G_MB_LIB.T6G(SCH_1):PAGE59
   U26 CH68 VSS_CH68 GENOA_SP5-SOCKET6096_13568-001,SMLF,IO,DGA^6000030     I3 @T6G_MB_LIB.T6G(SCH_1):PAGE59
   U26 CH71 VSS_CH71 GENOA_SP5-SOCKET6096_13568-001,SMLF,IO,DGA^6000030     I3 @T6G_MB_LIB.T6G(SCH_1):PAGE59
   U26 CH73 VSS_CH73 GENOA_SP5-SOCKET6096_13568-001,SMLF,IO,DGA^6000030     I3 @T6G_MB_LIB.T6G(SCH_1):PAGE59
   U26  CJ1 VSS_CJ1 GENOA_SP5-SOCKET6096_13568-001,SMLF,IO,DGA^6000030     I3 @T6G_MB_LIB.T6G(SCH_1):PAGE59
   U26  CJ4 VSS_CJ4 GENOA_SP5-SOCKET6096_13568-001,SMLF,IO,DGA^6000030     I3 @T6G_MB_LIB.T6G(SCH_1):PAGE59
   U26  CJ6 VSS_CJ6 GENOA_SP5-SOCKET6096_13568-001,SMLF,IO,DGA^6000030     I3 @T6G_MB_LIB.T6G(SCH_1):PAGE59
   U26  CJ8 VSS_CJ8 GENOA_SP5-SOCKET6096_13568-001,SMLF,IO,DGA^6000030     I3 @T6G_MB_LIB.T6G(SCH_1):PAGE59
   U26 CJ11 VSS_CJ11 GENOA_SP5-SOCKET6096_13568-001,SMLF,IO,DGA^6000030     I3 @T6G_MB_LIB.T6G(SCH_1):PAGE59
   U26 CJ13 VSS_CJ13 GENOA_SP5-SOCKET6096_13568-001,SMLF,IO,DGA^6000030     I3 @T6G_MB_LIB.T6G(SCH_1):PAGE59
   U26 CJ15 VSS_CJ15 GENOA_SP5-SOCKET6096_13568-001,SMLF,IO,DGA^6000030     I3 @T6G_MB_LIB.T6G(SCH_1):PAGE59
   U26 CJ18 VSS_CJ18 GENOA_SP5-SOCKET6096_13568-001,SMLF,IO,DGA^6000030     I3 @T6G_MB_LIB.T6G(SCH_1):PAGE59
   U26 CJ20 VSS_CJ20 GENOA_SP5-SOCKET6096_13568-001,SMLF,IO,DGA^6000030     I3 @T6G_MB_LIB.T6G(SCH_1):PAGE59
   U26 CJ23 VSS_CJ23 GENOA_SP5-SOCKET6096_13568-001,SMLF,IO,DGA^6000030     I3 @T6G_MB_LIB.T6G(SCH_1):PAGE59
   U26 CJ31 VSS_CJ31 GENOA_SP5-SOCKET6096_13568-001,SMLF,IO,DGA^6000030     I3 @T6G_MB_LIB.T6G(SCH_1):PAGE59
   U26 CJ34 VSS_CJ34 GENOA_SP5-SOCKET6096_13568-001,SMLF,IO,DGA^6000030     I3 @T6G_MB_LIB.T6G(SCH_1):PAGE59
   U26 CJ35 VSS_CJ35 GENOA_SP5-SOCKET6096_13568-001,SMLF,IO,DGA^6000030     I3 @T6G_MB_LIB.T6G(SCH_1):PAGE59
   U26 CJ36 VSS_CJ36 GENOA_SP5-SOCKET6096_13568-001,SMLF,IO,DGA^6000030     I3 @T6G_MB_LIB.T6G(SCH_1):PAGE59
   U26 CJ40 VSS_CJ40 GENOA_SP5-SOCKET6096_13568-001,SMLF,IO,DGA^6000030     I3 @T6G_MB_LIB.T6G(SCH_1):PAGE59
   U26 CJ41 VSS_CJ41 GENOA_SP5-SOCKET6096_13568-001,SMLF,IO,DGA^6000030     I3 @T6G_MB_LIB.T6G(SCH_1):PAGE59
   U26 CJ42 VSS_CJ42 GENOA_SP5-SOCKET6096_13568-001,SMLF,IO,DGA^6000030     I3 @T6G_MB_LIB.T6G(SCH_1):PAGE59
   U26 CJ45 VSS_CJ45 GENOA_SP5-SOCKET6096_13568-001,SMLF,IO,DGA^6000030     I3 @T6G_MB_LIB.T6G(SCH_1):PAGE59
   U26 CJ56 VSS_CJ56 GENOA_SP5-SOCKET6096_13568-001,SMLF,IO,DGA^6000030     I3 @T6G_MB_LIB.T6G(SCH_1):PAGE59
   U26 CJ58 VSS_CJ58 GENOA_SP5-SOCKET6096_13568-001,SMLF,IO,DGA^6000030     I3 @T6G_MB_LIB.T6G(SCH_1):PAGE59
   U26 CJ61 VSS_CJ61 GENOA_SP5-SOCKET6096_13568-001,SMLF,IO,DGA^6000030     I3 @T6G_MB_LIB.T6G(SCH_1):PAGE59
   U26 CJ63 VSS_CJ63 GENOA_SP5-SOCKET6096_13568-001,SMLF,IO,DGA^6000030     I3 @T6G_MB_LIB.T6G(SCH_1):PAGE59
   U26 CJ65 VSS_CJ65 GENOA_SP5-SOCKET6096_13568-001,SMLF,IO,DGA^6000030     I3 @T6G_MB_LIB.T6G(SCH_1):PAGE59
   U26 CJ68 VSS_CJ68 GENOA_SP5-SOCKET6096_13568-001,SMLF,IO,DGA^6000030     I3 @T6G_MB_LIB.T6G(SCH_1):PAGE59
   U26 CJ70 VSS_CJ70 GENOA_SP5-SOCKET6096_13568-001,SMLF,IO,DGA^6000030     I3 @T6G_MB_LIB.T6G(SCH_1):PAGE59
   U26 CJ72 VSS_CJ72 GENOA_SP5-SOCKET6096_13568-001,SMLF,IO,DGA^6000030     I3 @T6G_MB_LIB.T6G(SCH_1):PAGE59
   U26 CJ75 VSS_CJ75 GENOA_SP5-SOCKET6096_13568-001,SMLF,IO,DGA^6000030     I3 @T6G_MB_LIB.T6G(SCH_1):PAGE59
   U26  CK3 VSS_CK3 GENOA_SP5-SOCKET6096_13568-001,SMLF,IO,DGA^6000030     I3 @T6G_MB_LIB.T6G(SCH_1):PAGE59
   U26  CK8 VSS_CK8 GENOA_SP5-SOCKET6096_13568-001,SMLF,IO,DGA^6000030     I3 @T6G_MB_LIB.T6G(SCH_1):PAGE59
   U26 CK15 VSS_CK15 GENOA_SP5-SOCKET6096_13568-001,SMLF,IO,DGA^6000030     I3 @T6G_MB_LIB.T6G(SCH_1):PAGE59
   U26 CK17 VSS_CK17 GENOA_SP5-SOCKET6096_13568-001,SMLF,IO,DGA^6000030     I3 @T6G_MB_LIB.T6G(SCH_1):PAGE59
   U26 CK22 VSS_CK22 GENOA_SP5-SOCKET6096_13568-001,SMLF,IO,DGA^6000030     I3 @T6G_MB_LIB.T6G(SCH_1):PAGE59
   U26 CK23 VSS_CK23 GENOA_SP5-SOCKET6096_13568-001,SMLF,IO,DGA^6000030     I3 @T6G_MB_LIB.T6G(SCH_1):PAGE59
   U26 CK24 VSS_CK24 GENOA_SP5-SOCKET6096_13568-001,SMLF,IO,DGA^6000030     I3 @T6G_MB_LIB.T6G(SCH_1):PAGE59
   U26 CK25 VSS_CK25 GENOA_SP5-SOCKET6096_13568-001,SMLF,IO,DGA^6000030     I3 @T6G_MB_LIB.T6G(SCH_1):PAGE59
   U26 CK26 VSS_CK26 GENOA_SP5-SOCKET6096_13568-001,SMLF,IO,DGA^6000030     I3 @T6G_MB_LIB.T6G(SCH_1):PAGE59
   U26 CK27 VSS_CK27 GENOA_SP5-SOCKET6096_13568-001,SMLF,IO,DGA^6000030     I3 @T6G_MB_LIB.T6G(SCH_1):PAGE59
   U26 CK28 VSS_CK28 GENOA_SP5-SOCKET6096_13568-001,SMLF,IO,DGA^6000030     I3 @T6G_MB_LIB.T6G(SCH_1):PAGE59
   U26 CK32 VSS_CK32 GENOA_SP5-SOCKET6096_13568-001,SMLF,IO,DGA^6000030     I3 @T6G_MB_LIB.T6G(SCH_1):PAGE59
   U26 CK33 VSS_CK33 GENOA_SP5-SOCKET6096_13568-001,SMLF,IO,DGA^6000030     I3 @T6G_MB_LIB.T6G(SCH_1):PAGE59
   U26 CK34 VSS_CK34 GENOA_SP5-SOCKET6096_13568-001,SMLF,IO,DGA^6000030     I3 @T6G_MB_LIB.T6G(SCH_1):PAGE59
   U26 CK37 VSS_CK37 GENOA_SP5-SOCKET6096_13568-001,SMLF,IO,DGA^6000030     I3 @T6G_MB_LIB.T6G(SCH_1):PAGE59
   U26 CK39 VSS_CK39 GENOA_SP5-SOCKET6096_13568-001,SMLF,IO,DGA^6000030     I3 @T6G_MB_LIB.T6G(SCH_1):PAGE59
   U26 CK42 VSS_CK42 GENOA_SP5-SOCKET6096_13568-001,SMLF,IO,DGA^6000030     I3 @T6G_MB_LIB.T6G(SCH_1):PAGE59
   U26 CK43 VSS_CK43 GENOA_SP5-SOCKET6096_13568-001,SMLF,IO,DGA^6000030     I3 @T6G_MB_LIB.T6G(SCH_1):PAGE59
   U26 CK44 VSS_CK44 GENOA_SP5-SOCKET6096_13568-001,SMLF,IO,DGA^6000030     I3 @T6G_MB_LIB.T6G(SCH_1):PAGE59
   U26 CK45 VSS_CK45 GENOA_SP5-SOCKET6096_13568-001,SMLF,IO,DGA^6000030     I3 @T6G_MB_LIB.T6G(SCH_1):PAGE59
   U26 CK48 VSS_CK48 GENOA_SP5-SOCKET6096_13568-001,SMLF,IO,DGA^6000030     I3 @T6G_MB_LIB.T6G(SCH_1):PAGE59
   U26 CK49 VSS_CK49 GENOA_SP5-SOCKET6096_13568-001,SMLF,IO,DGA^6000030     I3 @T6G_MB_LIB.T6G(SCH_1):PAGE59
   U26 CK50 VSS_CK50 GENOA_SP5-SOCKET6096_13568-001,SMLF,IO,DGA^6000030     I3 @T6G_MB_LIB.T6G(SCH_1):PAGE59
   U26 CK51 VSS_CK51 GENOA_SP5-SOCKET6096_13568-001,SMLF,IO,DGA^6000030     I3 @T6G_MB_LIB.T6G(SCH_1):PAGE59
   U26 CK52 VSS_CK52 GENOA_SP5-SOCKET6096_13568-001,SMLF,IO,DGA^6000030     I3 @T6G_MB_LIB.T6G(SCH_1):PAGE59
   U26 CK53 VSS_CK53 GENOA_SP5-SOCKET6096_13568-001,SMLF,IO,DGA^6000030     I3 @T6G_MB_LIB.T6G(SCH_1):PAGE59
   U26 CK54 VSS_CK54 GENOA_SP5-SOCKET6096_13568-001,SMLF,IO,DGA^6000030     I3 @T6G_MB_LIB.T6G(SCH_1):PAGE59
   U26 CK59 VSS_CK59 GENOA_SP5-SOCKET6096_13568-001,SMLF,IO,DGA^6000030     I3 @T6G_MB_LIB.T6G(SCH_1):PAGE59
   U26 CK61 VSS_CK61 GENOA_SP5-SOCKET6096_13568-001,SMLF,IO,DGA^6000030     I3 @T6G_MB_LIB.T6G(SCH_1):PAGE59
   U26 CK66 VSS_CK66 GENOA_SP5-SOCKET6096_13568-001,SMLF,IO,DGA^6000030     I3 @T6G_MB_LIB.T6G(SCH_1):PAGE59
   U26 CK68 VSS_CK68 GENOA_SP5-SOCKET6096_13568-001,SMLF,IO,DGA^6000030     I3 @T6G_MB_LIB.T6G(SCH_1):PAGE59
   U26 CK73 VSS_CK73 GENOA_SP5-SOCKET6096_13568-001,SMLF,IO,DGA^6000030     I3 @T6G_MB_LIB.T6G(SCH_1):PAGE59
   U26  CL1 VSS_CL1 GENOA_SP5-SOCKET6096_13568-001,SMLF,IO,DGA^6000030     I3 @T6G_MB_LIB.T6G(SCH_1):PAGE59
   U26  CL4 VSS_CL4 GENOA_SP5-SOCKET6096_13568-001,SMLF,IO,DGA^6000030     I3 @T6G_MB_LIB.T6G(SCH_1):PAGE59
   U26  CL6 VSS_CL6 GENOA_SP5-SOCKET6096_13568-001,SMLF,IO,DGA^6000030     I3 @T6G_MB_LIB.T6G(SCH_1):PAGE59
   U26  CL8 VSS_CL8 GENOA_SP5-SOCKET6096_13568-001,SMLF,IO,DGA^6000030     I3 @T6G_MB_LIB.T6G(SCH_1):PAGE59
   U26 CL11 VSS_CL11 GENOA_SP5-SOCKET6096_13568-001,SMLF,IO,DGA^6000030     I3 @T6G_MB_LIB.T6G(SCH_1):PAGE59
   U26 CL13 VSS_CL13 GENOA_SP5-SOCKET6096_13568-001,SMLF,IO,DGA^6000030     I3 @T6G_MB_LIB.T6G(SCH_1):PAGE59
   U26 CL15 VSS_CL15 GENOA_SP5-SOCKET6096_13568-001,SMLF,IO,DGA^6000030     I3 @T6G_MB_LIB.T6G(SCH_1):PAGE59
   U26 CL18 VSS_CL18 GENOA_SP5-SOCKET6096_13568-001,SMLF,IO,DGA^6000030     I3 @T6G_MB_LIB.T6G(SCH_1):PAGE59
   U26 CL20 VSS_CL20 GENOA_SP5-SOCKET6096_13568-001,SMLF,IO,DGA^6000030     I3 @T6G_MB_LIB.T6G(SCH_1):PAGE59
   U26 CL22 VSS_CL22 GENOA_SP5-SOCKET6096_13568-001,SMLF,IO,DGA^6000030     I3 @T6G_MB_LIB.T6G(SCH_1):PAGE59
   U26 CL25 VSS_CL25 GENOA_SP5-SOCKET6096_13568-001,SMLF,IO,DGA^6000030     I3 @T6G_MB_LIB.T6G(SCH_1):PAGE59
   U26 CL28 VSS_CL28 GENOA_SP5-SOCKET6096_13568-001,SMLF,IO,DGA^6000030     I3 @T6G_MB_LIB.T6G(SCH_1):PAGE59
   U26 CL31 VSS_CL31 GENOA_SP5-SOCKET6096_13568-001,SMLF,IO,DGA^6000030     I3 @T6G_MB_LIB.T6G(SCH_1):PAGE59
   U26 CL34 VSS_CL34 GENOA_SP5-SOCKET6096_13568-001,SMLF,IO,DGA^6000030     I3 @T6G_MB_LIB.T6G(SCH_1):PAGE59
   U26 CL35 VSS_CL35 GENOA_SP5-SOCKET6096_13568-001,SMLF,IO,DGA^6000030     I3 @T6G_MB_LIB.T6G(SCH_1):PAGE59
   U26 CL36 VSS_CL36 GENOA_SP5-SOCKET6096_13568-001,SMLF,IO,DGA^6000030     I3 @T6G_MB_LIB.T6G(SCH_1):PAGE59
   U26 CL40 VSS_CL40 GENOA_SP5-SOCKET6096_13568-001,SMLF,IO,DGA^6000030     I3 @T6G_MB_LIB.T6G(SCH_1):PAGE59
   U26 CL41 VSS_CL41 GENOA_SP5-SOCKET6096_13568-001,SMLF,IO,DGA^6000030     I3 @T6G_MB_LIB.T6G(SCH_1):PAGE59
   U26 CL42 VSS_CL42 GENOA_SP5-SOCKET6096_13568-001,SMLF,IO,DGA^6000030     I3 @T6G_MB_LIB.T6G(SCH_1):PAGE59
   U26 CL45 VSS_CL45 GENOA_SP5-SOCKET6096_13568-001,SMLF,IO,DGA^6000030     I3 @T6G_MB_LIB.T6G(SCH_1):PAGE59
   U26 CL48 VSS_CL48 GENOA_SP5-SOCKET6096_13568-001,SMLF,IO,DGA^6000030     I3 @T6G_MB_LIB.T6G(SCH_1):PAGE59
   U26 CL51 VSS_CL51 GENOA_SP5-SOCKET6096_13568-001,SMLF,IO,DGA^6000030     I3 @T6G_MB_LIB.T6G(SCH_1):PAGE59
   U26 CL54 VSS_CL54 GENOA_SP5-SOCKET6096_13568-001,SMLF,IO,DGA^6000030     I3 @T6G_MB_LIB.T6G(SCH_1):PAGE59
   U26 CL56 VSS_CL56 GENOA_SP5-SOCKET6096_13568-001,SMLF,IO,DGA^6000030     I3 @T6G_MB_LIB.T6G(SCH_1):PAGE59
   U26 CL58 VSS_CL58 GENOA_SP5-SOCKET6096_13568-001,SMLF,IO,DGA^6000030     I3 @T6G_MB_LIB.T6G(SCH_1):PAGE59
   U26 CL61 VSS_CL61 GENOA_SP5-SOCKET6096_13568-001,SMLF,IO,DGA^6000030     I3 @T6G_MB_LIB.T6G(SCH_1):PAGE59
   U26 CL63 VSS_CL63 GENOA_SP5-SOCKET6096_13568-001,SMLF,IO,DGA^6000030     I3 @T6G_MB_LIB.T6G(SCH_1):PAGE59
   U26 CL65 VSS_CL65 GENOA_SP5-SOCKET6096_13568-001,SMLF,IO,DGA^6000030     I3 @T6G_MB_LIB.T6G(SCH_1):PAGE59
   U26 CL68 VSS_CL68 GENOA_SP5-SOCKET6096_13568-001,SMLF,IO,DGA^6000030     I3 @T6G_MB_LIB.T6G(SCH_1):PAGE59
   U26 CL70 VSS_CL70 GENOA_SP5-SOCKET6096_13568-001,SMLF,IO,DGA^6000030     I3 @T6G_MB_LIB.T6G(SCH_1):PAGE59
   U26 CL72 VSS_CL72 GENOA_SP5-SOCKET6096_13568-001,SMLF,IO,DGA^6000030     I3 @T6G_MB_LIB.T6G(SCH_1):PAGE59
   U26 CL75 VSS_CL75 GENOA_SP5-SOCKET6096_13568-001,SMLF,IO,DGA^6000030     I3 @T6G_MB_LIB.T6G(SCH_1):PAGE59
   U26  CM3 VSS_CM3 GENOA_SP5-SOCKET6096_13568-001,SMLF,IO,DGA^6000030     I3 @T6G_MB_LIB.T6G(SCH_1):PAGE59
   U26  CM5 VSS_CM5 GENOA_SP5-SOCKET6096_13568-001,SMLF,IO,DGA^6000030     I3 @T6G_MB_LIB.T6G(SCH_1):PAGE59
   U26  CM8 VSS_CM8 GENOA_SP5-SOCKET6096_13568-001,SMLF,IO,DGA^6000030     I3 @T6G_MB_LIB.T6G(SCH_1):PAGE59
   U26 CM10 VSS_CM10 GENOA_SP5-SOCKET6096_13568-001,SMLF,IO,DGA^6000030     I3 @T6G_MB_LIB.T6G(SCH_1):PAGE59
   U26 CM12 VSS_CM12 GENOA_SP5-SOCKET6096_13568-001,SMLF,IO,DGA^6000030     I3 @T6G_MB_LIB.T6G(SCH_1):PAGE59
   U26 CM15 VSS_CM15 GENOA_SP5-SOCKET6096_13568-001,SMLF,IO,DGA^6000030     I3 @T6G_MB_LIB.T6G(SCH_1):PAGE59
   U26 CM17 VSS_CM17 GENOA_SP5-SOCKET6096_13568-001,SMLF,IO,DGA^6000030     I3 @T6G_MB_LIB.T6G(SCH_1):PAGE59
   U26 CM19 VSS_CM19 GENOA_SP5-SOCKET6096_13568-001,SMLF,IO,DGA^6000030     I3 @T6G_MB_LIB.T6G(SCH_1):PAGE59
   U26 CM23 VSS_CM23 GENOA_SP5-SOCKET6096_13568-001,SMLF,IO,DGA^6000030     I3 @T6G_MB_LIB.T6G(SCH_1):PAGE59
   U26 CM24 VSS_CM24 GENOA_SP5-SOCKET6096_13568-001,SMLF,IO,DGA^6000030     I3 @T6G_MB_LIB.T6G(SCH_1):PAGE59
   U26 CM25 VSS_CM25 GENOA_SP5-SOCKET6096_13568-001,SMLF,IO,DGA^6000030     I3 @T6G_MB_LIB.T6G(SCH_1):PAGE59
   U26 CM26 VSS_CM26 GENOA_SP5-SOCKET6096_13568-001,SMLF,IO,DGA^6000030     I3 @T6G_MB_LIB.T6G(SCH_1):PAGE59
   U26 CM27 VSS_CM27 GENOA_SP5-SOCKET6096_13568-001,SMLF,IO,DGA^6000030     I3 @T6G_MB_LIB.T6G(SCH_1):PAGE59
   U26 CM28 VSS_CM28 GENOA_SP5-SOCKET6096_13568-001,SMLF,IO,DGA^6000030     I3 @T6G_MB_LIB.T6G(SCH_1):PAGE59
   U26 CM29 VSS_CM29 GENOA_SP5-SOCKET6096_13568-001,SMLF,IO,DGA^6000030     I3 @T6G_MB_LIB.T6G(SCH_1):PAGE59
   U26 CM30 VSS_CM30 GENOA_SP5-SOCKET6096_13568-001,SMLF,IO,DGA^6000030     I3 @T6G_MB_LIB.T6G(SCH_1):PAGE59
   U26 CM31 VSS_CM31 GENOA_SP5-SOCKET6096_13568-001,SMLF,IO,DGA^6000030     I3 @T6G_MB_LIB.T6G(SCH_1):PAGE59
   U26 CM32 VSS_CM32 GENOA_SP5-SOCKET6096_13568-001,SMLF,IO,DGA^6000030     I3 @T6G_MB_LIB.T6G(SCH_1):PAGE59
   U26 CM33 VSS_CM33 GENOA_SP5-SOCKET6096_13568-001,SMLF,IO,DGA^6000030     I3 @T6G_MB_LIB.T6G(SCH_1):PAGE59
   U26 CM34 VSS_CM34 GENOA_SP5-SOCKET6096_13568-001,SMLF,IO,DGA^6000030     I3 @T6G_MB_LIB.T6G(SCH_1):PAGE59
   U26 CM37 VSS_CM37 GENOA_SP5-SOCKET6096_13568-001,SMLF,IO,DGA^6000030     I3 @T6G_MB_LIB.T6G(SCH_1):PAGE59
   U26 CM39 VSS_CM39 GENOA_SP5-SOCKET6096_13568-001,SMLF,IO,DGA^6000030     I3 @T6G_MB_LIB.T6G(SCH_1):PAGE59
   U26 CM42 VSS_CM42 GENOA_SP5-SOCKET6096_13568-001,SMLF,IO,DGA^6000030     I3 @T6G_MB_LIB.T6G(SCH_1):PAGE59
   U26 CM43 VSS_CM43 GENOA_SP5-SOCKET6096_13568-001,SMLF,IO,DGA^6000030     I3 @T6G_MB_LIB.T6G(SCH_1):PAGE59
   U26 CM44 VSS_CM44 GENOA_SP5-SOCKET6096_13568-001,SMLF,IO,DGA^6000030     I3 @T6G_MB_LIB.T6G(SCH_1):PAGE59
   U26 CM45 VSS_CM45 GENOA_SP5-SOCKET6096_13568-001,SMLF,IO,DGA^6000030     I3 @T6G_MB_LIB.T6G(SCH_1):PAGE59
   U26 CM46 VSS_CM46 GENOA_SP5-SOCKET6096_13568-001,SMLF,IO,DGA^6000030     I3 @T6G_MB_LIB.T6G(SCH_1):PAGE59
   U26 CM47 VSS_CM47 GENOA_SP5-SOCKET6096_13568-001,SMLF,IO,DGA^6000030     I3 @T6G_MB_LIB.T6G(SCH_1):PAGE59
   U26 CM48 VSS_CM48 GENOA_SP5-SOCKET6096_13568-001,SMLF,IO,DGA^6000030     I3 @T6G_MB_LIB.T6G(SCH_1):PAGE59
   U26 CM49 VSS_CM49 GENOA_SP5-SOCKET6096_13568-001,SMLF,IO,DGA^6000030     I3 @T6G_MB_LIB.T6G(SCH_1):PAGE59
   U26 CM51 VSS_CM51 GENOA_SP5-SOCKET6096_13568-001,SMLF,IO,DGA^6000030     I3 @T6G_MB_LIB.T6G(SCH_1):PAGE59
   U26 CM52 VSS_CM52 GENOA_SP5-SOCKET6096_13568-001,SMLF,IO,DGA^6000030     I3 @T6G_MB_LIB.T6G(SCH_1):PAGE59
   U26 CM53 VSS_CM53 GENOA_SP5-SOCKET6096_13568-001,SMLF,IO,DGA^6000030     I3 @T6G_MB_LIB.T6G(SCH_1):PAGE59
   U26 CM57 VSS_CM57 GENOA_SP5-SOCKET6096_13568-001,SMLF,IO,DGA^6000030     I3 @T6G_MB_LIB.T6G(SCH_1):PAGE59
   U26 CM59 VSS_CM59 GENOA_SP5-SOCKET6096_13568-001,SMLF,IO,DGA^6000030     I3 @T6G_MB_LIB.T6G(SCH_1):PAGE59
   U26 CM61 VSS_CM61 GENOA_SP5-SOCKET6096_13568-001,SMLF,IO,DGA^6000030     I3 @T6G_MB_LIB.T6G(SCH_1):PAGE59
   U26 CM64 VSS_CM64 GENOA_SP5-SOCKET6096_13568-001,SMLF,IO,DGA^6000030     I3 @T6G_MB_LIB.T6G(SCH_1):PAGE59
   U26 CM66 VSS_CM66 GENOA_SP5-SOCKET6096_13568-001,SMLF,IO,DGA^6000030     I3 @T6G_MB_LIB.T6G(SCH_1):PAGE59
   U26 CM68 VSS_CM68 GENOA_SP5-SOCKET6096_13568-001,SMLF,IO,DGA^6000030     I3 @T6G_MB_LIB.T6G(SCH_1):PAGE59
   U26 CM71 VSS_CM71 GENOA_SP5-SOCKET6096_13568-001,SMLF,IO,DGA^6000030     I3 @T6G_MB_LIB.T6G(SCH_1):PAGE59
   U26 CM73 VSS_CM73 GENOA_SP5-SOCKET6096_13568-001,SMLF,IO,DGA^6000030     I3 @T6G_MB_LIB.T6G(SCH_1):PAGE59
   U26  CN1 VSS_CN1 GENOA_SP5-SOCKET6096_13568-001,SMLF,IO,DGA^6000030     I3 @T6G_MB_LIB.T6G(SCH_1):PAGE59
   U26  CN6 VSS_CN6 GENOA_SP5-SOCKET6096_13568-001,SMLF,IO,DGA^6000030     I3 @T6G_MB_LIB.T6G(SCH_1):PAGE59
   U26  CN8 VSS_CN8 GENOA_SP5-SOCKET6096_13568-001,SMLF,IO,DGA^6000030     I3 @T6G_MB_LIB.T6G(SCH_1):PAGE59
   U26 CN13 VSS_CN13 GENOA_SP5-SOCKET6096_13568-001,SMLF,IO,DGA^6000030     I3 @T6G_MB_LIB.T6G(SCH_1):PAGE59
   U26 CN15 VSS_CN15 GENOA_SP5-SOCKET6096_13568-001,SMLF,IO,DGA^6000030     I3 @T6G_MB_LIB.T6G(SCH_1):PAGE59
   U26 CN20 VSS_CN20 GENOA_SP5-SOCKET6096_13568-001,SMLF,IO,DGA^6000030     I3 @T6G_MB_LIB.T6G(SCH_1):PAGE59
   U26 CN22 VSS_CN22 GENOA_SP5-SOCKET6096_13568-001,SMLF,IO,DGA^6000030     I3 @T6G_MB_LIB.T6G(SCH_1):PAGE59
   U26 CN25 VSS_CN25 GENOA_SP5-SOCKET6096_13568-001,SMLF,IO,DGA^6000030     I3 @T6G_MB_LIB.T6G(SCH_1):PAGE59
   U26 CN28 VSS_CN28 GENOA_SP5-SOCKET6096_13568-001,SMLF,IO,DGA^6000030     I3 @T6G_MB_LIB.T6G(SCH_1):PAGE59
   U26 CN31 VSS_CN31 GENOA_SP5-SOCKET6096_13568-001,SMLF,IO,DGA^6000030     I3 @T6G_MB_LIB.T6G(SCH_1):PAGE59
   U26 CN34 VSS_CN34 GENOA_SP5-SOCKET6096_13568-001,SMLF,IO,DGA^6000030     I3 @T6G_MB_LIB.T6G(SCH_1):PAGE59
   U26 CN42 VSS_CN42 GENOA_SP5-SOCKET6096_13568-001,SMLF,IO,DGA^6000030     I3 @T6G_MB_LIB.T6G(SCH_1):PAGE59
   U26 CN45 VSS_CN45 GENOA_SP5-SOCKET6096_13568-001,SMLF,IO,DGA^6000030     I3 @T6G_MB_LIB.T6G(SCH_1):PAGE59
   U26 CN48 VSS_CN48 GENOA_SP5-SOCKET6096_13568-001,SMLF,IO,DGA^6000030     I3 @T6G_MB_LIB.T6G(SCH_1):PAGE59
   U26 CN51 VSS_CN51 GENOA_SP5-SOCKET6096_13568-001,SMLF,IO,DGA^6000030     I3 @T6G_MB_LIB.T6G(SCH_1):PAGE59
   U26 CN56 VSS_CN56 GENOA_SP5-SOCKET6096_13568-001,SMLF,IO,DGA^6000030     I3 @T6G_MB_LIB.T6G(SCH_1):PAGE59
   U26 CN61 VSS_CN61 GENOA_SP5-SOCKET6096_13568-001,SMLF,IO,DGA^6000030     I3 @T6G_MB_LIB.T6G(SCH_1):PAGE59
   U26 CN63 VSS_CN63 GENOA_SP5-SOCKET6096_13568-001,SMLF,IO,DGA^6000030     I3 @T6G_MB_LIB.T6G(SCH_1):PAGE59
   U26 CN68 VSS_CN68 GENOA_SP5-SOCKET6096_13568-001,SMLF,IO,DGA^6000030     I3 @T6G_MB_LIB.T6G(SCH_1):PAGE59
   U26 CN70 VSS_CN70 GENOA_SP5-SOCKET6096_13568-001,SMLF,IO,DGA^6000030     I3 @T6G_MB_LIB.T6G(SCH_1):PAGE59
   U26 CN75 VSS_CN75 GENOA_SP5-SOCKET6096_13568-001,SMLF,IO,DGA^6000030     I3 @T6G_MB_LIB.T6G(SCH_1):PAGE59
   U26  CP3 VSS_CP3 GENOA_SP5-SOCKET6096_13568-001,SMLF,IO,DGA^6000030     I3 @T6G_MB_LIB.T6G(SCH_1):PAGE59
   U26  CP5 VSS_CP5 GENOA_SP5-SOCKET6096_13568-001,SMLF,IO,DGA^6000030     I3 @T6G_MB_LIB.T6G(SCH_1):PAGE59
   U26  CP8 VSS_CP8 GENOA_SP5-SOCKET6096_13568-001,SMLF,IO,DGA^6000030     I3 @T6G_MB_LIB.T6G(SCH_1):PAGE59
   U26 CP10 VSS_CP10 GENOA_SP5-SOCKET6096_13568-001,SMLF,IO,DGA^6000030     I3 @T6G_MB_LIB.T6G(SCH_1):PAGE59
   U26 CP12 VSS_CP12 GENOA_SP5-SOCKET6096_13568-001,SMLF,IO,DGA^6000030     I3 @T6G_MB_LIB.T6G(SCH_1):PAGE59
   U26 CP15 VSS_CP15 GENOA_SP5-SOCKET6096_13568-001,SMLF,IO,DGA^6000030     I3 @T6G_MB_LIB.T6G(SCH_1):PAGE59
   U26 CP17 VSS_CP17 GENOA_SP5-SOCKET6096_13568-001,SMLF,IO,DGA^6000030     I3 @T6G_MB_LIB.T6G(SCH_1):PAGE59
   U26 CP19 VSS_CP19 GENOA_SP5-SOCKET6096_13568-001,SMLF,IO,DGA^6000030     I3 @T6G_MB_LIB.T6G(SCH_1):PAGE59
   U26 CP22 VSS_CP22 GENOA_SP5-SOCKET6096_13568-001,SMLF,IO,DGA^6000030     I4 @T6G_MB_LIB.T6G(SCH_1):PAGE59
   U26 CP25 VSS_CP25 GENOA_SP5-SOCKET6096_13568-001,SMLF,IO,DGA^6000030     I4 @T6G_MB_LIB.T6G(SCH_1):PAGE59
   U26 CP28 VSS_CP28 GENOA_SP5-SOCKET6096_13568-001,SMLF,IO,DGA^6000030     I4 @T6G_MB_LIB.T6G(SCH_1):PAGE59
   U26 CP31 VSS_CP31 GENOA_SP5-SOCKET6096_13568-001,SMLF,IO,DGA^6000030     I4 @T6G_MB_LIB.T6G(SCH_1):PAGE59
   U26 CP34 VSS_CP34 GENOA_SP5-SOCKET6096_13568-001,SMLF,IO,DGA^6000030     I4 @T6G_MB_LIB.T6G(SCH_1):PAGE59
   U26 CP37 VSS_CP37 GENOA_SP5-SOCKET6096_13568-001,SMLF,IO,DGA^6000030     I4 @T6G_MB_LIB.T6G(SCH_1):PAGE59
   U26 CP39 VSS_CP39 GENOA_SP5-SOCKET6096_13568-001,SMLF,IO,DGA^6000030     I4 @T6G_MB_LIB.T6G(SCH_1):PAGE59
   U26 CP42 VSS_CP42 GENOA_SP5-SOCKET6096_13568-001,SMLF,IO,DGA^6000030     I4 @T6G_MB_LIB.T6G(SCH_1):PAGE59
   U26 CP45 VSS_CP45 GENOA_SP5-SOCKET6096_13568-001,SMLF,IO,DGA^6000030     I4 @T6G_MB_LIB.T6G(SCH_1):PAGE59
   U26 CP48 VSS_CP48 GENOA_SP5-SOCKET6096_13568-001,SMLF,IO,DGA^6000030     I4 @T6G_MB_LIB.T6G(SCH_1):PAGE59
   U26 CP51 VSS_CP51 GENOA_SP5-SOCKET6096_13568-001,SMLF,IO,DGA^6000030     I4 @T6G_MB_LIB.T6G(SCH_1):PAGE59
   U26 CP54 VSS_CP54 GENOA_SP5-SOCKET6096_13568-001,SMLF,IO,DGA^6000030     I4 @T6G_MB_LIB.T6G(SCH_1):PAGE59
   U26 CP57 VSS_CP57 GENOA_SP5-SOCKET6096_13568-001,SMLF,IO,DGA^6000030     I4 @T6G_MB_LIB.T6G(SCH_1):PAGE59
   U26 CP59 VSS_CP59 GENOA_SP5-SOCKET6096_13568-001,SMLF,IO,DGA^6000030     I4 @T6G_MB_LIB.T6G(SCH_1):PAGE59
   U26 CP61 VSS_CP61 GENOA_SP5-SOCKET6096_13568-001,SMLF,IO,DGA^6000030     I4 @T6G_MB_LIB.T6G(SCH_1):PAGE59
   U26 CP64 VSS_CP64 GENOA_SP5-SOCKET6096_13568-001,SMLF,IO,DGA^6000030     I4 @T6G_MB_LIB.T6G(SCH_1):PAGE59
   U26 CP66 VSS_CP66 GENOA_SP5-SOCKET6096_13568-001,SMLF,IO,DGA^6000030     I4 @T6G_MB_LIB.T6G(SCH_1):PAGE59
   U26 CP68 VSS_CP68 GENOA_SP5-SOCKET6096_13568-001,SMLF,IO,DGA^6000030     I4 @T6G_MB_LIB.T6G(SCH_1):PAGE59
   U26 CP71 VSS_CP71 GENOA_SP5-SOCKET6096_13568-001,SMLF,IO,DGA^6000030     I4 @T6G_MB_LIB.T6G(SCH_1):PAGE59
   U26 CP73 VSS_CP73 GENOA_SP5-SOCKET6096_13568-001,SMLF,IO,DGA^6000030     I4 @T6G_MB_LIB.T6G(SCH_1):PAGE59
   U26  CR1 VSS_CR1 GENOA_SP5-SOCKET6096_13568-001,SMLF,IO,DGA^6000030     I4 @T6G_MB_LIB.T6G(SCH_1):PAGE59
   U26  CR4 VSS_CR4 GENOA_SP5-SOCKET6096_13568-001,SMLF,IO,DGA^6000030     I4 @T6G_MB_LIB.T6G(SCH_1):PAGE59
   U26  CR6 VSS_CR6 GENOA_SP5-SOCKET6096_13568-001,SMLF,IO,DGA^6000030     I4 @T6G_MB_LIB.T6G(SCH_1):PAGE59
   U26  CR8 VSS_CR8 GENOA_SP5-SOCKET6096_13568-001,SMLF,IO,DGA^6000030     I4 @T6G_MB_LIB.T6G(SCH_1):PAGE59
   U26 CR11 VSS_CR11 GENOA_SP5-SOCKET6096_13568-001,SMLF,IO,DGA^6000030     I4 @T6G_MB_LIB.T6G(SCH_1):PAGE59
   U26 CR13 VSS_CR13 GENOA_SP5-SOCKET6096_13568-001,SMLF,IO,DGA^6000030     I4 @T6G_MB_LIB.T6G(SCH_1):PAGE59
   U26 CR15 VSS_CR15 GENOA_SP5-SOCKET6096_13568-001,SMLF,IO,DGA^6000030     I4 @T6G_MB_LIB.T6G(SCH_1):PAGE59
   U26 CR18 VSS_CR18 GENOA_SP5-SOCKET6096_13568-001,SMLF,IO,DGA^6000030     I4 @T6G_MB_LIB.T6G(SCH_1):PAGE59
   U26 CR20 VSS_CR20 GENOA_SP5-SOCKET6096_13568-001,SMLF,IO,DGA^6000030     I4 @T6G_MB_LIB.T6G(SCH_1):PAGE59
   U26 CR22 VSS_CR22 GENOA_SP5-SOCKET6096_13568-001,SMLF,IO,DGA^6000030     I4 @T6G_MB_LIB.T6G(SCH_1):PAGE59
   U26 CR25 VSS_CR25 GENOA_SP5-SOCKET6096_13568-001,SMLF,IO,DGA^6000030     I4 @T6G_MB_LIB.T6G(SCH_1):PAGE59
   U26 CR28 VSS_CR28 GENOA_SP5-SOCKET6096_13568-001,SMLF,IO,DGA^6000030     I4 @T6G_MB_LIB.T6G(SCH_1):PAGE59
   U26 CR31 VSS_CR31 GENOA_SP5-SOCKET6096_13568-001,SMLF,IO,DGA^6000030     I4 @T6G_MB_LIB.T6G(SCH_1):PAGE59
   U26 CR34 VSS_CR34 GENOA_SP5-SOCKET6096_13568-001,SMLF,IO,DGA^6000030     I4 @T6G_MB_LIB.T6G(SCH_1):PAGE59
   U26 CR35 VSS_CR35 GENOA_SP5-SOCKET6096_13568-001,SMLF,IO,DGA^6000030     I4 @T6G_MB_LIB.T6G(SCH_1):PAGE59
   U26 CR36 VSS_CR36 GENOA_SP5-SOCKET6096_13568-001,SMLF,IO,DGA^6000030     I4 @T6G_MB_LIB.T6G(SCH_1):PAGE59
   U26 CR40 VSS_CR40 GENOA_SP5-SOCKET6096_13568-001,SMLF,IO,DGA^6000030     I4 @T6G_MB_LIB.T6G(SCH_1):PAGE59
   U26 CR41 VSS_CR41 GENOA_SP5-SOCKET6096_13568-001,SMLF,IO,DGA^6000030     I4 @T6G_MB_LIB.T6G(SCH_1):PAGE59
   U26 CR42 VSS_CR42 GENOA_SP5-SOCKET6096_13568-001,SMLF,IO,DGA^6000030     I4 @T6G_MB_LIB.T6G(SCH_1):PAGE59
   U26 CR45 VSS_CR45 GENOA_SP5-SOCKET6096_13568-001,SMLF,IO,DGA^6000030     I4 @T6G_MB_LIB.T6G(SCH_1):PAGE59
   U26 CR48 VSS_CR48 GENOA_SP5-SOCKET6096_13568-001,SMLF,IO,DGA^6000030     I4 @T6G_MB_LIB.T6G(SCH_1):PAGE59
   U26 CR51 VSS_CR51 GENOA_SP5-SOCKET6096_13568-001,SMLF,IO,DGA^6000030     I4 @T6G_MB_LIB.T6G(SCH_1):PAGE59
   U26 CR54 VSS_CR54 GENOA_SP5-SOCKET6096_13568-001,SMLF,IO,DGA^6000030     I4 @T6G_MB_LIB.T6G(SCH_1):PAGE59
   U26 CR56 VSS_CR56 GENOA_SP5-SOCKET6096_13568-001,SMLF,IO,DGA^6000030     I4 @T6G_MB_LIB.T6G(SCH_1):PAGE59
   U26 CR58 VSS_CR58 GENOA_SP5-SOCKET6096_13568-001,SMLF,IO,DGA^6000030     I4 @T6G_MB_LIB.T6G(SCH_1):PAGE59
   U26 CR61 VSS_CR61 GENOA_SP5-SOCKET6096_13568-001,SMLF,IO,DGA^6000030     I4 @T6G_MB_LIB.T6G(SCH_1):PAGE59
   U26 CR63 VSS_CR63 GENOA_SP5-SOCKET6096_13568-001,SMLF,IO,DGA^6000030     I4 @T6G_MB_LIB.T6G(SCH_1):PAGE59
   U26 CR65 VSS_CR65 GENOA_SP5-SOCKET6096_13568-001,SMLF,IO,DGA^6000030     I4 @T6G_MB_LIB.T6G(SCH_1):PAGE59
   U26 CR68 VSS_CR68 GENOA_SP5-SOCKET6096_13568-001,SMLF,IO,DGA^6000030     I4 @T6G_MB_LIB.T6G(SCH_1):PAGE59
   U26 CR70 VSS_CR70 GENOA_SP5-SOCKET6096_13568-001,SMLF,IO,DGA^6000030     I4 @T6G_MB_LIB.T6G(SCH_1):PAGE59
   U26 CR72 VSS_CR72 GENOA_SP5-SOCKET6096_13568-001,SMLF,IO,DGA^6000030     I4 @T6G_MB_LIB.T6G(SCH_1):PAGE59
   U26 CR75 VSS_CR75 GENOA_SP5-SOCKET6096_13568-001,SMLF,IO,DGA^6000030     I4 @T6G_MB_LIB.T6G(SCH_1):PAGE59
   U26  CT3 VSS_CT3 GENOA_SP5-SOCKET6096_13568-001,SMLF,IO,DGA^6000030     I4 @T6G_MB_LIB.T6G(SCH_1):PAGE59
   U26  CT8 VSS_CT8 GENOA_SP5-SOCKET6096_13568-001,SMLF,IO,DGA^6000030     I4 @T6G_MB_LIB.T6G(SCH_1):PAGE59
   U26 CT10 VSS_CT10 GENOA_SP5-SOCKET6096_13568-001,SMLF,IO,DGA^6000030     I4 @T6G_MB_LIB.T6G(SCH_1):PAGE59
   U26 CT15 VSS_CT15 GENOA_SP5-SOCKET6096_13568-001,SMLF,IO,DGA^6000030     I4 @T6G_MB_LIB.T6G(SCH_1):PAGE59
   U26 CT17 VSS_CT17 GENOA_SP5-SOCKET6096_13568-001,SMLF,IO,DGA^6000030     I4 @T6G_MB_LIB.T6G(SCH_1):PAGE59
   U26 CT23 VSS_CT23 GENOA_SP5-SOCKET6096_13568-001,SMLF,IO,DGA^6000030     I4 @T6G_MB_LIB.T6G(SCH_1):PAGE59
   U26 CT24 VSS_CT24 GENOA_SP5-SOCKET6096_13568-001,SMLF,IO,DGA^6000030     I4 @T6G_MB_LIB.T6G(SCH_1):PAGE59
   U26 CT25 VSS_CT25 GENOA_SP5-SOCKET6096_13568-001,SMLF,IO,DGA^6000030     I4 @T6G_MB_LIB.T6G(SCH_1):PAGE59
   U26 CT26 VSS_CT26 GENOA_SP5-SOCKET6096_13568-001,SMLF,IO,DGA^6000030     I4 @T6G_MB_LIB.T6G(SCH_1):PAGE59
   U26 CT27 VSS_CT27 GENOA_SP5-SOCKET6096_13568-001,SMLF,IO,DGA^6000030     I4 @T6G_MB_LIB.T6G(SCH_1):PAGE59
   U26 CT28 VSS_CT28 GENOA_SP5-SOCKET6096_13568-001,SMLF,IO,DGA^6000030     I4 @T6G_MB_LIB.T6G(SCH_1):PAGE59
   U26 CT29 VSS_CT29 GENOA_SP5-SOCKET6096_13568-001,SMLF,IO,DGA^6000030     I4 @T6G_MB_LIB.T6G(SCH_1):PAGE59
   U26 CT30 VSS_CT30 GENOA_SP5-SOCKET6096_13568-001,SMLF,IO,DGA^6000030     I4 @T6G_MB_LIB.T6G(SCH_1):PAGE59
   U26 CT31 VSS_CT31 GENOA_SP5-SOCKET6096_13568-001,SMLF,IO,DGA^6000030     I4 @T6G_MB_LIB.T6G(SCH_1):PAGE59
   U26 CT32 VSS_CT32 GENOA_SP5-SOCKET6096_13568-001,SMLF,IO,DGA^6000030     I4 @T6G_MB_LIB.T6G(SCH_1):PAGE59
   U26 CT33 VSS_CT33 GENOA_SP5-SOCKET6096_13568-001,SMLF,IO,DGA^6000030     I4 @T6G_MB_LIB.T6G(SCH_1):PAGE59
   U26 CT34 VSS_CT34 GENOA_SP5-SOCKET6096_13568-001,SMLF,IO,DGA^6000030     I4 @T6G_MB_LIB.T6G(SCH_1):PAGE59
   U26 CT37 VSS_CT37 GENOA_SP5-SOCKET6096_13568-001,SMLF,IO,DGA^6000030     I4 @T6G_MB_LIB.T6G(SCH_1):PAGE59
   U26 CT39 VSS_CT39 GENOA_SP5-SOCKET6096_13568-001,SMLF,IO,DGA^6000030     I4 @T6G_MB_LIB.T6G(SCH_1):PAGE59
   U26 CT42 VSS_CT42 GENOA_SP5-SOCKET6096_13568-001,SMLF,IO,DGA^6000030     I4 @T6G_MB_LIB.T6G(SCH_1):PAGE59
   U26 CT43 VSS_CT43 GENOA_SP5-SOCKET6096_13568-001,SMLF,IO,DGA^6000030     I4 @T6G_MB_LIB.T6G(SCH_1):PAGE59
   U26 CT44 VSS_CT44 GENOA_SP5-SOCKET6096_13568-001,SMLF,IO,DGA^6000030     I4 @T6G_MB_LIB.T6G(SCH_1):PAGE59
   U26 CT45 VSS_CT45 GENOA_SP5-SOCKET6096_13568-001,SMLF,IO,DGA^6000030     I4 @T6G_MB_LIB.T6G(SCH_1):PAGE59
   U26 CT46 VSS_CT46 GENOA_SP5-SOCKET6096_13568-001,SMLF,IO,DGA^6000030     I4 @T6G_MB_LIB.T6G(SCH_1):PAGE59
   U26 CT47 VSS_CT47 GENOA_SP5-SOCKET6096_13568-001,SMLF,IO,DGA^6000030     I4 @T6G_MB_LIB.T6G(SCH_1):PAGE59
   U26 CT48 VSS_CT48 GENOA_SP5-SOCKET6096_13568-001,SMLF,IO,DGA^6000030     I4 @T6G_MB_LIB.T6G(SCH_1):PAGE59
   U26 CT49 VSS_CT49 GENOA_SP5-SOCKET6096_13568-001,SMLF,IO,DGA^6000030     I4 @T6G_MB_LIB.T6G(SCH_1):PAGE59
   U26 CT50 VSS_CT50 GENOA_SP5-SOCKET6096_13568-001,SMLF,IO,DGA^6000030     I4 @T6G_MB_LIB.T6G(SCH_1):PAGE59
   U26 CT51 VSS_CT51 GENOA_SP5-SOCKET6096_13568-001,SMLF,IO,DGA^6000030     I4 @T6G_MB_LIB.T6G(SCH_1):PAGE59
   U26 CT53 VSS_CT53 GENOA_SP5-SOCKET6096_13568-001,SMLF,IO,DGA^6000030     I4 @T6G_MB_LIB.T6G(SCH_1):PAGE59
   U26 CT59 VSS_CT59 GENOA_SP5-SOCKET6096_13568-001,SMLF,IO,DGA^6000030     I4 @T6G_MB_LIB.T6G(SCH_1):PAGE59
   U26 CT61 VSS_CT61 GENOA_SP5-SOCKET6096_13568-001,SMLF,IO,DGA^6000030     I4 @T6G_MB_LIB.T6G(SCH_1):PAGE59
   U26 CT66 VSS_CT66 GENOA_SP5-SOCKET6096_13568-001,SMLF,IO,DGA^6000030     I4 @T6G_MB_LIB.T6G(SCH_1):PAGE59
   U26 CT68 VSS_CT68 GENOA_SP5-SOCKET6096_13568-001,SMLF,IO,DGA^6000030     I4 @T6G_MB_LIB.T6G(SCH_1):PAGE59
   U26 CT73 VSS_CT73 GENOA_SP5-SOCKET6096_13568-001,SMLF,IO,DGA^6000030     I4 @T6G_MB_LIB.T6G(SCH_1):PAGE59
   U26  CU1 VSS_CU1 GENOA_SP5-SOCKET6096_13568-001,SMLF,IO,DGA^6000030     I4 @T6G_MB_LIB.T6G(SCH_1):PAGE59
   U26  CU4 VSS_CU4 GENOA_SP5-SOCKET6096_13568-001,SMLF,IO,DGA^6000030     I4 @T6G_MB_LIB.T6G(SCH_1):PAGE59
   U26  CU6 VSS_CU6 GENOA_SP5-SOCKET6096_13568-001,SMLF,IO,DGA^6000030     I4 @T6G_MB_LIB.T6G(SCH_1):PAGE59
   U26  CU8 VSS_CU8 GENOA_SP5-SOCKET6096_13568-001,SMLF,IO,DGA^6000030     I4 @T6G_MB_LIB.T6G(SCH_1):PAGE59
   U26 CU11 VSS_CU11 GENOA_SP5-SOCKET6096_13568-001,SMLF,IO,DGA^6000030     I4 @T6G_MB_LIB.T6G(SCH_1):PAGE59
   U26 CU13 VSS_CU13 GENOA_SP5-SOCKET6096_13568-001,SMLF,IO,DGA^6000030     I4 @T6G_MB_LIB.T6G(SCH_1):PAGE59
   U26 CU15 VSS_CU15 GENOA_SP5-SOCKET6096_13568-001,SMLF,IO,DGA^6000030     I4 @T6G_MB_LIB.T6G(SCH_1):PAGE59
   U26 CU18 VSS_CU18 GENOA_SP5-SOCKET6096_13568-001,SMLF,IO,DGA^6000030     I4 @T6G_MB_LIB.T6G(SCH_1):PAGE59
   U26 CU20 VSS_CU20 GENOA_SP5-SOCKET6096_13568-001,SMLF,IO,DGA^6000030     I4 @T6G_MB_LIB.T6G(SCH_1):PAGE59
   U26 CU22 VSS_CU22 GENOA_SP5-SOCKET6096_13568-001,SMLF,IO,DGA^6000030     I4 @T6G_MB_LIB.T6G(SCH_1):PAGE59
   U26 CU25 VSS_CU25 GENOA_SP5-SOCKET6096_13568-001,SMLF,IO,DGA^6000030     I4 @T6G_MB_LIB.T6G(SCH_1):PAGE59
   U26 CU28 VSS_CU28 GENOA_SP5-SOCKET6096_13568-001,SMLF,IO,DGA^6000030     I4 @T6G_MB_LIB.T6G(SCH_1):PAGE59
   U26 CU31 VSS_CU31 GENOA_SP5-SOCKET6096_13568-001,SMLF,IO,DGA^6000030     I4 @T6G_MB_LIB.T6G(SCH_1):PAGE59
   U26 CU34 VSS_CU34 GENOA_SP5-SOCKET6096_13568-001,SMLF,IO,DGA^6000030     I4 @T6G_MB_LIB.T6G(SCH_1):PAGE59
   U26 CU42 VSS_CU42 GENOA_SP5-SOCKET6096_13568-001,SMLF,IO,DGA^6000030     I4 @T6G_MB_LIB.T6G(SCH_1):PAGE59
   U26 CU45 VSS_CU45 GENOA_SP5-SOCKET6096_13568-001,SMLF,IO,DGA^6000030     I4 @T6G_MB_LIB.T6G(SCH_1):PAGE59
   U26 CU48 VSS_CU48 GENOA_SP5-SOCKET6096_13568-001,SMLF,IO,DGA^6000030     I4 @T6G_MB_LIB.T6G(SCH_1):PAGE59
   U26 CU51 VSS_CU51 GENOA_SP5-SOCKET6096_13568-001,SMLF,IO,DGA^6000030     I4 @T6G_MB_LIB.T6G(SCH_1):PAGE59
   U26 CU54 VSS_CU54 GENOA_SP5-SOCKET6096_13568-001,SMLF,IO,DGA^6000030     I4 @T6G_MB_LIB.T6G(SCH_1):PAGE59
   U26 CU56 VSS_CU56 GENOA_SP5-SOCKET6096_13568-001,SMLF,IO,DGA^6000030     I4 @T6G_MB_LIB.T6G(SCH_1):PAGE59
   U26 CU61 VSS_CU61 GENOA_SP5-SOCKET6096_13568-001,SMLF,IO,DGA^6000030     I4 @T6G_MB_LIB.T6G(SCH_1):PAGE59
   U26 CU63 VSS_CU63 GENOA_SP5-SOCKET6096_13568-001,SMLF,IO,DGA^6000030     I4 @T6G_MB_LIB.T6G(SCH_1):PAGE59
   U26 CU65 VSS_CU65 GENOA_SP5-SOCKET6096_13568-001,SMLF,IO,DGA^6000030     I4 @T6G_MB_LIB.T6G(SCH_1):PAGE59
   U26 CU68 VSS_CU68 GENOA_SP5-SOCKET6096_13568-001,SMLF,IO,DGA^6000030     I4 @T6G_MB_LIB.T6G(SCH_1):PAGE59
   U26 CU70 VSS_CU70 GENOA_SP5-SOCKET6096_13568-001,SMLF,IO,DGA^6000030     I4 @T6G_MB_LIB.T6G(SCH_1):PAGE59
   U26 CU72 VSS_CU72 GENOA_SP5-SOCKET6096_13568-001,SMLF,IO,DGA^6000030     I4 @T6G_MB_LIB.T6G(SCH_1):PAGE59
   U26 CU75 VSS_CU75 GENOA_SP5-SOCKET6096_13568-001,SMLF,IO,DGA^6000030     I4 @T6G_MB_LIB.T6G(SCH_1):PAGE59
   U26  CV3 VSS_CV3 GENOA_SP5-SOCKET6096_13568-001,SMLF,IO,DGA^6000030     I4 @T6G_MB_LIB.T6G(SCH_1):PAGE59
   U26  CV5 VSS_CV5 GENOA_SP5-SOCKET6096_13568-001,SMLF,IO,DGA^6000030     I4 @T6G_MB_LIB.T6G(SCH_1):PAGE59
   U26  CV8 VSS_CV8 GENOA_SP5-SOCKET6096_13568-001,SMLF,IO,DGA^6000030     I4 @T6G_MB_LIB.T6G(SCH_1):PAGE59
   U26 CV10 VSS_CV10 GENOA_SP5-SOCKET6096_13568-001,SMLF,IO,DGA^6000030     I4 @T6G_MB_LIB.T6G(SCH_1):PAGE59
   U26 CV12 VSS_CV12 GENOA_SP5-SOCKET6096_13568-001,SMLF,IO,DGA^6000030     I4 @T6G_MB_LIB.T6G(SCH_1):PAGE59
   U26 CV15 VSS_CV15 GENOA_SP5-SOCKET6096_13568-001,SMLF,IO,DGA^6000030     I4 @T6G_MB_LIB.T6G(SCH_1):PAGE59
   U26 CV17 VSS_CV17 GENOA_SP5-SOCKET6096_13568-001,SMLF,IO,DGA^6000030     I4 @T6G_MB_LIB.T6G(SCH_1):PAGE59
   U26 CV19 VSS_CV19 GENOA_SP5-SOCKET6096_13568-001,SMLF,IO,DGA^6000030     I4 @T6G_MB_LIB.T6G(SCH_1):PAGE59
   U26 CV22 VSS_CV22 GENOA_SP5-SOCKET6096_13568-001,SMLF,IO,DGA^6000030     I4 @T6G_MB_LIB.T6G(SCH_1):PAGE59
   U26 CV25 VSS_CV25 GENOA_SP5-SOCKET6096_13568-001,SMLF,IO,DGA^6000030     I4 @T6G_MB_LIB.T6G(SCH_1):PAGE59
   U26 CV28 VSS_CV28 GENOA_SP5-SOCKET6096_13568-001,SMLF,IO,DGA^6000030     I4 @T6G_MB_LIB.T6G(SCH_1):PAGE59
   U26 CV31 VSS_CV31 GENOA_SP5-SOCKET6096_13568-001,SMLF,IO,DGA^6000030     I4 @T6G_MB_LIB.T6G(SCH_1):PAGE59
   U26 CV34 VSS_CV34 GENOA_SP5-SOCKET6096_13568-001,SMLF,IO,DGA^6000030     I4 @T6G_MB_LIB.T6G(SCH_1):PAGE59
   U26 CV37 VSS_CV37 GENOA_SP5-SOCKET6096_13568-001,SMLF,IO,DGA^6000030     I4 @T6G_MB_LIB.T6G(SCH_1):PAGE59
   U26 CV39 VSS_CV39 GENOA_SP5-SOCKET6096_13568-001,SMLF,IO,DGA^6000030     I4 @T6G_MB_LIB.T6G(SCH_1):PAGE59
   U26 CV42 VSS_CV42 GENOA_SP5-SOCKET6096_13568-001,SMLF,IO,DGA^6000030     I4 @T6G_MB_LIB.T6G(SCH_1):PAGE59
   U26 CV45 VSS_CV45 GENOA_SP5-SOCKET6096_13568-001,SMLF,IO,DGA^6000030     I4 @T6G_MB_LIB.T6G(SCH_1):PAGE59
   U26 CV48 VSS_CV48 GENOA_SP5-SOCKET6096_13568-001,SMLF,IO,DGA^6000030     I4 @T6G_MB_LIB.T6G(SCH_1):PAGE59
   U26 CV51 VSS_CV51 GENOA_SP5-SOCKET6096_13568-001,SMLF,IO,DGA^6000030     I4 @T6G_MB_LIB.T6G(SCH_1):PAGE59
   U26 CV54 VSS_CV54 GENOA_SP5-SOCKET6096_13568-001,SMLF,IO,DGA^6000030     I4 @T6G_MB_LIB.T6G(SCH_1):PAGE59
   U26 CV57 VSS_CV57 GENOA_SP5-SOCKET6096_13568-001,SMLF,IO,DGA^6000030     I4 @T6G_MB_LIB.T6G(SCH_1):PAGE59
   U26 CV59 VSS_CV59 GENOA_SP5-SOCKET6096_13568-001,SMLF,IO,DGA^6000030     I4 @T6G_MB_LIB.T6G(SCH_1):PAGE59
   U26 CV61 VSS_CV61 GENOA_SP5-SOCKET6096_13568-001,SMLF,IO,DGA^6000030     I4 @T6G_MB_LIB.T6G(SCH_1):PAGE59
   U26 CV64 VSS_CV64 GENOA_SP5-SOCKET6096_13568-001,SMLF,IO,DGA^6000030     I4 @T6G_MB_LIB.T6G(SCH_1):PAGE59
   U26 CV66 VSS_CV66 GENOA_SP5-SOCKET6096_13568-001,SMLF,IO,DGA^6000030     I4 @T6G_MB_LIB.T6G(SCH_1):PAGE59
   U26 CV68 VSS_CV68 GENOA_SP5-SOCKET6096_13568-001,SMLF,IO,DGA^6000030     I4 @T6G_MB_LIB.T6G(SCH_1):PAGE59
   U26 CV71 VSS_CV71 GENOA_SP5-SOCKET6096_13568-001,SMLF,IO,DGA^6000030     I4 @T6G_MB_LIB.T6G(SCH_1):PAGE59
   U26 CV73 VSS_CV73 GENOA_SP5-SOCKET6096_13568-001,SMLF,IO,DGA^6000030     I4 @T6G_MB_LIB.T6G(SCH_1):PAGE59
   U26  CW1 VSS_CW1 GENOA_SP5-SOCKET6096_13568-001,SMLF,IO,DGA^6000030     I4 @T6G_MB_LIB.T6G(SCH_1):PAGE59
   U26  CW6 VSS_CW6 GENOA_SP5-SOCKET6096_13568-001,SMLF,IO,DGA^6000030     I4 @T6G_MB_LIB.T6G(SCH_1):PAGE59
   U26  CW8 VSS_CW8 GENOA_SP5-SOCKET6096_13568-001,SMLF,IO,DGA^6000030     I4 @T6G_MB_LIB.T6G(SCH_1):PAGE59
   U26 CW13 VSS_CW13 GENOA_SP5-SOCKET6096_13568-001,SMLF,IO,DGA^6000030     I4 @T6G_MB_LIB.T6G(SCH_1):PAGE59
   U26 CW15 VSS_CW15 GENOA_SP5-SOCKET6096_13568-001,SMLF,IO,DGA^6000030     I4 @T6G_MB_LIB.T6G(SCH_1):PAGE59
   U26 CW20 VSS_CW20 GENOA_SP5-SOCKET6096_13568-001,SMLF,IO,DGA^6000030     I4 @T6G_MB_LIB.T6G(SCH_1):PAGE59
   U26 CW22 VSS_CW22 GENOA_SP5-SOCKET6096_13568-001,SMLF,IO,DGA^6000030     I4 @T6G_MB_LIB.T6G(SCH_1):PAGE59
   U26 CW25 VSS_CW25 GENOA_SP5-SOCKET6096_13568-001,SMLF,IO,DGA^6000030     I4 @T6G_MB_LIB.T6G(SCH_1):PAGE59
   U26 CW28 VSS_CW28 GENOA_SP5-SOCKET6096_13568-001,SMLF,IO,DGA^6000030     I4 @T6G_MB_LIB.T6G(SCH_1):PAGE59
   U26 CW31 VSS_CW31 GENOA_SP5-SOCKET6096_13568-001,SMLF,IO,DGA^6000030     I4 @T6G_MB_LIB.T6G(SCH_1):PAGE59
   U26 CW34 VSS_CW34 GENOA_SP5-SOCKET6096_13568-001,SMLF,IO,DGA^6000030     I4 @T6G_MB_LIB.T6G(SCH_1):PAGE59
   U26 CW35 VSS_CW35 GENOA_SP5-SOCKET6096_13568-001,SMLF,IO,DGA^6000030     I4 @T6G_MB_LIB.T6G(SCH_1):PAGE59
   U26 CW36 VSS_CW36 GENOA_SP5-SOCKET6096_13568-001,SMLF,IO,DGA^6000030     I4 @T6G_MB_LIB.T6G(SCH_1):PAGE59
   U26 CW40 VSS_CW40 GENOA_SP5-SOCKET6096_13568-001,SMLF,IO,DGA^6000030     I4 @T6G_MB_LIB.T6G(SCH_1):PAGE59
   U26 CW41 VSS_CW41 GENOA_SP5-SOCKET6096_13568-001,SMLF,IO,DGA^6000030     I4 @T6G_MB_LIB.T6G(SCH_1):PAGE59
   U26 CW42 VSS_CW42 GENOA_SP5-SOCKET6096_13568-001,SMLF,IO,DGA^6000030     I4 @T6G_MB_LIB.T6G(SCH_1):PAGE59
   U26 CW45 VSS_CW45 GENOA_SP5-SOCKET6096_13568-001,SMLF,IO,DGA^6000030     I4 @T6G_MB_LIB.T6G(SCH_1):PAGE59
   U26 CW48 VSS_CW48 GENOA_SP5-SOCKET6096_13568-001,SMLF,IO,DGA^6000030     I4 @T6G_MB_LIB.T6G(SCH_1):PAGE59
   U26 CW51 VSS_CW51 GENOA_SP5-SOCKET6096_13568-001,SMLF,IO,DGA^6000030     I4 @T6G_MB_LIB.T6G(SCH_1):PAGE59
   U26 CW54 VSS_CW54 GENOA_SP5-SOCKET6096_13568-001,SMLF,IO,DGA^6000030     I4 @T6G_MB_LIB.T6G(SCH_1):PAGE59
   U26 CW56 VSS_CW56 GENOA_SP5-SOCKET6096_13568-001,SMLF,IO,DGA^6000030     I4 @T6G_MB_LIB.T6G(SCH_1):PAGE59
   U26 CW61 VSS_CW61 GENOA_SP5-SOCKET6096_13568-001,SMLF,IO,DGA^6000030     I4 @T6G_MB_LIB.T6G(SCH_1):PAGE59
   U26 CW63 VSS_CW63 GENOA_SP5-SOCKET6096_13568-001,SMLF,IO,DGA^6000030     I4 @T6G_MB_LIB.T6G(SCH_1):PAGE59
   U26 CW68 VSS_CW68 GENOA_SP5-SOCKET6096_13568-001,SMLF,IO,DGA^6000030     I4 @T6G_MB_LIB.T6G(SCH_1):PAGE59
   U26 CW70 VSS_CW70 GENOA_SP5-SOCKET6096_13568-001,SMLF,IO,DGA^6000030     I4 @T6G_MB_LIB.T6G(SCH_1):PAGE59
   U26 CW75 VSS_CW75 GENOA_SP5-SOCKET6096_13568-001,SMLF,IO,DGA^6000030     I4 @T6G_MB_LIB.T6G(SCH_1):PAGE59
   U26  CY3 VSS_CY3 GENOA_SP5-SOCKET6096_13568-001,SMLF,IO,DGA^6000030     I4 @T6G_MB_LIB.T6G(SCH_1):PAGE59
   U26  CY5 VSS_CY5 GENOA_SP5-SOCKET6096_13568-001,SMLF,IO,DGA^6000030     I4 @T6G_MB_LIB.T6G(SCH_1):PAGE59
   U26  CY8 VSS_CY8 GENOA_SP5-SOCKET6096_13568-001,SMLF,IO,DGA^6000030     I4 @T6G_MB_LIB.T6G(SCH_1):PAGE59
   U26 CY10 VSS_CY10 GENOA_SP5-SOCKET6096_13568-001,SMLF,IO,DGA^6000030     I4 @T6G_MB_LIB.T6G(SCH_1):PAGE59
   U26 CY12 VSS_CY12 GENOA_SP5-SOCKET6096_13568-001,SMLF,IO,DGA^6000030     I4 @T6G_MB_LIB.T6G(SCH_1):PAGE59
   U26 CY15 VSS_CY15 GENOA_SP5-SOCKET6096_13568-001,SMLF,IO,DGA^6000030     I4 @T6G_MB_LIB.T6G(SCH_1):PAGE59
   U26 CY17 VSS_CY17 GENOA_SP5-SOCKET6096_13568-001,SMLF,IO,DGA^6000030     I4 @T6G_MB_LIB.T6G(SCH_1):PAGE59
   U26 CY19 VSS_CY19 GENOA_SP5-SOCKET6096_13568-001,SMLF,IO,DGA^6000030     I4 @T6G_MB_LIB.T6G(SCH_1):PAGE59
   U26 CY23 VSS_CY23 GENOA_SP5-SOCKET6096_13568-001,SMLF,IO,DGA^6000030     I4 @T6G_MB_LIB.T6G(SCH_1):PAGE59
   U26 CY24 VSS_CY24 GENOA_SP5-SOCKET6096_13568-001,SMLF,IO,DGA^6000030     I4 @T6G_MB_LIB.T6G(SCH_1):PAGE59
   U26 CY25 VSS_CY25 GENOA_SP5-SOCKET6096_13568-001,SMLF,IO,DGA^6000030     I4 @T6G_MB_LIB.T6G(SCH_1):PAGE59
   U26 CY26 VSS_CY26 GENOA_SP5-SOCKET6096_13568-001,SMLF,IO,DGA^6000030     I4 @T6G_MB_LIB.T6G(SCH_1):PAGE59
   U26 CY27 VSS_CY27 GENOA_SP5-SOCKET6096_13568-001,SMLF,IO,DGA^6000030     I4 @T6G_MB_LIB.T6G(SCH_1):PAGE59
   U26 CY28 VSS_CY28 GENOA_SP5-SOCKET6096_13568-001,SMLF,IO,DGA^6000030     I4 @T6G_MB_LIB.T6G(SCH_1):PAGE59
   U26 CY29 VSS_CY29 GENOA_SP5-SOCKET6096_13568-001,SMLF,IO,DGA^6000030     I4 @T6G_MB_LIB.T6G(SCH_1):PAGE59
   U26 CY30 VSS_CY30 GENOA_SP5-SOCKET6096_13568-001,SMLF,IO,DGA^6000030     I4 @T6G_MB_LIB.T6G(SCH_1):PAGE59
   U26 CY31 VSS_CY31 GENOA_SP5-SOCKET6096_13568-001,SMLF,IO,DGA^6000030     I4 @T6G_MB_LIB.T6G(SCH_1):PAGE59
   U26 CY32 VSS_CY32 GENOA_SP5-SOCKET6096_13568-001,SMLF,IO,DGA^6000030     I4 @T6G_MB_LIB.T6G(SCH_1):PAGE59
   U26 CY33 VSS_CY33 GENOA_SP5-SOCKET6096_13568-001,SMLF,IO,DGA^6000030     I4 @T6G_MB_LIB.T6G(SCH_1):PAGE59
   U26 CY34 VSS_CY34 GENOA_SP5-SOCKET6096_13568-001,SMLF,IO,DGA^6000030     I4 @T6G_MB_LIB.T6G(SCH_1):PAGE59
   U26 CY37 VSS_CY37 GENOA_SP5-SOCKET6096_13568-001,SMLF,IO,DGA^6000030     I4 @T6G_MB_LIB.T6G(SCH_1):PAGE59
   U26 CY39 VSS_CY39 GENOA_SP5-SOCKET6096_13568-001,SMLF,IO,DGA^6000030     I4 @T6G_MB_LIB.T6G(SCH_1):PAGE59
   U26 CY42 VSS_CY42 GENOA_SP5-SOCKET6096_13568-001,SMLF,IO,DGA^6000030     I4 @T6G_MB_LIB.T6G(SCH_1):PAGE59
   U26 CY43 VSS_CY43 GENOA_SP5-SOCKET6096_13568-001,SMLF,IO,DGA^6000030     I4 @T6G_MB_LIB.T6G(SCH_1):PAGE59
   U26 CY44 VSS_CY44 GENOA_SP5-SOCKET6096_13568-001,SMLF,IO,DGA^6000030     I4 @T6G_MB_LIB.T6G(SCH_1):PAGE59
   U26 CY45 VSS_CY45 GENOA_SP5-SOCKET6096_13568-001,SMLF,IO,DGA^6000030     I4 @T6G_MB_LIB.T6G(SCH_1):PAGE59
   U26 CY46 VSS_CY46 GENOA_SP5-SOCKET6096_13568-001,SMLF,IO,DGA^6000030     I4 @T6G_MB_LIB.T6G(SCH_1):PAGE59
   U26 CY47 VSS_CY47 GENOA_SP5-SOCKET6096_13568-001,SMLF,IO,DGA^6000030     I4 @T6G_MB_LIB.T6G(SCH_1):PAGE59
   U26 CY48 VSS_CY48 GENOA_SP5-SOCKET6096_13568-001,SMLF,IO,DGA^6000030     I4 @T6G_MB_LIB.T6G(SCH_1):PAGE59
   U26 CY49 VSS_CY49 GENOA_SP5-SOCKET6096_13568-001,SMLF,IO,DGA^6000030     I4 @T6G_MB_LIB.T6G(SCH_1):PAGE59
   U26 CY50 VSS_CY50 GENOA_SP5-SOCKET6096_13568-001,SMLF,IO,DGA^6000030     I4 @T6G_MB_LIB.T6G(SCH_1):PAGE59
   U26 CY51 VSS_CY51 GENOA_SP5-SOCKET6096_13568-001,SMLF,IO,DGA^6000030     I4 @T6G_MB_LIB.T6G(SCH_1):PAGE59
   U26 CY52 VSS_CY52 GENOA_SP5-SOCKET6096_13568-001,SMLF,IO,DGA^6000030     I4 @T6G_MB_LIB.T6G(SCH_1):PAGE59
   U26 CY53 VSS_CY53 GENOA_SP5-SOCKET6096_13568-001,SMLF,IO,DGA^6000030     I4 @T6G_MB_LIB.T6G(SCH_1):PAGE59
   U26 CY59 VSS_CY59 GENOA_SP5-SOCKET6096_13568-001,SMLF,IO,DGA^6000030     I4 @T6G_MB_LIB.T6G(SCH_1):PAGE59
   U26 CY61 VSS_CY61 GENOA_SP5-SOCKET6096_13568-001,SMLF,IO,DGA^6000030     I4 @T6G_MB_LIB.T6G(SCH_1):PAGE59
   U26 CY64 VSS_CY64 GENOA_SP5-SOCKET6096_13568-001,SMLF,IO,DGA^6000030     I4 @T6G_MB_LIB.T6G(SCH_1):PAGE59
   U26 CY66 VSS_CY66 GENOA_SP5-SOCKET6096_13568-001,SMLF,IO,DGA^6000030     I4 @T6G_MB_LIB.T6G(SCH_1):PAGE59
   U26 CY68 VSS_CY68 GENOA_SP5-SOCKET6096_13568-001,SMLF,IO,DGA^6000030     I4 @T6G_MB_LIB.T6G(SCH_1):PAGE59
   U26 CY71 VSS_CY71 GENOA_SP5-SOCKET6096_13568-001,SMLF,IO,DGA^6000030     I4 @T6G_MB_LIB.T6G(SCH_1):PAGE59
   U26 CY73 VSS_CY73 GENOA_SP5-SOCKET6096_13568-001,SMLF,IO,DGA^6000030     I4 @T6G_MB_LIB.T6G(SCH_1):PAGE59
   U26  DA1 VSS_DA1 GENOA_SP5-SOCKET6096_13568-001,SMLF,IO,DGA^6000030     I4 @T6G_MB_LIB.T6G(SCH_1):PAGE59
   U26  DA4 VSS_DA4 GENOA_SP5-SOCKET6096_13568-001,SMLF,IO,DGA^6000030     I4 @T6G_MB_LIB.T6G(SCH_1):PAGE59
   U26  DA6 VSS_DA6 GENOA_SP5-SOCKET6096_13568-001,SMLF,IO,DGA^6000030     I4 @T6G_MB_LIB.T6G(SCH_1):PAGE59
   U26  DA8 VSS_DA8 GENOA_SP5-SOCKET6096_13568-001,SMLF,IO,DGA^6000030     I4 @T6G_MB_LIB.T6G(SCH_1):PAGE59
   U26 DA11 VSS_DA11 GENOA_SP5-SOCKET6096_13568-001,SMLF,IO,DGA^6000030     I4 @T6G_MB_LIB.T6G(SCH_1):PAGE59
   U26 DA13 VSS_DA13 GENOA_SP5-SOCKET6096_13568-001,SMLF,IO,DGA^6000030     I4 @T6G_MB_LIB.T6G(SCH_1):PAGE59
   U26 DA15 VSS_DA15 GENOA_SP5-SOCKET6096_13568-001,SMLF,IO,DGA^6000030     I4 @T6G_MB_LIB.T6G(SCH_1):PAGE59
   U26 DA18 VSS_DA18 GENOA_SP5-SOCKET6096_13568-001,SMLF,IO,DGA^6000030     I4 @T6G_MB_LIB.T6G(SCH_1):PAGE59
   U26 DA20 VSS_DA20 GENOA_SP5-SOCKET6096_13568-001,SMLF,IO,DGA^6000030     I4 @T6G_MB_LIB.T6G(SCH_1):PAGE59
   U26 DA22 VSS_DA22 GENOA_SP5-SOCKET6096_13568-001,SMLF,IO,DGA^6000030     I4 @T6G_MB_LIB.T6G(SCH_1):PAGE59
   U26 DA25 VSS_DA25 GENOA_SP5-SOCKET6096_13568-001,SMLF,IO,DGA^6000030     I4 @T6G_MB_LIB.T6G(SCH_1):PAGE59
   U26 DA28 VSS_DA28 GENOA_SP5-SOCKET6096_13568-001,SMLF,IO,DGA^6000030     I4 @T6G_MB_LIB.T6G(SCH_1):PAGE59
   U26 DA31 VSS_DA31 GENOA_SP5-SOCKET6096_13568-001,SMLF,IO,DGA^6000030     I4 @T6G_MB_LIB.T6G(SCH_1):PAGE59
   U26 DA34 VSS_DA34 GENOA_SP5-SOCKET6096_13568-001,SMLF,IO,DGA^6000030     I4 @T6G_MB_LIB.T6G(SCH_1):PAGE59
   U26 DA42 VSS_DA42 GENOA_SP5-SOCKET6096_13568-001,SMLF,IO,DGA^6000030     I4 @T6G_MB_LIB.T6G(SCH_1):PAGE59
   U26 DA45 VSS_DA45 GENOA_SP5-SOCKET6096_13568-001,SMLF,IO,DGA^6000030     I4 @T6G_MB_LIB.T6G(SCH_1):PAGE59
   U26 DA48 VSS_DA48 GENOA_SP5-SOCKET6096_13568-001,SMLF,IO,DGA^6000030     I4 @T6G_MB_LIB.T6G(SCH_1):PAGE59
   U26 DA51 VSS_DA51 GENOA_SP5-SOCKET6096_13568-001,SMLF,IO,DGA^6000030     I4 @T6G_MB_LIB.T6G(SCH_1):PAGE59
   U26 DA54 VSS_DA54 GENOA_SP5-SOCKET6096_13568-001,SMLF,IO,DGA^6000030     I4 @T6G_MB_LIB.T6G(SCH_1):PAGE59
   U26 DA58 VSS_DA58 GENOA_SP5-SOCKET6096_13568-001,SMLF,IO,DGA^6000030     I4 @T6G_MB_LIB.T6G(SCH_1):PAGE59
   U26 DA61 VSS_DA61 GENOA_SP5-SOCKET6096_13568-001,SMLF,IO,DGA^6000030     I4 @T6G_MB_LIB.T6G(SCH_1):PAGE59
   U26 DA63 VSS_DA63 GENOA_SP5-SOCKET6096_13568-001,SMLF,IO,DGA^6000030     I4 @T6G_MB_LIB.T6G(SCH_1):PAGE59
   U26 DA65 VSS_DA65 GENOA_SP5-SOCKET6096_13568-001,SMLF,IO,DGA^6000030     I4 @T6G_MB_LIB.T6G(SCH_1):PAGE59
   U26 DA68 VSS_DA68 GENOA_SP5-SOCKET6096_13568-001,SMLF,IO,DGA^6000030     I4 @T6G_MB_LIB.T6G(SCH_1):PAGE59
   U26 DA70 VSS_DA70 GENOA_SP5-SOCKET6096_13568-001,SMLF,IO,DGA^6000030     I4 @T6G_MB_LIB.T6G(SCH_1):PAGE59
   U26 AA42 VSS_AA42 GENOA_SP5-SOCKET6096_13568-001,SMLF,IO,DGA^6000030     I3 @T6G_MB_LIB.T6G(SCH_1):PAGE60
   U26 AA72 VSS_AA72 GENOA_SP5-SOCKET6096_13568-001,SMLF,IO,DGA^6000030     I3 @T6G_MB_LIB.T6G(SCH_1):PAGE60
   U26 AD31 VSS_AD31 GENOA_SP5-SOCKET6096_13568-001,SMLF,IO,DGA^6000030     I3 @T6G_MB_LIB.T6G(SCH_1):PAGE60
   U26  AE4 VSS_AE4 GENOA_SP5-SOCKET6096_13568-001,SMLF,IO,DGA^6000030     I3 @T6G_MB_LIB.T6G(SCH_1):PAGE60
   U26 AH33 VSS_AH33 GENOA_SP5-SOCKET6096_13568-001,SMLF,IO,DGA^6000030     I3 @T6G_MB_LIB.T6G(SCH_1):PAGE60
   U26 AJ13 VSS_AJ13 GENOA_SP5-SOCKET6096_13568-001,SMLF,IO,DGA^6000030     I3 @T6G_MB_LIB.T6G(SCH_1):PAGE60
   U26 AM37 VSS_AM37 GENOA_SP5-SOCKET6096_13568-001,SMLF,IO,DGA^6000030     I3 @T6G_MB_LIB.T6G(SCH_1):PAGE60
   U26 AN20 VSS_AN20 GENOA_SP5-SOCKET6096_13568-001,SMLF,IO,DGA^6000030     I3 @T6G_MB_LIB.T6G(SCH_1):PAGE60
   U26 BV42 VSS_BV42 GENOA_SP5-SOCKET6096_13568-001,SMLF,IO,DGA^6000030     I3 @T6G_MB_LIB.T6G(SCH_1):PAGE60
   U26 BW25 VSS_BW25 GENOA_SP5-SOCKET6096_13568-001,SMLF,IO,DGA^6000030     I3 @T6G_MB_LIB.T6G(SCH_1):PAGE60
   U26 CB44 VSS_CB44 GENOA_SP5-SOCKET6096_13568-001,SMLF,IO,DGA^6000030     I3 @T6G_MB_LIB.T6G(SCH_1):PAGE60
   U26 CC22 VSS_CC22 GENOA_SP5-SOCKET6096_13568-001,SMLF,IO,DGA^6000030     I3 @T6G_MB_LIB.T6G(SCH_1):PAGE60
   U26 CF46 VSS_CF46 GENOA_SP5-SOCKET6096_13568-001,SMLF,IO,DGA^6000030     I3 @T6G_MB_LIB.T6G(SCH_1):PAGE60
   U26 CG42 VSS_CG42 GENOA_SP5-SOCKET6096_13568-001,SMLF,IO,DGA^6000030     I3 @T6G_MB_LIB.T6G(SCH_1):PAGE60
   U26 CK10 VSS_CK10 GENOA_SP5-SOCKET6096_13568-001,SMLF,IO,DGA^6000030     I3 @T6G_MB_LIB.T6G(SCH_1):PAGE60
   U26 CK31 VSS_CK31 GENOA_SP5-SOCKET6096_13568-001,SMLF,IO,DGA^6000030     I3 @T6G_MB_LIB.T6G(SCH_1):PAGE60
   U26 CM50 VSS_CM50 GENOA_SP5-SOCKET6096_13568-001,SMLF,IO,DGA^6000030     I3 @T6G_MB_LIB.T6G(SCH_1):PAGE60
   U26 CN54 VSS_CN54 GENOA_SP5-SOCKET6096_13568-001,SMLF,IO,DGA^6000030     I3 @T6G_MB_LIB.T6G(SCH_1):PAGE60
   U26 CT52 VSS_CT52 GENOA_SP5-SOCKET6096_13568-001,SMLF,IO,DGA^6000030     I3 @T6G_MB_LIB.T6G(SCH_1):PAGE60
   U26 CU58 VSS_CU58 GENOA_SP5-SOCKET6096_13568-001,SMLF,IO,DGA^6000030     I3 @T6G_MB_LIB.T6G(SCH_1):PAGE60
   U26 CY57 VSS_CY57 GENOA_SP5-SOCKET6096_13568-001,SMLF,IO,DGA^6000030     I3 @T6G_MB_LIB.T6G(SCH_1):PAGE60
   U26 DA56 VSS_DA56 GENOA_SP5-SOCKET6096_13568-001,SMLF,IO,DGA^6000030     I3 @T6G_MB_LIB.T6G(SCH_1):PAGE60
   U26 DA72 VSS_DA72 GENOA_SP5-SOCKET6096_13568-001,SMLF,IO,DGA^6000030     I3 @T6G_MB_LIB.T6G(SCH_1):PAGE60
   U26 DA75 VSS_DA75 GENOA_SP5-SOCKET6096_13568-001,SMLF,IO,DGA^6000030     I3 @T6G_MB_LIB.T6G(SCH_1):PAGE60
   U26  DB3 VSS_DB3 GENOA_SP5-SOCKET6096_13568-001,SMLF,IO,DGA^6000030     I3 @T6G_MB_LIB.T6G(SCH_1):PAGE60
   U26  DB8 VSS_DB8 GENOA_SP5-SOCKET6096_13568-001,SMLF,IO,DGA^6000030     I3 @T6G_MB_LIB.T6G(SCH_1):PAGE60
   U26 DB10 VSS_DB10 GENOA_SP5-SOCKET6096_13568-001,SMLF,IO,DGA^6000030     I3 @T6G_MB_LIB.T6G(SCH_1):PAGE60
   U26 DB15 VSS_DB15 GENOA_SP5-SOCKET6096_13568-001,SMLF,IO,DGA^6000030     I3 @T6G_MB_LIB.T6G(SCH_1):PAGE60
   U26 DB17 VSS_DB17 GENOA_SP5-SOCKET6096_13568-001,SMLF,IO,DGA^6000030     I3 @T6G_MB_LIB.T6G(SCH_1):PAGE60
   U26 DB22 VSS_DB22 GENOA_SP5-SOCKET6096_13568-001,SMLF,IO,DGA^6000030     I3 @T6G_MB_LIB.T6G(SCH_1):PAGE60
   U26 DB25 VSS_DB25 GENOA_SP5-SOCKET6096_13568-001,SMLF,IO,DGA^6000030     I3 @T6G_MB_LIB.T6G(SCH_1):PAGE60
   U26 DB28 VSS_DB28 GENOA_SP5-SOCKET6096_13568-001,SMLF,IO,DGA^6000030     I3 @T6G_MB_LIB.T6G(SCH_1):PAGE60
   U26 DB31 VSS_DB31 GENOA_SP5-SOCKET6096_13568-001,SMLF,IO,DGA^6000030     I3 @T6G_MB_LIB.T6G(SCH_1):PAGE60
   U26 DB34 VSS_DB34 GENOA_SP5-SOCKET6096_13568-001,SMLF,IO,DGA^6000030     I3 @T6G_MB_LIB.T6G(SCH_1):PAGE60
   U26 DB37 VSS_DB37 GENOA_SP5-SOCKET6096_13568-001,SMLF,IO,DGA^6000030     I3 @T6G_MB_LIB.T6G(SCH_1):PAGE60
   U26 DB39 VSS_DB39 GENOA_SP5-SOCKET6096_13568-001,SMLF,IO,DGA^6000030     I3 @T6G_MB_LIB.T6G(SCH_1):PAGE60
   U26 DB42 VSS_DB42 GENOA_SP5-SOCKET6096_13568-001,SMLF,IO,DGA^6000030     I3 @T6G_MB_LIB.T6G(SCH_1):PAGE60
   U26 DB45 VSS_DB45 GENOA_SP5-SOCKET6096_13568-001,SMLF,IO,DGA^6000030     I3 @T6G_MB_LIB.T6G(SCH_1):PAGE60
   U26 DB48 VSS_DB48 GENOA_SP5-SOCKET6096_13568-001,SMLF,IO,DGA^6000030     I3 @T6G_MB_LIB.T6G(SCH_1):PAGE60
   U26 DB51 VSS_DB51 GENOA_SP5-SOCKET6096_13568-001,SMLF,IO,DGA^6000030     I3 @T6G_MB_LIB.T6G(SCH_1):PAGE60
   U26 DB54 VSS_DB54 GENOA_SP5-SOCKET6096_13568-001,SMLF,IO,DGA^6000030     I3 @T6G_MB_LIB.T6G(SCH_1):PAGE60
   U26 DB59 VSS_DB59 GENOA_SP5-SOCKET6096_13568-001,SMLF,IO,DGA^6000030     I3 @T6G_MB_LIB.T6G(SCH_1):PAGE60
   U26 DB61 VSS_DB61 GENOA_SP5-SOCKET6096_13568-001,SMLF,IO,DGA^6000030     I3 @T6G_MB_LIB.T6G(SCH_1):PAGE60
   U26 DB66 VSS_DB66 GENOA_SP5-SOCKET6096_13568-001,SMLF,IO,DGA^6000030     I3 @T6G_MB_LIB.T6G(SCH_1):PAGE60
   U26 DB68 VSS_DB68 GENOA_SP5-SOCKET6096_13568-001,SMLF,IO,DGA^6000030     I3 @T6G_MB_LIB.T6G(SCH_1):PAGE60
   U26 DB73 VSS_DB73 GENOA_SP5-SOCKET6096_13568-001,SMLF,IO,DGA^6000030     I3 @T6G_MB_LIB.T6G(SCH_1):PAGE60
   U26  DC1 VSS_DC1 GENOA_SP5-SOCKET6096_13568-001,SMLF,IO,DGA^6000030     I3 @T6G_MB_LIB.T6G(SCH_1):PAGE60
   U26  DC4 VSS_DC4 GENOA_SP5-SOCKET6096_13568-001,SMLF,IO,DGA^6000030     I3 @T6G_MB_LIB.T6G(SCH_1):PAGE60
   U26  DC6 VSS_DC6 GENOA_SP5-SOCKET6096_13568-001,SMLF,IO,DGA^6000030     I3 @T6G_MB_LIB.T6G(SCH_1):PAGE60
   U26  DC8 VSS_DC8 GENOA_SP5-SOCKET6096_13568-001,SMLF,IO,DGA^6000030     I3 @T6G_MB_LIB.T6G(SCH_1):PAGE60
   U26 DC11 VSS_DC11 GENOA_SP5-SOCKET6096_13568-001,SMLF,IO,DGA^6000030     I3 @T6G_MB_LIB.T6G(SCH_1):PAGE60
   U26 DC13 VSS_DC13 GENOA_SP5-SOCKET6096_13568-001,SMLF,IO,DGA^6000030     I3 @T6G_MB_LIB.T6G(SCH_1):PAGE60
   U26 DC15 VSS_DC15 GENOA_SP5-SOCKET6096_13568-001,SMLF,IO,DGA^6000030     I3 @T6G_MB_LIB.T6G(SCH_1):PAGE60
   U26 DC18 VSS_DC18 GENOA_SP5-SOCKET6096_13568-001,SMLF,IO,DGA^6000030     I3 @T6G_MB_LIB.T6G(SCH_1):PAGE60
   U26 DC20 VSS_DC20 GENOA_SP5-SOCKET6096_13568-001,SMLF,IO,DGA^6000030     I3 @T6G_MB_LIB.T6G(SCH_1):PAGE60
   U26 DC22 VSS_DC22 GENOA_SP5-SOCKET6096_13568-001,SMLF,IO,DGA^6000030     I3 @T6G_MB_LIB.T6G(SCH_1):PAGE60
   U26 DC25 VSS_DC25 GENOA_SP5-SOCKET6096_13568-001,SMLF,IO,DGA^6000030     I3 @T6G_MB_LIB.T6G(SCH_1):PAGE60
   U26 DC28 VSS_DC28 GENOA_SP5-SOCKET6096_13568-001,SMLF,IO,DGA^6000030     I3 @T6G_MB_LIB.T6G(SCH_1):PAGE60
   U26 DC31 VSS_DC31 GENOA_SP5-SOCKET6096_13568-001,SMLF,IO,DGA^6000030     I3 @T6G_MB_LIB.T6G(SCH_1):PAGE60
   U26 DC34 VSS_DC34 GENOA_SP5-SOCKET6096_13568-001,SMLF,IO,DGA^6000030     I3 @T6G_MB_LIB.T6G(SCH_1):PAGE60
   U26 DC42 VSS_DC42 GENOA_SP5-SOCKET6096_13568-001,SMLF,IO,DGA^6000030     I3 @T6G_MB_LIB.T6G(SCH_1):PAGE60
   U26 DC45 VSS_DC45 GENOA_SP5-SOCKET6096_13568-001,SMLF,IO,DGA^6000030     I3 @T6G_MB_LIB.T6G(SCH_1):PAGE60
   U26 DC48 VSS_DC48 GENOA_SP5-SOCKET6096_13568-001,SMLF,IO,DGA^6000030     I3 @T6G_MB_LIB.T6G(SCH_1):PAGE60
   U26 DC51 VSS_DC51 GENOA_SP5-SOCKET6096_13568-001,SMLF,IO,DGA^6000030     I3 @T6G_MB_LIB.T6G(SCH_1):PAGE60
   U26 DC54 VSS_DC54 GENOA_SP5-SOCKET6096_13568-001,SMLF,IO,DGA^6000030     I3 @T6G_MB_LIB.T6G(SCH_1):PAGE60
   U26 DC56 VSS_DC56 GENOA_SP5-SOCKET6096_13568-001,SMLF,IO,DGA^6000030     I3 @T6G_MB_LIB.T6G(SCH_1):PAGE60
   U26 DC58 VSS_DC58 GENOA_SP5-SOCKET6096_13568-001,SMLF,IO,DGA^6000030     I3 @T6G_MB_LIB.T6G(SCH_1):PAGE60
   U26 DC61 VSS_DC61 GENOA_SP5-SOCKET6096_13568-001,SMLF,IO,DGA^6000030     I3 @T6G_MB_LIB.T6G(SCH_1):PAGE60
   U26 DC63 VSS_DC63 GENOA_SP5-SOCKET6096_13568-001,SMLF,IO,DGA^6000030     I3 @T6G_MB_LIB.T6G(SCH_1):PAGE60
   U26 DC65 VSS_DC65 GENOA_SP5-SOCKET6096_13568-001,SMLF,IO,DGA^6000030     I3 @T6G_MB_LIB.T6G(SCH_1):PAGE60
   U26 DC68 VSS_DC68 GENOA_SP5-SOCKET6096_13568-001,SMLF,IO,DGA^6000030     I3 @T6G_MB_LIB.T6G(SCH_1):PAGE60
   U26 DC70 VSS_DC70 GENOA_SP5-SOCKET6096_13568-001,SMLF,IO,DGA^6000030     I3 @T6G_MB_LIB.T6G(SCH_1):PAGE60
   U26 DC72 VSS_DC72 GENOA_SP5-SOCKET6096_13568-001,SMLF,IO,DGA^6000030     I3 @T6G_MB_LIB.T6G(SCH_1):PAGE60
   U26 DC75 VSS_DC75 GENOA_SP5-SOCKET6096_13568-001,SMLF,IO,DGA^6000030     I3 @T6G_MB_LIB.T6G(SCH_1):PAGE60
   U26  DD3 VSS_DD3 GENOA_SP5-SOCKET6096_13568-001,SMLF,IO,DGA^6000030     I3 @T6G_MB_LIB.T6G(SCH_1):PAGE60
   U26  DD5 VSS_DD5 GENOA_SP5-SOCKET6096_13568-001,SMLF,IO,DGA^6000030     I3 @T6G_MB_LIB.T6G(SCH_1):PAGE60
   U26  DD8 VSS_DD8 GENOA_SP5-SOCKET6096_13568-001,SMLF,IO,DGA^6000030     I3 @T6G_MB_LIB.T6G(SCH_1):PAGE60
   U26 DD10 VSS_DD10 GENOA_SP5-SOCKET6096_13568-001,SMLF,IO,DGA^6000030     I3 @T6G_MB_LIB.T6G(SCH_1):PAGE60
   U26 DD12 VSS_DD12 GENOA_SP5-SOCKET6096_13568-001,SMLF,IO,DGA^6000030     I3 @T6G_MB_LIB.T6G(SCH_1):PAGE60
   U26 DD15 VSS_DD15 GENOA_SP5-SOCKET6096_13568-001,SMLF,IO,DGA^6000030     I3 @T6G_MB_LIB.T6G(SCH_1):PAGE60
   U26 DD17 VSS_DD17 GENOA_SP5-SOCKET6096_13568-001,SMLF,IO,DGA^6000030     I3 @T6G_MB_LIB.T6G(SCH_1):PAGE60
   U26 DD19 VSS_DD19 GENOA_SP5-SOCKET6096_13568-001,SMLF,IO,DGA^6000030     I3 @T6G_MB_LIB.T6G(SCH_1):PAGE60
   U26 DD23 VSS_DD23 GENOA_SP5-SOCKET6096_13568-001,SMLF,IO,DGA^6000030     I3 @T6G_MB_LIB.T6G(SCH_1):PAGE60
   U26 DD24 VSS_DD24 GENOA_SP5-SOCKET6096_13568-001,SMLF,IO,DGA^6000030     I3 @T6G_MB_LIB.T6G(SCH_1):PAGE60
   U26 DD26 VSS_DD26 GENOA_SP5-SOCKET6096_13568-001,SMLF,IO,DGA^6000030     I3 @T6G_MB_LIB.T6G(SCH_1):PAGE60
   U26 DD27 VSS_DD27 GENOA_SP5-SOCKET6096_13568-001,SMLF,IO,DGA^6000030     I3 @T6G_MB_LIB.T6G(SCH_1):PAGE60
   U26 DD29 VSS_DD29 GENOA_SP5-SOCKET6096_13568-001,SMLF,IO,DGA^6000030     I3 @T6G_MB_LIB.T6G(SCH_1):PAGE60
   U26 DD30 VSS_DD30 GENOA_SP5-SOCKET6096_13568-001,SMLF,IO,DGA^6000030     I3 @T6G_MB_LIB.T6G(SCH_1):PAGE60
   U26 DD32 VSS_DD32 GENOA_SP5-SOCKET6096_13568-001,SMLF,IO,DGA^6000030     I3 @T6G_MB_LIB.T6G(SCH_1):PAGE60
   U26 DD33 VSS_DD33 GENOA_SP5-SOCKET6096_13568-001,SMLF,IO,DGA^6000030     I3 @T6G_MB_LIB.T6G(SCH_1):PAGE60
   U26 DD35 VSS_DD35 GENOA_SP5-SOCKET6096_13568-001,SMLF,IO,DGA^6000030     I3 @T6G_MB_LIB.T6G(SCH_1):PAGE60
   U26 DD36 VSS_DD36 GENOA_SP5-SOCKET6096_13568-001,SMLF,IO,DGA^6000030     I3 @T6G_MB_LIB.T6G(SCH_1):PAGE60
   U26 DD37 VSS_DD37 GENOA_SP5-SOCKET6096_13568-001,SMLF,IO,DGA^6000030     I3 @T6G_MB_LIB.T6G(SCH_1):PAGE60
   U26 DD39 VSS_DD39 GENOA_SP5-SOCKET6096_13568-001,SMLF,IO,DGA^6000030     I3 @T6G_MB_LIB.T6G(SCH_1):PAGE60
   U26 DD40 VSS_DD40 GENOA_SP5-SOCKET6096_13568-001,SMLF,IO,DGA^6000030     I3 @T6G_MB_LIB.T6G(SCH_1):PAGE60
   U26 DD41 VSS_DD41 GENOA_SP5-SOCKET6096_13568-001,SMLF,IO,DGA^6000030     I3 @T6G_MB_LIB.T6G(SCH_1):PAGE60
   U26 DD43 VSS_DD43 GENOA_SP5-SOCKET6096_13568-001,SMLF,IO,DGA^6000030     I3 @T6G_MB_LIB.T6G(SCH_1):PAGE60
   U26 DD44 VSS_DD44 GENOA_SP5-SOCKET6096_13568-001,SMLF,IO,DGA^6000030     I3 @T6G_MB_LIB.T6G(SCH_1):PAGE60
   U26 DD46 VSS_DD46 GENOA_SP5-SOCKET6096_13568-001,SMLF,IO,DGA^6000030     I3 @T6G_MB_LIB.T6G(SCH_1):PAGE60
   U26 DD47 VSS_DD47 GENOA_SP5-SOCKET6096_13568-001,SMLF,IO,DGA^6000030     I3 @T6G_MB_LIB.T6G(SCH_1):PAGE60
   U26 DD49 VSS_DD49 GENOA_SP5-SOCKET6096_13568-001,SMLF,IO,DGA^6000030     I3 @T6G_MB_LIB.T6G(SCH_1):PAGE60
   U26 DD50 VSS_DD50 GENOA_SP5-SOCKET6096_13568-001,SMLF,IO,DGA^6000030     I3 @T6G_MB_LIB.T6G(SCH_1):PAGE60
   U26 DD52 VSS_DD52 GENOA_SP5-SOCKET6096_13568-001,SMLF,IO,DGA^6000030     I3 @T6G_MB_LIB.T6G(SCH_1):PAGE60
   U26 DD53 VSS_DD53 GENOA_SP5-SOCKET6096_13568-001,SMLF,IO,DGA^6000030     I3 @T6G_MB_LIB.T6G(SCH_1):PAGE60
   U26 DD57 VSS_DD57 GENOA_SP5-SOCKET6096_13568-001,SMLF,IO,DGA^6000030     I3 @T6G_MB_LIB.T6G(SCH_1):PAGE60
   U26 DD59 VSS_DD59 GENOA_SP5-SOCKET6096_13568-001,SMLF,IO,DGA^6000030     I3 @T6G_MB_LIB.T6G(SCH_1):PAGE60
   U26 DD61 VSS_DD61 GENOA_SP5-SOCKET6096_13568-001,SMLF,IO,DGA^6000030     I3 @T6G_MB_LIB.T6G(SCH_1):PAGE60
   U26 DD64 VSS_DD64 GENOA_SP5-SOCKET6096_13568-001,SMLF,IO,DGA^6000030     I3 @T6G_MB_LIB.T6G(SCH_1):PAGE60
   U26 DD66 VSS_DD66 GENOA_SP5-SOCKET6096_13568-001,SMLF,IO,DGA^6000030     I3 @T6G_MB_LIB.T6G(SCH_1):PAGE60
   U26 DD68 VSS_DD68 GENOA_SP5-SOCKET6096_13568-001,SMLF,IO,DGA^6000030     I3 @T6G_MB_LIB.T6G(SCH_1):PAGE60
   U26 DD71 VSS_DD71 GENOA_SP5-SOCKET6096_13568-001,SMLF,IO,DGA^6000030     I3 @T6G_MB_LIB.T6G(SCH_1):PAGE60
   U26 DD73 VSS_DD73 GENOA_SP5-SOCKET6096_13568-001,SMLF,IO,DGA^6000030     I3 @T6G_MB_LIB.T6G(SCH_1):PAGE60
   U26  DE1 VSS_DE1 GENOA_SP5-SOCKET6096_13568-001,SMLF,IO,DGA^6000030     I3 @T6G_MB_LIB.T6G(SCH_1):PAGE60
   U26  DE6 VSS_DE6 GENOA_SP5-SOCKET6096_13568-001,SMLF,IO,DGA^6000030     I3 @T6G_MB_LIB.T6G(SCH_1):PAGE60
   U26  DE8 VSS_DE8 GENOA_SP5-SOCKET6096_13568-001,SMLF,IO,DGA^6000030     I3 @T6G_MB_LIB.T6G(SCH_1):PAGE60
   U26 DE13 VSS_DE13 GENOA_SP5-SOCKET6096_13568-001,SMLF,IO,DGA^6000030     I3 @T6G_MB_LIB.T6G(SCH_1):PAGE60
   U26 DE15 VSS_DE15 GENOA_SP5-SOCKET6096_13568-001,SMLF,IO,DGA^6000030     I3 @T6G_MB_LIB.T6G(SCH_1):PAGE60
   U26 DE20 VSS_DE20 GENOA_SP5-SOCKET6096_13568-001,SMLF,IO,DGA^6000030     I3 @T6G_MB_LIB.T6G(SCH_1):PAGE60
   U26 DE23 VSS_DE23 GENOA_SP5-SOCKET6096_13568-001,SMLF,IO,DGA^6000030     I3 @T6G_MB_LIB.T6G(SCH_1):PAGE60
   U26 DE26 VSS_DE26 GENOA_SP5-SOCKET6096_13568-001,SMLF,IO,DGA^6000030     I3 @T6G_MB_LIB.T6G(SCH_1):PAGE60
   U26 DE29 VSS_DE29 GENOA_SP5-SOCKET6096_13568-001,SMLF,IO,DGA^6000030     I3 @T6G_MB_LIB.T6G(SCH_1):PAGE60
   U26 DE33 VSS_DE33 GENOA_SP5-SOCKET6096_13568-001,SMLF,IO,DGA^6000030     I3 @T6G_MB_LIB.T6G(SCH_1):PAGE60
   U26 DE56 VSS_DE56 GENOA_SP5-SOCKET6096_13568-001,SMLF,IO,DGA^6000030     I3 @T6G_MB_LIB.T6G(SCH_1):PAGE60
   U26 DE61 VSS_DE61 GENOA_SP5-SOCKET6096_13568-001,SMLF,IO,DGA^6000030     I3 @T6G_MB_LIB.T6G(SCH_1):PAGE60
   U26 DE63 VSS_DE63 GENOA_SP5-SOCKET6096_13568-001,SMLF,IO,DGA^6000030     I3 @T6G_MB_LIB.T6G(SCH_1):PAGE60
   U26 DE68 VSS_DE68 GENOA_SP5-SOCKET6096_13568-001,SMLF,IO,DGA^6000030     I3 @T6G_MB_LIB.T6G(SCH_1):PAGE60
   U26 DE70 VSS_DE70 GENOA_SP5-SOCKET6096_13568-001,SMLF,IO,DGA^6000030     I3 @T6G_MB_LIB.T6G(SCH_1):PAGE60
   U26 DE75 VSS_DE75 GENOA_SP5-SOCKET6096_13568-001,SMLF,IO,DGA^6000030     I3 @T6G_MB_LIB.T6G(SCH_1):PAGE60
   U26  DF3 VSS_DF3 GENOA_SP5-SOCKET6096_13568-001,SMLF,IO,DGA^6000030     I3 @T6G_MB_LIB.T6G(SCH_1):PAGE60
   U26  DF4 VSS_DF4 GENOA_SP5-SOCKET6096_13568-001,SMLF,IO,DGA^6000030     I3 @T6G_MB_LIB.T6G(SCH_1):PAGE60
   U26  DF5 VSS_DF5 GENOA_SP5-SOCKET6096_13568-001,SMLF,IO,DGA^6000030     I3 @T6G_MB_LIB.T6G(SCH_1):PAGE60
   U26  DF6 VSS_DF6 GENOA_SP5-SOCKET6096_13568-001,SMLF,IO,DGA^6000030     I3 @T6G_MB_LIB.T6G(SCH_1):PAGE60
   U26  DF8 VSS_DF8 GENOA_SP5-SOCKET6096_13568-001,SMLF,IO,DGA^6000030     I3 @T6G_MB_LIB.T6G(SCH_1):PAGE60
   U26 DF10 VSS_DF10 GENOA_SP5-SOCKET6096_13568-001,SMLF,IO,DGA^6000030     I3 @T6G_MB_LIB.T6G(SCH_1):PAGE60
   U26 DF11 VSS_DF11 GENOA_SP5-SOCKET6096_13568-001,SMLF,IO,DGA^6000030     I3 @T6G_MB_LIB.T6G(SCH_1):PAGE60
   U26 DF12 VSS_DF12 GENOA_SP5-SOCKET6096_13568-001,SMLF,IO,DGA^6000030     I3 @T6G_MB_LIB.T6G(SCH_1):PAGE60
   U26 DF13 VSS_DF13 GENOA_SP5-SOCKET6096_13568-001,SMLF,IO,DGA^6000030     I3 @T6G_MB_LIB.T6G(SCH_1):PAGE60
   U26 DF15 VSS_DF15 GENOA_SP5-SOCKET6096_13568-001,SMLF,IO,DGA^6000030     I3 @T6G_MB_LIB.T6G(SCH_1):PAGE60
   U26 DF17 VSS_DF17 GENOA_SP5-SOCKET6096_13568-001,SMLF,IO,DGA^6000030     I3 @T6G_MB_LIB.T6G(SCH_1):PAGE60
   U26 DF18 VSS_DF18 GENOA_SP5-SOCKET6096_13568-001,SMLF,IO,DGA^6000030     I3 @T6G_MB_LIB.T6G(SCH_1):PAGE60
   U26 DF19 VSS_DF19 GENOA_SP5-SOCKET6096_13568-001,SMLF,IO,DGA^6000030     I3 @T6G_MB_LIB.T6G(SCH_1):PAGE60
   U26 DF20 VSS_DF20 GENOA_SP5-SOCKET6096_13568-001,SMLF,IO,DGA^6000030     I3 @T6G_MB_LIB.T6G(SCH_1):PAGE60
   U26 DF22 VSS_DF22 GENOA_SP5-SOCKET6096_13568-001,SMLF,IO,DGA^6000030     I3 @T6G_MB_LIB.T6G(SCH_1):PAGE60
   U26 DF23 VSS_DF23 GENOA_SP5-SOCKET6096_13568-001,SMLF,IO,DGA^6000030     I3 @T6G_MB_LIB.T6G(SCH_1):PAGE60
   U26 DF26 VSS_DF26 GENOA_SP5-SOCKET6096_13568-001,SMLF,IO,DGA^6000030     I3 @T6G_MB_LIB.T6G(SCH_1):PAGE60
   U26 DF29 VSS_DF29 GENOA_SP5-SOCKET6096_13568-001,SMLF,IO,DGA^6000030     I3 @T6G_MB_LIB.T6G(SCH_1):PAGE60
   U26 DF32 VSS_DF32 GENOA_SP5-SOCKET6096_13568-001,SMLF,IO,DGA^6000030     I3 @T6G_MB_LIB.T6G(SCH_1):PAGE60
   U26 DF35 VSS_DF35 GENOA_SP5-SOCKET6096_13568-001,SMLF,IO,DGA^6000030     I3 @T6G_MB_LIB.T6G(SCH_1):PAGE60
   U26 DF37 VSS_DF37 GENOA_SP5-SOCKET6096_13568-001,SMLF,IO,DGA^6000030     I3 @T6G_MB_LIB.T6G(SCH_1):PAGE60
   U26 DF39 VSS_DF39 GENOA_SP5-SOCKET6096_13568-001,SMLF,IO,DGA^6000030     I3 @T6G_MB_LIB.T6G(SCH_1):PAGE60
   U26 DF42 VSS_DF42 GENOA_SP5-SOCKET6096_13568-001,SMLF,IO,DGA^6000030     I3 @T6G_MB_LIB.T6G(SCH_1):PAGE60
   U26 DF43 VSS_DF43 GENOA_SP5-SOCKET6096_13568-001,SMLF,IO,DGA^6000030     I3 @T6G_MB_LIB.T6G(SCH_1):PAGE60
   U26 DF44 VSS_DF44 GENOA_SP5-SOCKET6096_13568-001,SMLF,IO,DGA^6000030     I3 @T6G_MB_LIB.T6G(SCH_1):PAGE60
   U26 DF45 VSS_DF45 GENOA_SP5-SOCKET6096_13568-001,SMLF,IO,DGA^6000030     I3 @T6G_MB_LIB.T6G(SCH_1):PAGE60
   U26 DF46 VSS_DF46 GENOA_SP5-SOCKET6096_13568-001,SMLF,IO,DGA^6000030     I3 @T6G_MB_LIB.T6G(SCH_1):PAGE60
   U26 DF47 VSS_DF47 GENOA_SP5-SOCKET6096_13568-001,SMLF,IO,DGA^6000030     I3 @T6G_MB_LIB.T6G(SCH_1):PAGE60
   U26 DF48 VSS_DF48 GENOA_SP5-SOCKET6096_13568-001,SMLF,IO,DGA^6000030     I3 @T6G_MB_LIB.T6G(SCH_1):PAGE60
   U26 DF49 VSS_DF49 GENOA_SP5-SOCKET6096_13568-001,SMLF,IO,DGA^6000030     I3 @T6G_MB_LIB.T6G(SCH_1):PAGE60
   U26 DF50 VSS_DF50 GENOA_SP5-SOCKET6096_13568-001,SMLF,IO,DGA^6000030     I3 @T6G_MB_LIB.T6G(SCH_1):PAGE60
   U26 DF51 VSS_DF51 GENOA_SP5-SOCKET6096_13568-001,SMLF,IO,DGA^6000030     I3 @T6G_MB_LIB.T6G(SCH_1):PAGE60
   U26 DF52 VSS_DF52 GENOA_SP5-SOCKET6096_13568-001,SMLF,IO,DGA^6000030     I3 @T6G_MB_LIB.T6G(SCH_1):PAGE60
   U26 DF53 VSS_DF53 GENOA_SP5-SOCKET6096_13568-001,SMLF,IO,DGA^6000030     I3 @T6G_MB_LIB.T6G(SCH_1):PAGE60
   U26 DF54 VSS_DF54 GENOA_SP5-SOCKET6096_13568-001,SMLF,IO,DGA^6000030     I3 @T6G_MB_LIB.T6G(SCH_1):PAGE60
   U26 DF56 VSS_DF56 GENOA_SP5-SOCKET6096_13568-001,SMLF,IO,DGA^6000030     I3 @T6G_MB_LIB.T6G(SCH_1):PAGE60
   U26 DF57 VSS_DF57 GENOA_SP5-SOCKET6096_13568-001,SMLF,IO,DGA^6000030     I3 @T6G_MB_LIB.T6G(SCH_1):PAGE60
   U26 DF58 VSS_DF58 GENOA_SP5-SOCKET6096_13568-001,SMLF,IO,DGA^6000030     I3 @T6G_MB_LIB.T6G(SCH_1):PAGE60
   U26 DF59 VSS_DF59 GENOA_SP5-SOCKET6096_13568-001,SMLF,IO,DGA^6000030     I3 @T6G_MB_LIB.T6G(SCH_1):PAGE60
   U26 DF61 VSS_DF61 GENOA_SP5-SOCKET6096_13568-001,SMLF,IO,DGA^6000030     I3 @T6G_MB_LIB.T6G(SCH_1):PAGE60
   U26 DF63 VSS_DF63 GENOA_SP5-SOCKET6096_13568-001,SMLF,IO,DGA^6000030     I3 @T6G_MB_LIB.T6G(SCH_1):PAGE60
   U26 DF64 VSS_DF64 GENOA_SP5-SOCKET6096_13568-001,SMLF,IO,DGA^6000030     I3 @T6G_MB_LIB.T6G(SCH_1):PAGE60
   U26 DF65 VSS_DF65 GENOA_SP5-SOCKET6096_13568-001,SMLF,IO,DGA^6000030     I3 @T6G_MB_LIB.T6G(SCH_1):PAGE60
   U26 DF66 VSS_DF66 GENOA_SP5-SOCKET6096_13568-001,SMLF,IO,DGA^6000030     I3 @T6G_MB_LIB.T6G(SCH_1):PAGE60
   U26 DF68 VSS_DF68 GENOA_SP5-SOCKET6096_13568-001,SMLF,IO,DGA^6000030     I3 @T6G_MB_LIB.T6G(SCH_1):PAGE60
   U26 DF70 VSS_DF70 GENOA_SP5-SOCKET6096_13568-001,SMLF,IO,DGA^6000030     I3 @T6G_MB_LIB.T6G(SCH_1):PAGE60
   U26 DF71 VSS_DF71 GENOA_SP5-SOCKET6096_13568-001,SMLF,IO,DGA^6000030     I3 @T6G_MB_LIB.T6G(SCH_1):PAGE60
   U26 DF72 VSS_DF72 GENOA_SP5-SOCKET6096_13568-001,SMLF,IO,DGA^6000030     I3 @T6G_MB_LIB.T6G(SCH_1):PAGE60
   U26 DF73 VSS_DF73 GENOA_SP5-SOCKET6096_13568-001,SMLF,IO,DGA^6000030     I3 @T6G_MB_LIB.T6G(SCH_1):PAGE60
   U26  DG1 VSS_DG1 GENOA_SP5-SOCKET6096_13568-001,SMLF,IO,DGA^6000030     I3 @T6G_MB_LIB.T6G(SCH_1):PAGE60
   U26  DG2 VSS_DG2 GENOA_SP5-SOCKET6096_13568-001,SMLF,IO,DGA^6000030     I3 @T6G_MB_LIB.T6G(SCH_1):PAGE60
   U26  DG6 VSS_DG6 GENOA_SP5-SOCKET6096_13568-001,SMLF,IO,DGA^6000030     I3 @T6G_MB_LIB.T6G(SCH_1):PAGE60
   U26  DG7 VSS_DG7 GENOA_SP5-SOCKET6096_13568-001,SMLF,IO,DGA^6000030     I3 @T6G_MB_LIB.T6G(SCH_1):PAGE60
   U26  DG8 VSS_DG8 GENOA_SP5-SOCKET6096_13568-001,SMLF,IO,DGA^6000030     I3 @T6G_MB_LIB.T6G(SCH_1):PAGE60
   U26  DG9 VSS_DG9 GENOA_SP5-SOCKET6096_13568-001,SMLF,IO,DGA^6000030     I3 @T6G_MB_LIB.T6G(SCH_1):PAGE60
   U26 DG13 VSS_DG13 GENOA_SP5-SOCKET6096_13568-001,SMLF,IO,DGA^6000030     I3 @T6G_MB_LIB.T6G(SCH_1):PAGE60
   U26 DG14 VSS_DG14 GENOA_SP5-SOCKET6096_13568-001,SMLF,IO,DGA^6000030     I3 @T6G_MB_LIB.T6G(SCH_1):PAGE60
   U26 DG15 VSS_DG15 GENOA_SP5-SOCKET6096_13568-001,SMLF,IO,DGA^6000030     I3 @T6G_MB_LIB.T6G(SCH_1):PAGE60
   U26 DG16 VSS_DG16 GENOA_SP5-SOCKET6096_13568-001,SMLF,IO,DGA^6000030     I3 @T6G_MB_LIB.T6G(SCH_1):PAGE60
   U26 DG18 VSS_DG18 GENOA_SP5-SOCKET6096_13568-001,SMLF,IO,DGA^6000030     I3 @T6G_MB_LIB.T6G(SCH_1):PAGE60
   U26 DG20 VSS_DG20 GENOA_SP5-SOCKET6096_13568-001,SMLF,IO,DGA^6000030     I3 @T6G_MB_LIB.T6G(SCH_1):PAGE60
   U26 DG21 VSS_DG21 GENOA_SP5-SOCKET6096_13568-001,SMLF,IO,DGA^6000030     I3 @T6G_MB_LIB.T6G(SCH_1):PAGE60
   U26 DG24 VSS_DG24 GENOA_SP5-SOCKET6096_13568-001,SMLF,IO,DGA^6000030     I3 @T6G_MB_LIB.T6G(SCH_1):PAGE60
   U26 DG27 VSS_DG27 GENOA_SP5-SOCKET6096_13568-001,SMLF,IO,DGA^6000030     I3 @T6G_MB_LIB.T6G(SCH_1):PAGE60
   U26 DG30 VSS_DG30 GENOA_SP5-SOCKET6096_13568-001,SMLF,IO,DGA^6000030     I3 @T6G_MB_LIB.T6G(SCH_1):PAGE60
   U26 DG33 VSS_DG33 GENOA_SP5-SOCKET6096_13568-001,SMLF,IO,DGA^6000030     I3 @T6G_MB_LIB.T6G(SCH_1):PAGE60
   U26 DG41 VSS_DG41 GENOA_SP5-SOCKET6096_13568-001,SMLF,IO,DGA^6000030     I3 @T6G_MB_LIB.T6G(SCH_1):PAGE60
   U26 DG43 VSS_DG43 GENOA_SP5-SOCKET6096_13568-001,SMLF,IO,DGA^6000030     I3 @T6G_MB_LIB.T6G(SCH_1):PAGE60
   U26 DG46 VSS_DG46 GENOA_SP5-SOCKET6096_13568-001,SMLF,IO,DGA^6000030     I3 @T6G_MB_LIB.T6G(SCH_1):PAGE60
   U26 DG49 VSS_DG49 GENOA_SP5-SOCKET6096_13568-001,SMLF,IO,DGA^6000030     I3 @T6G_MB_LIB.T6G(SCH_1):PAGE60
   U26 DG52 VSS_DG52 GENOA_SP5-SOCKET6096_13568-001,SMLF,IO,DGA^6000030     I3 @T6G_MB_LIB.T6G(SCH_1):PAGE60
   U26 DG55 VSS_DG55 GENOA_SP5-SOCKET6096_13568-001,SMLF,IO,DGA^6000030     I3 @T6G_MB_LIB.T6G(SCH_1):PAGE60
   U26 DG56 VSS_DG56 GENOA_SP5-SOCKET6096_13568-001,SMLF,IO,DGA^6000030     I3 @T6G_MB_LIB.T6G(SCH_1):PAGE60
   U26 DG59 VSS_DG59 GENOA_SP5-SOCKET6096_13568-001,SMLF,IO,DGA^6000030     I3 @T6G_MB_LIB.T6G(SCH_1):PAGE60
   U26 DG60 VSS_DG60 GENOA_SP5-SOCKET6096_13568-001,SMLF,IO,DGA^6000030     I3 @T6G_MB_LIB.T6G(SCH_1):PAGE60
   U26 DG61 VSS_DG61 GENOA_SP5-SOCKET6096_13568-001,SMLF,IO,DGA^6000030     I3 @T6G_MB_LIB.T6G(SCH_1):PAGE60
   U26 DG62 VSS_DG62 GENOA_SP5-SOCKET6096_13568-001,SMLF,IO,DGA^6000030     I3 @T6G_MB_LIB.T6G(SCH_1):PAGE60
   U26 DG63 VSS_DG63 GENOA_SP5-SOCKET6096_13568-001,SMLF,IO,DGA^6000030     I3 @T6G_MB_LIB.T6G(SCH_1):PAGE60
   U26 DG65 VSS_DG65 GENOA_SP5-SOCKET6096_13568-001,SMLF,IO,DGA^6000030     I3 @T6G_MB_LIB.T6G(SCH_1):PAGE60
   U26 DG66 VSS_DG66 GENOA_SP5-SOCKET6096_13568-001,SMLF,IO,DGA^6000030     I3 @T6G_MB_LIB.T6G(SCH_1):PAGE60
   U26 DG67 VSS_DG67 GENOA_SP5-SOCKET6096_13568-001,SMLF,IO,DGA^6000030     I3 @T6G_MB_LIB.T6G(SCH_1):PAGE60
   U26 DG68 VSS_DG68 GENOA_SP5-SOCKET6096_13568-001,SMLF,IO,DGA^6000030     I3 @T6G_MB_LIB.T6G(SCH_1):PAGE60
   U26 DG69 VSS_DG69 GENOA_SP5-SOCKET6096_13568-001,SMLF,IO,DGA^6000030     I3 @T6G_MB_LIB.T6G(SCH_1):PAGE60
   U26 DG70 VSS_DG70 GENOA_SP5-SOCKET6096_13568-001,SMLF,IO,DGA^6000030     I3 @T6G_MB_LIB.T6G(SCH_1):PAGE60
   U26 DG74 VSS_DG74 GENOA_SP5-SOCKET6096_13568-001,SMLF,IO,DGA^6000030     I3 @T6G_MB_LIB.T6G(SCH_1):PAGE60
   U26 DG75 VSS_DG75 GENOA_SP5-SOCKET6096_13568-001,SMLF,IO,DGA^6000030     I3 @T6G_MB_LIB.T6G(SCH_1):PAGE60
   U26  DH5 VSS_DH5 GENOA_SP5-SOCKET6096_13568-001,SMLF,IO,DGA^6000030     I3 @T6G_MB_LIB.T6G(SCH_1):PAGE60
   U26 DH11 VSS_DH11 GENOA_SP5-SOCKET6096_13568-001,SMLF,IO,DGA^6000030     I3 @T6G_MB_LIB.T6G(SCH_1):PAGE60
   U26 DH18 VSS_DH18 GENOA_SP5-SOCKET6096_13568-001,SMLF,IO,DGA^6000030     I3 @T6G_MB_LIB.T6G(SCH_1):PAGE60
   U26 DH37 VSS_DH37 GENOA_SP5-SOCKET6096_13568-001,SMLF,IO,DGA^6000030     I3 @T6G_MB_LIB.T6G(SCH_1):PAGE60
   U26 DH39 VSS_DH39 GENOA_SP5-SOCKET6096_13568-001,SMLF,IO,DGA^6000030     I3 @T6G_MB_LIB.T6G(SCH_1):PAGE60
   U26 DH43 VSS_DH43 GENOA_SP5-SOCKET6096_13568-001,SMLF,IO,DGA^6000030     I3 @T6G_MB_LIB.T6G(SCH_1):PAGE60
   U26 DH46 VSS_DH46 GENOA_SP5-SOCKET6096_13568-001,SMLF,IO,DGA^6000030     I3 @T6G_MB_LIB.T6G(SCH_1):PAGE60
   U26 DH49 VSS_DH49 GENOA_SP5-SOCKET6096_13568-001,SMLF,IO,DGA^6000030     I3 @T6G_MB_LIB.T6G(SCH_1):PAGE60
   U26 DH52 VSS_DH52 GENOA_SP5-SOCKET6096_13568-001,SMLF,IO,DGA^6000030     I3 @T6G_MB_LIB.T6G(SCH_1):PAGE60
   U26 DH55 VSS_DH55 GENOA_SP5-SOCKET6096_13568-001,SMLF,IO,DGA^6000030     I3 @T6G_MB_LIB.T6G(SCH_1):PAGE60
   U26 DH59 VSS_DH59 GENOA_SP5-SOCKET6096_13568-001,SMLF,IO,DGA^6000030     I3 @T6G_MB_LIB.T6G(SCH_1):PAGE60
   U26 DH61 VSS_DH61 GENOA_SP5-SOCKET6096_13568-001,SMLF,IO,DGA^6000030     I3 @T6G_MB_LIB.T6G(SCH_1):PAGE60
   U26 DH63 VSS_DH63 GENOA_SP5-SOCKET6096_13568-001,SMLF,IO,DGA^6000030     I3 @T6G_MB_LIB.T6G(SCH_1):PAGE60
   U26 DH64 VSS_DH64 GENOA_SP5-SOCKET6096_13568-001,SMLF,IO,DGA^6000030     I3 @T6G_MB_LIB.T6G(SCH_1):PAGE60
   U26 DH66 VSS_DH66 GENOA_SP5-SOCKET6096_13568-001,SMLF,IO,DGA^6000030     I3 @T6G_MB_LIB.T6G(SCH_1):PAGE60
   U26 DH68 VSS_DH68 GENOA_SP5-SOCKET6096_13568-001,SMLF,IO,DGA^6000030     I3 @T6G_MB_LIB.T6G(SCH_1):PAGE60
   U26 DH70 VSS_DH70 GENOA_SP5-SOCKET6096_13568-001,SMLF,IO,DGA^6000030     I3 @T6G_MB_LIB.T6G(SCH_1):PAGE60
   U26  DJ7 VSS_DJ7 GENOA_SP5-SOCKET6096_13568-001,SMLF,IO,DGA^6000030     I3 @T6G_MB_LIB.T6G(SCH_1):PAGE60
   U26 DJ15 VSS_DJ15 GENOA_SP5-SOCKET6096_13568-001,SMLF,IO,DGA^6000030     I3 @T6G_MB_LIB.T6G(SCH_1):PAGE60
   U26 DJ19 VSS_DJ19 GENOA_SP5-SOCKET6096_13568-001,SMLF,IO,DGA^6000030     I3 @T6G_MB_LIB.T6G(SCH_1):PAGE60
   U26 DJ43 VSS_DJ43 GENOA_SP5-SOCKET6096_13568-001,SMLF,IO,DGA^6000030     I3 @T6G_MB_LIB.T6G(SCH_1):PAGE60
   U26 DJ49 VSS_DJ49 GENOA_SP5-SOCKET6096_13568-001,SMLF,IO,DGA^6000030     I3 @T6G_MB_LIB.T6G(SCH_1):PAGE60
   U26 DJ59 VSS_DJ59 GENOA_SP5-SOCKET6096_13568-001,SMLF,IO,DGA^6000030     I3 @T6G_MB_LIB.T6G(SCH_1):PAGE60
   U26 DJ61 VSS_DJ61 GENOA_SP5-SOCKET6096_13568-001,SMLF,IO,DGA^6000030     I3 @T6G_MB_LIB.T6G(SCH_1):PAGE60
   U26 DJ63 VSS_DJ63 GENOA_SP5-SOCKET6096_13568-001,SMLF,IO,DGA^6000030     I3 @T6G_MB_LIB.T6G(SCH_1):PAGE60
   U26 DJ66 VSS_DJ66 GENOA_SP5-SOCKET6096_13568-001,SMLF,IO,DGA^6000030     I3 @T6G_MB_LIB.T6G(SCH_1):PAGE60
   U26 DJ68 VSS_DJ68 GENOA_SP5-SOCKET6096_13568-001,SMLF,IO,DGA^6000030     I3 @T6G_MB_LIB.T6G(SCH_1):PAGE60
   U26 DJ73 VSS_DJ73 GENOA_SP5-SOCKET6096_13568-001,SMLF,IO,DGA^6000030     I3 @T6G_MB_LIB.T6G(SCH_1):PAGE60
   U26  K23 VSS_K23 GENOA_SP5-SOCKET6096_13568-001,SMLF,IO,DGA^6000030     I3 @T6G_MB_LIB.T6G(SCH_1):PAGE60
   U26  K59 VSS_K59 GENOA_SP5-SOCKET6096_13568-001,SMLF,IO,DGA^6000030     I3 @T6G_MB_LIB.T6G(SCH_1):PAGE60
   U26  P25 VSS_P25 GENOA_SP5-SOCKET6096_13568-001,SMLF,IO,DGA^6000030     I3 @T6G_MB_LIB.T6G(SCH_1):PAGE60
   U26  P68 VSS_P68 GENOA_SP5-SOCKET6096_13568-001,SMLF,IO,DGA^6000030     I3 @T6G_MB_LIB.T6G(SCH_1):PAGE60
   U26  V27 VSS_V27 GENOA_SP5-SOCKET6096_13568-001,SMLF,IO,DGA^6000030     I3 @T6G_MB_LIB.T6G(SCH_1):PAGE60
   U26  V68 VSS_V68 GENOA_SP5-SOCKET6096_13568-001,SMLF,IO,DGA^6000030     I3 @T6G_MB_LIB.T6G(SCH_1):PAGE60
 C3888    2      B Q_CAP_C0402-22UF,4V,20%,X6S,CH622KMEB02    I83 @T6G_MB_LIB.T6G(SCH_1):PAGE67
 C2130    2      B Q_CAP_C0402-22UF,4V,20%,X6S,CH622KMEB02    I85 @T6G_MB_LIB.T6G(SCH_1):PAGE67
 C3889    2      B Q_CAP_C0402-22UF,4V,20%,X6S,CH622KMEB02    I86 @T6G_MB_LIB.T6G(SCH_1):PAGE67
 C2135    2      B Q_CAP_C0402-22UF,4V,20%,X6S,CH622KMEB02    I87 @T6G_MB_LIB.T6G(SCH_1):PAGE67
 C2129    2      B Q_CAP_C0402-22UF,4V,20%,X6S,CH622KMEB02    I89 @T6G_MB_LIB.T6G(SCH_1):PAGE67
 C2134    2      B Q_CAP_C0402-22UF,4V,20%,X6S,CH622KMEB02    I90 @T6G_MB_LIB.T6G(SCH_1):PAGE67
 C2140    2      B Q_CAP_C0402-22UF,4V,20%,X6S,CH622KMEB02    I92 @T6G_MB_LIB.T6G(SCH_1):PAGE67
 C2144    2      B Q_CAP_C0402-22UF,4V,20%,X6S,CH622KMEB02    I93 @T6G_MB_LIB.T6G(SCH_1):PAGE67
 C2148    2      B Q_CAP_C0402-22UF,4V,20%,X6S,CH622KMEB02    I94 @T6G_MB_LIB.T6G(SCH_1):PAGE67
 C2139    2      B Q_CAP_C0402-22UF,4V,20%,X6S,CH622KMEB02    I95 @T6G_MB_LIB.T6G(SCH_1):PAGE67
 C2143    2      B Q_CAP_C0402-22UF,4V,20%,X6S,CH622KMEB02    I96 @T6G_MB_LIB.T6G(SCH_1):PAGE67
 C2152    2      B Q_CAP_C0402-22UF,4V,20%,X6S,CH622KMEB02    I97 @T6G_MB_LIB.T6G(SCH_1):PAGE67
 C2155    2      B Q_CAP_C0402-22UF,4V,20%,X6S,CH622KMEB02    I98 @T6G_MB_LIB.T6G(SCH_1):PAGE67
 C2151    2      B Q_CAP_C0402-22UF,4V,20%,X6S,CH622KMEB02    I99 @T6G_MB_LIB.T6G(SCH_1):PAGE67
 C2154    2      B Q_CAP_C0402-22UF,4V,20%,X6S,CH622KMEB02   I100 @T6G_MB_LIB.T6G(SCH_1):PAGE67
 C3894    2      B Q_CAP_C0402-22UF,4V,20%,X6S,CH622KMEB02   I101 @T6G_MB_LIB.T6G(SCH_1):PAGE67
 C3895    2      B Q_CAP_C0402-22UF,4V,20%,X6S,CH622KMEB02   I102 @T6G_MB_LIB.T6G(SCH_1):PAGE67
 C2157    2      B Q_CAP_C0402-22UF,4V,20%,X6S,CH622KMEB02   I103 @T6G_MB_LIB.T6G(SCH_1):PAGE67
 C2159    2      B Q_CAP_C0402-22UF,4V,20%,X6S,CH622KMEB02   I104 @T6G_MB_LIB.T6G(SCH_1):PAGE67
 C3896    2      B Q_CAP_C0402-22UF,4V,20%,X6S,CH622KMEB02   I106 @T6G_MB_LIB.T6G(SCH_1):PAGE67
 C2161    2      B Q_CAP_C0402-22UF,4V,20%,X6S,CH622KMEB02   I108 @T6G_MB_LIB.T6G(SCH_1):PAGE67
 C2147    2      B Q_CAP_C0402-22UF,4V,20%,X6S,CH622KMEB02   I109 @T6G_MB_LIB.T6G(SCH_1):PAGE67
 C2133    2      B Q_CAP_C0402-22UF,4V,20%,X6S,CH622KMEB02   I110 @T6G_MB_LIB.T6G(SCH_1):PAGE67
 C2138    2      B Q_CAP_C0402-22UF,4V,20%,X6S,CH622KMEB02   I112 @T6G_MB_LIB.T6G(SCH_1):PAGE67
 C2132    2      B Q_CAP_C0402-22UF,4V,20%,X6S,CH622KMEB02   I113 @T6G_MB_LIB.T6G(SCH_1):PAGE67
 C2137    2      B Q_CAP_C0402-22UF,4V,20%,X6S,CH622KMEB02   I115 @T6G_MB_LIB.T6G(SCH_1):PAGE67
 C3890    2      B Q_CAP_C0402-22UF,4V,20%,X6S,CH622KMEB02   I116 @T6G_MB_LIB.T6G(SCH_1):PAGE67
 C3891    2      B Q_CAP_C0402-22UF,4V,20%,X6S,CH622KMEB02   I117 @T6G_MB_LIB.T6G(SCH_1):PAGE67
 C3892    2      B Q_CAP_C0402-22UF,4V,20%,X6S,CH622KMEB02   I118 @T6G_MB_LIB.T6G(SCH_1):PAGE67
 C3893    2      B Q_CAP_C0402-22UF,4V,20%,X6S,CH622KMEB02   I120 @T6G_MB_LIB.T6G(SCH_1):PAGE67
 C2142    2      B Q_CAP_C0402-22UF,4V,20%,X6S,CH622KMEB02   I121 @T6G_MB_LIB.T6G(SCH_1):PAGE67
 C2146    2      B Q_CAP_C0402-22UF,4V,20%,X6S,CH622KMEB02   I122 @T6G_MB_LIB.T6G(SCH_1):PAGE67
 C2150    2      B Q_CAP_C0402-22UF,4V,20%,X6S,CH622KMEB02   I123 @T6G_MB_LIB.T6G(SCH_1):PAGE67
 C2153    2      B Q_CAP_C0402-22UF,4V,20%,X6S,CH622KMEB02   I124 @T6G_MB_LIB.T6G(SCH_1):PAGE67
 C2156    2      B Q_CAP_C0402-22UF,4V,20%,X6S,CH622KMEB02   I125 @T6G_MB_LIB.T6G(SCH_1):PAGE67
 C2158    2      B Q_CAP_C0402-22UF,4V,20%,X6S,CH622KMEB02   I127 @T6G_MB_LIB.T6G(SCH_1):PAGE67
 C2160    2      B Q_CAP_C0402-22UF,4V,20%,X6S,CH622KMEB02   I128 @T6G_MB_LIB.T6G(SCH_1):PAGE67
 C2162    2      B Q_CAP_C0402-22UF,4V,20%,X6S,CH622KMEB02   I129 @T6G_MB_LIB.T6G(SCH_1):PAGE67
 C2163    2      B Q_CAP_C0402-22UF,4V,20%,X6S,CH622KMEB02   I131 @T6G_MB_LIB.T6G(SCH_1):PAGE67
 C2164    2      B Q_CAP_C0402-22UF,4V,20%,X6S,CH622KMEB02   I133 @T6G_MB_LIB.T6G(SCH_1):PAGE67
 C3897    2      B Q_CAP_C0402-22UF,4V,20%,X6S,CH622KMEB02   I134 @T6G_MB_LIB.T6G(SCH_1):PAGE67
 C2131    2      B Q_CAP_C0402-22UF,4V,20%,X6S,CH622KMEB02   I135 @T6G_MB_LIB.T6G(SCH_1):PAGE67
 C2136    2      B Q_CAP_C0402-22UF,4V,20%,X6S,CH622KMEB02   I136 @T6G_MB_LIB.T6G(SCH_1):PAGE67
 C2141    2      B Q_CAP_C0402-22UF,4V,20%,X6S,CH622KMEB02   I137 @T6G_MB_LIB.T6G(SCH_1):PAGE67
 C2145    2      B Q_CAP_C0402-22UF,4V,20%,X6S,CH622KMEB02   I138 @T6G_MB_LIB.T6G(SCH_1):PAGE67
 C2149    2      B Q_CAP_C0402-22UF,4V,20%,X6S,CH622KMEB02   I139 @T6G_MB_LIB.T6G(SCH_1):PAGE67
 C3898    2      B Q_CAP_C0402-22UF,4V,20%,X6S,CH622KMEB02   I141 @T6G_MB_LIB.T6G(SCH_1):PAGE67
 C3899    2      B Q_CAP_C0402-22UF,4V,20%,X6S,CH622KMEB02   I143 @T6G_MB_LIB.T6G(SCH_1):PAGE67
 C2167    2      B Q_CAP_C0402-22UF,4V,20%,X6S,CH622KMEB02     I1 @T6G_MB_LIB.T6G(SCH_1):PAGE68
 C2171    2      B Q_CAP_C0402-22UF,4V,20%,X6S,CH622KMEB02     I2 @T6G_MB_LIB.T6G(SCH_1):PAGE68
 C2166    2      B Q_CAP_C0402-22UF,4V,20%,X6S,CH622KMEB02     I4 @T6G_MB_LIB.T6G(SCH_1):PAGE68
 C2170    2      B Q_CAP_C0402-22UF,4V,20%,X6S,CH622KMEB02     I5 @T6G_MB_LIB.T6G(SCH_1):PAGE68
 C2165    2      B Q_CAP_C0402-22UF,4V,20%,X6S,CH622KMEB02     I7 @T6G_MB_LIB.T6G(SCH_1):PAGE68
 C2169    2      B Q_CAP_C0402-22UF,4V,20%,X6S,CH622KMEB02     I9 @T6G_MB_LIB.T6G(SCH_1):PAGE68
  C246    2      B Q_CAP_C0402-22UF,4V,20%,X6S,CH622KMEB02    I10 @T6G_MB_LIB.T6G(SCH_1):PAGE68
  C252    2      B Q_CAP_C0402-22UF,4V,20%,X6S,CH622KMEB02    I12 @T6G_MB_LIB.T6G(SCH_1):PAGE68
  C245    2      B Q_CAP_C0402-22UF,4V,20%,X6S,CH622KMEB02    I14 @T6G_MB_LIB.T6G(SCH_1):PAGE68
  C251    2      B Q_CAP_C0402-22UF,4V,20%,X6S,CH622KMEB02    I15 @T6G_MB_LIB.T6G(SCH_1):PAGE68
 C2175    2      B Q_CAP_C0402-22UF,4V,20%,X6S,CH622KMEB02    I16 @T6G_MB_LIB.T6G(SCH_1):PAGE68
C10179    2      B Q_CAP_C0402-22UF,4V,20%,X6S,CH622KMEB02    I17 @T6G_MB_LIB.T6G(SCH_1):PAGE68
 C2183    2      B Q_CAP_C0402-22UF,4V,20%,X6S,CH622KMEB02    I19 @T6G_MB_LIB.T6G(SCH_1):PAGE68
 C2174    2      B Q_CAP_C0402-22UF,4V,20%,X6S,CH622KMEB02    I20 @T6G_MB_LIB.T6G(SCH_1):PAGE68
 C2178    2      B Q_CAP_C0402-22UF,4V,20%,X6S,CH622KMEB02    I21 @T6G_MB_LIB.T6G(SCH_1):PAGE68
 C2173    2      B Q_CAP_C0402-22UF,4V,20%,X6S,CH622KMEB02    I22 @T6G_MB_LIB.T6G(SCH_1):PAGE68
 C2177    2      B Q_CAP_C0402-22UF,4V,20%,X6S,CH622KMEB02    I23 @T6G_MB_LIB.T6G(SCH_1):PAGE68
 C2182    2      B Q_CAP_C0402-22UF,4V,20%,X6S,CH622KMEB02    I24 @T6G_MB_LIB.T6G(SCH_1):PAGE68
 C2181    2      B Q_CAP_C0402-22UF,4V,20%,X6S,CH622KMEB02    I25 @T6G_MB_LIB.T6G(SCH_1):PAGE68
 C2186    2      B Q_CAP_C0402-22UF,4V,20%,X6S,CH622KMEB02    I26 @T6G_MB_LIB.T6G(SCH_1):PAGE68
 C2190    2      B Q_CAP_C0402-22UF,4V,20%,X6S,CH622KMEB02    I27 @T6G_MB_LIB.T6G(SCH_1):PAGE68
 C2185    2      B Q_CAP_C0402-22UF,4V,20%,X6S,CH622KMEB02    I28 @T6G_MB_LIB.T6G(SCH_1):PAGE68
 C2189    2      B Q_CAP_C0402-22UF,4V,20%,X6S,CH622KMEB02    I29 @T6G_MB_LIB.T6G(SCH_1):PAGE68
 C2205    2      B Q_CAP_C0402-22UF,4V,20%,X6S,CH622KMEB02    I30 @T6G_MB_LIB.T6G(SCH_1):PAGE68
 C2193    2      B Q_CAP_C0402-22UF,4V,20%,X6S,CH622KMEB02    I31 @T6G_MB_LIB.T6G(SCH_1):PAGE68
 C2196    2      B Q_CAP_C0402-22UF,4V,20%,X6S,CH622KMEB02    I32 @T6G_MB_LIB.T6G(SCH_1):PAGE68
 C2192    2      B Q_CAP_C0402-22UF,4V,20%,X6S,CH622KMEB02    I33 @T6G_MB_LIB.T6G(SCH_1):PAGE68
 C2195    2      B Q_CAP_C0402-22UF,4V,20%,X6S,CH622KMEB02    I34 @T6G_MB_LIB.T6G(SCH_1):PAGE68
 C2199    2      B Q_CAP_C0402-22UF,4V,20%,X6S,CH622KMEB02    I36 @T6G_MB_LIB.T6G(SCH_1):PAGE68
 C2204    2      B Q_CAP_C0402-22UF,4V,20%,X6S,CH622KMEB02    I38 @T6G_MB_LIB.T6G(SCH_1):PAGE68
 C2198    2      B Q_CAP_C0402-22UF,4V,20%,X6S,CH622KMEB02    I40 @T6G_MB_LIB.T6G(SCH_1):PAGE68
 C2203    2      B Q_CAP_C0402-22UF,4V,20%,X6S,CH622KMEB02    I43 @T6G_MB_LIB.T6G(SCH_1):PAGE68
 C1922    2      B Q_CAP_C0402-22UF,4V,20%,X6S,CH622KMEB02    I45 @T6G_MB_LIB.T6G(SCH_1):PAGE68
  C263    2      B Q_CAP_C0402-22UF,4V,20%,X6S,CH622KMEB02    I46 @T6G_MB_LIB.T6G(SCH_1):PAGE68
 C4178    2      B Q_CAP_C0402-22UF,4V,20%,X6S,CH622KMEB02    I47 @T6G_MB_LIB.T6G(SCH_1):PAGE68
 C4179    2      B Q_CAP_C0402-22UF,4V,20%,X6S,CH622KMEB02    I48 @T6G_MB_LIB.T6G(SCH_1):PAGE68
  C268    2      B Q_CAP_C0402-22UF,4V,20%,X6S,CH622KMEB02    I49 @T6G_MB_LIB.T6G(SCH_1):PAGE68
  C267    2      B Q_CAP_C0402-22UF,4V,20%,X6S,CH622KMEB02    I50 @T6G_MB_LIB.T6G(SCH_1):PAGE68
  C271    2      B Q_CAP_C0402-22UF,4V,20%,X6S,CH622KMEB02    I51 @T6G_MB_LIB.T6G(SCH_1):PAGE68
  C273    2      B Q_CAP_C0402-22UF,4V,20%,X6S,CH622KMEB02    I52 @T6G_MB_LIB.T6G(SCH_1):PAGE68
  C270    2      B Q_CAP_C0402-22UF,4V,20%,X6S,CH622KMEB02    I53 @T6G_MB_LIB.T6G(SCH_1):PAGE68
  C275    2      B Q_CAP_C0402-22UF,4V,20%,X6S,CH622KMEB02    I54 @T6G_MB_LIB.T6G(SCH_1):PAGE68
  C277    2      B Q_CAP_C0402-22UF,4V,20%,X6S,CH622KMEB02    I55 @T6G_MB_LIB.T6G(SCH_1):PAGE68
  C274    2      B Q_CAP_C0402-22UF,4V,20%,X6S,CH622KMEB02    I56 @T6G_MB_LIB.T6G(SCH_1):PAGE68
  C276    2      B Q_CAP_C0402-22UF,4V,20%,X6S,CH622KMEB02    I57 @T6G_MB_LIB.T6G(SCH_1):PAGE68
  C279    2      B Q_CAP_C0402-22UF,4V,20%,X6S,CH622KMEB02    I58 @T6G_MB_LIB.T6G(SCH_1):PAGE68
 C2202    2      B Q_CAP_C0402-22UF,4V,20%,X6S,CH622KMEB02    I60 @T6G_MB_LIB.T6G(SCH_1):PAGE68
  C278    2      B Q_CAP_C0402-22UF,4V,20%,X6S,CH622KMEB02    I62 @T6G_MB_LIB.T6G(SCH_1):PAGE68
 C2201    2      B Q_CAP_C0402-22UF,4V,20%,X6S,CH622KMEB02    I63 @T6G_MB_LIB.T6G(SCH_1):PAGE68
 C2211    2      B Q_CAP_C0402-22UF,4V,20%,X6S,CH622KMEB02    I65 @T6G_MB_LIB.T6G(SCH_1):PAGE68
 C2217    2      B Q_CAP_C0402-22UF,4V,20%,X6S,CH622KMEB02    I66 @T6G_MB_LIB.T6G(SCH_1):PAGE68
 C2223    2      B Q_CAP_C0402-22UF,4V,20%,X6S,CH622KMEB02    I67 @T6G_MB_LIB.T6G(SCH_1):PAGE68
 C2229    2      B Q_CAP_C0402-22UF,4V,20%,X6S,CH622KMEB02    I69 @T6G_MB_LIB.T6G(SCH_1):PAGE68
 C2210    2      B Q_CAP_C0402-22UF,4V,20%,X6S,CH622KMEB02    I70 @T6G_MB_LIB.T6G(SCH_1):PAGE68
 C2216    2      B Q_CAP_C0402-22UF,4V,20%,X6S,CH622KMEB02    I71 @T6G_MB_LIB.T6G(SCH_1):PAGE68
 C2209    2      B Q_CAP_C0402-22UF,4V,20%,X6S,CH622KMEB02    I72 @T6G_MB_LIB.T6G(SCH_1):PAGE68
 C2215    2      B Q_CAP_C0402-22UF,4V,20%,X6S,CH622KMEB02    I73 @T6G_MB_LIB.T6G(SCH_1):PAGE68
 C2222    2      B Q_CAP_C0402-22UF,4V,20%,X6S,CH622KMEB02    I74 @T6G_MB_LIB.T6G(SCH_1):PAGE68
 C2228    2      B Q_CAP_C0402-22UF,4V,20%,X6S,CH622KMEB02    I75 @T6G_MB_LIB.T6G(SCH_1):PAGE68
 C2234    2      B Q_CAP_C0402-22UF,4V,20%,X6S,CH622KMEB02    I76 @T6G_MB_LIB.T6G(SCH_1):PAGE68
 C2221    2      B Q_CAP_C0402-22UF,4V,20%,X6S,CH622KMEB02    I77 @T6G_MB_LIB.T6G(SCH_1):PAGE68
 C2227    2      B Q_CAP_C0402-22UF,4V,20%,X6S,CH622KMEB02    I78 @T6G_MB_LIB.T6G(SCH_1):PAGE68
 C2233    2      B Q_CAP_C0402-22UF,4V,20%,X6S,CH622KMEB02    I79 @T6G_MB_LIB.T6G(SCH_1):PAGE68
 C2240    2      B Q_CAP_C0402-22UF,4V,20%,X6S,CH622KMEB02    I80 @T6G_MB_LIB.T6G(SCH_1):PAGE68
 C2246    2      B Q_CAP_C0402-22UF,4V,20%,X6S,CH622KMEB02    I81 @T6G_MB_LIB.T6G(SCH_1):PAGE68
 C2239    2      B Q_CAP_C0402-22UF,4V,20%,X6S,CH622KMEB02    I82 @T6G_MB_LIB.T6G(SCH_1):PAGE68
 C2245    2      B Q_CAP_C0402-22UF,4V,20%,X6S,CH622KMEB02    I83 @T6G_MB_LIB.T6G(SCH_1):PAGE68
 C2251    2      B Q_CAP_C0402-22UF,4V,20%,X6S,CH622KMEB02    I84 @T6G_MB_LIB.T6G(SCH_1):PAGE68
 C2256    2      B Q_CAP_C0402-22UF,4V,20%,X6S,CH622KMEB02    I86 @T6G_MB_LIB.T6G(SCH_1):PAGE68
 C2250    2      B Q_CAP_C0402-22UF,4V,20%,X6S,CH622KMEB02    I87 @T6G_MB_LIB.T6G(SCH_1):PAGE68
 C2255    2      B Q_CAP_C0402-22UF,4V,20%,X6S,CH622KMEB02    I89 @T6G_MB_LIB.T6G(SCH_1):PAGE68
 C2208    2      B Q_CAP_C0402-22UF,4V,20%,X6S,CH622KMEB02    I91 @T6G_MB_LIB.T6G(SCH_1):PAGE68
 C2214    2      B Q_CAP_C0402-22UF,4V,20%,X6S,CH622KMEB02    I92 @T6G_MB_LIB.T6G(SCH_1):PAGE68
 C2207    2      B Q_CAP_C0402-22UF,4V,20%,X6S,CH622KMEB02    I93 @T6G_MB_LIB.T6G(SCH_1):PAGE68
 C2213    2      B Q_CAP_C0402-22UF,4V,20%,X6S,CH622KMEB02    I94 @T6G_MB_LIB.T6G(SCH_1):PAGE68
 C2220    2      B Q_CAP_C0402-22UF,4V,20%,X6S,CH622KMEB02    I95 @T6G_MB_LIB.T6G(SCH_1):PAGE68
 C2226    2      B Q_CAP_C0402-22UF,4V,20%,X6S,CH622KMEB02    I96 @T6G_MB_LIB.T6G(SCH_1):PAGE68
 C2232    2      B Q_CAP_C0402-22UF,4V,20%,X6S,CH622KMEB02    I97 @T6G_MB_LIB.T6G(SCH_1):PAGE68
 C2219    2      B Q_CAP_C0402-22UF,4V,20%,X6S,CH622KMEB02    I98 @T6G_MB_LIB.T6G(SCH_1):PAGE68
 C2225    2      B Q_CAP_C0402-22UF,4V,20%,X6S,CH622KMEB02    I99 @T6G_MB_LIB.T6G(SCH_1):PAGE68
 C2231    2      B Q_CAP_C0402-22UF,4V,20%,X6S,CH622KMEB02   I100 @T6G_MB_LIB.T6G(SCH_1):PAGE68
 C2238    2      B Q_CAP_C0402-22UF,4V,20%,X6S,CH622KMEB02   I101 @T6G_MB_LIB.T6G(SCH_1):PAGE68
 C2244    2      B Q_CAP_C0402-22UF,4V,20%,X6S,CH622KMEB02   I102 @T6G_MB_LIB.T6G(SCH_1):PAGE68
 C2237    2      B Q_CAP_C0402-22UF,4V,20%,X6S,CH622KMEB02   I103 @T6G_MB_LIB.T6G(SCH_1):PAGE68
 C2243    2      B Q_CAP_C0402-22UF,4V,20%,X6S,CH622KMEB02   I104 @T6G_MB_LIB.T6G(SCH_1):PAGE68
 C2249    2      B Q_CAP_C0402-22UF,4V,20%,X6S,CH622KMEB02   I105 @T6G_MB_LIB.T6G(SCH_1):PAGE68
 C2254    2      B Q_CAP_C0402-22UF,4V,20%,X6S,CH622KMEB02   I106 @T6G_MB_LIB.T6G(SCH_1):PAGE68
 C2248    2      B Q_CAP_C0402-22UF,4V,20%,X6S,CH622KMEB02   I108 @T6G_MB_LIB.T6G(SCH_1):PAGE68
 C2253    2      B Q_CAP_C0402-22UF,4V,20%,X6S,CH622KMEB02   I109 @T6G_MB_LIB.T6G(SCH_1):PAGE68
  C272    2      B Q_CAP_C0402-22UF,4V,20%,X6S,CH622KMEB02   I110 @T6G_MB_LIB.T6G(SCH_1):PAGE68
 C3925    2      B Q_CAP_C0402-22UF,4V,20%,X6S,CH622KMEB02     I1 @T6G_MB_LIB.T6G(SCH_1):PAGE69
 C3926    2      B Q_CAP_C0402-22UF,4V,20%,X6S,CH622KMEB02     I3 @T6G_MB_LIB.T6G(SCH_1):PAGE69
 C2533    2      B Q_CAP_C0402-22UF,4V,20%,X6S,CH622KMEB02     I4 @T6G_MB_LIB.T6G(SCH_1):PAGE69
 C2540    2      B Q_CAP_C0402-22UF,4V,20%,X6S,CH622KMEB02     I6 @T6G_MB_LIB.T6G(SCH_1):PAGE69
 C2532    2      B Q_CAP_C0402-22UF,4V,20%,X6S,CH622KMEB02     I7 @T6G_MB_LIB.T6G(SCH_1):PAGE69
 C2531    2      B Q_CAP_C0402-22UF,4V,20%,X6S,CH622KMEB02     I9 @T6G_MB_LIB.T6G(SCH_1):PAGE69
 C2539    2      B Q_CAP_C0402-22UF,4V,20%,X6S,CH622KMEB02    I10 @T6G_MB_LIB.T6G(SCH_1):PAGE69
 C2538    2      B Q_CAP_C0402-22UF,4V,20%,X6S,CH622KMEB02    I11 @T6G_MB_LIB.T6G(SCH_1):PAGE69
 C2530    2      B Q_CAP_C0402-22UF,4V,20%,X6S,CH622KMEB02    I13 @T6G_MB_LIB.T6G(SCH_1):PAGE69
 C2537    2      B Q_CAP_C0402-22UF,4V,20%,X6S,CH622KMEB02    I15 @T6G_MB_LIB.T6G(SCH_1):PAGE69
 C2529    2      B Q_CAP_C0402-22UF,4V,20%,X6S,CH622KMEB02    I16 @T6G_MB_LIB.T6G(SCH_1):PAGE69
 C2528    2      B Q_CAP_C0402-22UF,4V,20%,X6S,CH622KMEB02    I18 @T6G_MB_LIB.T6G(SCH_1):PAGE69
 C2536    2      B Q_CAP_C0402-22UF,4V,20%,X6S,CH622KMEB02    I19 @T6G_MB_LIB.T6G(SCH_1):PAGE69
 C2535    2      B Q_CAP_C0402-22UF,4V,20%,X6S,CH622KMEB02    I20 @T6G_MB_LIB.T6G(SCH_1):PAGE69
 C2527    2      B Q_CAP_C0402-22UF,4V,20%,X6S,CH622KMEB02    I22 @T6G_MB_LIB.T6G(SCH_1):PAGE69
 C2534    2      B Q_CAP_C0402-22UF,4V,20%,X6S,CH622KMEB02    I24 @T6G_MB_LIB.T6G(SCH_1):PAGE69
 C3927    2      B Q_CAP_C0402-22UF,4V,20%,X6S,CH622KMEB02    I25 @T6G_MB_LIB.T6G(SCH_1):PAGE69
 C3928    2      B Q_CAP_C0402-22UF,4V,20%,X6S,CH622KMEB02    I26 @T6G_MB_LIB.T6G(SCH_1):PAGE69
 C3929    2      B Q_CAP_C0402-22UF,4V,20%,X6S,CH622KMEB02    I27 @T6G_MB_LIB.T6G(SCH_1):PAGE69
 C2547    2      B Q_CAP_C0402-22UF,4V,20%,X6S,CH622KMEB02    I28 @T6G_MB_LIB.T6G(SCH_1):PAGE69
 C2554    2      B Q_CAP_C0402-22UF,4V,20%,X6S,CH622KMEB02    I29 @T6G_MB_LIB.T6G(SCH_1):PAGE69
 C2561    2      B Q_CAP_C0402-22UF,4V,20%,X6S,CH622KMEB02    I30 @T6G_MB_LIB.T6G(SCH_1):PAGE69
 C3930    2      B Q_CAP_C0402-22UF,4V,20%,X6S,CH622KMEB02    I31 @T6G_MB_LIB.T6G(SCH_1):PAGE69
 C3931    2      B Q_CAP_C0402-22UF,4V,20%,X6S,CH622KMEB02    I33 @T6G_MB_LIB.T6G(SCH_1):PAGE69
 C2568    2      B Q_CAP_C0402-22UF,4V,20%,X6S,CH622KMEB02    I34 @T6G_MB_LIB.T6G(SCH_1):PAGE69
 C2575    2      B Q_CAP_C0402-22UF,4V,20%,X6S,CH622KMEB02    I35 @T6G_MB_LIB.T6G(SCH_1):PAGE69
 C2546    2      B Q_CAP_C0402-22UF,4V,20%,X6S,CH622KMEB02    I36 @T6G_MB_LIB.T6G(SCH_1):PAGE69
 C2545    2      B Q_CAP_C0402-22UF,4V,20%,X6S,CH622KMEB02    I37 @T6G_MB_LIB.T6G(SCH_1):PAGE69
 C2553    2      B Q_CAP_C0402-22UF,4V,20%,X6S,CH622KMEB02    I38 @T6G_MB_LIB.T6G(SCH_1):PAGE69
 C2560    2      B Q_CAP_C0402-22UF,4V,20%,X6S,CH622KMEB02    I39 @T6G_MB_LIB.T6G(SCH_1):PAGE69
 C2552    2      B Q_CAP_C0402-22UF,4V,20%,X6S,CH622KMEB02    I40 @T6G_MB_LIB.T6G(SCH_1):PAGE69
 C2559    2      B Q_CAP_C0402-22UF,4V,20%,X6S,CH622KMEB02    I41 @T6G_MB_LIB.T6G(SCH_1):PAGE69
 C2544    2      B Q_CAP_C0402-22UF,4V,20%,X6S,CH622KMEB02    I42 @T6G_MB_LIB.T6G(SCH_1):PAGE69
 C2551    2      B Q_CAP_C0402-22UF,4V,20%,X6S,CH622KMEB02    I43 @T6G_MB_LIB.T6G(SCH_1):PAGE69
 C2558    2      B Q_CAP_C0402-22UF,4V,20%,X6S,CH622KMEB02    I44 @T6G_MB_LIB.T6G(SCH_1):PAGE69
 C2567    2      B Q_CAP_C0402-22UF,4V,20%,X6S,CH622KMEB02    I45 @T6G_MB_LIB.T6G(SCH_1):PAGE69
 C2566    2      B Q_CAP_C0402-22UF,4V,20%,X6S,CH622KMEB02    I46 @T6G_MB_LIB.T6G(SCH_1):PAGE69
 C2574    2      B Q_CAP_C0402-22UF,4V,20%,X6S,CH622KMEB02    I47 @T6G_MB_LIB.T6G(SCH_1):PAGE69
 C2573    2      B Q_CAP_C0402-22UF,4V,20%,X6S,CH622KMEB02    I48 @T6G_MB_LIB.T6G(SCH_1):PAGE69
 C2565    2      B Q_CAP_C0402-22UF,4V,20%,X6S,CH622KMEB02    I49 @T6G_MB_LIB.T6G(SCH_1):PAGE69
 C2572    2      B Q_CAP_C0402-22UF,4V,20%,X6S,CH622KMEB02    I50 @T6G_MB_LIB.T6G(SCH_1):PAGE69
 C2582    2      B Q_CAP_C0402-22UF,4V,20%,X6S,CH622KMEB02    I51 @T6G_MB_LIB.T6G(SCH_1):PAGE69
 C2589    2      B Q_CAP_C0402-22UF,4V,20%,X6S,CH622KMEB02    I52 @T6G_MB_LIB.T6G(SCH_1):PAGE69
 C3932    2      B Q_CAP_C0402-22UF,4V,20%,X6S,CH622KMEB02    I53 @T6G_MB_LIB.T6G(SCH_1):PAGE69
 C2596    2      B Q_CAP_C0402-22UF,4V,20%,X6S,CH622KMEB02    I56 @T6G_MB_LIB.T6G(SCH_1):PAGE69
 C2603    2      B Q_CAP_C0402-22UF,4V,20%,X6S,CH622KMEB02    I58 @T6G_MB_LIB.T6G(SCH_1):PAGE69
 C2602    2      B Q_CAP_C0402-22UF,4V,20%,X6S,CH622KMEB02    I60 @T6G_MB_LIB.T6G(SCH_1):PAGE69
 C2581    2      B Q_CAP_C0402-22UF,4V,20%,X6S,CH622KMEB02    I61 @T6G_MB_LIB.T6G(SCH_1):PAGE69
 C2580    2      B Q_CAP_C0402-22UF,4V,20%,X6S,CH622KMEB02    I62 @T6G_MB_LIB.T6G(SCH_1):PAGE69
 C2588    2      B Q_CAP_C0402-22UF,4V,20%,X6S,CH622KMEB02    I63 @T6G_MB_LIB.T6G(SCH_1):PAGE69
 C2587    2      B Q_CAP_C0402-22UF,4V,20%,X6S,CH622KMEB02    I64 @T6G_MB_LIB.T6G(SCH_1):PAGE69
 C2579    2      B Q_CAP_C0402-22UF,4V,20%,X6S,CH622KMEB02    I65 @T6G_MB_LIB.T6G(SCH_1):PAGE69
 C2586    2      B Q_CAP_C0402-22UF,4V,20%,X6S,CH622KMEB02    I66 @T6G_MB_LIB.T6G(SCH_1):PAGE69
 C2595    2      B Q_CAP_C0402-22UF,4V,20%,X6S,CH622KMEB02    I67 @T6G_MB_LIB.T6G(SCH_1):PAGE69
 C2594    2      B Q_CAP_C0402-22UF,4V,20%,X6S,CH622KMEB02    I69 @T6G_MB_LIB.T6G(SCH_1):PAGE69
 C2601    2      B Q_CAP_C0402-22UF,4V,20%,X6S,CH622KMEB02    I71 @T6G_MB_LIB.T6G(SCH_1):PAGE69
 C2593    2      B Q_CAP_C0402-22UF,4V,20%,X6S,CH622KMEB02    I74 @T6G_MB_LIB.T6G(SCH_1):PAGE69
 C2600    2      B Q_CAP_C0402-22UF,4V,20%,X6S,CH622KMEB02    I76 @T6G_MB_LIB.T6G(SCH_1):PAGE69
 C2543    2      B Q_CAP_C0402-22UF,4V,20%,X6S,CH622KMEB02    I78 @T6G_MB_LIB.T6G(SCH_1):PAGE69
 C2542    2      B Q_CAP_C0402-22UF,4V,20%,X6S,CH622KMEB02    I79 @T6G_MB_LIB.T6G(SCH_1):PAGE69
 C2550    2      B Q_CAP_C0402-22UF,4V,20%,X6S,CH622KMEB02    I80 @T6G_MB_LIB.T6G(SCH_1):PAGE69
 C2549    2      B Q_CAP_C0402-22UF,4V,20%,X6S,CH622KMEB02    I81 @T6G_MB_LIB.T6G(SCH_1):PAGE69
 C2557    2      B Q_CAP_C0402-22UF,4V,20%,X6S,CH622KMEB02    I82 @T6G_MB_LIB.T6G(SCH_1):PAGE69
 C2556    2      B Q_CAP_C0402-22UF,4V,20%,X6S,CH622KMEB02    I83 @T6G_MB_LIB.T6G(SCH_1):PAGE69
 C2541    2      B Q_CAP_C0402-22UF,4V,20%,X6S,CH622KMEB02    I84 @T6G_MB_LIB.T6G(SCH_1):PAGE69
 C2548    2      B Q_CAP_C0402-22UF,4V,20%,X6S,CH622KMEB02    I85 @T6G_MB_LIB.T6G(SCH_1):PAGE69
 C2555    2      B Q_CAP_C0402-22UF,4V,20%,X6S,CH622KMEB02    I86 @T6G_MB_LIB.T6G(SCH_1):PAGE69
 C2564    2      B Q_CAP_C0402-22UF,4V,20%,X6S,CH622KMEB02    I87 @T6G_MB_LIB.T6G(SCH_1):PAGE69
 C2563    2      B Q_CAP_C0402-22UF,4V,20%,X6S,CH622KMEB02    I88 @T6G_MB_LIB.T6G(SCH_1):PAGE69
 C2571    2      B Q_CAP_C0402-22UF,4V,20%,X6S,CH622KMEB02    I89 @T6G_MB_LIB.T6G(SCH_1):PAGE69
 C2570    2      B Q_CAP_C0402-22UF,4V,20%,X6S,CH622KMEB02    I90 @T6G_MB_LIB.T6G(SCH_1):PAGE69
 C2562    2      B Q_CAP_C0402-22UF,4V,20%,X6S,CH622KMEB02    I91 @T6G_MB_LIB.T6G(SCH_1):PAGE69
 C2569    2      B Q_CAP_C0402-22UF,4V,20%,X6S,CH622KMEB02    I92 @T6G_MB_LIB.T6G(SCH_1):PAGE69
 C2578    2      B Q_CAP_C0402-22UF,4V,20%,X6S,CH622KMEB02    I93 @T6G_MB_LIB.T6G(SCH_1):PAGE69
 C2577    2      B Q_CAP_C0402-22UF,4V,20%,X6S,CH622KMEB02    I94 @T6G_MB_LIB.T6G(SCH_1):PAGE69
 C2585    2      B Q_CAP_C0402-22UF,4V,20%,X6S,CH622KMEB02    I95 @T6G_MB_LIB.T6G(SCH_1):PAGE69
 C2584    2      B Q_CAP_C0402-22UF,4V,20%,X6S,CH622KMEB02    I96 @T6G_MB_LIB.T6G(SCH_1):PAGE69
 C2576    2      B Q_CAP_C0402-22UF,4V,20%,X6S,CH622KMEB02    I97 @T6G_MB_LIB.T6G(SCH_1):PAGE69
 C2583    2      B Q_CAP_C0402-22UF,4V,20%,X6S,CH622KMEB02    I98 @T6G_MB_LIB.T6G(SCH_1):PAGE69
 C2592    2      B Q_CAP_C0402-22UF,4V,20%,X6S,CH622KMEB02    I99 @T6G_MB_LIB.T6G(SCH_1):PAGE69
 C2591    2      B Q_CAP_C0402-22UF,4V,20%,X6S,CH622KMEB02   I101 @T6G_MB_LIB.T6G(SCH_1):PAGE69
 C2599    2      B Q_CAP_C0402-22UF,4V,20%,X6S,CH622KMEB02   I102 @T6G_MB_LIB.T6G(SCH_1):PAGE69
 C2598    2      B Q_CAP_C0402-22UF,4V,20%,X6S,CH622KMEB02   I104 @T6G_MB_LIB.T6G(SCH_1):PAGE69
 C2590    2      B Q_CAP_C0402-22UF,4V,20%,X6S,CH622KMEB02   I106 @T6G_MB_LIB.T6G(SCH_1):PAGE69
 C2597    2      B Q_CAP_C0402-22UF,4V,20%,X6S,CH622KMEB02   I108 @T6G_MB_LIB.T6G(SCH_1):PAGE69
 C3933    2      B Q_CAP_C0402-22UF,4V,20%,X6S,CH622KMEB02   I111 @T6G_MB_LIB.T6G(SCH_1):PAGE69
 C2610    2      B Q_CAP_C0402-22UF,4V,20%,X6S,CH622KMEB02   I112 @T6G_MB_LIB.T6G(SCH_1):PAGE69
 C2609    2      B Q_CAP_C0402-22UF,4V,20%,X6S,CH622KMEB02   I113 @T6G_MB_LIB.T6G(SCH_1):PAGE69
 C2617    2      B Q_CAP_C0402-22UF,4V,20%,X6S,CH622KMEB02   I114 @T6G_MB_LIB.T6G(SCH_1):PAGE69
 C2616    2      B Q_CAP_C0402-22UF,4V,20%,X6S,CH622KMEB02   I115 @T6G_MB_LIB.T6G(SCH_1):PAGE69
 C2624    2      B Q_CAP_C0402-22UF,4V,20%,X6S,CH622KMEB02   I116 @T6G_MB_LIB.T6G(SCH_1):PAGE69
 C2623    2      B Q_CAP_C0402-22UF,4V,20%,X6S,CH622KMEB02   I117 @T6G_MB_LIB.T6G(SCH_1):PAGE69
 C2630    2      B Q_CAP_C0402-22UF,4V,20%,X6S,CH622KMEB02   I118 @T6G_MB_LIB.T6G(SCH_1):PAGE69
 C2629    2      B Q_CAP_C0402-22UF,4V,20%,X6S,CH622KMEB02   I119 @T6G_MB_LIB.T6G(SCH_1):PAGE69
 C2636    2      B Q_CAP_C0402-22UF,4V,20%,X6S,CH622KMEB02   I120 @T6G_MB_LIB.T6G(SCH_1):PAGE69
 C2635    2      B Q_CAP_C0402-22UF,4V,20%,X6S,CH622KMEB02   I121 @T6G_MB_LIB.T6G(SCH_1):PAGE69
 C2608    2      B Q_CAP_C0402-22UF,4V,20%,X6S,CH622KMEB02   I122 @T6G_MB_LIB.T6G(SCH_1):PAGE69
 C2615    2      B Q_CAP_C0402-22UF,4V,20%,X6S,CH622KMEB02   I123 @T6G_MB_LIB.T6G(SCH_1):PAGE69
 C2607    2      B Q_CAP_C0402-22UF,4V,20%,X6S,CH622KMEB02   I124 @T6G_MB_LIB.T6G(SCH_1):PAGE69
 C2614    2      B Q_CAP_C0402-22UF,4V,20%,X6S,CH622KMEB02   I125 @T6G_MB_LIB.T6G(SCH_1):PAGE69
 C2622    2      B Q_CAP_C0402-22UF,4V,20%,X6S,CH622KMEB02   I126 @T6G_MB_LIB.T6G(SCH_1):PAGE69
 C2621    2      B Q_CAP_C0402-22UF,4V,20%,X6S,CH622KMEB02   I127 @T6G_MB_LIB.T6G(SCH_1):PAGE69
 C2628    2      B Q_CAP_C0402-22UF,4V,20%,X6S,CH622KMEB02   I129 @T6G_MB_LIB.T6G(SCH_1):PAGE69
 C2634    2      B Q_CAP_C0402-22UF,4V,20%,X6S,CH622KMEB02   I130 @T6G_MB_LIB.T6G(SCH_1):PAGE69
 C2627    2      B Q_CAP_C0402-22UF,4V,20%,X6S,CH622KMEB02   I131 @T6G_MB_LIB.T6G(SCH_1):PAGE69
 C2633    2      B Q_CAP_C0402-22UF,4V,20%,X6S,CH622KMEB02   I132 @T6G_MB_LIB.T6G(SCH_1):PAGE69
 C2642    2      B Q_CAP_C0402-22UF,4V,20%,X6S,CH622KMEB02   I133 @T6G_MB_LIB.T6G(SCH_1):PAGE69
 C2641    2      B Q_CAP_C0402-22UF,4V,20%,X6S,CH622KMEB02   I134 @T6G_MB_LIB.T6G(SCH_1):PAGE69
 C2648    2      B Q_CAP_C0402-22UF,4V,20%,X6S,CH622KMEB02   I135 @T6G_MB_LIB.T6G(SCH_1):PAGE69
 C2647    2      B Q_CAP_C0402-22UF,4V,20%,X6S,CH622KMEB02   I136 @T6G_MB_LIB.T6G(SCH_1):PAGE69
 C3934    2      B Q_CAP_C0402-22UF,4V,20%,X6S,CH622KMEB02   I138 @T6G_MB_LIB.T6G(SCH_1):PAGE69
 C2653    2      B Q_CAP_C0402-22UF,4V,20%,X6S,CH622KMEB02   I139 @T6G_MB_LIB.T6G(SCH_1):PAGE69
 C3935    2      B Q_CAP_C0402-22UF,4V,20%,X6S,CH622KMEB02   I140 @T6G_MB_LIB.T6G(SCH_1):PAGE69
 C2658    2      B Q_CAP_C0402-22UF,4V,20%,X6S,CH622KMEB02   I142 @T6G_MB_LIB.T6G(SCH_1):PAGE69
 C2640    2      B Q_CAP_C0402-22UF,4V,20%,X6S,CH622KMEB02   I143 @T6G_MB_LIB.T6G(SCH_1):PAGE69
 C2646    2      B Q_CAP_C0402-22UF,4V,20%,X6S,CH622KMEB02   I144 @T6G_MB_LIB.T6G(SCH_1):PAGE69
 C2639    2      B Q_CAP_C0402-22UF,4V,20%,X6S,CH622KMEB02   I145 @T6G_MB_LIB.T6G(SCH_1):PAGE69
 C2645    2      B Q_CAP_C0402-22UF,4V,20%,X6S,CH622KMEB02   I146 @T6G_MB_LIB.T6G(SCH_1):PAGE69
 C2652    2      B Q_CAP_C0402-22UF,4V,20%,X6S,CH622KMEB02   I147 @T6G_MB_LIB.T6G(SCH_1):PAGE69
 C2657    2      B Q_CAP_C0402-22UF,4V,20%,X6S,CH622KMEB02   I149 @T6G_MB_LIB.T6G(SCH_1):PAGE69
 C2651    2      B Q_CAP_C0402-22UF,4V,20%,X6S,CH622KMEB02   I151 @T6G_MB_LIB.T6G(SCH_1):PAGE69
 C2656    2      B Q_CAP_C0402-22UF,4V,20%,X6S,CH622KMEB02   I152 @T6G_MB_LIB.T6G(SCH_1):PAGE69
 C2606    2      B Q_CAP_C0402-22UF,4V,20%,X6S,CH622KMEB02   I153 @T6G_MB_LIB.T6G(SCH_1):PAGE69
 C2605    2      B Q_CAP_C0402-22UF,4V,20%,X6S,CH622KMEB02   I154 @T6G_MB_LIB.T6G(SCH_1):PAGE69
 C2613    2      B Q_CAP_C0402-22UF,4V,20%,X6S,CH622KMEB02   I155 @T6G_MB_LIB.T6G(SCH_1):PAGE69
 C2612    2      B Q_CAP_C0402-22UF,4V,20%,X6S,CH622KMEB02   I156 @T6G_MB_LIB.T6G(SCH_1):PAGE69
 C2619    2      B Q_CAP_C0402-22UF,4V,20%,X6S,CH622KMEB02   I157 @T6G_MB_LIB.T6G(SCH_1):PAGE69
 C2604    2      B Q_CAP_C0402-22UF,4V,20%,X6S,CH622KMEB02   I158 @T6G_MB_LIB.T6G(SCH_1):PAGE69
 C2611    2      B Q_CAP_C0402-22UF,4V,20%,X6S,CH622KMEB02   I159 @T6G_MB_LIB.T6G(SCH_1):PAGE69
 C2618    2      B Q_CAP_C0402-22UF,4V,20%,X6S,CH622KMEB02   I160 @T6G_MB_LIB.T6G(SCH_1):PAGE69
 C2620    2      B Q_CAP_C0402-22UF,4V,20%,X6S,CH622KMEB02   I161 @T6G_MB_LIB.T6G(SCH_1):PAGE69
 C2626    2      B Q_CAP_C0402-22UF,4V,20%,X6S,CH622KMEB02   I162 @T6G_MB_LIB.T6G(SCH_1):PAGE69
 C2632    2      B Q_CAP_C0402-22UF,4V,20%,X6S,CH622KMEB02   I163 @T6G_MB_LIB.T6G(SCH_1):PAGE69
 C2625    2      B Q_CAP_C0402-22UF,4V,20%,X6S,CH622KMEB02   I164 @T6G_MB_LIB.T6G(SCH_1):PAGE69
 C2631    2      B Q_CAP_C0402-22UF,4V,20%,X6S,CH622KMEB02   I165 @T6G_MB_LIB.T6G(SCH_1):PAGE69
 C2638    2      B Q_CAP_C0402-22UF,4V,20%,X6S,CH622KMEB02   I166 @T6G_MB_LIB.T6G(SCH_1):PAGE69
 C2644    2      B Q_CAP_C0402-22UF,4V,20%,X6S,CH622KMEB02   I167 @T6G_MB_LIB.T6G(SCH_1):PAGE69
 C2637    2      B Q_CAP_C0402-22UF,4V,20%,X6S,CH622KMEB02   I168 @T6G_MB_LIB.T6G(SCH_1):PAGE69
 C2643    2      B Q_CAP_C0402-22UF,4V,20%,X6S,CH622KMEB02   I169 @T6G_MB_LIB.T6G(SCH_1):PAGE69
 C2650    2      B Q_CAP_C0402-22UF,4V,20%,X6S,CH622KMEB02   I170 @T6G_MB_LIB.T6G(SCH_1):PAGE69
 C2655    2      B Q_CAP_C0402-22UF,4V,20%,X6S,CH622KMEB02   I172 @T6G_MB_LIB.T6G(SCH_1):PAGE69
 C2649    2      B Q_CAP_C0402-22UF,4V,20%,X6S,CH622KMEB02   I173 @T6G_MB_LIB.T6G(SCH_1):PAGE69
 C2654    2      B Q_CAP_C0402-22UF,4V,20%,X6S,CH622KMEB02   I175 @T6G_MB_LIB.T6G(SCH_1):PAGE69
 C2514    2      B Q_CAP_C0402-22UF,4V,20%,X6S,CH622KMEB02     I1 @T6G_MB_LIB.T6G(SCH_1):PAGE70
 C2513    2      B Q_CAP_C0402-22UF,4V,20%,X6S,CH622KMEB02     I3 @T6G_MB_LIB.T6G(SCH_1):PAGE70
 C2517    2      B Q_CAP_C0402-22UF,4V,20%,X6S,CH622KMEB02     I8 @T6G_MB_LIB.T6G(SCH_1):PAGE70
 C2516    2      B Q_CAP_C0402-22UF,4V,20%,X6S,CH622KMEB02     I9 @T6G_MB_LIB.T6G(SCH_1):PAGE70
 C2518    2      B Q_CAP_C0402-22UF,4V,20%,X6S,CH622KMEB02    I10 @T6G_MB_LIB.T6G(SCH_1):PAGE70
 C2520    2      B Q_CAP_C0402-22UF,4V,20%,X6S,CH622KMEB02    I11 @T6G_MB_LIB.T6G(SCH_1):PAGE70
 C2521    2      B Q_CAP_C0402-22UF,4V,20%,X6S,CH622KMEB02    I12 @T6G_MB_LIB.T6G(SCH_1):PAGE70
 C2522    2      B Q_CAP_C0402-22UF,4V,20%,X6S,CH622KMEB02    I13 @T6G_MB_LIB.T6G(SCH_1):PAGE70
 C2523    2      B Q_CAP_C0402-22UF,4V,20%,X6S,CH622KMEB02    I14 @T6G_MB_LIB.T6G(SCH_1):PAGE70
 C2524    2      B Q_CAP_C0402-22UF,4V,20%,X6S,CH622KMEB02    I15 @T6G_MB_LIB.T6G(SCH_1):PAGE70
 C2525    2      B Q_CAP_C0402-22UF,4V,20%,X6S,CH622KMEB02    I16 @T6G_MB_LIB.T6G(SCH_1):PAGE70
 C2526    2      B Q_CAP_C0402-22UF,4V,20%,X6S,CH622KMEB02    I18 @T6G_MB_LIB.T6G(SCH_1):PAGE70
 C2262    2      B Q_CAP_C0402-22UF,4V,20%,X6S,CH622KMEB02     I1 @T6G_MB_LIB.T6G(SCH_1):PAGE71
 C2261    2      B Q_CAP_C0402-22UF,4V,20%,X6S,CH622KMEB02     I3 @T6G_MB_LIB.T6G(SCH_1):PAGE71
 C3900    2      B Q_CAP_C0402-22UF,4V,20%,X6S,CH622KMEB02     I5 @T6G_MB_LIB.T6G(SCH_1):PAGE71
 C2259    2      B Q_CAP_C0402-22UF,4V,20%,X6S,CH622KMEB02     I7 @T6G_MB_LIB.T6G(SCH_1):PAGE71
 C2258    2      B Q_CAP_C0402-22UF,4V,20%,X6S,CH622KMEB02     I9 @T6G_MB_LIB.T6G(SCH_1):PAGE71
 C2267    2      B Q_CAP_C0402-22UF,4V,20%,X6S,CH622KMEB02    I11 @T6G_MB_LIB.T6G(SCH_1):PAGE71
 C3902    2      B Q_CAP_C0402-22UF,4V,20%,X6S,CH622KMEB02    I12 @T6G_MB_LIB.T6G(SCH_1):PAGE71
 C2266    2      B Q_CAP_C0402-22UF,4V,20%,X6S,CH622KMEB02    I13 @T6G_MB_LIB.T6G(SCH_1):PAGE71
 C2271    2      B Q_CAP_C0402-22UF,4V,20%,X6S,CH622KMEB02    I14 @T6G_MB_LIB.T6G(SCH_1):PAGE71
 C3903    2      B Q_CAP_C0402-22UF,4V,20%,X6S,CH622KMEB02    I15 @T6G_MB_LIB.T6G(SCH_1):PAGE71
 C3904    2      B Q_CAP_C0402-22UF,4V,20%,X6S,CH622KMEB02    I16 @T6G_MB_LIB.T6G(SCH_1):PAGE71
 C3905    2      B Q_CAP_C0402-22UF,4V,20%,X6S,CH622KMEB02    I18 @T6G_MB_LIB.T6G(SCH_1):PAGE71
 C2275    2      B Q_CAP_C0402-22UF,4V,20%,X6S,CH622KMEB02    I19 @T6G_MB_LIB.T6G(SCH_1):PAGE71
 C2279    2      B Q_CAP_C0402-22UF,4V,20%,X6S,CH622KMEB02    I20 @T6G_MB_LIB.T6G(SCH_1):PAGE71
 C2282    2      B Q_CAP_C0402-22UF,4V,20%,X6S,CH622KMEB02    I21 @T6G_MB_LIB.T6G(SCH_1):PAGE71
 C3901    2      B Q_CAP_C0402-22UF,4V,20%,X6S,CH622KMEB02    I23 @T6G_MB_LIB.T6G(SCH_1):PAGE71
 C2285    2      B Q_CAP_C0402-22UF,4V,20%,X6S,CH622KMEB02    I24 @T6G_MB_LIB.T6G(SCH_1):PAGE71
 C2287    2      B Q_CAP_C0402-22UF,4V,20%,X6S,CH622KMEB02    I25 @T6G_MB_LIB.T6G(SCH_1):PAGE71
 C2289    2      B Q_CAP_C0402-22UF,4V,20%,X6S,CH622KMEB02    I26 @T6G_MB_LIB.T6G(SCH_1):PAGE71
 C2291    2      B Q_CAP_C0402-22UF,4V,20%,X6S,CH622KMEB02    I28 @T6G_MB_LIB.T6G(SCH_1):PAGE71
 C2264    2      B Q_CAP_C0402-22UF,4V,20%,X6S,CH622KMEB02    I30 @T6G_MB_LIB.T6G(SCH_1):PAGE71
 C2263    2      B Q_CAP_C0402-22UF,4V,20%,X6S,CH622KMEB02    I31 @T6G_MB_LIB.T6G(SCH_1):PAGE71
 C2269    2      B Q_CAP_C0402-22UF,4V,20%,X6S,CH622KMEB02    I32 @T6G_MB_LIB.T6G(SCH_1):PAGE71
 C2268    2      B Q_CAP_C0402-22UF,4V,20%,X6S,CH622KMEB02    I33 @T6G_MB_LIB.T6G(SCH_1):PAGE71
 C2272    2      B Q_CAP_C0402-22UF,4V,20%,X6S,CH622KMEB02    I34 @T6G_MB_LIB.T6G(SCH_1):PAGE71
 C2273    2      B Q_CAP_C0402-22UF,4V,20%,X6S,CH622KMEB02    I35 @T6G_MB_LIB.T6G(SCH_1):PAGE71
 C2277    2      B Q_CAP_C0402-22UF,4V,20%,X6S,CH622KMEB02    I36 @T6G_MB_LIB.T6G(SCH_1):PAGE71
 C2281    2      B Q_CAP_C0402-22UF,4V,20%,X6S,CH622KMEB02    I37 @T6G_MB_LIB.T6G(SCH_1):PAGE71
 C2280    2      B Q_CAP_C0402-22UF,4V,20%,X6S,CH622KMEB02    I38 @T6G_MB_LIB.T6G(SCH_1):PAGE71
 C2284    2      B Q_CAP_C0402-22UF,4V,20%,X6S,CH622KMEB02    I39 @T6G_MB_LIB.T6G(SCH_1):PAGE71
 C2283    2      B Q_CAP_C0402-22UF,4V,20%,X6S,CH622KMEB02    I40 @T6G_MB_LIB.T6G(SCH_1):PAGE71
 C3906    2      B Q_CAP_C0402-22UF,4V,20%,X6S,CH622KMEB02    I41 @T6G_MB_LIB.T6G(SCH_1):PAGE71
 C2286    2      B Q_CAP_C0402-22UF,4V,20%,X6S,CH622KMEB02    I42 @T6G_MB_LIB.T6G(SCH_1):PAGE71
 C3907    2      B Q_CAP_C0402-22UF,4V,20%,X6S,CH622KMEB02    I43 @T6G_MB_LIB.T6G(SCH_1):PAGE71
 C2288    2      B Q_CAP_C0402-22UF,4V,20%,X6S,CH622KMEB02    I44 @T6G_MB_LIB.T6G(SCH_1):PAGE71
 C3908    2      B Q_CAP_C0402-22UF,4V,20%,X6S,CH622KMEB02    I45 @T6G_MB_LIB.T6G(SCH_1):PAGE71
 C2290    2      B Q_CAP_C0402-22UF,4V,20%,X6S,CH622KMEB02    I47 @T6G_MB_LIB.T6G(SCH_1):PAGE71
 C2292    2      B Q_CAP_C0402-22UF,4V,20%,X6S,CH622KMEB02    I49 @T6G_MB_LIB.T6G(SCH_1):PAGE71
 C2293    2      B Q_CAP_C0402-22UF,4V,20%,X6S,CH622KMEB02    I50 @T6G_MB_LIB.T6G(SCH_1):PAGE71
 C3909    2      B Q_CAP_C0402-22UF,4V,20%,X6S,CH622KMEB02    I52 @T6G_MB_LIB.T6G(SCH_1):PAGE71
 C2260    2      B Q_CAP_C0402-22UF,4V,20%,X6S,CH622KMEB02    I53 @T6G_MB_LIB.T6G(SCH_1):PAGE71
 C2265    2      B Q_CAP_C0402-22UF,4V,20%,X6S,CH622KMEB02    I54 @T6G_MB_LIB.T6G(SCH_1):PAGE71
 C2270    2      B Q_CAP_C0402-22UF,4V,20%,X6S,CH622KMEB02    I56 @T6G_MB_LIB.T6G(SCH_1):PAGE71
 C2274    2      B Q_CAP_C0402-22UF,4V,20%,X6S,CH622KMEB02    I57 @T6G_MB_LIB.T6G(SCH_1):PAGE71
 C2278    2      B Q_CAP_C0402-22UF,4V,20%,X6S,CH622KMEB02    I58 @T6G_MB_LIB.T6G(SCH_1):PAGE71
 C3910    2      B Q_CAP_C0402-22UF,4V,20%,X6S,CH622KMEB02    I59 @T6G_MB_LIB.T6G(SCH_1):PAGE71
 C3911    2      B Q_CAP_C0402-22UF,4V,20%,X6S,CH622KMEB02    I61 @T6G_MB_LIB.T6G(SCH_1):PAGE71
 C2276    2      B Q_CAP_C0402-22UF,4V,20%,X6S,CH622KMEB02    I62 @T6G_MB_LIB.T6G(SCH_1):PAGE71
 C2298    2      B Q_CAP_C0402-22UF,4V,20%,X6S,CH622KMEB02     I1 @T6G_MB_LIB.T6G(SCH_1):PAGE72
 C2304    2      B Q_CAP_C0402-22UF,4V,20%,X6S,CH622KMEB02     I3 @T6G_MB_LIB.T6G(SCH_1):PAGE72
 C2310    2      B Q_CAP_C0402-22UF,4V,20%,X6S,CH622KMEB02     I4 @T6G_MB_LIB.T6G(SCH_1):PAGE72
 C2297    2      B Q_CAP_C0402-22UF,4V,20%,X6S,CH622KMEB02     I5 @T6G_MB_LIB.T6G(SCH_1):PAGE72
 C2296    2      B Q_CAP_C0402-22UF,4V,20%,X6S,CH622KMEB02     I7 @T6G_MB_LIB.T6G(SCH_1):PAGE72
 C2295    2      B Q_CAP_C0402-22UF,4V,20%,X6S,CH622KMEB02     I9 @T6G_MB_LIB.T6G(SCH_1):PAGE72
 C2303    2      B Q_CAP_C0402-22UF,4V,20%,X6S,CH622KMEB02    I10 @T6G_MB_LIB.T6G(SCH_1):PAGE72
 C2309    2      B Q_CAP_C0402-22UF,4V,20%,X6S,CH622KMEB02    I11 @T6G_MB_LIB.T6G(SCH_1):PAGE72
 C2302    2      B Q_CAP_C0402-22UF,4V,20%,X6S,CH622KMEB02    I12 @T6G_MB_LIB.T6G(SCH_1):PAGE72
 C2301    2      B Q_CAP_C0402-22UF,4V,20%,X6S,CH622KMEB02    I13 @T6G_MB_LIB.T6G(SCH_1):PAGE72
 C2308    2      B Q_CAP_C0402-22UF,4V,20%,X6S,CH622KMEB02    I14 @T6G_MB_LIB.T6G(SCH_1):PAGE72
 C2307    2      B Q_CAP_C0402-22UF,4V,20%,X6S,CH622KMEB02    I15 @T6G_MB_LIB.T6G(SCH_1):PAGE72
 C2294    2      B Q_CAP_C0402-22UF,4V,20%,X6S,CH622KMEB02    I17 @T6G_MB_LIB.T6G(SCH_1):PAGE72
 C2300    2      B Q_CAP_C0402-22UF,4V,20%,X6S,CH622KMEB02    I19 @T6G_MB_LIB.T6G(SCH_1):PAGE72
 C2306    2      B Q_CAP_C0402-22UF,4V,20%,X6S,CH622KMEB02    I20 @T6G_MB_LIB.T6G(SCH_1):PAGE72
 C2316    2      B Q_CAP_C0402-22UF,4V,20%,X6S,CH622KMEB02    I21 @T6G_MB_LIB.T6G(SCH_1):PAGE72
 C2322    2      B Q_CAP_C0402-22UF,4V,20%,X6S,CH622KMEB02    I23 @T6G_MB_LIB.T6G(SCH_1):PAGE72
 C2315    2      B Q_CAP_C0402-22UF,4V,20%,X6S,CH622KMEB02    I24 @T6G_MB_LIB.T6G(SCH_1):PAGE72
 C2321    2      B Q_CAP_C0402-22UF,4V,20%,X6S,CH622KMEB02    I25 @T6G_MB_LIB.T6G(SCH_1):PAGE72
 C2327    2      B Q_CAP_C0402-22UF,4V,20%,X6S,CH622KMEB02    I26 @T6G_MB_LIB.T6G(SCH_1):PAGE72
 C2314    2      B Q_CAP_C0402-22UF,4V,20%,X6S,CH622KMEB02    I27 @T6G_MB_LIB.T6G(SCH_1):PAGE72
 C2313    2      B Q_CAP_C0402-22UF,4V,20%,X6S,CH622KMEB02    I28 @T6G_MB_LIB.T6G(SCH_1):PAGE72
 C2320    2      B Q_CAP_C0402-22UF,4V,20%,X6S,CH622KMEB02    I29 @T6G_MB_LIB.T6G(SCH_1):PAGE72
 C2326    2      B Q_CAP_C0402-22UF,4V,20%,X6S,CH622KMEB02    I30 @T6G_MB_LIB.T6G(SCH_1):PAGE72
 C2319    2      B Q_CAP_C0402-22UF,4V,20%,X6S,CH622KMEB02    I31 @T6G_MB_LIB.T6G(SCH_1):PAGE72
 C2325    2      B Q_CAP_C0402-22UF,4V,20%,X6S,CH622KMEB02    I32 @T6G_MB_LIB.T6G(SCH_1):PAGE72
 C2333    2      B Q_CAP_C0402-22UF,4V,20%,X6S,CH622KMEB02    I33 @T6G_MB_LIB.T6G(SCH_1):PAGE72
 C2338    2      B Q_CAP_C0402-22UF,4V,20%,X6S,CH622KMEB02    I34 @T6G_MB_LIB.T6G(SCH_1):PAGE72
 C2332    2      B Q_CAP_C0402-22UF,4V,20%,X6S,CH622KMEB02    I35 @T6G_MB_LIB.T6G(SCH_1):PAGE72
 C2331    2      B Q_CAP_C0402-22UF,4V,20%,X6S,CH622KMEB02    I36 @T6G_MB_LIB.T6G(SCH_1):PAGE72
 C2337    2      B Q_CAP_C0402-22UF,4V,20%,X6S,CH622KMEB02    I37 @T6G_MB_LIB.T6G(SCH_1):PAGE72
 C2336    2      B Q_CAP_C0402-22UF,4V,20%,X6S,CH622KMEB02    I38 @T6G_MB_LIB.T6G(SCH_1):PAGE72
 C2354    2      B Q_CAP_C0402-22UF,4V,20%,X6S,CH622KMEB02    I40 @T6G_MB_LIB.T6G(SCH_1):PAGE72
 C2360    2      B Q_CAP_C0402-22UF,4V,20%,X6S,CH622KMEB02    I41 @T6G_MB_LIB.T6G(SCH_1):PAGE72
 C2343    2      B Q_CAP_C0402-22UF,4V,20%,X6S,CH622KMEB02    I42 @T6G_MB_LIB.T6G(SCH_1):PAGE72
 C2348    2      B Q_CAP_C0402-22UF,4V,20%,X6S,CH622KMEB02    I44 @T6G_MB_LIB.T6G(SCH_1):PAGE72
 C2342    2      B Q_CAP_C0402-22UF,4V,20%,X6S,CH622KMEB02    I46 @T6G_MB_LIB.T6G(SCH_1):PAGE72
 C2341    2      B Q_CAP_C0402-22UF,4V,20%,X6S,CH622KMEB02    I47 @T6G_MB_LIB.T6G(SCH_1):PAGE72
 C2347    2      B Q_CAP_C0402-22UF,4V,20%,X6S,CH622KMEB02    I48 @T6G_MB_LIB.T6G(SCH_1):PAGE72
 C2346    2      B Q_CAP_C0402-22UF,4V,20%,X6S,CH622KMEB02    I50 @T6G_MB_LIB.T6G(SCH_1):PAGE72
 C2353    2      B Q_CAP_C0402-22UF,4V,20%,X6S,CH622KMEB02    I51 @T6G_MB_LIB.T6G(SCH_1):PAGE72
 C2359    2      B Q_CAP_C0402-22UF,4V,20%,X6S,CH622KMEB02    I53 @T6G_MB_LIB.T6G(SCH_1):PAGE72
 C2352    2      B Q_CAP_C0402-22UF,4V,20%,X6S,CH622KMEB02    I55 @T6G_MB_LIB.T6G(SCH_1):PAGE72
 C2351    2      B Q_CAP_C0402-22UF,4V,20%,X6S,CH622KMEB02    I56 @T6G_MB_LIB.T6G(SCH_1):PAGE72
 C2358    2      B Q_CAP_C0402-22UF,4V,20%,X6S,CH622KMEB02    I57 @T6G_MB_LIB.T6G(SCH_1):PAGE72
 C2357    2      B Q_CAP_C0402-22UF,4V,20%,X6S,CH622KMEB02    I58 @T6G_MB_LIB.T6G(SCH_1):PAGE72
 C2312    2      B Q_CAP_C0402-22UF,4V,20%,X6S,CH622KMEB02    I59 @T6G_MB_LIB.T6G(SCH_1):PAGE72
 C2318    2      B Q_CAP_C0402-22UF,4V,20%,X6S,CH622KMEB02    I60 @T6G_MB_LIB.T6G(SCH_1):PAGE72
 C2324    2      B Q_CAP_C0402-22UF,4V,20%,X6S,CH622KMEB02    I61 @T6G_MB_LIB.T6G(SCH_1):PAGE72
 C2330    2      B Q_CAP_C0402-22UF,4V,20%,X6S,CH622KMEB02    I62 @T6G_MB_LIB.T6G(SCH_1):PAGE72
 C2335    2      B Q_CAP_C0402-22UF,4V,20%,X6S,CH622KMEB02    I63 @T6G_MB_LIB.T6G(SCH_1):PAGE72
 C2340    2      B Q_CAP_C0402-22UF,4V,20%,X6S,CH622KMEB02    I64 @T6G_MB_LIB.T6G(SCH_1):PAGE72
 C2345    2      B Q_CAP_C0402-22UF,4V,20%,X6S,CH622KMEB02    I66 @T6G_MB_LIB.T6G(SCH_1):PAGE72
 C2356    2      B Q_CAP_C0402-22UF,4V,20%,X6S,CH622KMEB02    I68 @T6G_MB_LIB.T6G(SCH_1):PAGE72
 C2366    2      B Q_CAP_C0402-22UF,4V,20%,X6S,CH622KMEB02    I70 @T6G_MB_LIB.T6G(SCH_1):PAGE72
 C2372    2      B Q_CAP_C0402-22UF,4V,20%,X6S,CH622KMEB02    I71 @T6G_MB_LIB.T6G(SCH_1):PAGE72
 C2378    2      B Q_CAP_C0402-22UF,4V,20%,X6S,CH622KMEB02    I72 @T6G_MB_LIB.T6G(SCH_1):PAGE72
 C2365    2      B Q_CAP_C0402-22UF,4V,20%,X6S,CH622KMEB02    I74 @T6G_MB_LIB.T6G(SCH_1):PAGE72
 C2371    2      B Q_CAP_C0402-22UF,4V,20%,X6S,CH622KMEB02    I75 @T6G_MB_LIB.T6G(SCH_1):PAGE72
 C2364    2      B Q_CAP_C0402-22UF,4V,20%,X6S,CH622KMEB02    I76 @T6G_MB_LIB.T6G(SCH_1):PAGE72
 C2363    2      B Q_CAP_C0402-22UF,4V,20%,X6S,CH622KMEB02    I77 @T6G_MB_LIB.T6G(SCH_1):PAGE72
 C2370    2      B Q_CAP_C0402-22UF,4V,20%,X6S,CH622KMEB02    I78 @T6G_MB_LIB.T6G(SCH_1):PAGE72
 C2369    2      B Q_CAP_C0402-22UF,4V,20%,X6S,CH622KMEB02    I79 @T6G_MB_LIB.T6G(SCH_1):PAGE72
 C2376    2      B Q_CAP_C0402-22UF,4V,20%,X6S,CH622KMEB02    I80 @T6G_MB_LIB.T6G(SCH_1):PAGE72
 C2377    2      B Q_CAP_C0402-22UF,4V,20%,X6S,CH622KMEB02    I81 @T6G_MB_LIB.T6G(SCH_1):PAGE72
 C2383    2      B Q_CAP_C0402-22UF,4V,20%,X6S,CH622KMEB02    I82 @T6G_MB_LIB.T6G(SCH_1):PAGE72
 C2389    2      B Q_CAP_C0402-22UF,4V,20%,X6S,CH622KMEB02    I83 @T6G_MB_LIB.T6G(SCH_1):PAGE72
 C2382    2      B Q_CAP_C0402-22UF,4V,20%,X6S,CH622KMEB02    I84 @T6G_MB_LIB.T6G(SCH_1):PAGE72
 C2375    2      B Q_CAP_C0402-22UF,4V,20%,X6S,CH622KMEB02    I85 @T6G_MB_LIB.T6G(SCH_1):PAGE72
 C2381    2      B Q_CAP_C0402-22UF,4V,20%,X6S,CH622KMEB02    I86 @T6G_MB_LIB.T6G(SCH_1):PAGE72
 C2388    2      B Q_CAP_C0402-22UF,4V,20%,X6S,CH622KMEB02    I87 @T6G_MB_LIB.T6G(SCH_1):PAGE72
 C2387    2      B Q_CAP_C0402-22UF,4V,20%,X6S,CH622KMEB02    I88 @T6G_MB_LIB.T6G(SCH_1):PAGE72
 C2395    2      B Q_CAP_C0402-22UF,4V,20%,X6S,CH622KMEB02    I89 @T6G_MB_LIB.T6G(SCH_1):PAGE72
 C2400    2      B Q_CAP_C0402-22UF,4V,20%,X6S,CH622KMEB02    I90 @T6G_MB_LIB.T6G(SCH_1):PAGE72
 C2394    2      B Q_CAP_C0402-22UF,4V,20%,X6S,CH622KMEB02    I91 @T6G_MB_LIB.T6G(SCH_1):PAGE72
 C2393    2      B Q_CAP_C0402-22UF,4V,20%,X6S,CH622KMEB02    I92 @T6G_MB_LIB.T6G(SCH_1):PAGE72
 C2399    2      B Q_CAP_C0402-22UF,4V,20%,X6S,CH622KMEB02    I93 @T6G_MB_LIB.T6G(SCH_1):PAGE72
 C2398    2      B Q_CAP_C0402-22UF,4V,20%,X6S,CH622KMEB02    I94 @T6G_MB_LIB.T6G(SCH_1):PAGE72
 C2405    2      B Q_CAP_C0402-22UF,4V,20%,X6S,CH622KMEB02    I96 @T6G_MB_LIB.T6G(SCH_1):PAGE72
 C2404    2      B Q_CAP_C0402-22UF,4V,20%,X6S,CH622KMEB02    I98 @T6G_MB_LIB.T6G(SCH_1):PAGE72
 C2403    2      B Q_CAP_C0402-22UF,4V,20%,X6S,CH622KMEB02   I100 @T6G_MB_LIB.T6G(SCH_1):PAGE72
 C2362    2      B Q_CAP_C0402-22UF,4V,20%,X6S,CH622KMEB02   I101 @T6G_MB_LIB.T6G(SCH_1):PAGE72
 C2368    2      B Q_CAP_C0402-22UF,4V,20%,X6S,CH622KMEB02   I102 @T6G_MB_LIB.T6G(SCH_1):PAGE72
 C2374    2      B Q_CAP_C0402-22UF,4V,20%,X6S,CH622KMEB02   I103 @T6G_MB_LIB.T6G(SCH_1):PAGE72
 C2380    2      B Q_CAP_C0402-22UF,4V,20%,X6S,CH622KMEB02   I104 @T6G_MB_LIB.T6G(SCH_1):PAGE72
 C2386    2      B Q_CAP_C0402-22UF,4V,20%,X6S,CH622KMEB02   I105 @T6G_MB_LIB.T6G(SCH_1):PAGE72
 C2392    2      B Q_CAP_C0402-22UF,4V,20%,X6S,CH622KMEB02   I106 @T6G_MB_LIB.T6G(SCH_1):PAGE72
 C2397    2      B Q_CAP_C0402-22UF,4V,20%,X6S,CH622KMEB02   I107 @T6G_MB_LIB.T6G(SCH_1):PAGE72
 C2402    2      B Q_CAP_C0402-22UF,4V,20%,X6S,CH622KMEB02   I109 @T6G_MB_LIB.T6G(SCH_1):PAGE72
 C2350    2      B Q_CAP_C0402-22UF,4V,20%,X6S,CH622KMEB02   I110 @T6G_MB_LIB.T6G(SCH_1):PAGE72
 C3912    2      B Q_CAP_C0402-22UF,4V,20%,X6S,CH622KMEB02     I1 @T6G_MB_LIB.T6G(SCH_1):PAGE73
 C2413    2      B Q_CAP_C0402-22UF,4V,20%,X6S,CH622KMEB02     I3 @T6G_MB_LIB.T6G(SCH_1):PAGE73
 C3913    2      B Q_CAP_C0402-22UF,4V,20%,X6S,CH622KMEB02     I4 @T6G_MB_LIB.T6G(SCH_1):PAGE73
 C2420    2      B Q_CAP_C0402-22UF,4V,20%,X6S,CH622KMEB02     I5 @T6G_MB_LIB.T6G(SCH_1):PAGE73
 C3914    2      B Q_CAP_C0402-22UF,4V,20%,X6S,CH622KMEB02     I6 @T6G_MB_LIB.T6G(SCH_1):PAGE73
 C2427    2      B Q_CAP_C0402-22UF,4V,20%,X6S,CH622KMEB02     I7 @T6G_MB_LIB.T6G(SCH_1):PAGE73
 C3915    2      B Q_CAP_C0402-22UF,4V,20%,X6S,CH622KMEB02     I8 @T6G_MB_LIB.T6G(SCH_1):PAGE73
 C2434    2      B Q_CAP_C0402-22UF,4V,20%,X6S,CH622KMEB02     I9 @T6G_MB_LIB.T6G(SCH_1):PAGE73
 C2412    2      B Q_CAP_C0402-22UF,4V,20%,X6S,CH622KMEB02    I11 @T6G_MB_LIB.T6G(SCH_1):PAGE73
 C2419    2      B Q_CAP_C0402-22UF,4V,20%,X6S,CH622KMEB02    I13 @T6G_MB_LIB.T6G(SCH_1):PAGE73
 C2411    2      B Q_CAP_C0402-22UF,4V,20%,X6S,CH622KMEB02    I14 @T6G_MB_LIB.T6G(SCH_1):PAGE73
 C2410    2      B Q_CAP_C0402-22UF,4V,20%,X6S,CH622KMEB02    I16 @T6G_MB_LIB.T6G(SCH_1):PAGE73
 C2418    2      B Q_CAP_C0402-22UF,4V,20%,X6S,CH622KMEB02    I17 @T6G_MB_LIB.T6G(SCH_1):PAGE73
 C2417    2      B Q_CAP_C0402-22UF,4V,20%,X6S,CH622KMEB02    I18 @T6G_MB_LIB.T6G(SCH_1):PAGE73
 C2426    2      B Q_CAP_C0402-22UF,4V,20%,X6S,CH622KMEB02    I19 @T6G_MB_LIB.T6G(SCH_1):PAGE73
 C2433    2      B Q_CAP_C0402-22UF,4V,20%,X6S,CH622KMEB02    I20 @T6G_MB_LIB.T6G(SCH_1):PAGE73
 C2425    2      B Q_CAP_C0402-22UF,4V,20%,X6S,CH622KMEB02    I21 @T6G_MB_LIB.T6G(SCH_1):PAGE73
 C2424    2      B Q_CAP_C0402-22UF,4V,20%,X6S,CH622KMEB02    I22 @T6G_MB_LIB.T6G(SCH_1):PAGE73
 C2432    2      B Q_CAP_C0402-22UF,4V,20%,X6S,CH622KMEB02    I23 @T6G_MB_LIB.T6G(SCH_1):PAGE73
 C2431    2      B Q_CAP_C0402-22UF,4V,20%,X6S,CH622KMEB02    I24 @T6G_MB_LIB.T6G(SCH_1):PAGE73
 C3916    2      B Q_CAP_C0402-22UF,4V,20%,X6S,CH622KMEB02    I25 @T6G_MB_LIB.T6G(SCH_1):PAGE73
 C2441    2      B Q_CAP_C0402-22UF,4V,20%,X6S,CH622KMEB02    I26 @T6G_MB_LIB.T6G(SCH_1):PAGE73
 C3917    2      B Q_CAP_C0402-22UF,4V,20%,X6S,CH622KMEB02    I27 @T6G_MB_LIB.T6G(SCH_1):PAGE73
 C2448    2      B Q_CAP_C0402-22UF,4V,20%,X6S,CH622KMEB02    I28 @T6G_MB_LIB.T6G(SCH_1):PAGE73
 C2455    2      B Q_CAP_C0402-22UF,4V,20%,X6S,CH622KMEB02    I29 @T6G_MB_LIB.T6G(SCH_1):PAGE73
 C3918    2      B Q_CAP_C0402-22UF,4V,20%,X6S,CH622KMEB02    I30 @T6G_MB_LIB.T6G(SCH_1):PAGE73
 C2462    2      B Q_CAP_C0402-22UF,4V,20%,X6S,CH622KMEB02    I32 @T6G_MB_LIB.T6G(SCH_1):PAGE73
 C2469    2      B Q_CAP_C0402-22UF,4V,20%,X6S,CH622KMEB02    I33 @T6G_MB_LIB.T6G(SCH_1):PAGE73
 C2440    2      B Q_CAP_C0402-22UF,4V,20%,X6S,CH622KMEB02    I34 @T6G_MB_LIB.T6G(SCH_1):PAGE73
 C2447    2      B Q_CAP_C0402-22UF,4V,20%,X6S,CH622KMEB02    I35 @T6G_MB_LIB.T6G(SCH_1):PAGE73
 C2439    2      B Q_CAP_C0402-22UF,4V,20%,X6S,CH622KMEB02    I36 @T6G_MB_LIB.T6G(SCH_1):PAGE73
 C2438    2      B Q_CAP_C0402-22UF,4V,20%,X6S,CH622KMEB02    I37 @T6G_MB_LIB.T6G(SCH_1):PAGE73
 C2446    2      B Q_CAP_C0402-22UF,4V,20%,X6S,CH622KMEB02    I38 @T6G_MB_LIB.T6G(SCH_1):PAGE73
 C2445    2      B Q_CAP_C0402-22UF,4V,20%,X6S,CH622KMEB02    I39 @T6G_MB_LIB.T6G(SCH_1):PAGE73
 C2452    2      B Q_CAP_C0402-22UF,4V,20%,X6S,CH622KMEB02    I40 @T6G_MB_LIB.T6G(SCH_1):PAGE73
 C2453    2      B Q_CAP_C0402-22UF,4V,20%,X6S,CH622KMEB02    I41 @T6G_MB_LIB.T6G(SCH_1):PAGE73
 C2454    2      B Q_CAP_C0402-22UF,4V,20%,X6S,CH622KMEB02    I42 @T6G_MB_LIB.T6G(SCH_1):PAGE73
 C2461    2      B Q_CAP_C0402-22UF,4V,20%,X6S,CH622KMEB02    I43 @T6G_MB_LIB.T6G(SCH_1):PAGE73
 C2468    2      B Q_CAP_C0402-22UF,4V,20%,X6S,CH622KMEB02    I44 @T6G_MB_LIB.T6G(SCH_1):PAGE73
 C2460    2      B Q_CAP_C0402-22UF,4V,20%,X6S,CH622KMEB02    I45 @T6G_MB_LIB.T6G(SCH_1):PAGE73
 C2459    2      B Q_CAP_C0402-22UF,4V,20%,X6S,CH622KMEB02    I46 @T6G_MB_LIB.T6G(SCH_1):PAGE73
 C2467    2      B Q_CAP_C0402-22UF,4V,20%,X6S,CH622KMEB02    I47 @T6G_MB_LIB.T6G(SCH_1):PAGE73
 C2466    2      B Q_CAP_C0402-22UF,4V,20%,X6S,CH622KMEB02    I48 @T6G_MB_LIB.T6G(SCH_1):PAGE73
 C2409    2      B Q_CAP_C0402-22UF,4V,20%,X6S,CH622KMEB02    I50 @T6G_MB_LIB.T6G(SCH_1):PAGE73
 C2416    2      B Q_CAP_C0402-22UF,4V,20%,X6S,CH622KMEB02    I52 @T6G_MB_LIB.T6G(SCH_1):PAGE73
 C2408    2      B Q_CAP_C0402-22UF,4V,20%,X6S,CH622KMEB02    I53 @T6G_MB_LIB.T6G(SCH_1):PAGE73
 C2407    2      B Q_CAP_C0402-22UF,4V,20%,X6S,CH622KMEB02    I55 @T6G_MB_LIB.T6G(SCH_1):PAGE73
 C2415    2      B Q_CAP_C0402-22UF,4V,20%,X6S,CH622KMEB02    I56 @T6G_MB_LIB.T6G(SCH_1):PAGE73
 C2414    2      B Q_CAP_C0402-22UF,4V,20%,X6S,CH622KMEB02    I57 @T6G_MB_LIB.T6G(SCH_1):PAGE73
 C2423    2      B Q_CAP_C0402-22UF,4V,20%,X6S,CH622KMEB02    I58 @T6G_MB_LIB.T6G(SCH_1):PAGE73
 C2430    2      B Q_CAP_C0402-22UF,4V,20%,X6S,CH622KMEB02    I59 @T6G_MB_LIB.T6G(SCH_1):PAGE73
 C2422    2      B Q_CAP_C0402-22UF,4V,20%,X6S,CH622KMEB02    I60 @T6G_MB_LIB.T6G(SCH_1):PAGE73
 C2421    2      B Q_CAP_C0402-22UF,4V,20%,X6S,CH622KMEB02    I61 @T6G_MB_LIB.T6G(SCH_1):PAGE73
 C2429    2      B Q_CAP_C0402-22UF,4V,20%,X6S,CH622KMEB02    I62 @T6G_MB_LIB.T6G(SCH_1):PAGE73
 C2437    2      B Q_CAP_C0402-22UF,4V,20%,X6S,CH622KMEB02    I64 @T6G_MB_LIB.T6G(SCH_1):PAGE73
 C2444    2      B Q_CAP_C0402-22UF,4V,20%,X6S,CH622KMEB02    I65 @T6G_MB_LIB.T6G(SCH_1):PAGE73
 C2436    2      B Q_CAP_C0402-22UF,4V,20%,X6S,CH622KMEB02    I66 @T6G_MB_LIB.T6G(SCH_1):PAGE73
 C2443    2      B Q_CAP_C0402-22UF,4V,20%,X6S,CH622KMEB02    I67 @T6G_MB_LIB.T6G(SCH_1):PAGE73
 C2449    2      B Q_CAP_C0402-22UF,4V,20%,X6S,CH622KMEB02    I68 @T6G_MB_LIB.T6G(SCH_1):PAGE73
 C2450    2      B Q_CAP_C0402-22UF,4V,20%,X6S,CH622KMEB02    I69 @T6G_MB_LIB.T6G(SCH_1):PAGE73
 C2451    2      B Q_CAP_C0402-22UF,4V,20%,X6S,CH622KMEB02    I70 @T6G_MB_LIB.T6G(SCH_1):PAGE73
 C2458    2      B Q_CAP_C0402-22UF,4V,20%,X6S,CH622KMEB02    I71 @T6G_MB_LIB.T6G(SCH_1):PAGE73
 C2465    2      B Q_CAP_C0402-22UF,4V,20%,X6S,CH622KMEB02    I72 @T6G_MB_LIB.T6G(SCH_1):PAGE73
 C2457    2      B Q_CAP_C0402-22UF,4V,20%,X6S,CH622KMEB02    I73 @T6G_MB_LIB.T6G(SCH_1):PAGE73
 C2456    2      B Q_CAP_C0402-22UF,4V,20%,X6S,CH622KMEB02    I74 @T6G_MB_LIB.T6G(SCH_1):PAGE73
 C2464    2      B Q_CAP_C0402-22UF,4V,20%,X6S,CH622KMEB02    I75 @T6G_MB_LIB.T6G(SCH_1):PAGE73
 C2463    2      B Q_CAP_C0402-22UF,4V,20%,X6S,CH622KMEB02    I76 @T6G_MB_LIB.T6G(SCH_1):PAGE73
 C3919    2      B Q_CAP_C0402-22UF,4V,20%,X6S,CH622KMEB02    I77 @T6G_MB_LIB.T6G(SCH_1):PAGE73
 C2476    2      B Q_CAP_C0402-22UF,4V,20%,X6S,CH622KMEB02    I79 @T6G_MB_LIB.T6G(SCH_1):PAGE73
 C2483    2      B Q_CAP_C0402-22UF,4V,20%,X6S,CH622KMEB02    I81 @T6G_MB_LIB.T6G(SCH_1):PAGE73
 C3920    2      B Q_CAP_C0402-22UF,4V,20%,X6S,CH622KMEB02    I84 @T6G_MB_LIB.T6G(SCH_1):PAGE73
 C2488    2      B Q_CAP_C0402-22UF,4V,20%,X6S,CH622KMEB02    I85 @T6G_MB_LIB.T6G(SCH_1):PAGE73
 C2492    2      B Q_CAP_C0402-22UF,4V,20%,X6S,CH622KMEB02    I86 @T6G_MB_LIB.T6G(SCH_1):PAGE73
 C2475    2      B Q_CAP_C0402-22UF,4V,20%,X6S,CH622KMEB02    I88 @T6G_MB_LIB.T6G(SCH_1):PAGE73
 C2482    2      B Q_CAP_C0402-22UF,4V,20%,X6S,CH622KMEB02    I90 @T6G_MB_LIB.T6G(SCH_1):PAGE73
 C2481    2      B Q_CAP_C0402-22UF,4V,20%,X6S,CH622KMEB02    I92 @T6G_MB_LIB.T6G(SCH_1):PAGE73
 C2474    2      B Q_CAP_C0402-22UF,4V,20%,X6S,CH622KMEB02    I94 @T6G_MB_LIB.T6G(SCH_1):PAGE73
 C2473    2      B Q_CAP_C0402-22UF,4V,20%,X6S,CH622KMEB02    I96 @T6G_MB_LIB.T6G(SCH_1):PAGE73
 C2480    2      B Q_CAP_C0402-22UF,4V,20%,X6S,CH622KMEB02    I97 @T6G_MB_LIB.T6G(SCH_1):PAGE73
 C2487    2      B Q_CAP_C0402-22UF,4V,20%,X6S,CH622KMEB02    I99 @T6G_MB_LIB.T6G(SCH_1):PAGE73
 C2486    2      B Q_CAP_C0402-22UF,4V,20%,X6S,CH622KMEB02   I100 @T6G_MB_LIB.T6G(SCH_1):PAGE73
 C2491    2      B Q_CAP_C0402-22UF,4V,20%,X6S,CH622KMEB02   I101 @T6G_MB_LIB.T6G(SCH_1):PAGE73
 C2490    2      B Q_CAP_C0402-22UF,4V,20%,X6S,CH622KMEB02   I102 @T6G_MB_LIB.T6G(SCH_1):PAGE73
 C2485    2      B Q_CAP_C0402-22UF,4V,20%,X6S,CH622KMEB02   I103 @T6G_MB_LIB.T6G(SCH_1):PAGE73
 C2489    2      B Q_CAP_C0402-22UF,4V,20%,X6S,CH622KMEB02   I104 @T6G_MB_LIB.T6G(SCH_1):PAGE73
 C2497    2      B Q_CAP_C0402-22UF,4V,20%,X6S,CH622KMEB02   I105 @T6G_MB_LIB.T6G(SCH_1):PAGE73
 C2502    2      B Q_CAP_C0402-22UF,4V,20%,X6S,CH622KMEB02   I106 @T6G_MB_LIB.T6G(SCH_1):PAGE73
 C2506    2      B Q_CAP_C0402-22UF,4V,20%,X6S,CH622KMEB02   I107 @T6G_MB_LIB.T6G(SCH_1):PAGE73
 C2115    2      B Q_CAP_C0402-22UF,4V,20%,X6S,CH622KMEB02   I108 @T6G_MB_LIB.T6G(SCH_1):PAGE73
 C2121    2      B Q_CAP_C0402-22UF,4V,20%,X6S,CH622KMEB02   I109 @T6G_MB_LIB.T6G(SCH_1):PAGE73
 C2496    2      B Q_CAP_C0402-22UF,4V,20%,X6S,CH622KMEB02   I110 @T6G_MB_LIB.T6G(SCH_1):PAGE73
 C2495    2      B Q_CAP_C0402-22UF,4V,20%,X6S,CH622KMEB02   I111 @T6G_MB_LIB.T6G(SCH_1):PAGE73
 C2501    2      B Q_CAP_C0402-22UF,4V,20%,X6S,CH622KMEB02   I112 @T6G_MB_LIB.T6G(SCH_1):PAGE73
 C2500    2      B Q_CAP_C0402-22UF,4V,20%,X6S,CH622KMEB02   I113 @T6G_MB_LIB.T6G(SCH_1):PAGE73
 C2494    2      B Q_CAP_C0402-22UF,4V,20%,X6S,CH622KMEB02   I114 @T6G_MB_LIB.T6G(SCH_1):PAGE73
 C2499    2      B Q_CAP_C0402-22UF,4V,20%,X6S,CH622KMEB02   I116 @T6G_MB_LIB.T6G(SCH_1):PAGE73
 C2505    2      B Q_CAP_C0402-22UF,4V,20%,X6S,CH622KMEB02   I117 @T6G_MB_LIB.T6G(SCH_1):PAGE73
 C2504    2      B Q_CAP_C0402-22UF,4V,20%,X6S,CH622KMEB02   I118 @T6G_MB_LIB.T6G(SCH_1):PAGE73
 C2113    2      B Q_CAP_C0402-22UF,4V,20%,X6S,CH622KMEB02   I119 @T6G_MB_LIB.T6G(SCH_1):PAGE73
 C2114    2      B Q_CAP_C0402-22UF,4V,20%,X6S,CH622KMEB02   I120 @T6G_MB_LIB.T6G(SCH_1):PAGE73
 C2120    2      B Q_CAP_C0402-22UF,4V,20%,X6S,CH622KMEB02   I121 @T6G_MB_LIB.T6G(SCH_1):PAGE73
 C2119    2      B Q_CAP_C0402-22UF,4V,20%,X6S,CH622KMEB02   I122 @T6G_MB_LIB.T6G(SCH_1):PAGE73
 C2503    2      B Q_CAP_C0402-22UF,4V,20%,X6S,CH622KMEB02   I123 @T6G_MB_LIB.T6G(SCH_1):PAGE73
 C2508    2      B Q_CAP_C0402-22UF,4V,20%,X6S,CH622KMEB02   I124 @T6G_MB_LIB.T6G(SCH_1):PAGE73
 C2118    2      B Q_CAP_C0402-22UF,4V,20%,X6S,CH622KMEB02   I125 @T6G_MB_LIB.T6G(SCH_1):PAGE73
 C2472    2      B Q_CAP_C0402-22UF,4V,20%,X6S,CH622KMEB02   I127 @T6G_MB_LIB.T6G(SCH_1):PAGE73
 C2479    2      B Q_CAP_C0402-22UF,4V,20%,X6S,CH622KMEB02   I129 @T6G_MB_LIB.T6G(SCH_1):PAGE73
 C2471    2      B Q_CAP_C0402-22UF,4V,20%,X6S,CH622KMEB02   I131 @T6G_MB_LIB.T6G(SCH_1):PAGE73
 C2470    2      B Q_CAP_C0402-22UF,4V,20%,X6S,CH622KMEB02   I133 @T6G_MB_LIB.T6G(SCH_1):PAGE73
 C2478    2      B Q_CAP_C0402-22UF,4V,20%,X6S,CH622KMEB02   I134 @T6G_MB_LIB.T6G(SCH_1):PAGE73
 C2477    2      B Q_CAP_C0402-22UF,4V,20%,X6S,CH622KMEB02   I136 @T6G_MB_LIB.T6G(SCH_1):PAGE73
 C2103    2      B Q_CAP_C0402-22UF,4V,20%,X6S,CH622KMEB02   I137 @T6G_MB_LIB.T6G(SCH_1):PAGE73
 C2106    2      B Q_CAP_C0402-22UF,4V,20%,X6S,CH622KMEB02   I138 @T6G_MB_LIB.T6G(SCH_1):PAGE73
 C2484    2      B Q_CAP_C0402-22UF,4V,20%,X6S,CH622KMEB02   I139 @T6G_MB_LIB.T6G(SCH_1):PAGE73
 C2102    2      B Q_CAP_C0402-22UF,4V,20%,X6S,CH622KMEB02   I140 @T6G_MB_LIB.T6G(SCH_1):PAGE73
 C2105    2      B Q_CAP_C0402-22UF,4V,20%,X6S,CH622KMEB02   I141 @T6G_MB_LIB.T6G(SCH_1):PAGE73
 C2104    2      B Q_CAP_C0402-22UF,4V,20%,X6S,CH622KMEB02   I142 @T6G_MB_LIB.T6G(SCH_1):PAGE73
 C2108    2      B Q_CAP_C0402-22UF,4V,20%,X6S,CH622KMEB02   I144 @T6G_MB_LIB.T6G(SCH_1):PAGE73
 C2107    2      B Q_CAP_C0402-22UF,4V,20%,X6S,CH622KMEB02   I145 @T6G_MB_LIB.T6G(SCH_1):PAGE73
 C2493    2      B Q_CAP_C0402-22UF,4V,20%,X6S,CH622KMEB02   I146 @T6G_MB_LIB.T6G(SCH_1):PAGE73
 C2498    2      B Q_CAP_C0402-22UF,4V,20%,X6S,CH622KMEB02   I147 @T6G_MB_LIB.T6G(SCH_1):PAGE73
 C2109    2      B Q_CAP_C0402-22UF,4V,20%,X6S,CH622KMEB02   I148 @T6G_MB_LIB.T6G(SCH_1):PAGE73
 C2111    2      B Q_CAP_C0402-22UF,4V,20%,X6S,CH622KMEB02   I149 @T6G_MB_LIB.T6G(SCH_1):PAGE73
 C2112    2      B Q_CAP_C0402-22UF,4V,20%,X6S,CH622KMEB02   I150 @T6G_MB_LIB.T6G(SCH_1):PAGE73
 C2110    2      B Q_CAP_C0402-22UF,4V,20%,X6S,CH622KMEB02   I151 @T6G_MB_LIB.T6G(SCH_1):PAGE73
 C2507    2      B Q_CAP_C0402-22UF,4V,20%,X6S,CH622KMEB02   I152 @T6G_MB_LIB.T6G(SCH_1):PAGE73
 C2117    2      B Q_CAP_C0402-22UF,4V,20%,X6S,CH622KMEB02   I153 @T6G_MB_LIB.T6G(SCH_1):PAGE73
 C2116    2      B Q_CAP_C0402-22UF,4V,20%,X6S,CH622KMEB02   I154 @T6G_MB_LIB.T6G(SCH_1):PAGE73
 C3921    2      B Q_CAP_C0402-22UF,4V,20%,X6S,CH622KMEB02   I155 @T6G_MB_LIB.T6G(SCH_1):PAGE73
 C3922    2      B Q_CAP_C0402-22UF,4V,20%,X6S,CH622KMEB02   I157 @T6G_MB_LIB.T6G(SCH_1):PAGE73
 C2126    2      B Q_CAP_C0402-22UF,4V,20%,X6S,CH622KMEB02   I159 @T6G_MB_LIB.T6G(SCH_1):PAGE73
 C2125    2      B Q_CAP_C0402-22UF,4V,20%,X6S,CH622KMEB02   I160 @T6G_MB_LIB.T6G(SCH_1):PAGE73
 C2511    2      B Q_CAP_C0402-22UF,4V,20%,X6S,CH622KMEB02   I161 @T6G_MB_LIB.T6G(SCH_1):PAGE73
 C2510    2      B Q_CAP_C0402-22UF,4V,20%,X6S,CH622KMEB02   I163 @T6G_MB_LIB.T6G(SCH_1):PAGE73
 C2124    2      B Q_CAP_C0402-22UF,4V,20%,X6S,CH622KMEB02   I164 @T6G_MB_LIB.T6G(SCH_1):PAGE73
 C2128    2      B Q_CAP_C0402-22UF,4V,20%,X6S,CH622KMEB02   I166 @T6G_MB_LIB.T6G(SCH_1):PAGE73
 C2123    2      B Q_CAP_C0402-22UF,4V,20%,X6S,CH622KMEB02   I168 @T6G_MB_LIB.T6G(SCH_1):PAGE73
 C2122    2      B Q_CAP_C0402-22UF,4V,20%,X6S,CH622KMEB02   I169 @T6G_MB_LIB.T6G(SCH_1):PAGE73
 C2509    2      B Q_CAP_C0402-22UF,4V,20%,X6S,CH622KMEB02   I170 @T6G_MB_LIB.T6G(SCH_1):PAGE73
 C2127    2      B Q_CAP_C0402-22UF,4V,20%,X6S,CH622KMEB02   I172 @T6G_MB_LIB.T6G(SCH_1):PAGE73
 C2442    2      B Q_CAP_C0402-22UF,4V,20%,X6S,CH622KMEB02   I173 @T6G_MB_LIB.T6G(SCH_1):PAGE73
 C2435    2      B Q_CAP_C0402-22UF,4V,20%,X6S,CH622KMEB02   I174 @T6G_MB_LIB.T6G(SCH_1):PAGE73
 C2428    2      B Q_CAP_C0402-22UF,4V,20%,X6S,CH622KMEB02   I175 @T6G_MB_LIB.T6G(SCH_1):PAGE73
 C2661    2      B Q_CAP_C0402-22UF,4V,20%,X6S,CH622KMEB02     I1 @T6G_MB_LIB.T6G(SCH_1):PAGE74
 C2660    2      B Q_CAP_C0402-22UF,4V,20%,X6S,CH622KMEB02     I3 @T6G_MB_LIB.T6G(SCH_1):PAGE74
 C2664    2      B Q_CAP_C0402-22UF,4V,20%,X6S,CH622KMEB02     I8 @T6G_MB_LIB.T6G(SCH_1):PAGE74
 C2663    2      B Q_CAP_C0402-22UF,4V,20%,X6S,CH622KMEB02     I9 @T6G_MB_LIB.T6G(SCH_1):PAGE74
 C2665    2      B Q_CAP_C0402-22UF,4V,20%,X6S,CH622KMEB02    I10 @T6G_MB_LIB.T6G(SCH_1):PAGE74
 C2667    2      B Q_CAP_C0402-22UF,4V,20%,X6S,CH622KMEB02    I11 @T6G_MB_LIB.T6G(SCH_1):PAGE74
 C2668    2      B Q_CAP_C0402-22UF,4V,20%,X6S,CH622KMEB02    I12 @T6G_MB_LIB.T6G(SCH_1):PAGE74
 C2669    2      B Q_CAP_C0402-22UF,4V,20%,X6S,CH622KMEB02    I13 @T6G_MB_LIB.T6G(SCH_1):PAGE74
 C2670    2      B Q_CAP_C0402-22UF,4V,20%,X6S,CH622KMEB02    I14 @T6G_MB_LIB.T6G(SCH_1):PAGE74
 C2671    2      B Q_CAP_C0402-22UF,4V,20%,X6S,CH622KMEB02    I15 @T6G_MB_LIB.T6G(SCH_1):PAGE74
 C2672    2      B Q_CAP_C0402-22UF,4V,20%,X6S,CH622KMEB02    I16 @T6G_MB_LIB.T6G(SCH_1):PAGE74
 C2673    2      B Q_CAP_C0402-22UF,4V,20%,X6S,CH622KMEB02    I18 @T6G_MB_LIB.T6G(SCH_1):PAGE74
  R747    1      A Q_RES_0402LF-1K,1%,1/16W,CHIP,CS21002FB06     I8 @T6G_MB_LIB.T6G(SCH_1):PAGE75
  R748    1      A Q_RES_0402LF-10K,5%,1/16W,EMPTY,CS31002JB08     I9 @T6G_MB_LIB.T6G(SCH_1):PAGE75
  R751    1      A Q_RES_0402LF-10K,5%,1/16W,CHIP,CS31002JB08    I12 @T6G_MB_LIB.T6G(SCH_1):PAGE75
  R750    1      A Q_RES_0402LF-30K,1%,1/16W,CHIP,CS33002FB02    I74 @T6G_MB_LIB.T6G(SCH_1):PAGE75
  R753    1      A Q_RES_0402LF-10K,5%,1/16W,CHIP,CS31002JB08    I75 @T6G_MB_LIB.T6G(SCH_1):PAGE75
 C1104    2      B Q_CAP_0402-0.1UF,25V,10%,X7R,CH4104K1B00    I50 @T6G_MB_LIB.T6G(SCH_1):PAGE76
 C1102    2      B Q_CAP_0402-0.1UF,25V,10%,X7R,CH4104K1B00    I53 @T6G_MB_LIB.T6G(SCH_1):PAGE76
 C1105    2      B Q_CAP_0402-0.1UF,25V,10%,X7R,CH4104K1B00    I59 @T6G_MB_LIB.T6G(SCH_1):PAGE76
   U53   10    GND SN74AVC4T774PWR-SN74AVC4T774PWR,SMLF,IC,AL04T774K00    I63 @T6G_MB_LIB.T6G(SCH_1):PAGE76
 C1103    2      B Q_CAP_0402-0.1UF,25V,10%,X7R,CH4104K1B00    I65 @T6G_MB_LIB.T6G(SCH_1):PAGE76
   U54    6    GND PI4ULS3V304AZMAEX-PI4ULS3V304AZMAEX,SMLF,IC,AL0003A    I67 @T6G_MB_LIB.T6G(SCH_1):PAGE76
  R702    2      B Q_RES_0402LF-10K,5%,1/16W,EMPTY,CS31002JB08     I1 @T6G_MB_LIB.T6G(SCH_1):PAGE77
  R703    2      B Q_RES_0402LF-10K,5%,1/16W,EMPTY,CS31002JB08     I5 @T6G_MB_LIB.T6G(SCH_1):PAGE77
  C223    2      B Q_CAP_0402-0.1UF,25V,10%,X7R,CH4104K1B00    I11 @T6G_MB_LIB.T6G(SCH_1):PAGE77
   U29    2    GND SN74LVC2G07DCKR_SMLF-SN74LVC2G07DCKR,IC,AL002G07006    I15 @T6G_MB_LIB.T6G(SCH_1):PAGE77
  C224    2      B Q_CAP_0402-0.1UF,25V,10%,X7R,CH4104K1B00    I19 @T6G_MB_LIB.T6G(SCH_1):PAGE77
   U40    2    GND SN74LVC2G07DCKR_SMLF-SN74LVC2G07DCKR,IC,AL002G07006    I21 @T6G_MB_LIB.T6G(SCH_1):PAGE77
    R7    2      B Q_RES_0402LF-10K,1%,1/16W,CHIP,CS31002FB08   I499 @T6G_MB_LIB.T6G(SCH_1):PAGE85
   C89    2      B Q_CAP_C0805-10UF,25V,10%,X6S,CH6104KEA00   I519 @T6G_MB_LIB.T6G(SCH_1):PAGE85
   C88    2      B Q_CAP_0402-0.1UF,25V,10%,X7R,CH4104K1B00   I523 @T6G_MB_LIB.T6G(SCH_1):PAGE85
  C142    2      B Q_CAP_C0805-10UF,25V,10%,X6S,CH6104KEA00   I534 @T6G_MB_LIB.T6G(SCH_1):PAGE85
  R761    2      B Q_RES_0402LF-15.4K,1%,1/16W,CHIP,CS31542FB02   I349 @T6G_MB_LIB.T6G(SCH_1):PAGE86
   J15   G1     G1 SCONN288_DDR506112002KQ-SCONN288_DDR506112002KQ,SMA   I352 @T6G_MB_LIB.T6G(SCH_1):PAGE86
   J15   G2     G2 SCONN288_DDR506112002KQ-SCONN288_DDR506112002KQ,SMA   I352 @T6G_MB_LIB.T6G(SCH_1):PAGE86
   J15   G3     G3 SCONN288_DDR506112002KQ-SCONN288_DDR506112002KQ,SMA   I352 @T6G_MB_LIB.T6G(SCH_1):PAGE86
   J15    6   VSS0 SCONN288_DDR506112002KQ-SCONN288_DDR506112002KQ,SMA   I352 @T6G_MB_LIB.T6G(SCH_1):PAGE86
   J15    8   VSS1 SCONN288_DDR506112002KQ-SCONN288_DDR506112002KQ,SMA   I352 @T6G_MB_LIB.T6G(SCH_1):PAGE86
   J15   10   VSS2 SCONN288_DDR506112002KQ-SCONN288_DDR506112002KQ,SMA   I352 @T6G_MB_LIB.T6G(SCH_1):PAGE86
   J15   13   VSS3 SCONN288_DDR506112002KQ-SCONN288_DDR506112002KQ,SMA   I352 @T6G_MB_LIB.T6G(SCH_1):PAGE86
   J15   15   VSS4 SCONN288_DDR506112002KQ-SCONN288_DDR506112002KQ,SMA   I352 @T6G_MB_LIB.T6G(SCH_1):PAGE86
   J15   17   VSS5 SCONN288_DDR506112002KQ-SCONN288_DDR506112002KQ,SMA   I352 @T6G_MB_LIB.T6G(SCH_1):PAGE86
   J15   19   VSS6 SCONN288_DDR506112002KQ-SCONN288_DDR506112002KQ,SMA   I352 @T6G_MB_LIB.T6G(SCH_1):PAGE86
   J15   21   VSS7 SCONN288_DDR506112002KQ-SCONN288_DDR506112002KQ,SMA   I352 @T6G_MB_LIB.T6G(SCH_1):PAGE86
   J15   24   VSS8 SCONN288_DDR506112002KQ-SCONN288_DDR506112002KQ,SMA   I352 @T6G_MB_LIB.T6G(SCH_1):PAGE86
   J15   26   VSS9 SCONN288_DDR506112002KQ-SCONN288_DDR506112002KQ,SMA   I352 @T6G_MB_LIB.T6G(SCH_1):PAGE86
   J15   28  VSS10 SCONN288_DDR506112002KQ-SCONN288_DDR506112002KQ,SMA   I352 @T6G_MB_LIB.T6G(SCH_1):PAGE86
   J15   30  VSS11 SCONN288_DDR506112002KQ-SCONN288_DDR506112002KQ,SMA   I352 @T6G_MB_LIB.T6G(SCH_1):PAGE86
   J15   32  VSS12 SCONN288_DDR506112002KQ-SCONN288_DDR506112002KQ,SMA   I352 @T6G_MB_LIB.T6G(SCH_1):PAGE86
   J15   35  VSS13 SCONN288_DDR506112002KQ-SCONN288_DDR506112002KQ,SMA   I352 @T6G_MB_LIB.T6G(SCH_1):PAGE86
   J15   37  VSS14 SCONN288_DDR506112002KQ-SCONN288_DDR506112002KQ,SMA   I352 @T6G_MB_LIB.T6G(SCH_1):PAGE86
   J15   39  VSS15 SCONN288_DDR506112002KQ-SCONN288_DDR506112002KQ,SMA   I352 @T6G_MB_LIB.T6G(SCH_1):PAGE86
   J15   41  VSS16 SCONN288_DDR506112002KQ-SCONN288_DDR506112002KQ,SMA   I352 @T6G_MB_LIB.T6G(SCH_1):PAGE86
   J15   43  VSS17 SCONN288_DDR506112002KQ-SCONN288_DDR506112002KQ,SMA   I352 @T6G_MB_LIB.T6G(SCH_1):PAGE86
   J15   46  VSS18 SCONN288_DDR506112002KQ-SCONN288_DDR506112002KQ,SMA   I352 @T6G_MB_LIB.T6G(SCH_1):PAGE86
   J15   48  VSS19 SCONN288_DDR506112002KQ-SCONN288_DDR506112002KQ,SMA   I352 @T6G_MB_LIB.T6G(SCH_1):PAGE86
   J15   50  VSS20 SCONN288_DDR506112002KQ-SCONN288_DDR506112002KQ,SMA   I352 @T6G_MB_LIB.T6G(SCH_1):PAGE86
   J15   52  VSS21 SCONN288_DDR506112002KQ-SCONN288_DDR506112002KQ,SMA   I352 @T6G_MB_LIB.T6G(SCH_1):PAGE86
   J15   54  VSS22 SCONN288_DDR506112002KQ-SCONN288_DDR506112002KQ,SMA   I352 @T6G_MB_LIB.T6G(SCH_1):PAGE86
   J15   57  VSS23 SCONN288_DDR506112002KQ-SCONN288_DDR506112002KQ,SMA   I352 @T6G_MB_LIB.T6G(SCH_1):PAGE86
   J15   59  VSS24 SCONN288_DDR506112002KQ-SCONN288_DDR506112002KQ,SMA   I352 @T6G_MB_LIB.T6G(SCH_1):PAGE86
   J15   61  VSS25 SCONN288_DDR506112002KQ-SCONN288_DDR506112002KQ,SMA   I352 @T6G_MB_LIB.T6G(SCH_1):PAGE86
   J15   63  VSS26 SCONN288_DDR506112002KQ-SCONN288_DDR506112002KQ,SMA   I352 @T6G_MB_LIB.T6G(SCH_1):PAGE86
   J15   65  VSS27 SCONN288_DDR506112002KQ-SCONN288_DDR506112002KQ,SMA   I352 @T6G_MB_LIB.T6G(SCH_1):PAGE86
   J15   67  VSS28 SCONN288_DDR506112002KQ-SCONN288_DDR506112002KQ,SMA   I352 @T6G_MB_LIB.T6G(SCH_1):PAGE86
   J15   69  VSS29 SCONN288_DDR506112002KQ-SCONN288_DDR506112002KQ,SMA   I352 @T6G_MB_LIB.T6G(SCH_1):PAGE86
   J15   71  VSS30 SCONN288_DDR506112002KQ-SCONN288_DDR506112002KQ,SMA   I352 @T6G_MB_LIB.T6G(SCH_1):PAGE86
   J15   73  VSS31 SCONN288_DDR506112002KQ-SCONN288_DDR506112002KQ,SMA   I352 @T6G_MB_LIB.T6G(SCH_1):PAGE86
   J15   75  VSS32 SCONN288_DDR506112002KQ-SCONN288_DDR506112002KQ,SMA   I352 @T6G_MB_LIB.T6G(SCH_1):PAGE86
   J15   77  VSS33 SCONN288_DDR506112002KQ-SCONN288_DDR506112002KQ,SMA   I352 @T6G_MB_LIB.T6G(SCH_1):PAGE86
   J15   79  VSS34 SCONN288_DDR506112002KQ-SCONN288_DDR506112002KQ,SMA   I352 @T6G_MB_LIB.T6G(SCH_1):PAGE86
   J15   81  VSS35 SCONN288_DDR506112002KQ-SCONN288_DDR506112002KQ,SMA   I352 @T6G_MB_LIB.T6G(SCH_1):PAGE86
   J15   83  VSS36 SCONN288_DDR506112002KQ-SCONN288_DDR506112002KQ,SMA   I352 @T6G_MB_LIB.T6G(SCH_1):PAGE86
   J15   85  VSS37 SCONN288_DDR506112002KQ-SCONN288_DDR506112002KQ,SMA   I352 @T6G_MB_LIB.T6G(SCH_1):PAGE86
   J15   88  VSS38 SCONN288_DDR506112002KQ-SCONN288_DDR506112002KQ,SMA   I352 @T6G_MB_LIB.T6G(SCH_1):PAGE86
   J15   90  VSS39 SCONN288_DDR506112002KQ-SCONN288_DDR506112002KQ,SMA   I352 @T6G_MB_LIB.T6G(SCH_1):PAGE86
   J15   92  VSS40 SCONN288_DDR506112002KQ-SCONN288_DDR506112002KQ,SMA   I352 @T6G_MB_LIB.T6G(SCH_1):PAGE86
   J15   95  VSS41 SCONN288_DDR506112002KQ-SCONN288_DDR506112002KQ,SMA   I352 @T6G_MB_LIB.T6G(SCH_1):PAGE86
   J15   97  VSS42 SCONN288_DDR506112002KQ-SCONN288_DDR506112002KQ,SMA   I352 @T6G_MB_LIB.T6G(SCH_1):PAGE86
   J15   99  VSS43 SCONN288_DDR506112002KQ-SCONN288_DDR506112002KQ,SMA   I352 @T6G_MB_LIB.T6G(SCH_1):PAGE86
   J15  101  VSS44 SCONN288_DDR506112002KQ-SCONN288_DDR506112002KQ,SMA   I352 @T6G_MB_LIB.T6G(SCH_1):PAGE86
   J15  103  VSS45 SCONN288_DDR506112002KQ-SCONN288_DDR506112002KQ,SMA   I352 @T6G_MB_LIB.T6G(SCH_1):PAGE86
   J15  106  VSS46 SCONN288_DDR506112002KQ-SCONN288_DDR506112002KQ,SMA   I352 @T6G_MB_LIB.T6G(SCH_1):PAGE86
   J15  108  VSS47 SCONN288_DDR506112002KQ-SCONN288_DDR506112002KQ,SMA   I352 @T6G_MB_LIB.T6G(SCH_1):PAGE86
   J15  110  VSS48 SCONN288_DDR506112002KQ-SCONN288_DDR506112002KQ,SMA   I352 @T6G_MB_LIB.T6G(SCH_1):PAGE86
   J15  112  VSS49 SCONN288_DDR506112002KQ-SCONN288_DDR506112002KQ,SMA   I352 @T6G_MB_LIB.T6G(SCH_1):PAGE86
   J15  114  VSS50 SCONN288_DDR506112002KQ-SCONN288_DDR506112002KQ,SMA   I352 @T6G_MB_LIB.T6G(SCH_1):PAGE86
   J15  117  VSS51 SCONN288_DDR506112002KQ-SCONN288_DDR506112002KQ,SMA   I352 @T6G_MB_LIB.T6G(SCH_1):PAGE86
   J15  119  VSS52 SCONN288_DDR506112002KQ-SCONN288_DDR506112002KQ,SMA   I352 @T6G_MB_LIB.T6G(SCH_1):PAGE86
   J15  121  VSS53 SCONN288_DDR506112002KQ-SCONN288_DDR506112002KQ,SMA   I352 @T6G_MB_LIB.T6G(SCH_1):PAGE86
   J15  123  VSS54 SCONN288_DDR506112002KQ-SCONN288_DDR506112002KQ,SMA   I352 @T6G_MB_LIB.T6G(SCH_1):PAGE86
   J15  125  VSS55 SCONN288_DDR506112002KQ-SCONN288_DDR506112002KQ,SMA   I352 @T6G_MB_LIB.T6G(SCH_1):PAGE86
   J15  128  VSS56 SCONN288_DDR506112002KQ-SCONN288_DDR506112002KQ,SMA   I352 @T6G_MB_LIB.T6G(SCH_1):PAGE86
   J15  130  VSS57 SCONN288_DDR506112002KQ-SCONN288_DDR506112002KQ,SMA   I352 @T6G_MB_LIB.T6G(SCH_1):PAGE86
   J15  132  VSS58 SCONN288_DDR506112002KQ-SCONN288_DDR506112002KQ,SMA   I352 @T6G_MB_LIB.T6G(SCH_1):PAGE86
   J15  134  VSS59 SCONN288_DDR506112002KQ-SCONN288_DDR506112002KQ,SMA   I352 @T6G_MB_LIB.T6G(SCH_1):PAGE86
   J15  136  VSS60 SCONN288_DDR506112002KQ-SCONN288_DDR506112002KQ,SMA   I352 @T6G_MB_LIB.T6G(SCH_1):PAGE86
   J15  139  VSS61 SCONN288_DDR506112002KQ-SCONN288_DDR506112002KQ,SMA   I352 @T6G_MB_LIB.T6G(SCH_1):PAGE86
   J15  141  VSS62 SCONN288_DDR506112002KQ-SCONN288_DDR506112002KQ,SMA   I352 @T6G_MB_LIB.T6G(SCH_1):PAGE86
   J15  143  VSS63 SCONN288_DDR506112002KQ-SCONN288_DDR506112002KQ,SMA   I352 @T6G_MB_LIB.T6G(SCH_1):PAGE86
   J15  151  VSS64 SCONN288_DDR506112002KQ-SCONN288_DDR506112002KQ,SMA   I352 @T6G_MB_LIB.T6G(SCH_1):PAGE86
   J15  153  VSS65 SCONN288_DDR506112002KQ-SCONN288_DDR506112002KQ,SMA   I352 @T6G_MB_LIB.T6G(SCH_1):PAGE86
   J15  155  VSS66 SCONN288_DDR506112002KQ-SCONN288_DDR506112002KQ,SMA   I352 @T6G_MB_LIB.T6G(SCH_1):PAGE86
   J15  158  VSS67 SCONN288_DDR506112002KQ-SCONN288_DDR506112002KQ,SMA   I352 @T6G_MB_LIB.T6G(SCH_1):PAGE86
   J15  160  VSS68 SCONN288_DDR506112002KQ-SCONN288_DDR506112002KQ,SMA   I352 @T6G_MB_LIB.T6G(SCH_1):PAGE86
   J15  162  VSS69 SCONN288_DDR506112002KQ-SCONN288_DDR506112002KQ,SMA   I352 @T6G_MB_LIB.T6G(SCH_1):PAGE86
   J15  164  VSS70 SCONN288_DDR506112002KQ-SCONN288_DDR506112002KQ,SMA   I352 @T6G_MB_LIB.T6G(SCH_1):PAGE86
   J15  166  VSS71 SCONN288_DDR506112002KQ-SCONN288_DDR506112002KQ,SMA   I352 @T6G_MB_LIB.T6G(SCH_1):PAGE86
   J15  169  VSS72 SCONN288_DDR506112002KQ-SCONN288_DDR506112002KQ,SMA   I352 @T6G_MB_LIB.T6G(SCH_1):PAGE86
   J15  171  VSS73 SCONN288_DDR506112002KQ-SCONN288_DDR506112002KQ,SMA   I352 @T6G_MB_LIB.T6G(SCH_1):PAGE86
   J15  173  VSS74 SCONN288_DDR506112002KQ-SCONN288_DDR506112002KQ,SMA   I352 @T6G_MB_LIB.T6G(SCH_1):PAGE86
   J15  175  VSS75 SCONN288_DDR506112002KQ-SCONN288_DDR506112002KQ,SMA   I352 @T6G_MB_LIB.T6G(SCH_1):PAGE86
   J15  177  VSS76 SCONN288_DDR506112002KQ-SCONN288_DDR506112002KQ,SMA   I352 @T6G_MB_LIB.T6G(SCH_1):PAGE86
   J15  180  VSS77 SCONN288_DDR506112002KQ-SCONN288_DDR506112002KQ,SMA   I352 @T6G_MB_LIB.T6G(SCH_1):PAGE86
   J15  182  VSS78 SCONN288_DDR506112002KQ-SCONN288_DDR506112002KQ,SMA   I352 @T6G_MB_LIB.T6G(SCH_1):PAGE86
   J15  184  VSS79 SCONN288_DDR506112002KQ-SCONN288_DDR506112002KQ,SMA   I352 @T6G_MB_LIB.T6G(SCH_1):PAGE86
   J15  186  VSS80 SCONN288_DDR506112002KQ-SCONN288_DDR506112002KQ,SMA   I352 @T6G_MB_LIB.T6G(SCH_1):PAGE86
   J15  188  VSS81 SCONN288_DDR506112002KQ-SCONN288_DDR506112002KQ,SMA   I352 @T6G_MB_LIB.T6G(SCH_1):PAGE86
   J15  191  VSS82 SCONN288_DDR506112002KQ-SCONN288_DDR506112002KQ,SMA   I352 @T6G_MB_LIB.T6G(SCH_1):PAGE86
   J15  193  VSS83 SCONN288_DDR506112002KQ-SCONN288_DDR506112002KQ,SMA   I352 @T6G_MB_LIB.T6G(SCH_1):PAGE86
   J15  195  VSS84 SCONN288_DDR506112002KQ-SCONN288_DDR506112002KQ,SMA   I352 @T6G_MB_LIB.T6G(SCH_1):PAGE86
   J15  197  VSS85 SCONN288_DDR506112002KQ-SCONN288_DDR506112002KQ,SMA   I352 @T6G_MB_LIB.T6G(SCH_1):PAGE86
   J15  199  VSS86 SCONN288_DDR506112002KQ-SCONN288_DDR506112002KQ,SMA   I352 @T6G_MB_LIB.T6G(SCH_1):PAGE86
   J15  202  VSS87 SCONN288_DDR506112002KQ-SCONN288_DDR506112002KQ,SMA   I352 @T6G_MB_LIB.T6G(SCH_1):PAGE86
   J15  204  VSS88 SCONN288_DDR506112002KQ-SCONN288_DDR506112002KQ,SMA   I352 @T6G_MB_LIB.T6G(SCH_1):PAGE86
   J15  206  VSS89 SCONN288_DDR506112002KQ-SCONN288_DDR506112002KQ,SMA   I352 @T6G_MB_LIB.T6G(SCH_1):PAGE86
   J15  208  VSS90 SCONN288_DDR506112002KQ-SCONN288_DDR506112002KQ,SMA   I352 @T6G_MB_LIB.T6G(SCH_1):PAGE86
   J15  210  VSS91 SCONN288_DDR506112002KQ-SCONN288_DDR506112002KQ,SMA   I352 @T6G_MB_LIB.T6G(SCH_1):PAGE86
   J15  212  VSS92 SCONN288_DDR506112002KQ-SCONN288_DDR506112002KQ,SMA   I352 @T6G_MB_LIB.T6G(SCH_1):PAGE86
   J15  214  VSS93 SCONN288_DDR506112002KQ-SCONN288_DDR506112002KQ,SMA   I352 @T6G_MB_LIB.T6G(SCH_1):PAGE86
   J15  216  VSS94 SCONN288_DDR506112002KQ-SCONN288_DDR506112002KQ,SMA   I352 @T6G_MB_LIB.T6G(SCH_1):PAGE86
   J15  219  VSS95 SCONN288_DDR506112002KQ-SCONN288_DDR506112002KQ,SMA   I352 @T6G_MB_LIB.T6G(SCH_1):PAGE86
   J15  222  VSS96 SCONN288_DDR506112002KQ-SCONN288_DDR506112002KQ,SMA   I352 @T6G_MB_LIB.T6G(SCH_1):PAGE86
   J15  224  VSS97 SCONN288_DDR506112002KQ-SCONN288_DDR506112002KQ,SMA   I352 @T6G_MB_LIB.T6G(SCH_1):PAGE86
   J15  226  VSS98 SCONN288_DDR506112002KQ-SCONN288_DDR506112002KQ,SMA   I352 @T6G_MB_LIB.T6G(SCH_1):PAGE86
   J15  228  VSS99 SCONN288_DDR506112002KQ-SCONN288_DDR506112002KQ,SMA   I352 @T6G_MB_LIB.T6G(SCH_1):PAGE86
   J15  230 VSS100 SCONN288_DDR506112002KQ-SCONN288_DDR506112002KQ,SMA   I352 @T6G_MB_LIB.T6G(SCH_1):PAGE86
   J15  233 VSS101 SCONN288_DDR506112002KQ-SCONN288_DDR506112002KQ,SMA   I352 @T6G_MB_LIB.T6G(SCH_1):PAGE86
   J15  235 VSS102 SCONN288_DDR506112002KQ-SCONN288_DDR506112002KQ,SMA   I352 @T6G_MB_LIB.T6G(SCH_1):PAGE86
   J15  237 VSS103 SCONN288_DDR506112002KQ-SCONN288_DDR506112002KQ,SMA   I352 @T6G_MB_LIB.T6G(SCH_1):PAGE86
   J15  240 VSS104 SCONN288_DDR506112002KQ-SCONN288_DDR506112002KQ,SMA   I352 @T6G_MB_LIB.T6G(SCH_1):PAGE86
   J15  242 VSS105 SCONN288_DDR506112002KQ-SCONN288_DDR506112002KQ,SMA   I352 @T6G_MB_LIB.T6G(SCH_1):PAGE86
   J15  244 VSS106 SCONN288_DDR506112002KQ-SCONN288_DDR506112002KQ,SMA   I352 @T6G_MB_LIB.T6G(SCH_1):PAGE86
   J15  246 VSS107 SCONN288_DDR506112002KQ-SCONN288_DDR506112002KQ,SMA   I352 @T6G_MB_LIB.T6G(SCH_1):PAGE86
   J15  248 VSS108 SCONN288_DDR506112002KQ-SCONN288_DDR506112002KQ,SMA   I352 @T6G_MB_LIB.T6G(SCH_1):PAGE86
   J15  251 VSS109 SCONN288_DDR506112002KQ-SCONN288_DDR506112002KQ,SMA   I352 @T6G_MB_LIB.T6G(SCH_1):PAGE86
   J15  253 VSS110 SCONN288_DDR506112002KQ-SCONN288_DDR506112002KQ,SMA   I352 @T6G_MB_LIB.T6G(SCH_1):PAGE86
   J15  255 VSS111 SCONN288_DDR506112002KQ-SCONN288_DDR506112002KQ,SMA   I352 @T6G_MB_LIB.T6G(SCH_1):PAGE86
   J15  257 VSS112 SCONN288_DDR506112002KQ-SCONN288_DDR506112002KQ,SMA   I352 @T6G_MB_LIB.T6G(SCH_1):PAGE86
   J15  259 VSS113 SCONN288_DDR506112002KQ-SCONN288_DDR506112002KQ,SMA   I352 @T6G_MB_LIB.T6G(SCH_1):PAGE86
   J15  262 VSS114 SCONN288_DDR506112002KQ-SCONN288_DDR506112002KQ,SMA   I352 @T6G_MB_LIB.T6G(SCH_1):PAGE86
   J15  264 VSS115 SCONN288_DDR506112002KQ-SCONN288_DDR506112002KQ,SMA   I352 @T6G_MB_LIB.T6G(SCH_1):PAGE86
   J15  266 VSS116 SCONN288_DDR506112002KQ-SCONN288_DDR506112002KQ,SMA   I352 @T6G_MB_LIB.T6G(SCH_1):PAGE86
   J15  268 VSS117 SCONN288_DDR506112002KQ-SCONN288_DDR506112002KQ,SMA   I352 @T6G_MB_LIB.T6G(SCH_1):PAGE86
   J15  270 VSS118 SCONN288_DDR506112002KQ-SCONN288_DDR506112002KQ,SMA   I352 @T6G_MB_LIB.T6G(SCH_1):PAGE86
   J15  273 VSS119 SCONN288_DDR506112002KQ-SCONN288_DDR506112002KQ,SMA   I352 @T6G_MB_LIB.T6G(SCH_1):PAGE86
   J15  275 VSS120 SCONN288_DDR506112002KQ-SCONN288_DDR506112002KQ,SMA   I352 @T6G_MB_LIB.T6G(SCH_1):PAGE86
   J15  277 VSS121 SCONN288_DDR506112002KQ-SCONN288_DDR506112002KQ,SMA   I352 @T6G_MB_LIB.T6G(SCH_1):PAGE86
   J15  279 VSS122 SCONN288_DDR506112002KQ-SCONN288_DDR506112002KQ,SMA   I352 @T6G_MB_LIB.T6G(SCH_1):PAGE86
   J15  281 VSS123 SCONN288_DDR506112002KQ-SCONN288_DDR506112002KQ,SMA   I352 @T6G_MB_LIB.T6G(SCH_1):PAGE86
   J15  284 VSS124 SCONN288_DDR506112002KQ-SCONN288_DDR506112002KQ,SMA   I352 @T6G_MB_LIB.T6G(SCH_1):PAGE86
   J15  286 VSS125 SCONN288_DDR506112002KQ-SCONN288_DDR506112002KQ,SMA   I352 @T6G_MB_LIB.T6G(SCH_1):PAGE86
   J15  288 VSS126 SCONN288_DDR506112002KQ-SCONN288_DDR506112002KQ,SMA   I352 @T6G_MB_LIB.T6G(SCH_1):PAGE86
   C92    2      B Q_CAP_0402-0.1UF,25V,10%,X7R,CH4104K1B00   I362 @T6G_MB_LIB.T6G(SCH_1):PAGE86
  C143    2      B Q_CAP_C0805-10UF,25V,10%,X6S,CH6104KEA00   I369 @T6G_MB_LIB.T6G(SCH_1):PAGE86
  C145    2      B Q_CAP_C0805-10UF,25V,10%,X6S,CH6104KEA00   I370 @T6G_MB_LIB.T6G(SCH_1):PAGE86
  R762    2      B Q_RES_0402LF-23.2K,1%,1/16W,CHIP,CS32322FB03   I349 @T6G_MB_LIB.T6G(SCH_1):PAGE87
   J17   G1     G1 SCONN288_DDR506112002KQ-SCONN288_DDR506112002KQ,SMA   I352 @T6G_MB_LIB.T6G(SCH_1):PAGE87
   J17   G2     G2 SCONN288_DDR506112002KQ-SCONN288_DDR506112002KQ,SMA   I352 @T6G_MB_LIB.T6G(SCH_1):PAGE87
   J17   G3     G3 SCONN288_DDR506112002KQ-SCONN288_DDR506112002KQ,SMA   I352 @T6G_MB_LIB.T6G(SCH_1):PAGE87
   J17    6   VSS0 SCONN288_DDR506112002KQ-SCONN288_DDR506112002KQ,SMA   I352 @T6G_MB_LIB.T6G(SCH_1):PAGE87
   J17    8   VSS1 SCONN288_DDR506112002KQ-SCONN288_DDR506112002KQ,SMA   I352 @T6G_MB_LIB.T6G(SCH_1):PAGE87
   J17   10   VSS2 SCONN288_DDR506112002KQ-SCONN288_DDR506112002KQ,SMA   I352 @T6G_MB_LIB.T6G(SCH_1):PAGE87
   J17   13   VSS3 SCONN288_DDR506112002KQ-SCONN288_DDR506112002KQ,SMA   I352 @T6G_MB_LIB.T6G(SCH_1):PAGE87
   J17   15   VSS4 SCONN288_DDR506112002KQ-SCONN288_DDR506112002KQ,SMA   I352 @T6G_MB_LIB.T6G(SCH_1):PAGE87
   J17   17   VSS5 SCONN288_DDR506112002KQ-SCONN288_DDR506112002KQ,SMA   I352 @T6G_MB_LIB.T6G(SCH_1):PAGE87
   J17   19   VSS6 SCONN288_DDR506112002KQ-SCONN288_DDR506112002KQ,SMA   I352 @T6G_MB_LIB.T6G(SCH_1):PAGE87
   J17   21   VSS7 SCONN288_DDR506112002KQ-SCONN288_DDR506112002KQ,SMA   I352 @T6G_MB_LIB.T6G(SCH_1):PAGE87
   J17   24   VSS8 SCONN288_DDR506112002KQ-SCONN288_DDR506112002KQ,SMA   I352 @T6G_MB_LIB.T6G(SCH_1):PAGE87
   J17   26   VSS9 SCONN288_DDR506112002KQ-SCONN288_DDR506112002KQ,SMA   I352 @T6G_MB_LIB.T6G(SCH_1):PAGE87
   J17   28  VSS10 SCONN288_DDR506112002KQ-SCONN288_DDR506112002KQ,SMA   I352 @T6G_MB_LIB.T6G(SCH_1):PAGE87
   J17   30  VSS11 SCONN288_DDR506112002KQ-SCONN288_DDR506112002KQ,SMA   I352 @T6G_MB_LIB.T6G(SCH_1):PAGE87
   J17   32  VSS12 SCONN288_DDR506112002KQ-SCONN288_DDR506112002KQ,SMA   I352 @T6G_MB_LIB.T6G(SCH_1):PAGE87
   J17   35  VSS13 SCONN288_DDR506112002KQ-SCONN288_DDR506112002KQ,SMA   I352 @T6G_MB_LIB.T6G(SCH_1):PAGE87
   J17   37  VSS14 SCONN288_DDR506112002KQ-SCONN288_DDR506112002KQ,SMA   I352 @T6G_MB_LIB.T6G(SCH_1):PAGE87
   J17   39  VSS15 SCONN288_DDR506112002KQ-SCONN288_DDR506112002KQ,SMA   I352 @T6G_MB_LIB.T6G(SCH_1):PAGE87
   J17   41  VSS16 SCONN288_DDR506112002KQ-SCONN288_DDR506112002KQ,SMA   I352 @T6G_MB_LIB.T6G(SCH_1):PAGE87
   J17   43  VSS17 SCONN288_DDR506112002KQ-SCONN288_DDR506112002KQ,SMA   I352 @T6G_MB_LIB.T6G(SCH_1):PAGE87
   J17   46  VSS18 SCONN288_DDR506112002KQ-SCONN288_DDR506112002KQ,SMA   I352 @T6G_MB_LIB.T6G(SCH_1):PAGE87
   J17   48  VSS19 SCONN288_DDR506112002KQ-SCONN288_DDR506112002KQ,SMA   I352 @T6G_MB_LIB.T6G(SCH_1):PAGE87
   J17   50  VSS20 SCONN288_DDR506112002KQ-SCONN288_DDR506112002KQ,SMA   I352 @T6G_MB_LIB.T6G(SCH_1):PAGE87
   J17   52  VSS21 SCONN288_DDR506112002KQ-SCONN288_DDR506112002KQ,SMA   I352 @T6G_MB_LIB.T6G(SCH_1):PAGE87
   J17   54  VSS22 SCONN288_DDR506112002KQ-SCONN288_DDR506112002KQ,SMA   I352 @T6G_MB_LIB.T6G(SCH_1):PAGE87
   J17   57  VSS23 SCONN288_DDR506112002KQ-SCONN288_DDR506112002KQ,SMA   I352 @T6G_MB_LIB.T6G(SCH_1):PAGE87
   J17   59  VSS24 SCONN288_DDR506112002KQ-SCONN288_DDR506112002KQ,SMA   I352 @T6G_MB_LIB.T6G(SCH_1):PAGE87
   J17   61  VSS25 SCONN288_DDR506112002KQ-SCONN288_DDR506112002KQ,SMA   I352 @T6G_MB_LIB.T6G(SCH_1):PAGE87
   J17   63  VSS26 SCONN288_DDR506112002KQ-SCONN288_DDR506112002KQ,SMA   I352 @T6G_MB_LIB.T6G(SCH_1):PAGE87
   J17   65  VSS27 SCONN288_DDR506112002KQ-SCONN288_DDR506112002KQ,SMA   I352 @T6G_MB_LIB.T6G(SCH_1):PAGE87
   J17   67  VSS28 SCONN288_DDR506112002KQ-SCONN288_DDR506112002KQ,SMA   I352 @T6G_MB_LIB.T6G(SCH_1):PAGE87
   J17   69  VSS29 SCONN288_DDR506112002KQ-SCONN288_DDR506112002KQ,SMA   I352 @T6G_MB_LIB.T6G(SCH_1):PAGE87
   J17   71  VSS30 SCONN288_DDR506112002KQ-SCONN288_DDR506112002KQ,SMA   I352 @T6G_MB_LIB.T6G(SCH_1):PAGE87
   J17   73  VSS31 SCONN288_DDR506112002KQ-SCONN288_DDR506112002KQ,SMA   I352 @T6G_MB_LIB.T6G(SCH_1):PAGE87
   J17   75  VSS32 SCONN288_DDR506112002KQ-SCONN288_DDR506112002KQ,SMA   I352 @T6G_MB_LIB.T6G(SCH_1):PAGE87
   J17   77  VSS33 SCONN288_DDR506112002KQ-SCONN288_DDR506112002KQ,SMA   I352 @T6G_MB_LIB.T6G(SCH_1):PAGE87
   J17   79  VSS34 SCONN288_DDR506112002KQ-SCONN288_DDR506112002KQ,SMA   I352 @T6G_MB_LIB.T6G(SCH_1):PAGE87
   J17   81  VSS35 SCONN288_DDR506112002KQ-SCONN288_DDR506112002KQ,SMA   I352 @T6G_MB_LIB.T6G(SCH_1):PAGE87
   J17   83  VSS36 SCONN288_DDR506112002KQ-SCONN288_DDR506112002KQ,SMA   I352 @T6G_MB_LIB.T6G(SCH_1):PAGE87
   J17   85  VSS37 SCONN288_DDR506112002KQ-SCONN288_DDR506112002KQ,SMA   I352 @T6G_MB_LIB.T6G(SCH_1):PAGE87
   J17   88  VSS38 SCONN288_DDR506112002KQ-SCONN288_DDR506112002KQ,SMA   I352 @T6G_MB_LIB.T6G(SCH_1):PAGE87
   J17   90  VSS39 SCONN288_DDR506112002KQ-SCONN288_DDR506112002KQ,SMA   I352 @T6G_MB_LIB.T6G(SCH_1):PAGE87
   J17   92  VSS40 SCONN288_DDR506112002KQ-SCONN288_DDR506112002KQ,SMA   I352 @T6G_MB_LIB.T6G(SCH_1):PAGE87
   J17   95  VSS41 SCONN288_DDR506112002KQ-SCONN288_DDR506112002KQ,SMA   I352 @T6G_MB_LIB.T6G(SCH_1):PAGE87
   J17   97  VSS42 SCONN288_DDR506112002KQ-SCONN288_DDR506112002KQ,SMA   I352 @T6G_MB_LIB.T6G(SCH_1):PAGE87
   J17   99  VSS43 SCONN288_DDR506112002KQ-SCONN288_DDR506112002KQ,SMA   I352 @T6G_MB_LIB.T6G(SCH_1):PAGE87
   J17  101  VSS44 SCONN288_DDR506112002KQ-SCONN288_DDR506112002KQ,SMA   I352 @T6G_MB_LIB.T6G(SCH_1):PAGE87
   J17  103  VSS45 SCONN288_DDR506112002KQ-SCONN288_DDR506112002KQ,SMA   I352 @T6G_MB_LIB.T6G(SCH_1):PAGE87
   J17  106  VSS46 SCONN288_DDR506112002KQ-SCONN288_DDR506112002KQ,SMA   I352 @T6G_MB_LIB.T6G(SCH_1):PAGE87
   J17  108  VSS47 SCONN288_DDR506112002KQ-SCONN288_DDR506112002KQ,SMA   I352 @T6G_MB_LIB.T6G(SCH_1):PAGE87
   J17  110  VSS48 SCONN288_DDR506112002KQ-SCONN288_DDR506112002KQ,SMA   I352 @T6G_MB_LIB.T6G(SCH_1):PAGE87
   J17  112  VSS49 SCONN288_DDR506112002KQ-SCONN288_DDR506112002KQ,SMA   I352 @T6G_MB_LIB.T6G(SCH_1):PAGE87
   J17  114  VSS50 SCONN288_DDR506112002KQ-SCONN288_DDR506112002KQ,SMA   I352 @T6G_MB_LIB.T6G(SCH_1):PAGE87
   J17  117  VSS51 SCONN288_DDR506112002KQ-SCONN288_DDR506112002KQ,SMA   I352 @T6G_MB_LIB.T6G(SCH_1):PAGE87
   J17  119  VSS52 SCONN288_DDR506112002KQ-SCONN288_DDR506112002KQ,SMA   I352 @T6G_MB_LIB.T6G(SCH_1):PAGE87
   J17  121  VSS53 SCONN288_DDR506112002KQ-SCONN288_DDR506112002KQ,SMA   I352 @T6G_MB_LIB.T6G(SCH_1):PAGE87
   J17  123  VSS54 SCONN288_DDR506112002KQ-SCONN288_DDR506112002KQ,SMA   I352 @T6G_MB_LIB.T6G(SCH_1):PAGE87
   J17  125  VSS55 SCONN288_DDR506112002KQ-SCONN288_DDR506112002KQ,SMA   I352 @T6G_MB_LIB.T6G(SCH_1):PAGE87
   J17  128  VSS56 SCONN288_DDR506112002KQ-SCONN288_DDR506112002KQ,SMA   I352 @T6G_MB_LIB.T6G(SCH_1):PAGE87
   J17  130  VSS57 SCONN288_DDR506112002KQ-SCONN288_DDR506112002KQ,SMA   I352 @T6G_MB_LIB.T6G(SCH_1):PAGE87
   J17  132  VSS58 SCONN288_DDR506112002KQ-SCONN288_DDR506112002KQ,SMA   I352 @T6G_MB_LIB.T6G(SCH_1):PAGE87
   J17  134  VSS59 SCONN288_DDR506112002KQ-SCONN288_DDR506112002KQ,SMA   I352 @T6G_MB_LIB.T6G(SCH_1):PAGE87
   J17  136  VSS60 SCONN288_DDR506112002KQ-SCONN288_DDR506112002KQ,SMA   I352 @T6G_MB_LIB.T6G(SCH_1):PAGE87
   J17  139  VSS61 SCONN288_DDR506112002KQ-SCONN288_DDR506112002KQ,SMA   I352 @T6G_MB_LIB.T6G(SCH_1):PAGE87
   J17  141  VSS62 SCONN288_DDR506112002KQ-SCONN288_DDR506112002KQ,SMA   I352 @T6G_MB_LIB.T6G(SCH_1):PAGE87
   J17  143  VSS63 SCONN288_DDR506112002KQ-SCONN288_DDR506112002KQ,SMA   I352 @T6G_MB_LIB.T6G(SCH_1):PAGE87
   J17  151  VSS64 SCONN288_DDR506112002KQ-SCONN288_DDR506112002KQ,SMA   I352 @T6G_MB_LIB.T6G(SCH_1):PAGE87
   J17  153  VSS65 SCONN288_DDR506112002KQ-SCONN288_DDR506112002KQ,SMA   I352 @T6G_MB_LIB.T6G(SCH_1):PAGE87
   J17  155  VSS66 SCONN288_DDR506112002KQ-SCONN288_DDR506112002KQ,SMA   I352 @T6G_MB_LIB.T6G(SCH_1):PAGE87
   J17  158  VSS67 SCONN288_DDR506112002KQ-SCONN288_DDR506112002KQ,SMA   I352 @T6G_MB_LIB.T6G(SCH_1):PAGE87
   J17  160  VSS68 SCONN288_DDR506112002KQ-SCONN288_DDR506112002KQ,SMA   I352 @T6G_MB_LIB.T6G(SCH_1):PAGE87
   J17  162  VSS69 SCONN288_DDR506112002KQ-SCONN288_DDR506112002KQ,SMA   I352 @T6G_MB_LIB.T6G(SCH_1):PAGE87
   J17  164  VSS70 SCONN288_DDR506112002KQ-SCONN288_DDR506112002KQ,SMA   I352 @T6G_MB_LIB.T6G(SCH_1):PAGE87
   J17  166  VSS71 SCONN288_DDR506112002KQ-SCONN288_DDR506112002KQ,SMA   I352 @T6G_MB_LIB.T6G(SCH_1):PAGE87
   J17  169  VSS72 SCONN288_DDR506112002KQ-SCONN288_DDR506112002KQ,SMA   I352 @T6G_MB_LIB.T6G(SCH_1):PAGE87
   J17  171  VSS73 SCONN288_DDR506112002KQ-SCONN288_DDR506112002KQ,SMA   I352 @T6G_MB_LIB.T6G(SCH_1):PAGE87
   J17  173  VSS74 SCONN288_DDR506112002KQ-SCONN288_DDR506112002KQ,SMA   I352 @T6G_MB_LIB.T6G(SCH_1):PAGE87
   J17  175  VSS75 SCONN288_DDR506112002KQ-SCONN288_DDR506112002KQ,SMA   I352 @T6G_MB_LIB.T6G(SCH_1):PAGE87
   J17  177  VSS76 SCONN288_DDR506112002KQ-SCONN288_DDR506112002KQ,SMA   I352 @T6G_MB_LIB.T6G(SCH_1):PAGE87
   J17  180  VSS77 SCONN288_DDR506112002KQ-SCONN288_DDR506112002KQ,SMA   I352 @T6G_MB_LIB.T6G(SCH_1):PAGE87
   J17  182  VSS78 SCONN288_DDR506112002KQ-SCONN288_DDR506112002KQ,SMA   I352 @T6G_MB_LIB.T6G(SCH_1):PAGE87
   J17  184  VSS79 SCONN288_DDR506112002KQ-SCONN288_DDR506112002KQ,SMA   I352 @T6G_MB_LIB.T6G(SCH_1):PAGE87
   J17  186  VSS80 SCONN288_DDR506112002KQ-SCONN288_DDR506112002KQ,SMA   I352 @T6G_MB_LIB.T6G(SCH_1):PAGE87
   J17  188  VSS81 SCONN288_DDR506112002KQ-SCONN288_DDR506112002KQ,SMA   I352 @T6G_MB_LIB.T6G(SCH_1):PAGE87
   J17  191  VSS82 SCONN288_DDR506112002KQ-SCONN288_DDR506112002KQ,SMA   I352 @T6G_MB_LIB.T6G(SCH_1):PAGE87
   J17  193  VSS83 SCONN288_DDR506112002KQ-SCONN288_DDR506112002KQ,SMA   I352 @T6G_MB_LIB.T6G(SCH_1):PAGE87
   J17  195  VSS84 SCONN288_DDR506112002KQ-SCONN288_DDR506112002KQ,SMA   I352 @T6G_MB_LIB.T6G(SCH_1):PAGE87
   J17  197  VSS85 SCONN288_DDR506112002KQ-SCONN288_DDR506112002KQ,SMA   I352 @T6G_MB_LIB.T6G(SCH_1):PAGE87
   J17  199  VSS86 SCONN288_DDR506112002KQ-SCONN288_DDR506112002KQ,SMA   I352 @T6G_MB_LIB.T6G(SCH_1):PAGE87
   J17  202  VSS87 SCONN288_DDR506112002KQ-SCONN288_DDR506112002KQ,SMA   I352 @T6G_MB_LIB.T6G(SCH_1):PAGE87
   J17  204  VSS88 SCONN288_DDR506112002KQ-SCONN288_DDR506112002KQ,SMA   I352 @T6G_MB_LIB.T6G(SCH_1):PAGE87
   J17  206  VSS89 SCONN288_DDR506112002KQ-SCONN288_DDR506112002KQ,SMA   I352 @T6G_MB_LIB.T6G(SCH_1):PAGE87
   J17  208  VSS90 SCONN288_DDR506112002KQ-SCONN288_DDR506112002KQ,SMA   I352 @T6G_MB_LIB.T6G(SCH_1):PAGE87
   J17  210  VSS91 SCONN288_DDR506112002KQ-SCONN288_DDR506112002KQ,SMA   I352 @T6G_MB_LIB.T6G(SCH_1):PAGE87
   J17  212  VSS92 SCONN288_DDR506112002KQ-SCONN288_DDR506112002KQ,SMA   I352 @T6G_MB_LIB.T6G(SCH_1):PAGE87
   J17  214  VSS93 SCONN288_DDR506112002KQ-SCONN288_DDR506112002KQ,SMA   I352 @T6G_MB_LIB.T6G(SCH_1):PAGE87
   J17  216  VSS94 SCONN288_DDR506112002KQ-SCONN288_DDR506112002KQ,SMA   I352 @T6G_MB_LIB.T6G(SCH_1):PAGE87
   J17  219  VSS95 SCONN288_DDR506112002KQ-SCONN288_DDR506112002KQ,SMA   I352 @T6G_MB_LIB.T6G(SCH_1):PAGE87
   J17  222  VSS96 SCONN288_DDR506112002KQ-SCONN288_DDR506112002KQ,SMA   I352 @T6G_MB_LIB.T6G(SCH_1):PAGE87
   J17  224  VSS97 SCONN288_DDR506112002KQ-SCONN288_DDR506112002KQ,SMA   I352 @T6G_MB_LIB.T6G(SCH_1):PAGE87
   J17  226  VSS98 SCONN288_DDR506112002KQ-SCONN288_DDR506112002KQ,SMA   I352 @T6G_MB_LIB.T6G(SCH_1):PAGE87
   J17  228  VSS99 SCONN288_DDR506112002KQ-SCONN288_DDR506112002KQ,SMA   I352 @T6G_MB_LIB.T6G(SCH_1):PAGE87
   J17  230 VSS100 SCONN288_DDR506112002KQ-SCONN288_DDR506112002KQ,SMA   I352 @T6G_MB_LIB.T6G(SCH_1):PAGE87
   J17  233 VSS101 SCONN288_DDR506112002KQ-SCONN288_DDR506112002KQ,SMA   I352 @T6G_MB_LIB.T6G(SCH_1):PAGE87
   J17  235 VSS102 SCONN288_DDR506112002KQ-SCONN288_DDR506112002KQ,SMA   I352 @T6G_MB_LIB.T6G(SCH_1):PAGE87
   J17  237 VSS103 SCONN288_DDR506112002KQ-SCONN288_DDR506112002KQ,SMA   I352 @T6G_MB_LIB.T6G(SCH_1):PAGE87
   J17  240 VSS104 SCONN288_DDR506112002KQ-SCONN288_DDR506112002KQ,SMA   I352 @T6G_MB_LIB.T6G(SCH_1):PAGE87
   J17  242 VSS105 SCONN288_DDR506112002KQ-SCONN288_DDR506112002KQ,SMA   I352 @T6G_MB_LIB.T6G(SCH_1):PAGE87
   J17  244 VSS106 SCONN288_DDR506112002KQ-SCONN288_DDR506112002KQ,SMA   I352 @T6G_MB_LIB.T6G(SCH_1):PAGE87
   J17  246 VSS107 SCONN288_DDR506112002KQ-SCONN288_DDR506112002KQ,SMA   I352 @T6G_MB_LIB.T6G(SCH_1):PAGE87
   J17  248 VSS108 SCONN288_DDR506112002KQ-SCONN288_DDR506112002KQ,SMA   I352 @T6G_MB_LIB.T6G(SCH_1):PAGE87
   J17  251 VSS109 SCONN288_DDR506112002KQ-SCONN288_DDR506112002KQ,SMA   I352 @T6G_MB_LIB.T6G(SCH_1):PAGE87
   J17  253 VSS110 SCONN288_DDR506112002KQ-SCONN288_DDR506112002KQ,SMA   I352 @T6G_MB_LIB.T6G(SCH_1):PAGE87
   J17  255 VSS111 SCONN288_DDR506112002KQ-SCONN288_DDR506112002KQ,SMA   I352 @T6G_MB_LIB.T6G(SCH_1):PAGE87
   J17  257 VSS112 SCONN288_DDR506112002KQ-SCONN288_DDR506112002KQ,SMA   I352 @T6G_MB_LIB.T6G(SCH_1):PAGE87
   J17  259 VSS113 SCONN288_DDR506112002KQ-SCONN288_DDR506112002KQ,SMA   I352 @T6G_MB_LIB.T6G(SCH_1):PAGE87
   J17  262 VSS114 SCONN288_DDR506112002KQ-SCONN288_DDR506112002KQ,SMA   I352 @T6G_MB_LIB.T6G(SCH_1):PAGE87
   J17  264 VSS115 SCONN288_DDR506112002KQ-SCONN288_DDR506112002KQ,SMA   I352 @T6G_MB_LIB.T6G(SCH_1):PAGE87
   J17  266 VSS116 SCONN288_DDR506112002KQ-SCONN288_DDR506112002KQ,SMA   I352 @T6G_MB_LIB.T6G(SCH_1):PAGE87
   J17  268 VSS117 SCONN288_DDR506112002KQ-SCONN288_DDR506112002KQ,SMA   I352 @T6G_MB_LIB.T6G(SCH_1):PAGE87
   J17  270 VSS118 SCONN288_DDR506112002KQ-SCONN288_DDR506112002KQ,SMA   I352 @T6G_MB_LIB.T6G(SCH_1):PAGE87
   J17  273 VSS119 SCONN288_DDR506112002KQ-SCONN288_DDR506112002KQ,SMA   I352 @T6G_MB_LIB.T6G(SCH_1):PAGE87
   J17  275 VSS120 SCONN288_DDR506112002KQ-SCONN288_DDR506112002KQ,SMA   I352 @T6G_MB_LIB.T6G(SCH_1):PAGE87
   J17  277 VSS121 SCONN288_DDR506112002KQ-SCONN288_DDR506112002KQ,SMA   I352 @T6G_MB_LIB.T6G(SCH_1):PAGE87
   J17  279 VSS122 SCONN288_DDR506112002KQ-SCONN288_DDR506112002KQ,SMA   I352 @T6G_MB_LIB.T6G(SCH_1):PAGE87
   J17  281 VSS123 SCONN288_DDR506112002KQ-SCONN288_DDR506112002KQ,SMA   I352 @T6G_MB_LIB.T6G(SCH_1):PAGE87
   J17  284 VSS124 SCONN288_DDR506112002KQ-SCONN288_DDR506112002KQ,SMA   I352 @T6G_MB_LIB.T6G(SCH_1):PAGE87
   J17  286 VSS125 SCONN288_DDR506112002KQ-SCONN288_DDR506112002KQ,SMA   I352 @T6G_MB_LIB.T6G(SCH_1):PAGE87
   J17  288 VSS126 SCONN288_DDR506112002KQ-SCONN288_DDR506112002KQ,SMA   I352 @T6G_MB_LIB.T6G(SCH_1):PAGE87
   C96    2      B Q_CAP_0402-0.1UF,25V,10%,X7R,CH4104K1B00   I362 @T6G_MB_LIB.T6G(SCH_1):PAGE87
  C146    2      B Q_CAP_C0805-10UF,25V,10%,X6S,CH6104KEA00   I413 @T6G_MB_LIB.T6G(SCH_1):PAGE87
  C147    2      B Q_CAP_C0805-10UF,25V,10%,X6S,CH6104KEA00   I414 @T6G_MB_LIB.T6G(SCH_1):PAGE87
  R763    2      B Q_RES_0402LF-35.7K,1%,1/16W,CHIP,CS33572FB01   I349 @T6G_MB_LIB.T6G(SCH_1):PAGE88
   J19   G1     G1 SCONN288_DDR506112002KQ-SCONN288_DDR506112002KQ,SMA   I352 @T6G_MB_LIB.T6G(SCH_1):PAGE88
   J19   G2     G2 SCONN288_DDR506112002KQ-SCONN288_DDR506112002KQ,SMA   I352 @T6G_MB_LIB.T6G(SCH_1):PAGE88
   J19   G3     G3 SCONN288_DDR506112002KQ-SCONN288_DDR506112002KQ,SMA   I352 @T6G_MB_LIB.T6G(SCH_1):PAGE88
   J19    6   VSS0 SCONN288_DDR506112002KQ-SCONN288_DDR506112002KQ,SMA   I352 @T6G_MB_LIB.T6G(SCH_1):PAGE88
   J19    8   VSS1 SCONN288_DDR506112002KQ-SCONN288_DDR506112002KQ,SMA   I352 @T6G_MB_LIB.T6G(SCH_1):PAGE88
   J19   10   VSS2 SCONN288_DDR506112002KQ-SCONN288_DDR506112002KQ,SMA   I352 @T6G_MB_LIB.T6G(SCH_1):PAGE88
   J19   13   VSS3 SCONN288_DDR506112002KQ-SCONN288_DDR506112002KQ,SMA   I352 @T6G_MB_LIB.T6G(SCH_1):PAGE88
   J19   15   VSS4 SCONN288_DDR506112002KQ-SCONN288_DDR506112002KQ,SMA   I352 @T6G_MB_LIB.T6G(SCH_1):PAGE88
   J19   17   VSS5 SCONN288_DDR506112002KQ-SCONN288_DDR506112002KQ,SMA   I352 @T6G_MB_LIB.T6G(SCH_1):PAGE88
   J19   19   VSS6 SCONN288_DDR506112002KQ-SCONN288_DDR506112002KQ,SMA   I352 @T6G_MB_LIB.T6G(SCH_1):PAGE88
   J19   21   VSS7 SCONN288_DDR506112002KQ-SCONN288_DDR506112002KQ,SMA   I352 @T6G_MB_LIB.T6G(SCH_1):PAGE88
   J19   24   VSS8 SCONN288_DDR506112002KQ-SCONN288_DDR506112002KQ,SMA   I352 @T6G_MB_LIB.T6G(SCH_1):PAGE88
   J19   26   VSS9 SCONN288_DDR506112002KQ-SCONN288_DDR506112002KQ,SMA   I352 @T6G_MB_LIB.T6G(SCH_1):PAGE88
   J19   28  VSS10 SCONN288_DDR506112002KQ-SCONN288_DDR506112002KQ,SMA   I352 @T6G_MB_LIB.T6G(SCH_1):PAGE88
   J19   30  VSS11 SCONN288_DDR506112002KQ-SCONN288_DDR506112002KQ,SMA   I352 @T6G_MB_LIB.T6G(SCH_1):PAGE88
   J19   32  VSS12 SCONN288_DDR506112002KQ-SCONN288_DDR506112002KQ,SMA   I352 @T6G_MB_LIB.T6G(SCH_1):PAGE88
   J19   35  VSS13 SCONN288_DDR506112002KQ-SCONN288_DDR506112002KQ,SMA   I352 @T6G_MB_LIB.T6G(SCH_1):PAGE88
   J19   37  VSS14 SCONN288_DDR506112002KQ-SCONN288_DDR506112002KQ,SMA   I352 @T6G_MB_LIB.T6G(SCH_1):PAGE88
   J19   39  VSS15 SCONN288_DDR506112002KQ-SCONN288_DDR506112002KQ,SMA   I352 @T6G_MB_LIB.T6G(SCH_1):PAGE88
   J19   41  VSS16 SCONN288_DDR506112002KQ-SCONN288_DDR506112002KQ,SMA   I352 @T6G_MB_LIB.T6G(SCH_1):PAGE88
   J19   43  VSS17 SCONN288_DDR506112002KQ-SCONN288_DDR506112002KQ,SMA   I352 @T6G_MB_LIB.T6G(SCH_1):PAGE88
   J19   46  VSS18 SCONN288_DDR506112002KQ-SCONN288_DDR506112002KQ,SMA   I352 @T6G_MB_LIB.T6G(SCH_1):PAGE88
   J19   48  VSS19 SCONN288_DDR506112002KQ-SCONN288_DDR506112002KQ,SMA   I352 @T6G_MB_LIB.T6G(SCH_1):PAGE88
   J19   50  VSS20 SCONN288_DDR506112002KQ-SCONN288_DDR506112002KQ,SMA   I352 @T6G_MB_LIB.T6G(SCH_1):PAGE88
   J19   52  VSS21 SCONN288_DDR506112002KQ-SCONN288_DDR506112002KQ,SMA   I352 @T6G_MB_LIB.T6G(SCH_1):PAGE88
   J19   54  VSS22 SCONN288_DDR506112002KQ-SCONN288_DDR506112002KQ,SMA   I352 @T6G_MB_LIB.T6G(SCH_1):PAGE88
   J19   57  VSS23 SCONN288_DDR506112002KQ-SCONN288_DDR506112002KQ,SMA   I352 @T6G_MB_LIB.T6G(SCH_1):PAGE88
   J19   59  VSS24 SCONN288_DDR506112002KQ-SCONN288_DDR506112002KQ,SMA   I352 @T6G_MB_LIB.T6G(SCH_1):PAGE88
   J19   61  VSS25 SCONN288_DDR506112002KQ-SCONN288_DDR506112002KQ,SMA   I352 @T6G_MB_LIB.T6G(SCH_1):PAGE88
   J19   63  VSS26 SCONN288_DDR506112002KQ-SCONN288_DDR506112002KQ,SMA   I352 @T6G_MB_LIB.T6G(SCH_1):PAGE88
   J19   65  VSS27 SCONN288_DDR506112002KQ-SCONN288_DDR506112002KQ,SMA   I352 @T6G_MB_LIB.T6G(SCH_1):PAGE88
   J19   67  VSS28 SCONN288_DDR506112002KQ-SCONN288_DDR506112002KQ,SMA   I352 @T6G_MB_LIB.T6G(SCH_1):PAGE88
   J19   69  VSS29 SCONN288_DDR506112002KQ-SCONN288_DDR506112002KQ,SMA   I352 @T6G_MB_LIB.T6G(SCH_1):PAGE88
   J19   71  VSS30 SCONN288_DDR506112002KQ-SCONN288_DDR506112002KQ,SMA   I352 @T6G_MB_LIB.T6G(SCH_1):PAGE88
   J19   73  VSS31 SCONN288_DDR506112002KQ-SCONN288_DDR506112002KQ,SMA   I352 @T6G_MB_LIB.T6G(SCH_1):PAGE88
   J19   75  VSS32 SCONN288_DDR506112002KQ-SCONN288_DDR506112002KQ,SMA   I352 @T6G_MB_LIB.T6G(SCH_1):PAGE88
   J19   77  VSS33 SCONN288_DDR506112002KQ-SCONN288_DDR506112002KQ,SMA   I352 @T6G_MB_LIB.T6G(SCH_1):PAGE88
   J19   79  VSS34 SCONN288_DDR506112002KQ-SCONN288_DDR506112002KQ,SMA   I352 @T6G_MB_LIB.T6G(SCH_1):PAGE88
   J19   81  VSS35 SCONN288_DDR506112002KQ-SCONN288_DDR506112002KQ,SMA   I352 @T6G_MB_LIB.T6G(SCH_1):PAGE88
   J19   83  VSS36 SCONN288_DDR506112002KQ-SCONN288_DDR506112002KQ,SMA   I352 @T6G_MB_LIB.T6G(SCH_1):PAGE88
   J19   85  VSS37 SCONN288_DDR506112002KQ-SCONN288_DDR506112002KQ,SMA   I352 @T6G_MB_LIB.T6G(SCH_1):PAGE88
   J19   88  VSS38 SCONN288_DDR506112002KQ-SCONN288_DDR506112002KQ,SMA   I352 @T6G_MB_LIB.T6G(SCH_1):PAGE88
   J19   90  VSS39 SCONN288_DDR506112002KQ-SCONN288_DDR506112002KQ,SMA   I352 @T6G_MB_LIB.T6G(SCH_1):PAGE88
   J19   92  VSS40 SCONN288_DDR506112002KQ-SCONN288_DDR506112002KQ,SMA   I352 @T6G_MB_LIB.T6G(SCH_1):PAGE88
   J19   95  VSS41 SCONN288_DDR506112002KQ-SCONN288_DDR506112002KQ,SMA   I352 @T6G_MB_LIB.T6G(SCH_1):PAGE88
   J19   97  VSS42 SCONN288_DDR506112002KQ-SCONN288_DDR506112002KQ,SMA   I352 @T6G_MB_LIB.T6G(SCH_1):PAGE88
   J19   99  VSS43 SCONN288_DDR506112002KQ-SCONN288_DDR506112002KQ,SMA   I352 @T6G_MB_LIB.T6G(SCH_1):PAGE88
   J19  101  VSS44 SCONN288_DDR506112002KQ-SCONN288_DDR506112002KQ,SMA   I352 @T6G_MB_LIB.T6G(SCH_1):PAGE88
   J19  103  VSS45 SCONN288_DDR506112002KQ-SCONN288_DDR506112002KQ,SMA   I352 @T6G_MB_LIB.T6G(SCH_1):PAGE88
   J19  106  VSS46 SCONN288_DDR506112002KQ-SCONN288_DDR506112002KQ,SMA   I352 @T6G_MB_LIB.T6G(SCH_1):PAGE88
   J19  108  VSS47 SCONN288_DDR506112002KQ-SCONN288_DDR506112002KQ,SMA   I352 @T6G_MB_LIB.T6G(SCH_1):PAGE88
   J19  110  VSS48 SCONN288_DDR506112002KQ-SCONN288_DDR506112002KQ,SMA   I352 @T6G_MB_LIB.T6G(SCH_1):PAGE88
   J19  112  VSS49 SCONN288_DDR506112002KQ-SCONN288_DDR506112002KQ,SMA   I352 @T6G_MB_LIB.T6G(SCH_1):PAGE88
   J19  114  VSS50 SCONN288_DDR506112002KQ-SCONN288_DDR506112002KQ,SMA   I352 @T6G_MB_LIB.T6G(SCH_1):PAGE88
   J19  117  VSS51 SCONN288_DDR506112002KQ-SCONN288_DDR506112002KQ,SMA   I352 @T6G_MB_LIB.T6G(SCH_1):PAGE88
   J19  119  VSS52 SCONN288_DDR506112002KQ-SCONN288_DDR506112002KQ,SMA   I352 @T6G_MB_LIB.T6G(SCH_1):PAGE88
   J19  121  VSS53 SCONN288_DDR506112002KQ-SCONN288_DDR506112002KQ,SMA   I352 @T6G_MB_LIB.T6G(SCH_1):PAGE88
   J19  123  VSS54 SCONN288_DDR506112002KQ-SCONN288_DDR506112002KQ,SMA   I352 @T6G_MB_LIB.T6G(SCH_1):PAGE88
   J19  125  VSS55 SCONN288_DDR506112002KQ-SCONN288_DDR506112002KQ,SMA   I352 @T6G_MB_LIB.T6G(SCH_1):PAGE88
   J19  128  VSS56 SCONN288_DDR506112002KQ-SCONN288_DDR506112002KQ,SMA   I352 @T6G_MB_LIB.T6G(SCH_1):PAGE88
   J19  130  VSS57 SCONN288_DDR506112002KQ-SCONN288_DDR506112002KQ,SMA   I352 @T6G_MB_LIB.T6G(SCH_1):PAGE88
   J19  132  VSS58 SCONN288_DDR506112002KQ-SCONN288_DDR506112002KQ,SMA   I352 @T6G_MB_LIB.T6G(SCH_1):PAGE88
   J19  134  VSS59 SCONN288_DDR506112002KQ-SCONN288_DDR506112002KQ,SMA   I352 @T6G_MB_LIB.T6G(SCH_1):PAGE88
   J19  136  VSS60 SCONN288_DDR506112002KQ-SCONN288_DDR506112002KQ,SMA   I352 @T6G_MB_LIB.T6G(SCH_1):PAGE88
   J19  139  VSS61 SCONN288_DDR506112002KQ-SCONN288_DDR506112002KQ,SMA   I352 @T6G_MB_LIB.T6G(SCH_1):PAGE88
   J19  141  VSS62 SCONN288_DDR506112002KQ-SCONN288_DDR506112002KQ,SMA   I352 @T6G_MB_LIB.T6G(SCH_1):PAGE88
   J19  143  VSS63 SCONN288_DDR506112002KQ-SCONN288_DDR506112002KQ,SMA   I352 @T6G_MB_LIB.T6G(SCH_1):PAGE88
   J19  151  VSS64 SCONN288_DDR506112002KQ-SCONN288_DDR506112002KQ,SMA   I352 @T6G_MB_LIB.T6G(SCH_1):PAGE88
   J19  153  VSS65 SCONN288_DDR506112002KQ-SCONN288_DDR506112002KQ,SMA   I352 @T6G_MB_LIB.T6G(SCH_1):PAGE88
   J19  155  VSS66 SCONN288_DDR506112002KQ-SCONN288_DDR506112002KQ,SMA   I352 @T6G_MB_LIB.T6G(SCH_1):PAGE88
   J19  158  VSS67 SCONN288_DDR506112002KQ-SCONN288_DDR506112002KQ,SMA   I352 @T6G_MB_LIB.T6G(SCH_1):PAGE88
   J19  160  VSS68 SCONN288_DDR506112002KQ-SCONN288_DDR506112002KQ,SMA   I352 @T6G_MB_LIB.T6G(SCH_1):PAGE88
   J19  162  VSS69 SCONN288_DDR506112002KQ-SCONN288_DDR506112002KQ,SMA   I352 @T6G_MB_LIB.T6G(SCH_1):PAGE88
   J19  164  VSS70 SCONN288_DDR506112002KQ-SCONN288_DDR506112002KQ,SMA   I352 @T6G_MB_LIB.T6G(SCH_1):PAGE88
   J19  166  VSS71 SCONN288_DDR506112002KQ-SCONN288_DDR506112002KQ,SMA   I352 @T6G_MB_LIB.T6G(SCH_1):PAGE88
   J19  169  VSS72 SCONN288_DDR506112002KQ-SCONN288_DDR506112002KQ,SMA   I352 @T6G_MB_LIB.T6G(SCH_1):PAGE88
   J19  171  VSS73 SCONN288_DDR506112002KQ-SCONN288_DDR506112002KQ,SMA   I352 @T6G_MB_LIB.T6G(SCH_1):PAGE88
   J19  173  VSS74 SCONN288_DDR506112002KQ-SCONN288_DDR506112002KQ,SMA   I352 @T6G_MB_LIB.T6G(SCH_1):PAGE88
   J19  175  VSS75 SCONN288_DDR506112002KQ-SCONN288_DDR506112002KQ,SMA   I352 @T6G_MB_LIB.T6G(SCH_1):PAGE88
   J19  177  VSS76 SCONN288_DDR506112002KQ-SCONN288_DDR506112002KQ,SMA   I352 @T6G_MB_LIB.T6G(SCH_1):PAGE88
   J19  180  VSS77 SCONN288_DDR506112002KQ-SCONN288_DDR506112002KQ,SMA   I352 @T6G_MB_LIB.T6G(SCH_1):PAGE88
   J19  182  VSS78 SCONN288_DDR506112002KQ-SCONN288_DDR506112002KQ,SMA   I352 @T6G_MB_LIB.T6G(SCH_1):PAGE88
   J19  184  VSS79 SCONN288_DDR506112002KQ-SCONN288_DDR506112002KQ,SMA   I352 @T6G_MB_LIB.T6G(SCH_1):PAGE88
   J19  186  VSS80 SCONN288_DDR506112002KQ-SCONN288_DDR506112002KQ,SMA   I352 @T6G_MB_LIB.T6G(SCH_1):PAGE88
   J19  188  VSS81 SCONN288_DDR506112002KQ-SCONN288_DDR506112002KQ,SMA   I352 @T6G_MB_LIB.T6G(SCH_1):PAGE88
   J19  191  VSS82 SCONN288_DDR506112002KQ-SCONN288_DDR506112002KQ,SMA   I352 @T6G_MB_LIB.T6G(SCH_1):PAGE88
   J19  193  VSS83 SCONN288_DDR506112002KQ-SCONN288_DDR506112002KQ,SMA   I352 @T6G_MB_LIB.T6G(SCH_1):PAGE88
   J19  195  VSS84 SCONN288_DDR506112002KQ-SCONN288_DDR506112002KQ,SMA   I352 @T6G_MB_LIB.T6G(SCH_1):PAGE88
   J19  197  VSS85 SCONN288_DDR506112002KQ-SCONN288_DDR506112002KQ,SMA   I352 @T6G_MB_LIB.T6G(SCH_1):PAGE88
   J19  199  VSS86 SCONN288_DDR506112002KQ-SCONN288_DDR506112002KQ,SMA   I352 @T6G_MB_LIB.T6G(SCH_1):PAGE88
   J19  202  VSS87 SCONN288_DDR506112002KQ-SCONN288_DDR506112002KQ,SMA   I352 @T6G_MB_LIB.T6G(SCH_1):PAGE88
   J19  204  VSS88 SCONN288_DDR506112002KQ-SCONN288_DDR506112002KQ,SMA   I352 @T6G_MB_LIB.T6G(SCH_1):PAGE88
   J19  206  VSS89 SCONN288_DDR506112002KQ-SCONN288_DDR506112002KQ,SMA   I352 @T6G_MB_LIB.T6G(SCH_1):PAGE88
   J19  208  VSS90 SCONN288_DDR506112002KQ-SCONN288_DDR506112002KQ,SMA   I352 @T6G_MB_LIB.T6G(SCH_1):PAGE88
   J19  210  VSS91 SCONN288_DDR506112002KQ-SCONN288_DDR506112002KQ,SMA   I352 @T6G_MB_LIB.T6G(SCH_1):PAGE88
   J19  212  VSS92 SCONN288_DDR506112002KQ-SCONN288_DDR506112002KQ,SMA   I352 @T6G_MB_LIB.T6G(SCH_1):PAGE88
   J19  214  VSS93 SCONN288_DDR506112002KQ-SCONN288_DDR506112002KQ,SMA   I352 @T6G_MB_LIB.T6G(SCH_1):PAGE88
   J19  216  VSS94 SCONN288_DDR506112002KQ-SCONN288_DDR506112002KQ,SMA   I352 @T6G_MB_LIB.T6G(SCH_1):PAGE88
   J19  219  VSS95 SCONN288_DDR506112002KQ-SCONN288_DDR506112002KQ,SMA   I352 @T6G_MB_LIB.T6G(SCH_1):PAGE88
   J19  222  VSS96 SCONN288_DDR506112002KQ-SCONN288_DDR506112002KQ,SMA   I352 @T6G_MB_LIB.T6G(SCH_1):PAGE88
   J19  224  VSS97 SCONN288_DDR506112002KQ-SCONN288_DDR506112002KQ,SMA   I352 @T6G_MB_LIB.T6G(SCH_1):PAGE88
   J19  226  VSS98 SCONN288_DDR506112002KQ-SCONN288_DDR506112002KQ,SMA   I352 @T6G_MB_LIB.T6G(SCH_1):PAGE88
   J19  228  VSS99 SCONN288_DDR506112002KQ-SCONN288_DDR506112002KQ,SMA   I352 @T6G_MB_LIB.T6G(SCH_1):PAGE88
   J19  230 VSS100 SCONN288_DDR506112002KQ-SCONN288_DDR506112002KQ,SMA   I352 @T6G_MB_LIB.T6G(SCH_1):PAGE88
   J19  233 VSS101 SCONN288_DDR506112002KQ-SCONN288_DDR506112002KQ,SMA   I352 @T6G_MB_LIB.T6G(SCH_1):PAGE88
   J19  235 VSS102 SCONN288_DDR506112002KQ-SCONN288_DDR506112002KQ,SMA   I352 @T6G_MB_LIB.T6G(SCH_1):PAGE88
   J19  237 VSS103 SCONN288_DDR506112002KQ-SCONN288_DDR506112002KQ,SMA   I352 @T6G_MB_LIB.T6G(SCH_1):PAGE88
   J19  240 VSS104 SCONN288_DDR506112002KQ-SCONN288_DDR506112002KQ,SMA   I352 @T6G_MB_LIB.T6G(SCH_1):PAGE88
   J19  242 VSS105 SCONN288_DDR506112002KQ-SCONN288_DDR506112002KQ,SMA   I352 @T6G_MB_LIB.T6G(SCH_1):PAGE88
   J19  244 VSS106 SCONN288_DDR506112002KQ-SCONN288_DDR506112002KQ,SMA   I352 @T6G_MB_LIB.T6G(SCH_1):PAGE88
   J19  246 VSS107 SCONN288_DDR506112002KQ-SCONN288_DDR506112002KQ,SMA   I352 @T6G_MB_LIB.T6G(SCH_1):PAGE88
   J19  248 VSS108 SCONN288_DDR506112002KQ-SCONN288_DDR506112002KQ,SMA   I352 @T6G_MB_LIB.T6G(SCH_1):PAGE88
   J19  251 VSS109 SCONN288_DDR506112002KQ-SCONN288_DDR506112002KQ,SMA   I352 @T6G_MB_LIB.T6G(SCH_1):PAGE88
   J19  253 VSS110 SCONN288_DDR506112002KQ-SCONN288_DDR506112002KQ,SMA   I352 @T6G_MB_LIB.T6G(SCH_1):PAGE88
   J19  255 VSS111 SCONN288_DDR506112002KQ-SCONN288_DDR506112002KQ,SMA   I352 @T6G_MB_LIB.T6G(SCH_1):PAGE88
   J19  257 VSS112 SCONN288_DDR506112002KQ-SCONN288_DDR506112002KQ,SMA   I352 @T6G_MB_LIB.T6G(SCH_1):PAGE88
   J19  259 VSS113 SCONN288_DDR506112002KQ-SCONN288_DDR506112002KQ,SMA   I352 @T6G_MB_LIB.T6G(SCH_1):PAGE88
   J19  262 VSS114 SCONN288_DDR506112002KQ-SCONN288_DDR506112002KQ,SMA   I352 @T6G_MB_LIB.T6G(SCH_1):PAGE88
   J19  264 VSS115 SCONN288_DDR506112002KQ-SCONN288_DDR506112002KQ,SMA   I352 @T6G_MB_LIB.T6G(SCH_1):PAGE88
   J19  266 VSS116 SCONN288_DDR506112002KQ-SCONN288_DDR506112002KQ,SMA   I352 @T6G_MB_LIB.T6G(SCH_1):PAGE88
   J19  268 VSS117 SCONN288_DDR506112002KQ-SCONN288_DDR506112002KQ,SMA   I352 @T6G_MB_LIB.T6G(SCH_1):PAGE88
   J19  270 VSS118 SCONN288_DDR506112002KQ-SCONN288_DDR506112002KQ,SMA   I352 @T6G_MB_LIB.T6G(SCH_1):PAGE88
   J19  273 VSS119 SCONN288_DDR506112002KQ-SCONN288_DDR506112002KQ,SMA   I352 @T6G_MB_LIB.T6G(SCH_1):PAGE88
   J19  275 VSS120 SCONN288_DDR506112002KQ-SCONN288_DDR506112002KQ,SMA   I352 @T6G_MB_LIB.T6G(SCH_1):PAGE88
   J19  277 VSS121 SCONN288_DDR506112002KQ-SCONN288_DDR506112002KQ,SMA   I352 @T6G_MB_LIB.T6G(SCH_1):PAGE88
   J19  279 VSS122 SCONN288_DDR506112002KQ-SCONN288_DDR506112002KQ,SMA   I352 @T6G_MB_LIB.T6G(SCH_1):PAGE88
   J19  281 VSS123 SCONN288_DDR506112002KQ-SCONN288_DDR506112002KQ,SMA   I352 @T6G_MB_LIB.T6G(SCH_1):PAGE88
   J19  284 VSS124 SCONN288_DDR506112002KQ-SCONN288_DDR506112002KQ,SMA   I352 @T6G_MB_LIB.T6G(SCH_1):PAGE88
   J19  286 VSS125 SCONN288_DDR506112002KQ-SCONN288_DDR506112002KQ,SMA   I352 @T6G_MB_LIB.T6G(SCH_1):PAGE88
   J19  288 VSS126 SCONN288_DDR506112002KQ-SCONN288_DDR506112002KQ,SMA   I352 @T6G_MB_LIB.T6G(SCH_1):PAGE88
  C100    2      B Q_CAP_0402-0.1UF,25V,10%,X7R,CH4104K1B00   I362 @T6G_MB_LIB.T6G(SCH_1):PAGE88
  C149    2      B Q_CAP_C0805-10UF,25V,10%,X6S,CH6104KEA00   I417 @T6G_MB_LIB.T6G(SCH_1):PAGE88
  C150    2      B Q_CAP_C0805-10UF,25V,10%,X6S,CH6104KEA00   I418 @T6G_MB_LIB.T6G(SCH_1):PAGE88
    R5    2      B Q_RES_0402LF-54.9K,1%,1/16W,CHIP,CS35492FB03   I331 @T6G_MB_LIB.T6G(SCH_1):PAGE89
   J21   G1     G1 SCONN288_DDR506112002KQ-SCONN288_DDR506112002KQ,SMA   I350 @T6G_MB_LIB.T6G(SCH_1):PAGE89
   J21   G2     G2 SCONN288_DDR506112002KQ-SCONN288_DDR506112002KQ,SMA   I350 @T6G_MB_LIB.T6G(SCH_1):PAGE89
   J21   G3     G3 SCONN288_DDR506112002KQ-SCONN288_DDR506112002KQ,SMA   I350 @T6G_MB_LIB.T6G(SCH_1):PAGE89
   J21    6   VSS0 SCONN288_DDR506112002KQ-SCONN288_DDR506112002KQ,SMA   I350 @T6G_MB_LIB.T6G(SCH_1):PAGE89
   J21    8   VSS1 SCONN288_DDR506112002KQ-SCONN288_DDR506112002KQ,SMA   I350 @T6G_MB_LIB.T6G(SCH_1):PAGE89
   J21   10   VSS2 SCONN288_DDR506112002KQ-SCONN288_DDR506112002KQ,SMA   I350 @T6G_MB_LIB.T6G(SCH_1):PAGE89
   J21   13   VSS3 SCONN288_DDR506112002KQ-SCONN288_DDR506112002KQ,SMA   I350 @T6G_MB_LIB.T6G(SCH_1):PAGE89
   J21   15   VSS4 SCONN288_DDR506112002KQ-SCONN288_DDR506112002KQ,SMA   I350 @T6G_MB_LIB.T6G(SCH_1):PAGE89
   J21   17   VSS5 SCONN288_DDR506112002KQ-SCONN288_DDR506112002KQ,SMA   I350 @T6G_MB_LIB.T6G(SCH_1):PAGE89
   J21   19   VSS6 SCONN288_DDR506112002KQ-SCONN288_DDR506112002KQ,SMA   I350 @T6G_MB_LIB.T6G(SCH_1):PAGE89
   J21   21   VSS7 SCONN288_DDR506112002KQ-SCONN288_DDR506112002KQ,SMA   I350 @T6G_MB_LIB.T6G(SCH_1):PAGE89
   J21   24   VSS8 SCONN288_DDR506112002KQ-SCONN288_DDR506112002KQ,SMA   I350 @T6G_MB_LIB.T6G(SCH_1):PAGE89
   J21   26   VSS9 SCONN288_DDR506112002KQ-SCONN288_DDR506112002KQ,SMA   I350 @T6G_MB_LIB.T6G(SCH_1):PAGE89
   J21   28  VSS10 SCONN288_DDR506112002KQ-SCONN288_DDR506112002KQ,SMA   I350 @T6G_MB_LIB.T6G(SCH_1):PAGE89
   J21   30  VSS11 SCONN288_DDR506112002KQ-SCONN288_DDR506112002KQ,SMA   I350 @T6G_MB_LIB.T6G(SCH_1):PAGE89
   J21   32  VSS12 SCONN288_DDR506112002KQ-SCONN288_DDR506112002KQ,SMA   I350 @T6G_MB_LIB.T6G(SCH_1):PAGE89
   J21   35  VSS13 SCONN288_DDR506112002KQ-SCONN288_DDR506112002KQ,SMA   I350 @T6G_MB_LIB.T6G(SCH_1):PAGE89
   J21   37  VSS14 SCONN288_DDR506112002KQ-SCONN288_DDR506112002KQ,SMA   I350 @T6G_MB_LIB.T6G(SCH_1):PAGE89
   J21   39  VSS15 SCONN288_DDR506112002KQ-SCONN288_DDR506112002KQ,SMA   I350 @T6G_MB_LIB.T6G(SCH_1):PAGE89
   J21   41  VSS16 SCONN288_DDR506112002KQ-SCONN288_DDR506112002KQ,SMA   I350 @T6G_MB_LIB.T6G(SCH_1):PAGE89
   J21   43  VSS17 SCONN288_DDR506112002KQ-SCONN288_DDR506112002KQ,SMA   I350 @T6G_MB_LIB.T6G(SCH_1):PAGE89
   J21   46  VSS18 SCONN288_DDR506112002KQ-SCONN288_DDR506112002KQ,SMA   I350 @T6G_MB_LIB.T6G(SCH_1):PAGE89
   J21   48  VSS19 SCONN288_DDR506112002KQ-SCONN288_DDR506112002KQ,SMA   I350 @T6G_MB_LIB.T6G(SCH_1):PAGE89
   J21   50  VSS20 SCONN288_DDR506112002KQ-SCONN288_DDR506112002KQ,SMA   I350 @T6G_MB_LIB.T6G(SCH_1):PAGE89
   J21   52  VSS21 SCONN288_DDR506112002KQ-SCONN288_DDR506112002KQ,SMA   I350 @T6G_MB_LIB.T6G(SCH_1):PAGE89
   J21   54  VSS22 SCONN288_DDR506112002KQ-SCONN288_DDR506112002KQ,SMA   I350 @T6G_MB_LIB.T6G(SCH_1):PAGE89
   J21   57  VSS23 SCONN288_DDR506112002KQ-SCONN288_DDR506112002KQ,SMA   I350 @T6G_MB_LIB.T6G(SCH_1):PAGE89
   J21   59  VSS24 SCONN288_DDR506112002KQ-SCONN288_DDR506112002KQ,SMA   I350 @T6G_MB_LIB.T6G(SCH_1):PAGE89
   J21   61  VSS25 SCONN288_DDR506112002KQ-SCONN288_DDR506112002KQ,SMA   I350 @T6G_MB_LIB.T6G(SCH_1):PAGE89
   J21   63  VSS26 SCONN288_DDR506112002KQ-SCONN288_DDR506112002KQ,SMA   I350 @T6G_MB_LIB.T6G(SCH_1):PAGE89
   J21   65  VSS27 SCONN288_DDR506112002KQ-SCONN288_DDR506112002KQ,SMA   I350 @T6G_MB_LIB.T6G(SCH_1):PAGE89
   J21   67  VSS28 SCONN288_DDR506112002KQ-SCONN288_DDR506112002KQ,SMA   I350 @T6G_MB_LIB.T6G(SCH_1):PAGE89
   J21   69  VSS29 SCONN288_DDR506112002KQ-SCONN288_DDR506112002KQ,SMA   I350 @T6G_MB_LIB.T6G(SCH_1):PAGE89
   J21   71  VSS30 SCONN288_DDR506112002KQ-SCONN288_DDR506112002KQ,SMA   I350 @T6G_MB_LIB.T6G(SCH_1):PAGE89
   J21   73  VSS31 SCONN288_DDR506112002KQ-SCONN288_DDR506112002KQ,SMA   I350 @T6G_MB_LIB.T6G(SCH_1):PAGE89
   J21   75  VSS32 SCONN288_DDR506112002KQ-SCONN288_DDR506112002KQ,SMA   I350 @T6G_MB_LIB.T6G(SCH_1):PAGE89
   J21   77  VSS33 SCONN288_DDR506112002KQ-SCONN288_DDR506112002KQ,SMA   I350 @T6G_MB_LIB.T6G(SCH_1):PAGE89
   J21   79  VSS34 SCONN288_DDR506112002KQ-SCONN288_DDR506112002KQ,SMA   I350 @T6G_MB_LIB.T6G(SCH_1):PAGE89
   J21   81  VSS35 SCONN288_DDR506112002KQ-SCONN288_DDR506112002KQ,SMA   I350 @T6G_MB_LIB.T6G(SCH_1):PAGE89
   J21   83  VSS36 SCONN288_DDR506112002KQ-SCONN288_DDR506112002KQ,SMA   I350 @T6G_MB_LIB.T6G(SCH_1):PAGE89
   J21   85  VSS37 SCONN288_DDR506112002KQ-SCONN288_DDR506112002KQ,SMA   I350 @T6G_MB_LIB.T6G(SCH_1):PAGE89
   J21   88  VSS38 SCONN288_DDR506112002KQ-SCONN288_DDR506112002KQ,SMA   I350 @T6G_MB_LIB.T6G(SCH_1):PAGE89
   J21   90  VSS39 SCONN288_DDR506112002KQ-SCONN288_DDR506112002KQ,SMA   I350 @T6G_MB_LIB.T6G(SCH_1):PAGE89
   J21   92  VSS40 SCONN288_DDR506112002KQ-SCONN288_DDR506112002KQ,SMA   I350 @T6G_MB_LIB.T6G(SCH_1):PAGE89
   J21   95  VSS41 SCONN288_DDR506112002KQ-SCONN288_DDR506112002KQ,SMA   I350 @T6G_MB_LIB.T6G(SCH_1):PAGE89
   J21   97  VSS42 SCONN288_DDR506112002KQ-SCONN288_DDR506112002KQ,SMA   I350 @T6G_MB_LIB.T6G(SCH_1):PAGE89
   J21   99  VSS43 SCONN288_DDR506112002KQ-SCONN288_DDR506112002KQ,SMA   I350 @T6G_MB_LIB.T6G(SCH_1):PAGE89
   J21  101  VSS44 SCONN288_DDR506112002KQ-SCONN288_DDR506112002KQ,SMA   I350 @T6G_MB_LIB.T6G(SCH_1):PAGE89
   J21  103  VSS45 SCONN288_DDR506112002KQ-SCONN288_DDR506112002KQ,SMA   I350 @T6G_MB_LIB.T6G(SCH_1):PAGE89
   J21  106  VSS46 SCONN288_DDR506112002KQ-SCONN288_DDR506112002KQ,SMA   I350 @T6G_MB_LIB.T6G(SCH_1):PAGE89
   J21  108  VSS47 SCONN288_DDR506112002KQ-SCONN288_DDR506112002KQ,SMA   I350 @T6G_MB_LIB.T6G(SCH_1):PAGE89
   J21  110  VSS48 SCONN288_DDR506112002KQ-SCONN288_DDR506112002KQ,SMA   I350 @T6G_MB_LIB.T6G(SCH_1):PAGE89
   J21  112  VSS49 SCONN288_DDR506112002KQ-SCONN288_DDR506112002KQ,SMA   I350 @T6G_MB_LIB.T6G(SCH_1):PAGE89
   J21  114  VSS50 SCONN288_DDR506112002KQ-SCONN288_DDR506112002KQ,SMA   I350 @T6G_MB_LIB.T6G(SCH_1):PAGE89
   J21  117  VSS51 SCONN288_DDR506112002KQ-SCONN288_DDR506112002KQ,SMA   I350 @T6G_MB_LIB.T6G(SCH_1):PAGE89
   J21  119  VSS52 SCONN288_DDR506112002KQ-SCONN288_DDR506112002KQ,SMA   I350 @T6G_MB_LIB.T6G(SCH_1):PAGE89
   J21  121  VSS53 SCONN288_DDR506112002KQ-SCONN288_DDR506112002KQ,SMA   I350 @T6G_MB_LIB.T6G(SCH_1):PAGE89
   J21  123  VSS54 SCONN288_DDR506112002KQ-SCONN288_DDR506112002KQ,SMA   I350 @T6G_MB_LIB.T6G(SCH_1):PAGE89
   J21  125  VSS55 SCONN288_DDR506112002KQ-SCONN288_DDR506112002KQ,SMA   I350 @T6G_MB_LIB.T6G(SCH_1):PAGE89
   J21  128  VSS56 SCONN288_DDR506112002KQ-SCONN288_DDR506112002KQ,SMA   I350 @T6G_MB_LIB.T6G(SCH_1):PAGE89
   J21  130  VSS57 SCONN288_DDR506112002KQ-SCONN288_DDR506112002KQ,SMA   I350 @T6G_MB_LIB.T6G(SCH_1):PAGE89
   J21  132  VSS58 SCONN288_DDR506112002KQ-SCONN288_DDR506112002KQ,SMA   I350 @T6G_MB_LIB.T6G(SCH_1):PAGE89
   J21  134  VSS59 SCONN288_DDR506112002KQ-SCONN288_DDR506112002KQ,SMA   I350 @T6G_MB_LIB.T6G(SCH_1):PAGE89
   J21  136  VSS60 SCONN288_DDR506112002KQ-SCONN288_DDR506112002KQ,SMA   I350 @T6G_MB_LIB.T6G(SCH_1):PAGE89
   J21  139  VSS61 SCONN288_DDR506112002KQ-SCONN288_DDR506112002KQ,SMA   I350 @T6G_MB_LIB.T6G(SCH_1):PAGE89
   J21  141  VSS62 SCONN288_DDR506112002KQ-SCONN288_DDR506112002KQ,SMA   I350 @T6G_MB_LIB.T6G(SCH_1):PAGE89
   J21  143  VSS63 SCONN288_DDR506112002KQ-SCONN288_DDR506112002KQ,SMA   I350 @T6G_MB_LIB.T6G(SCH_1):PAGE89
   J21  151  VSS64 SCONN288_DDR506112002KQ-SCONN288_DDR506112002KQ,SMA   I350 @T6G_MB_LIB.T6G(SCH_1):PAGE89
   J21  153  VSS65 SCONN288_DDR506112002KQ-SCONN288_DDR506112002KQ,SMA   I350 @T6G_MB_LIB.T6G(SCH_1):PAGE89
   J21  155  VSS66 SCONN288_DDR506112002KQ-SCONN288_DDR506112002KQ,SMA   I350 @T6G_MB_LIB.T6G(SCH_1):PAGE89
   J21  158  VSS67 SCONN288_DDR506112002KQ-SCONN288_DDR506112002KQ,SMA   I350 @T6G_MB_LIB.T6G(SCH_1):PAGE89
   J21  160  VSS68 SCONN288_DDR506112002KQ-SCONN288_DDR506112002KQ,SMA   I350 @T6G_MB_LIB.T6G(SCH_1):PAGE89
   J21  162  VSS69 SCONN288_DDR506112002KQ-SCONN288_DDR506112002KQ,SMA   I350 @T6G_MB_LIB.T6G(SCH_1):PAGE89
   J21  164  VSS70 SCONN288_DDR506112002KQ-SCONN288_DDR506112002KQ,SMA   I350 @T6G_MB_LIB.T6G(SCH_1):PAGE89
   J21  166  VSS71 SCONN288_DDR506112002KQ-SCONN288_DDR506112002KQ,SMA   I350 @T6G_MB_LIB.T6G(SCH_1):PAGE89
   J21  169  VSS72 SCONN288_DDR506112002KQ-SCONN288_DDR506112002KQ,SMA   I350 @T6G_MB_LIB.T6G(SCH_1):PAGE89
   J21  171  VSS73 SCONN288_DDR506112002KQ-SCONN288_DDR506112002KQ,SMA   I350 @T6G_MB_LIB.T6G(SCH_1):PAGE89
   J21  173  VSS74 SCONN288_DDR506112002KQ-SCONN288_DDR506112002KQ,SMA   I350 @T6G_MB_LIB.T6G(SCH_1):PAGE89
   J21  175  VSS75 SCONN288_DDR506112002KQ-SCONN288_DDR506112002KQ,SMA   I350 @T6G_MB_LIB.T6G(SCH_1):PAGE89
   J21  177  VSS76 SCONN288_DDR506112002KQ-SCONN288_DDR506112002KQ,SMA   I350 @T6G_MB_LIB.T6G(SCH_1):PAGE89
   J21  180  VSS77 SCONN288_DDR506112002KQ-SCONN288_DDR506112002KQ,SMA   I350 @T6G_MB_LIB.T6G(SCH_1):PAGE89
   J21  182  VSS78 SCONN288_DDR506112002KQ-SCONN288_DDR506112002KQ,SMA   I350 @T6G_MB_LIB.T6G(SCH_1):PAGE89
   J21  184  VSS79 SCONN288_DDR506112002KQ-SCONN288_DDR506112002KQ,SMA   I350 @T6G_MB_LIB.T6G(SCH_1):PAGE89
   J21  186  VSS80 SCONN288_DDR506112002KQ-SCONN288_DDR506112002KQ,SMA   I350 @T6G_MB_LIB.T6G(SCH_1):PAGE89
   J21  188  VSS81 SCONN288_DDR506112002KQ-SCONN288_DDR506112002KQ,SMA   I350 @T6G_MB_LIB.T6G(SCH_1):PAGE89
   J21  191  VSS82 SCONN288_DDR506112002KQ-SCONN288_DDR506112002KQ,SMA   I350 @T6G_MB_LIB.T6G(SCH_1):PAGE89
   J21  193  VSS83 SCONN288_DDR506112002KQ-SCONN288_DDR506112002KQ,SMA   I350 @T6G_MB_LIB.T6G(SCH_1):PAGE89
   J21  195  VSS84 SCONN288_DDR506112002KQ-SCONN288_DDR506112002KQ,SMA   I350 @T6G_MB_LIB.T6G(SCH_1):PAGE89
   J21  197  VSS85 SCONN288_DDR506112002KQ-SCONN288_DDR506112002KQ,SMA   I350 @T6G_MB_LIB.T6G(SCH_1):PAGE89
   J21  199  VSS86 SCONN288_DDR506112002KQ-SCONN288_DDR506112002KQ,SMA   I350 @T6G_MB_LIB.T6G(SCH_1):PAGE89
   J21  202  VSS87 SCONN288_DDR506112002KQ-SCONN288_DDR506112002KQ,SMA   I350 @T6G_MB_LIB.T6G(SCH_1):PAGE89
   J21  204  VSS88 SCONN288_DDR506112002KQ-SCONN288_DDR506112002KQ,SMA   I350 @T6G_MB_LIB.T6G(SCH_1):PAGE89
   J21  206  VSS89 SCONN288_DDR506112002KQ-SCONN288_DDR506112002KQ,SMA   I350 @T6G_MB_LIB.T6G(SCH_1):PAGE89
   J21  208  VSS90 SCONN288_DDR506112002KQ-SCONN288_DDR506112002KQ,SMA   I350 @T6G_MB_LIB.T6G(SCH_1):PAGE89
   J21  210  VSS91 SCONN288_DDR506112002KQ-SCONN288_DDR506112002KQ,SMA   I350 @T6G_MB_LIB.T6G(SCH_1):PAGE89
   J21  212  VSS92 SCONN288_DDR506112002KQ-SCONN288_DDR506112002KQ,SMA   I350 @T6G_MB_LIB.T6G(SCH_1):PAGE89
   J21  214  VSS93 SCONN288_DDR506112002KQ-SCONN288_DDR506112002KQ,SMA   I350 @T6G_MB_LIB.T6G(SCH_1):PAGE89
   J21  216  VSS94 SCONN288_DDR506112002KQ-SCONN288_DDR506112002KQ,SMA   I350 @T6G_MB_LIB.T6G(SCH_1):PAGE89
   J21  219  VSS95 SCONN288_DDR506112002KQ-SCONN288_DDR506112002KQ,SMA   I350 @T6G_MB_LIB.T6G(SCH_1):PAGE89
   J21  222  VSS96 SCONN288_DDR506112002KQ-SCONN288_DDR506112002KQ,SMA   I350 @T6G_MB_LIB.T6G(SCH_1):PAGE89
   J21  224  VSS97 SCONN288_DDR506112002KQ-SCONN288_DDR506112002KQ,SMA   I350 @T6G_MB_LIB.T6G(SCH_1):PAGE89
   J21  226  VSS98 SCONN288_DDR506112002KQ-SCONN288_DDR506112002KQ,SMA   I350 @T6G_MB_LIB.T6G(SCH_1):PAGE89
   J21  228  VSS99 SCONN288_DDR506112002KQ-SCONN288_DDR506112002KQ,SMA   I350 @T6G_MB_LIB.T6G(SCH_1):PAGE89
   J21  230 VSS100 SCONN288_DDR506112002KQ-SCONN288_DDR506112002KQ,SMA   I350 @T6G_MB_LIB.T6G(SCH_1):PAGE89
   J21  233 VSS101 SCONN288_DDR506112002KQ-SCONN288_DDR506112002KQ,SMA   I350 @T6G_MB_LIB.T6G(SCH_1):PAGE89
   J21  235 VSS102 SCONN288_DDR506112002KQ-SCONN288_DDR506112002KQ,SMA   I350 @T6G_MB_LIB.T6G(SCH_1):PAGE89
   J21  237 VSS103 SCONN288_DDR506112002KQ-SCONN288_DDR506112002KQ,SMA   I350 @T6G_MB_LIB.T6G(SCH_1):PAGE89
   J21  240 VSS104 SCONN288_DDR506112002KQ-SCONN288_DDR506112002KQ,SMA   I350 @T6G_MB_LIB.T6G(SCH_1):PAGE89
   J21  242 VSS105 SCONN288_DDR506112002KQ-SCONN288_DDR506112002KQ,SMA   I350 @T6G_MB_LIB.T6G(SCH_1):PAGE89
   J21  244 VSS106 SCONN288_DDR506112002KQ-SCONN288_DDR506112002KQ,SMA   I350 @T6G_MB_LIB.T6G(SCH_1):PAGE89
   J21  246 VSS107 SCONN288_DDR506112002KQ-SCONN288_DDR506112002KQ,SMA   I350 @T6G_MB_LIB.T6G(SCH_1):PAGE89
   J21  248 VSS108 SCONN288_DDR506112002KQ-SCONN288_DDR506112002KQ,SMA   I350 @T6G_MB_LIB.T6G(SCH_1):PAGE89
   J21  251 VSS109 SCONN288_DDR506112002KQ-SCONN288_DDR506112002KQ,SMA   I350 @T6G_MB_LIB.T6G(SCH_1):PAGE89
   J21  253 VSS110 SCONN288_DDR506112002KQ-SCONN288_DDR506112002KQ,SMA   I350 @T6G_MB_LIB.T6G(SCH_1):PAGE89
   J21  255 VSS111 SCONN288_DDR506112002KQ-SCONN288_DDR506112002KQ,SMA   I350 @T6G_MB_LIB.T6G(SCH_1):PAGE89
   J21  257 VSS112 SCONN288_DDR506112002KQ-SCONN288_DDR506112002KQ,SMA   I350 @T6G_MB_LIB.T6G(SCH_1):PAGE89
   J21  259 VSS113 SCONN288_DDR506112002KQ-SCONN288_DDR506112002KQ,SMA   I350 @T6G_MB_LIB.T6G(SCH_1):PAGE89
   J21  262 VSS114 SCONN288_DDR506112002KQ-SCONN288_DDR506112002KQ,SMA   I350 @T6G_MB_LIB.T6G(SCH_1):PAGE89
   J21  264 VSS115 SCONN288_DDR506112002KQ-SCONN288_DDR506112002KQ,SMA   I350 @T6G_MB_LIB.T6G(SCH_1):PAGE89
   J21  266 VSS116 SCONN288_DDR506112002KQ-SCONN288_DDR506112002KQ,SMA   I350 @T6G_MB_LIB.T6G(SCH_1):PAGE89
   J21  268 VSS117 SCONN288_DDR506112002KQ-SCONN288_DDR506112002KQ,SMA   I350 @T6G_MB_LIB.T6G(SCH_1):PAGE89
   J21  270 VSS118 SCONN288_DDR506112002KQ-SCONN288_DDR506112002KQ,SMA   I350 @T6G_MB_LIB.T6G(SCH_1):PAGE89
   J21  273 VSS119 SCONN288_DDR506112002KQ-SCONN288_DDR506112002KQ,SMA   I350 @T6G_MB_LIB.T6G(SCH_1):PAGE89
   J21  275 VSS120 SCONN288_DDR506112002KQ-SCONN288_DDR506112002KQ,SMA   I350 @T6G_MB_LIB.T6G(SCH_1):PAGE89
   J21  277 VSS121 SCONN288_DDR506112002KQ-SCONN288_DDR506112002KQ,SMA   I350 @T6G_MB_LIB.T6G(SCH_1):PAGE89
   J21  279 VSS122 SCONN288_DDR506112002KQ-SCONN288_DDR506112002KQ,SMA   I350 @T6G_MB_LIB.T6G(SCH_1):PAGE89
   J21  281 VSS123 SCONN288_DDR506112002KQ-SCONN288_DDR506112002KQ,SMA   I350 @T6G_MB_LIB.T6G(SCH_1):PAGE89
   J21  284 VSS124 SCONN288_DDR506112002KQ-SCONN288_DDR506112002KQ,SMA   I350 @T6G_MB_LIB.T6G(SCH_1):PAGE89
   J21  286 VSS125 SCONN288_DDR506112002KQ-SCONN288_DDR506112002KQ,SMA   I350 @T6G_MB_LIB.T6G(SCH_1):PAGE89
   J21  288 VSS126 SCONN288_DDR506112002KQ-SCONN288_DDR506112002KQ,SMA   I350 @T6G_MB_LIB.T6G(SCH_1):PAGE89
  C104    2      B Q_CAP_0402-0.1UF,25V,10%,X7R,CH4104K1B00   I360 @T6G_MB_LIB.T6G(SCH_1):PAGE89
  C151    2      B Q_CAP_C0805-10UF,25V,10%,X6S,CH6104KEA00   I412 @T6G_MB_LIB.T6G(SCH_1):PAGE89
  C153    2      B Q_CAP_C0805-10UF,25V,10%,X6S,CH6104KEA00   I413 @T6G_MB_LIB.T6G(SCH_1):PAGE89
  R764    2      B Q_RES_0402LF-84.5K,1%,1/16W,CHIP,CS38452FB05   I349 @T6G_MB_LIB.T6G(SCH_1):PAGE90
   J23   G1     G1 SCONN288_DDR506112002KQ-SCONN288_DDR506112002KQ,SMA   I352 @T6G_MB_LIB.T6G(SCH_1):PAGE90
   J23   G2     G2 SCONN288_DDR506112002KQ-SCONN288_DDR506112002KQ,SMA   I352 @T6G_MB_LIB.T6G(SCH_1):PAGE90
   J23   G3     G3 SCONN288_DDR506112002KQ-SCONN288_DDR506112002KQ,SMA   I352 @T6G_MB_LIB.T6G(SCH_1):PAGE90
   J23    6   VSS0 SCONN288_DDR506112002KQ-SCONN288_DDR506112002KQ,SMA   I352 @T6G_MB_LIB.T6G(SCH_1):PAGE90
   J23    8   VSS1 SCONN288_DDR506112002KQ-SCONN288_DDR506112002KQ,SMA   I352 @T6G_MB_LIB.T6G(SCH_1):PAGE90
   J23   10   VSS2 SCONN288_DDR506112002KQ-SCONN288_DDR506112002KQ,SMA   I352 @T6G_MB_LIB.T6G(SCH_1):PAGE90
   J23   13   VSS3 SCONN288_DDR506112002KQ-SCONN288_DDR506112002KQ,SMA   I352 @T6G_MB_LIB.T6G(SCH_1):PAGE90
   J23   15   VSS4 SCONN288_DDR506112002KQ-SCONN288_DDR506112002KQ,SMA   I352 @T6G_MB_LIB.T6G(SCH_1):PAGE90
   J23   17   VSS5 SCONN288_DDR506112002KQ-SCONN288_DDR506112002KQ,SMA   I352 @T6G_MB_LIB.T6G(SCH_1):PAGE90
   J23   19   VSS6 SCONN288_DDR506112002KQ-SCONN288_DDR506112002KQ,SMA   I352 @T6G_MB_LIB.T6G(SCH_1):PAGE90
   J23   21   VSS7 SCONN288_DDR506112002KQ-SCONN288_DDR506112002KQ,SMA   I352 @T6G_MB_LIB.T6G(SCH_1):PAGE90
   J23   24   VSS8 SCONN288_DDR506112002KQ-SCONN288_DDR506112002KQ,SMA   I352 @T6G_MB_LIB.T6G(SCH_1):PAGE90
   J23   26   VSS9 SCONN288_DDR506112002KQ-SCONN288_DDR506112002KQ,SMA   I352 @T6G_MB_LIB.T6G(SCH_1):PAGE90
   J23   28  VSS10 SCONN288_DDR506112002KQ-SCONN288_DDR506112002KQ,SMA   I352 @T6G_MB_LIB.T6G(SCH_1):PAGE90
   J23   30  VSS11 SCONN288_DDR506112002KQ-SCONN288_DDR506112002KQ,SMA   I352 @T6G_MB_LIB.T6G(SCH_1):PAGE90
   J23   32  VSS12 SCONN288_DDR506112002KQ-SCONN288_DDR506112002KQ,SMA   I352 @T6G_MB_LIB.T6G(SCH_1):PAGE90
   J23   35  VSS13 SCONN288_DDR506112002KQ-SCONN288_DDR506112002KQ,SMA   I352 @T6G_MB_LIB.T6G(SCH_1):PAGE90
   J23   37  VSS14 SCONN288_DDR506112002KQ-SCONN288_DDR506112002KQ,SMA   I352 @T6G_MB_LIB.T6G(SCH_1):PAGE90
   J23   39  VSS15 SCONN288_DDR506112002KQ-SCONN288_DDR506112002KQ,SMA   I352 @T6G_MB_LIB.T6G(SCH_1):PAGE90
   J23   41  VSS16 SCONN288_DDR506112002KQ-SCONN288_DDR506112002KQ,SMA   I352 @T6G_MB_LIB.T6G(SCH_1):PAGE90
   J23   43  VSS17 SCONN288_DDR506112002KQ-SCONN288_DDR506112002KQ,SMA   I352 @T6G_MB_LIB.T6G(SCH_1):PAGE90
   J23   46  VSS18 SCONN288_DDR506112002KQ-SCONN288_DDR506112002KQ,SMA   I352 @T6G_MB_LIB.T6G(SCH_1):PAGE90
   J23   48  VSS19 SCONN288_DDR506112002KQ-SCONN288_DDR506112002KQ,SMA   I352 @T6G_MB_LIB.T6G(SCH_1):PAGE90
   J23   50  VSS20 SCONN288_DDR506112002KQ-SCONN288_DDR506112002KQ,SMA   I352 @T6G_MB_LIB.T6G(SCH_1):PAGE90
   J23   52  VSS21 SCONN288_DDR506112002KQ-SCONN288_DDR506112002KQ,SMA   I352 @T6G_MB_LIB.T6G(SCH_1):PAGE90
   J23   54  VSS22 SCONN288_DDR506112002KQ-SCONN288_DDR506112002KQ,SMA   I352 @T6G_MB_LIB.T6G(SCH_1):PAGE90
   J23   57  VSS23 SCONN288_DDR506112002KQ-SCONN288_DDR506112002KQ,SMA   I352 @T6G_MB_LIB.T6G(SCH_1):PAGE90
   J23   59  VSS24 SCONN288_DDR506112002KQ-SCONN288_DDR506112002KQ,SMA   I352 @T6G_MB_LIB.T6G(SCH_1):PAGE90
   J23   61  VSS25 SCONN288_DDR506112002KQ-SCONN288_DDR506112002KQ,SMA   I352 @T6G_MB_LIB.T6G(SCH_1):PAGE90
   J23   63  VSS26 SCONN288_DDR506112002KQ-SCONN288_DDR506112002KQ,SMA   I352 @T6G_MB_LIB.T6G(SCH_1):PAGE90
   J23   65  VSS27 SCONN288_DDR506112002KQ-SCONN288_DDR506112002KQ,SMA   I352 @T6G_MB_LIB.T6G(SCH_1):PAGE90
   J23   67  VSS28 SCONN288_DDR506112002KQ-SCONN288_DDR506112002KQ,SMA   I352 @T6G_MB_LIB.T6G(SCH_1):PAGE90
   J23   69  VSS29 SCONN288_DDR506112002KQ-SCONN288_DDR506112002KQ,SMA   I352 @T6G_MB_LIB.T6G(SCH_1):PAGE90
   J23   71  VSS30 SCONN288_DDR506112002KQ-SCONN288_DDR506112002KQ,SMA   I352 @T6G_MB_LIB.T6G(SCH_1):PAGE90
   J23   73  VSS31 SCONN288_DDR506112002KQ-SCONN288_DDR506112002KQ,SMA   I352 @T6G_MB_LIB.T6G(SCH_1):PAGE90
   J23   75  VSS32 SCONN288_DDR506112002KQ-SCONN288_DDR506112002KQ,SMA   I352 @T6G_MB_LIB.T6G(SCH_1):PAGE90
   J23   77  VSS33 SCONN288_DDR506112002KQ-SCONN288_DDR506112002KQ,SMA   I352 @T6G_MB_LIB.T6G(SCH_1):PAGE90
   J23   79  VSS34 SCONN288_DDR506112002KQ-SCONN288_DDR506112002KQ,SMA   I352 @T6G_MB_LIB.T6G(SCH_1):PAGE90
   J23   81  VSS35 SCONN288_DDR506112002KQ-SCONN288_DDR506112002KQ,SMA   I352 @T6G_MB_LIB.T6G(SCH_1):PAGE90
   J23   83  VSS36 SCONN288_DDR506112002KQ-SCONN288_DDR506112002KQ,SMA   I352 @T6G_MB_LIB.T6G(SCH_1):PAGE90
   J23   85  VSS37 SCONN288_DDR506112002KQ-SCONN288_DDR506112002KQ,SMA   I352 @T6G_MB_LIB.T6G(SCH_1):PAGE90
   J23   88  VSS38 SCONN288_DDR506112002KQ-SCONN288_DDR506112002KQ,SMA   I352 @T6G_MB_LIB.T6G(SCH_1):PAGE90
   J23   90  VSS39 SCONN288_DDR506112002KQ-SCONN288_DDR506112002KQ,SMA   I352 @T6G_MB_LIB.T6G(SCH_1):PAGE90
   J23   92  VSS40 SCONN288_DDR506112002KQ-SCONN288_DDR506112002KQ,SMA   I352 @T6G_MB_LIB.T6G(SCH_1):PAGE90
   J23   95  VSS41 SCONN288_DDR506112002KQ-SCONN288_DDR506112002KQ,SMA   I352 @T6G_MB_LIB.T6G(SCH_1):PAGE90
   J23   97  VSS42 SCONN288_DDR506112002KQ-SCONN288_DDR506112002KQ,SMA   I352 @T6G_MB_LIB.T6G(SCH_1):PAGE90
   J23   99  VSS43 SCONN288_DDR506112002KQ-SCONN288_DDR506112002KQ,SMA   I352 @T6G_MB_LIB.T6G(SCH_1):PAGE90
   J23  101  VSS44 SCONN288_DDR506112002KQ-SCONN288_DDR506112002KQ,SMA   I352 @T6G_MB_LIB.T6G(SCH_1):PAGE90
   J23  103  VSS45 SCONN288_DDR506112002KQ-SCONN288_DDR506112002KQ,SMA   I352 @T6G_MB_LIB.T6G(SCH_1):PAGE90
   J23  106  VSS46 SCONN288_DDR506112002KQ-SCONN288_DDR506112002KQ,SMA   I352 @T6G_MB_LIB.T6G(SCH_1):PAGE90
   J23  108  VSS47 SCONN288_DDR506112002KQ-SCONN288_DDR506112002KQ,SMA   I352 @T6G_MB_LIB.T6G(SCH_1):PAGE90
   J23  110  VSS48 SCONN288_DDR506112002KQ-SCONN288_DDR506112002KQ,SMA   I352 @T6G_MB_LIB.T6G(SCH_1):PAGE90
   J23  112  VSS49 SCONN288_DDR506112002KQ-SCONN288_DDR506112002KQ,SMA   I352 @T6G_MB_LIB.T6G(SCH_1):PAGE90
   J23  114  VSS50 SCONN288_DDR506112002KQ-SCONN288_DDR506112002KQ,SMA   I352 @T6G_MB_LIB.T6G(SCH_1):PAGE90
   J23  117  VSS51 SCONN288_DDR506112002KQ-SCONN288_DDR506112002KQ,SMA   I352 @T6G_MB_LIB.T6G(SCH_1):PAGE90
   J23  119  VSS52 SCONN288_DDR506112002KQ-SCONN288_DDR506112002KQ,SMA   I352 @T6G_MB_LIB.T6G(SCH_1):PAGE90
   J23  121  VSS53 SCONN288_DDR506112002KQ-SCONN288_DDR506112002KQ,SMA   I352 @T6G_MB_LIB.T6G(SCH_1):PAGE90
   J23  123  VSS54 SCONN288_DDR506112002KQ-SCONN288_DDR506112002KQ,SMA   I352 @T6G_MB_LIB.T6G(SCH_1):PAGE90
   J23  125  VSS55 SCONN288_DDR506112002KQ-SCONN288_DDR506112002KQ,SMA   I352 @T6G_MB_LIB.T6G(SCH_1):PAGE90
   J23  128  VSS56 SCONN288_DDR506112002KQ-SCONN288_DDR506112002KQ,SMA   I352 @T6G_MB_LIB.T6G(SCH_1):PAGE90
   J23  130  VSS57 SCONN288_DDR506112002KQ-SCONN288_DDR506112002KQ,SMA   I352 @T6G_MB_LIB.T6G(SCH_1):PAGE90
   J23  132  VSS58 SCONN288_DDR506112002KQ-SCONN288_DDR506112002KQ,SMA   I352 @T6G_MB_LIB.T6G(SCH_1):PAGE90
   J23  134  VSS59 SCONN288_DDR506112002KQ-SCONN288_DDR506112002KQ,SMA   I352 @T6G_MB_LIB.T6G(SCH_1):PAGE90
   J23  136  VSS60 SCONN288_DDR506112002KQ-SCONN288_DDR506112002KQ,SMA   I352 @T6G_MB_LIB.T6G(SCH_1):PAGE90
   J23  139  VSS61 SCONN288_DDR506112002KQ-SCONN288_DDR506112002KQ,SMA   I352 @T6G_MB_LIB.T6G(SCH_1):PAGE90
   J23  141  VSS62 SCONN288_DDR506112002KQ-SCONN288_DDR506112002KQ,SMA   I352 @T6G_MB_LIB.T6G(SCH_1):PAGE90
   J23  143  VSS63 SCONN288_DDR506112002KQ-SCONN288_DDR506112002KQ,SMA   I352 @T6G_MB_LIB.T6G(SCH_1):PAGE90
   J23  151  VSS64 SCONN288_DDR506112002KQ-SCONN288_DDR506112002KQ,SMA   I352 @T6G_MB_LIB.T6G(SCH_1):PAGE90
   J23  153  VSS65 SCONN288_DDR506112002KQ-SCONN288_DDR506112002KQ,SMA   I352 @T6G_MB_LIB.T6G(SCH_1):PAGE90
   J23  155  VSS66 SCONN288_DDR506112002KQ-SCONN288_DDR506112002KQ,SMA   I352 @T6G_MB_LIB.T6G(SCH_1):PAGE90
   J23  158  VSS67 SCONN288_DDR506112002KQ-SCONN288_DDR506112002KQ,SMA   I352 @T6G_MB_LIB.T6G(SCH_1):PAGE90
   J23  160  VSS68 SCONN288_DDR506112002KQ-SCONN288_DDR506112002KQ,SMA   I352 @T6G_MB_LIB.T6G(SCH_1):PAGE90
   J23  162  VSS69 SCONN288_DDR506112002KQ-SCONN288_DDR506112002KQ,SMA   I352 @T6G_MB_LIB.T6G(SCH_1):PAGE90
   J23  164  VSS70 SCONN288_DDR506112002KQ-SCONN288_DDR506112002KQ,SMA   I352 @T6G_MB_LIB.T6G(SCH_1):PAGE90
   J23  166  VSS71 SCONN288_DDR506112002KQ-SCONN288_DDR506112002KQ,SMA   I352 @T6G_MB_LIB.T6G(SCH_1):PAGE90
   J23  169  VSS72 SCONN288_DDR506112002KQ-SCONN288_DDR506112002KQ,SMA   I352 @T6G_MB_LIB.T6G(SCH_1):PAGE90
   J23  171  VSS73 SCONN288_DDR506112002KQ-SCONN288_DDR506112002KQ,SMA   I352 @T6G_MB_LIB.T6G(SCH_1):PAGE90
   J23  173  VSS74 SCONN288_DDR506112002KQ-SCONN288_DDR506112002KQ,SMA   I352 @T6G_MB_LIB.T6G(SCH_1):PAGE90
   J23  175  VSS75 SCONN288_DDR506112002KQ-SCONN288_DDR506112002KQ,SMA   I352 @T6G_MB_LIB.T6G(SCH_1):PAGE90
   J23  177  VSS76 SCONN288_DDR506112002KQ-SCONN288_DDR506112002KQ,SMA   I352 @T6G_MB_LIB.T6G(SCH_1):PAGE90
   J23  180  VSS77 SCONN288_DDR506112002KQ-SCONN288_DDR506112002KQ,SMA   I352 @T6G_MB_LIB.T6G(SCH_1):PAGE90
   J23  182  VSS78 SCONN288_DDR506112002KQ-SCONN288_DDR506112002KQ,SMA   I352 @T6G_MB_LIB.T6G(SCH_1):PAGE90
   J23  184  VSS79 SCONN288_DDR506112002KQ-SCONN288_DDR506112002KQ,SMA   I352 @T6G_MB_LIB.T6G(SCH_1):PAGE90
   J23  186  VSS80 SCONN288_DDR506112002KQ-SCONN288_DDR506112002KQ,SMA   I352 @T6G_MB_LIB.T6G(SCH_1):PAGE90
   J23  188  VSS81 SCONN288_DDR506112002KQ-SCONN288_DDR506112002KQ,SMA   I352 @T6G_MB_LIB.T6G(SCH_1):PAGE90
   J23  191  VSS82 SCONN288_DDR506112002KQ-SCONN288_DDR506112002KQ,SMA   I352 @T6G_MB_LIB.T6G(SCH_1):PAGE90
   J23  193  VSS83 SCONN288_DDR506112002KQ-SCONN288_DDR506112002KQ,SMA   I352 @T6G_MB_LIB.T6G(SCH_1):PAGE90
   J23  195  VSS84 SCONN288_DDR506112002KQ-SCONN288_DDR506112002KQ,SMA   I352 @T6G_MB_LIB.T6G(SCH_1):PAGE90
   J23  197  VSS85 SCONN288_DDR506112002KQ-SCONN288_DDR506112002KQ,SMA   I352 @T6G_MB_LIB.T6G(SCH_1):PAGE90
   J23  199  VSS86 SCONN288_DDR506112002KQ-SCONN288_DDR506112002KQ,SMA   I352 @T6G_MB_LIB.T6G(SCH_1):PAGE90
   J23  202  VSS87 SCONN288_DDR506112002KQ-SCONN288_DDR506112002KQ,SMA   I352 @T6G_MB_LIB.T6G(SCH_1):PAGE90
   J23  204  VSS88 SCONN288_DDR506112002KQ-SCONN288_DDR506112002KQ,SMA   I352 @T6G_MB_LIB.T6G(SCH_1):PAGE90
   J23  206  VSS89 SCONN288_DDR506112002KQ-SCONN288_DDR506112002KQ,SMA   I352 @T6G_MB_LIB.T6G(SCH_1):PAGE90
   J23  208  VSS90 SCONN288_DDR506112002KQ-SCONN288_DDR506112002KQ,SMA   I352 @T6G_MB_LIB.T6G(SCH_1):PAGE90
   J23  210  VSS91 SCONN288_DDR506112002KQ-SCONN288_DDR506112002KQ,SMA   I352 @T6G_MB_LIB.T6G(SCH_1):PAGE90
   J23  212  VSS92 SCONN288_DDR506112002KQ-SCONN288_DDR506112002KQ,SMA   I352 @T6G_MB_LIB.T6G(SCH_1):PAGE90
   J23  214  VSS93 SCONN288_DDR506112002KQ-SCONN288_DDR506112002KQ,SMA   I352 @T6G_MB_LIB.T6G(SCH_1):PAGE90
   J23  216  VSS94 SCONN288_DDR506112002KQ-SCONN288_DDR506112002KQ,SMA   I352 @T6G_MB_LIB.T6G(SCH_1):PAGE90
   J23  219  VSS95 SCONN288_DDR506112002KQ-SCONN288_DDR506112002KQ,SMA   I352 @T6G_MB_LIB.T6G(SCH_1):PAGE90
   J23  222  VSS96 SCONN288_DDR506112002KQ-SCONN288_DDR506112002KQ,SMA   I352 @T6G_MB_LIB.T6G(SCH_1):PAGE90
   J23  224  VSS97 SCONN288_DDR506112002KQ-SCONN288_DDR506112002KQ,SMA   I352 @T6G_MB_LIB.T6G(SCH_1):PAGE90
   J23  226  VSS98 SCONN288_DDR506112002KQ-SCONN288_DDR506112002KQ,SMA   I352 @T6G_MB_LIB.T6G(SCH_1):PAGE90
   J23  228  VSS99 SCONN288_DDR506112002KQ-SCONN288_DDR506112002KQ,SMA   I352 @T6G_MB_LIB.T6G(SCH_1):PAGE90
   J23  230 VSS100 SCONN288_DDR506112002KQ-SCONN288_DDR506112002KQ,SMA   I352 @T6G_MB_LIB.T6G(SCH_1):PAGE90
   J23  233 VSS101 SCONN288_DDR506112002KQ-SCONN288_DDR506112002KQ,SMA   I352 @T6G_MB_LIB.T6G(SCH_1):PAGE90
   J23  235 VSS102 SCONN288_DDR506112002KQ-SCONN288_DDR506112002KQ,SMA   I352 @T6G_MB_LIB.T6G(SCH_1):PAGE90
   J23  237 VSS103 SCONN288_DDR506112002KQ-SCONN288_DDR506112002KQ,SMA   I352 @T6G_MB_LIB.T6G(SCH_1):PAGE90
   J23  240 VSS104 SCONN288_DDR506112002KQ-SCONN288_DDR506112002KQ,SMA   I352 @T6G_MB_LIB.T6G(SCH_1):PAGE90
   J23  242 VSS105 SCONN288_DDR506112002KQ-SCONN288_DDR506112002KQ,SMA   I352 @T6G_MB_LIB.T6G(SCH_1):PAGE90
   J23  244 VSS106 SCONN288_DDR506112002KQ-SCONN288_DDR506112002KQ,SMA   I352 @T6G_MB_LIB.T6G(SCH_1):PAGE90
   J23  246 VSS107 SCONN288_DDR506112002KQ-SCONN288_DDR506112002KQ,SMA   I352 @T6G_MB_LIB.T6G(SCH_1):PAGE90
   J23  248 VSS108 SCONN288_DDR506112002KQ-SCONN288_DDR506112002KQ,SMA   I352 @T6G_MB_LIB.T6G(SCH_1):PAGE90
   J23  251 VSS109 SCONN288_DDR506112002KQ-SCONN288_DDR506112002KQ,SMA   I352 @T6G_MB_LIB.T6G(SCH_1):PAGE90
   J23  253 VSS110 SCONN288_DDR506112002KQ-SCONN288_DDR506112002KQ,SMA   I352 @T6G_MB_LIB.T6G(SCH_1):PAGE90
   J23  255 VSS111 SCONN288_DDR506112002KQ-SCONN288_DDR506112002KQ,SMA   I352 @T6G_MB_LIB.T6G(SCH_1):PAGE90
   J23  257 VSS112 SCONN288_DDR506112002KQ-SCONN288_DDR506112002KQ,SMA   I352 @T6G_MB_LIB.T6G(SCH_1):PAGE90
   J23  259 VSS113 SCONN288_DDR506112002KQ-SCONN288_DDR506112002KQ,SMA   I352 @T6G_MB_LIB.T6G(SCH_1):PAGE90
   J23  262 VSS114 SCONN288_DDR506112002KQ-SCONN288_DDR506112002KQ,SMA   I352 @T6G_MB_LIB.T6G(SCH_1):PAGE90
   J23  264 VSS115 SCONN288_DDR506112002KQ-SCONN288_DDR506112002KQ,SMA   I352 @T6G_MB_LIB.T6G(SCH_1):PAGE90
   J23  266 VSS116 SCONN288_DDR506112002KQ-SCONN288_DDR506112002KQ,SMA   I352 @T6G_MB_LIB.T6G(SCH_1):PAGE90
   J23  268 VSS117 SCONN288_DDR506112002KQ-SCONN288_DDR506112002KQ,SMA   I352 @T6G_MB_LIB.T6G(SCH_1):PAGE90
   J23  270 VSS118 SCONN288_DDR506112002KQ-SCONN288_DDR506112002KQ,SMA   I352 @T6G_MB_LIB.T6G(SCH_1):PAGE90
   J23  273 VSS119 SCONN288_DDR506112002KQ-SCONN288_DDR506112002KQ,SMA   I352 @T6G_MB_LIB.T6G(SCH_1):PAGE90
   J23  275 VSS120 SCONN288_DDR506112002KQ-SCONN288_DDR506112002KQ,SMA   I352 @T6G_MB_LIB.T6G(SCH_1):PAGE90
   J23  277 VSS121 SCONN288_DDR506112002KQ-SCONN288_DDR506112002KQ,SMA   I352 @T6G_MB_LIB.T6G(SCH_1):PAGE90
   J23  279 VSS122 SCONN288_DDR506112002KQ-SCONN288_DDR506112002KQ,SMA   I352 @T6G_MB_LIB.T6G(SCH_1):PAGE90
   J23  281 VSS123 SCONN288_DDR506112002KQ-SCONN288_DDR506112002KQ,SMA   I352 @T6G_MB_LIB.T6G(SCH_1):PAGE90
   J23  284 VSS124 SCONN288_DDR506112002KQ-SCONN288_DDR506112002KQ,SMA   I352 @T6G_MB_LIB.T6G(SCH_1):PAGE90
   J23  286 VSS125 SCONN288_DDR506112002KQ-SCONN288_DDR506112002KQ,SMA   I352 @T6G_MB_LIB.T6G(SCH_1):PAGE90
   J23  288 VSS126 SCONN288_DDR506112002KQ-SCONN288_DDR506112002KQ,SMA   I352 @T6G_MB_LIB.T6G(SCH_1):PAGE90
  C108    2      B Q_CAP_0402-0.1UF,25V,10%,X7R,CH4104K1B00   I361 @T6G_MB_LIB.T6G(SCH_1):PAGE90
  C154    2      B Q_CAP_C0805-10UF,25V,10%,X6S,CH6104KEA00   I414 @T6G_MB_LIB.T6G(SCH_1):PAGE90
  C155    2      B Q_CAP_C0805-10UF,25V,10%,X6S,CH6104KEA00   I415 @T6G_MB_LIB.T6G(SCH_1):PAGE90
   R35    2      B Q_RES_0402LF-10K,1%,1/16W,CHIP,CS31002FB08   I129 @T6G_MB_LIB.T6G(SCH_1):PAGE91
   J16   G1     G1 SCONN288_DDR506112002KQ-SCONN288_DDR506112002KQ,SMA   I177 @T6G_MB_LIB.T6G(SCH_1):PAGE91
   J16   G2     G2 SCONN288_DDR506112002KQ-SCONN288_DDR506112002KQ,SMA   I177 @T6G_MB_LIB.T6G(SCH_1):PAGE91
   J16   G3     G3 SCONN288_DDR506112002KQ-SCONN288_DDR506112002KQ,SMA   I177 @T6G_MB_LIB.T6G(SCH_1):PAGE91
   J16    6   VSS0 SCONN288_DDR506112002KQ-SCONN288_DDR506112002KQ,SMA   I177 @T6G_MB_LIB.T6G(SCH_1):PAGE91
   J16    8   VSS1 SCONN288_DDR506112002KQ-SCONN288_DDR506112002KQ,SMA   I177 @T6G_MB_LIB.T6G(SCH_1):PAGE91
   J16   10   VSS2 SCONN288_DDR506112002KQ-SCONN288_DDR506112002KQ,SMA   I177 @T6G_MB_LIB.T6G(SCH_1):PAGE91
   J16   13   VSS3 SCONN288_DDR506112002KQ-SCONN288_DDR506112002KQ,SMA   I177 @T6G_MB_LIB.T6G(SCH_1):PAGE91
   J16   15   VSS4 SCONN288_DDR506112002KQ-SCONN288_DDR506112002KQ,SMA   I177 @T6G_MB_LIB.T6G(SCH_1):PAGE91
   J16   17   VSS5 SCONN288_DDR506112002KQ-SCONN288_DDR506112002KQ,SMA   I177 @T6G_MB_LIB.T6G(SCH_1):PAGE91
   J16   19   VSS6 SCONN288_DDR506112002KQ-SCONN288_DDR506112002KQ,SMA   I177 @T6G_MB_LIB.T6G(SCH_1):PAGE91
   J16   21   VSS7 SCONN288_DDR506112002KQ-SCONN288_DDR506112002KQ,SMA   I177 @T6G_MB_LIB.T6G(SCH_1):PAGE91
   J16   24   VSS8 SCONN288_DDR506112002KQ-SCONN288_DDR506112002KQ,SMA   I177 @T6G_MB_LIB.T6G(SCH_1):PAGE91
   J16   26   VSS9 SCONN288_DDR506112002KQ-SCONN288_DDR506112002KQ,SMA   I177 @T6G_MB_LIB.T6G(SCH_1):PAGE91
   J16   28  VSS10 SCONN288_DDR506112002KQ-SCONN288_DDR506112002KQ,SMA   I177 @T6G_MB_LIB.T6G(SCH_1):PAGE91
   J16   30  VSS11 SCONN288_DDR506112002KQ-SCONN288_DDR506112002KQ,SMA   I177 @T6G_MB_LIB.T6G(SCH_1):PAGE91
   J16   32  VSS12 SCONN288_DDR506112002KQ-SCONN288_DDR506112002KQ,SMA   I177 @T6G_MB_LIB.T6G(SCH_1):PAGE91
   J16   35  VSS13 SCONN288_DDR506112002KQ-SCONN288_DDR506112002KQ,SMA   I177 @T6G_MB_LIB.T6G(SCH_1):PAGE91
   J16   37  VSS14 SCONN288_DDR506112002KQ-SCONN288_DDR506112002KQ,SMA   I177 @T6G_MB_LIB.T6G(SCH_1):PAGE91
   J16   39  VSS15 SCONN288_DDR506112002KQ-SCONN288_DDR506112002KQ,SMA   I177 @T6G_MB_LIB.T6G(SCH_1):PAGE91
   J16   41  VSS16 SCONN288_DDR506112002KQ-SCONN288_DDR506112002KQ,SMA   I177 @T6G_MB_LIB.T6G(SCH_1):PAGE91
   J16   43  VSS17 SCONN288_DDR506112002KQ-SCONN288_DDR506112002KQ,SMA   I177 @T6G_MB_LIB.T6G(SCH_1):PAGE91
   J16   46  VSS18 SCONN288_DDR506112002KQ-SCONN288_DDR506112002KQ,SMA   I177 @T6G_MB_LIB.T6G(SCH_1):PAGE91
   J16   48  VSS19 SCONN288_DDR506112002KQ-SCONN288_DDR506112002KQ,SMA   I177 @T6G_MB_LIB.T6G(SCH_1):PAGE91
   J16   50  VSS20 SCONN288_DDR506112002KQ-SCONN288_DDR506112002KQ,SMA   I177 @T6G_MB_LIB.T6G(SCH_1):PAGE91
   J16   52  VSS21 SCONN288_DDR506112002KQ-SCONN288_DDR506112002KQ,SMA   I177 @T6G_MB_LIB.T6G(SCH_1):PAGE91
   J16   54  VSS22 SCONN288_DDR506112002KQ-SCONN288_DDR506112002KQ,SMA   I177 @T6G_MB_LIB.T6G(SCH_1):PAGE91
   J16   57  VSS23 SCONN288_DDR506112002KQ-SCONN288_DDR506112002KQ,SMA   I177 @T6G_MB_LIB.T6G(SCH_1):PAGE91
   J16   59  VSS24 SCONN288_DDR506112002KQ-SCONN288_DDR506112002KQ,SMA   I177 @T6G_MB_LIB.T6G(SCH_1):PAGE91
   J16   61  VSS25 SCONN288_DDR506112002KQ-SCONN288_DDR506112002KQ,SMA   I177 @T6G_MB_LIB.T6G(SCH_1):PAGE91
   J16   63  VSS26 SCONN288_DDR506112002KQ-SCONN288_DDR506112002KQ,SMA   I177 @T6G_MB_LIB.T6G(SCH_1):PAGE91
   J16   65  VSS27 SCONN288_DDR506112002KQ-SCONN288_DDR506112002KQ,SMA   I177 @T6G_MB_LIB.T6G(SCH_1):PAGE91
   J16   67  VSS28 SCONN288_DDR506112002KQ-SCONN288_DDR506112002KQ,SMA   I177 @T6G_MB_LIB.T6G(SCH_1):PAGE91
   J16   69  VSS29 SCONN288_DDR506112002KQ-SCONN288_DDR506112002KQ,SMA   I177 @T6G_MB_LIB.T6G(SCH_1):PAGE91
   J16   71  VSS30 SCONN288_DDR506112002KQ-SCONN288_DDR506112002KQ,SMA   I177 @T6G_MB_LIB.T6G(SCH_1):PAGE91
   J16   73  VSS31 SCONN288_DDR506112002KQ-SCONN288_DDR506112002KQ,SMA   I177 @T6G_MB_LIB.T6G(SCH_1):PAGE91
   J16   75  VSS32 SCONN288_DDR506112002KQ-SCONN288_DDR506112002KQ,SMA   I177 @T6G_MB_LIB.T6G(SCH_1):PAGE91
   J16   77  VSS33 SCONN288_DDR506112002KQ-SCONN288_DDR506112002KQ,SMA   I177 @T6G_MB_LIB.T6G(SCH_1):PAGE91
   J16   79  VSS34 SCONN288_DDR506112002KQ-SCONN288_DDR506112002KQ,SMA   I177 @T6G_MB_LIB.T6G(SCH_1):PAGE91
   J16   81  VSS35 SCONN288_DDR506112002KQ-SCONN288_DDR506112002KQ,SMA   I177 @T6G_MB_LIB.T6G(SCH_1):PAGE91
   J16   83  VSS36 SCONN288_DDR506112002KQ-SCONN288_DDR506112002KQ,SMA   I177 @T6G_MB_LIB.T6G(SCH_1):PAGE91
   J16   85  VSS37 SCONN288_DDR506112002KQ-SCONN288_DDR506112002KQ,SMA   I177 @T6G_MB_LIB.T6G(SCH_1):PAGE91
   J16   88  VSS38 SCONN288_DDR506112002KQ-SCONN288_DDR506112002KQ,SMA   I177 @T6G_MB_LIB.T6G(SCH_1):PAGE91
   J16   90  VSS39 SCONN288_DDR506112002KQ-SCONN288_DDR506112002KQ,SMA   I177 @T6G_MB_LIB.T6G(SCH_1):PAGE91
   J16   92  VSS40 SCONN288_DDR506112002KQ-SCONN288_DDR506112002KQ,SMA   I177 @T6G_MB_LIB.T6G(SCH_1):PAGE91
   J16   95  VSS41 SCONN288_DDR506112002KQ-SCONN288_DDR506112002KQ,SMA   I177 @T6G_MB_LIB.T6G(SCH_1):PAGE91
   J16   97  VSS42 SCONN288_DDR506112002KQ-SCONN288_DDR506112002KQ,SMA   I177 @T6G_MB_LIB.T6G(SCH_1):PAGE91
   J16   99  VSS43 SCONN288_DDR506112002KQ-SCONN288_DDR506112002KQ,SMA   I177 @T6G_MB_LIB.T6G(SCH_1):PAGE91
   J16  101  VSS44 SCONN288_DDR506112002KQ-SCONN288_DDR506112002KQ,SMA   I177 @T6G_MB_LIB.T6G(SCH_1):PAGE91
   J16  103  VSS45 SCONN288_DDR506112002KQ-SCONN288_DDR506112002KQ,SMA   I177 @T6G_MB_LIB.T6G(SCH_1):PAGE91
   J16  106  VSS46 SCONN288_DDR506112002KQ-SCONN288_DDR506112002KQ,SMA   I177 @T6G_MB_LIB.T6G(SCH_1):PAGE91
   J16  108  VSS47 SCONN288_DDR506112002KQ-SCONN288_DDR506112002KQ,SMA   I177 @T6G_MB_LIB.T6G(SCH_1):PAGE91
   J16  110  VSS48 SCONN288_DDR506112002KQ-SCONN288_DDR506112002KQ,SMA   I177 @T6G_MB_LIB.T6G(SCH_1):PAGE91
   J16  112  VSS49 SCONN288_DDR506112002KQ-SCONN288_DDR506112002KQ,SMA   I177 @T6G_MB_LIB.T6G(SCH_1):PAGE91
   J16  114  VSS50 SCONN288_DDR506112002KQ-SCONN288_DDR506112002KQ,SMA   I177 @T6G_MB_LIB.T6G(SCH_1):PAGE91
   J16  117  VSS51 SCONN288_DDR506112002KQ-SCONN288_DDR506112002KQ,SMA   I177 @T6G_MB_LIB.T6G(SCH_1):PAGE91
   J16  119  VSS52 SCONN288_DDR506112002KQ-SCONN288_DDR506112002KQ,SMA   I177 @T6G_MB_LIB.T6G(SCH_1):PAGE91
   J16  121  VSS53 SCONN288_DDR506112002KQ-SCONN288_DDR506112002KQ,SMA   I177 @T6G_MB_LIB.T6G(SCH_1):PAGE91
   J16  123  VSS54 SCONN288_DDR506112002KQ-SCONN288_DDR506112002KQ,SMA   I177 @T6G_MB_LIB.T6G(SCH_1):PAGE91
   J16  125  VSS55 SCONN288_DDR506112002KQ-SCONN288_DDR506112002KQ,SMA   I177 @T6G_MB_LIB.T6G(SCH_1):PAGE91
   J16  128  VSS56 SCONN288_DDR506112002KQ-SCONN288_DDR506112002KQ,SMA   I177 @T6G_MB_LIB.T6G(SCH_1):PAGE91
   J16  130  VSS57 SCONN288_DDR506112002KQ-SCONN288_DDR506112002KQ,SMA   I177 @T6G_MB_LIB.T6G(SCH_1):PAGE91
   J16  132  VSS58 SCONN288_DDR506112002KQ-SCONN288_DDR506112002KQ,SMA   I177 @T6G_MB_LIB.T6G(SCH_1):PAGE91
   J16  134  VSS59 SCONN288_DDR506112002KQ-SCONN288_DDR506112002KQ,SMA   I177 @T6G_MB_LIB.T6G(SCH_1):PAGE91
   J16  136  VSS60 SCONN288_DDR506112002KQ-SCONN288_DDR506112002KQ,SMA   I177 @T6G_MB_LIB.T6G(SCH_1):PAGE91
   J16  139  VSS61 SCONN288_DDR506112002KQ-SCONN288_DDR506112002KQ,SMA   I177 @T6G_MB_LIB.T6G(SCH_1):PAGE91
   J16  141  VSS62 SCONN288_DDR506112002KQ-SCONN288_DDR506112002KQ,SMA   I177 @T6G_MB_LIB.T6G(SCH_1):PAGE91
   J16  143  VSS63 SCONN288_DDR506112002KQ-SCONN288_DDR506112002KQ,SMA   I177 @T6G_MB_LIB.T6G(SCH_1):PAGE91
   J16  151  VSS64 SCONN288_DDR506112002KQ-SCONN288_DDR506112002KQ,SMA   I177 @T6G_MB_LIB.T6G(SCH_1):PAGE91
   J16  153  VSS65 SCONN288_DDR506112002KQ-SCONN288_DDR506112002KQ,SMA   I177 @T6G_MB_LIB.T6G(SCH_1):PAGE91
   J16  155  VSS66 SCONN288_DDR506112002KQ-SCONN288_DDR506112002KQ,SMA   I177 @T6G_MB_LIB.T6G(SCH_1):PAGE91
   J16  158  VSS67 SCONN288_DDR506112002KQ-SCONN288_DDR506112002KQ,SMA   I177 @T6G_MB_LIB.T6G(SCH_1):PAGE91
   J16  160  VSS68 SCONN288_DDR506112002KQ-SCONN288_DDR506112002KQ,SMA   I177 @T6G_MB_LIB.T6G(SCH_1):PAGE91
   J16  162  VSS69 SCONN288_DDR506112002KQ-SCONN288_DDR506112002KQ,SMA   I177 @T6G_MB_LIB.T6G(SCH_1):PAGE91
   J16  164  VSS70 SCONN288_DDR506112002KQ-SCONN288_DDR506112002KQ,SMA   I177 @T6G_MB_LIB.T6G(SCH_1):PAGE91
   J16  166  VSS71 SCONN288_DDR506112002KQ-SCONN288_DDR506112002KQ,SMA   I177 @T6G_MB_LIB.T6G(SCH_1):PAGE91
   J16  169  VSS72 SCONN288_DDR506112002KQ-SCONN288_DDR506112002KQ,SMA   I177 @T6G_MB_LIB.T6G(SCH_1):PAGE91
   J16  171  VSS73 SCONN288_DDR506112002KQ-SCONN288_DDR506112002KQ,SMA   I177 @T6G_MB_LIB.T6G(SCH_1):PAGE91
   J16  173  VSS74 SCONN288_DDR506112002KQ-SCONN288_DDR506112002KQ,SMA   I177 @T6G_MB_LIB.T6G(SCH_1):PAGE91
   J16  175  VSS75 SCONN288_DDR506112002KQ-SCONN288_DDR506112002KQ,SMA   I177 @T6G_MB_LIB.T6G(SCH_1):PAGE91
   J16  177  VSS76 SCONN288_DDR506112002KQ-SCONN288_DDR506112002KQ,SMA   I177 @T6G_MB_LIB.T6G(SCH_1):PAGE91
   J16  180  VSS77 SCONN288_DDR506112002KQ-SCONN288_DDR506112002KQ,SMA   I177 @T6G_MB_LIB.T6G(SCH_1):PAGE91
   J16  182  VSS78 SCONN288_DDR506112002KQ-SCONN288_DDR506112002KQ,SMA   I177 @T6G_MB_LIB.T6G(SCH_1):PAGE91
   J16  184  VSS79 SCONN288_DDR506112002KQ-SCONN288_DDR506112002KQ,SMA   I177 @T6G_MB_LIB.T6G(SCH_1):PAGE91
   J16  186  VSS80 SCONN288_DDR506112002KQ-SCONN288_DDR506112002KQ,SMA   I177 @T6G_MB_LIB.T6G(SCH_1):PAGE91
   J16  188  VSS81 SCONN288_DDR506112002KQ-SCONN288_DDR506112002KQ,SMA   I177 @T6G_MB_LIB.T6G(SCH_1):PAGE91
   J16  191  VSS82 SCONN288_DDR506112002KQ-SCONN288_DDR506112002KQ,SMA   I177 @T6G_MB_LIB.T6G(SCH_1):PAGE91
   J16  193  VSS83 SCONN288_DDR506112002KQ-SCONN288_DDR506112002KQ,SMA   I177 @T6G_MB_LIB.T6G(SCH_1):PAGE91
   J16  195  VSS84 SCONN288_DDR506112002KQ-SCONN288_DDR506112002KQ,SMA   I177 @T6G_MB_LIB.T6G(SCH_1):PAGE91
   J16  197  VSS85 SCONN288_DDR506112002KQ-SCONN288_DDR506112002KQ,SMA   I177 @T6G_MB_LIB.T6G(SCH_1):PAGE91
   J16  199  VSS86 SCONN288_DDR506112002KQ-SCONN288_DDR506112002KQ,SMA   I177 @T6G_MB_LIB.T6G(SCH_1):PAGE91
   J16  202  VSS87 SCONN288_DDR506112002KQ-SCONN288_DDR506112002KQ,SMA   I177 @T6G_MB_LIB.T6G(SCH_1):PAGE91
   J16  204  VSS88 SCONN288_DDR506112002KQ-SCONN288_DDR506112002KQ,SMA   I177 @T6G_MB_LIB.T6G(SCH_1):PAGE91
   J16  206  VSS89 SCONN288_DDR506112002KQ-SCONN288_DDR506112002KQ,SMA   I177 @T6G_MB_LIB.T6G(SCH_1):PAGE91
   J16  208  VSS90 SCONN288_DDR506112002KQ-SCONN288_DDR506112002KQ,SMA   I177 @T6G_MB_LIB.T6G(SCH_1):PAGE91
   J16  210  VSS91 SCONN288_DDR506112002KQ-SCONN288_DDR506112002KQ,SMA   I177 @T6G_MB_LIB.T6G(SCH_1):PAGE91
   J16  212  VSS92 SCONN288_DDR506112002KQ-SCONN288_DDR506112002KQ,SMA   I177 @T6G_MB_LIB.T6G(SCH_1):PAGE91
   J16  214  VSS93 SCONN288_DDR506112002KQ-SCONN288_DDR506112002KQ,SMA   I177 @T6G_MB_LIB.T6G(SCH_1):PAGE91
   J16  216  VSS94 SCONN288_DDR506112002KQ-SCONN288_DDR506112002KQ,SMA   I177 @T6G_MB_LIB.T6G(SCH_1):PAGE91
   J16  219  VSS95 SCONN288_DDR506112002KQ-SCONN288_DDR506112002KQ,SMA   I177 @T6G_MB_LIB.T6G(SCH_1):PAGE91
   J16  222  VSS96 SCONN288_DDR506112002KQ-SCONN288_DDR506112002KQ,SMA   I177 @T6G_MB_LIB.T6G(SCH_1):PAGE91
   J16  224  VSS97 SCONN288_DDR506112002KQ-SCONN288_DDR506112002KQ,SMA   I177 @T6G_MB_LIB.T6G(SCH_1):PAGE91
   J16  226  VSS98 SCONN288_DDR506112002KQ-SCONN288_DDR506112002KQ,SMA   I177 @T6G_MB_LIB.T6G(SCH_1):PAGE91
   J16  228  VSS99 SCONN288_DDR506112002KQ-SCONN288_DDR506112002KQ,SMA   I177 @T6G_MB_LIB.T6G(SCH_1):PAGE91
   J16  230 VSS100 SCONN288_DDR506112002KQ-SCONN288_DDR506112002KQ,SMA   I177 @T6G_MB_LIB.T6G(SCH_1):PAGE91
   J16  233 VSS101 SCONN288_DDR506112002KQ-SCONN288_DDR506112002KQ,SMA   I177 @T6G_MB_LIB.T6G(SCH_1):PAGE91
   J16  235 VSS102 SCONN288_DDR506112002KQ-SCONN288_DDR506112002KQ,SMA   I177 @T6G_MB_LIB.T6G(SCH_1):PAGE91
   J16  237 VSS103 SCONN288_DDR506112002KQ-SCONN288_DDR506112002KQ,SMA   I177 @T6G_MB_LIB.T6G(SCH_1):PAGE91
   J16  240 VSS104 SCONN288_DDR506112002KQ-SCONN288_DDR506112002KQ,SMA   I177 @T6G_MB_LIB.T6G(SCH_1):PAGE91
   J16  242 VSS105 SCONN288_DDR506112002KQ-SCONN288_DDR506112002KQ,SMA   I177 @T6G_MB_LIB.T6G(SCH_1):PAGE91
   J16  244 VSS106 SCONN288_DDR506112002KQ-SCONN288_DDR506112002KQ,SMA   I177 @T6G_MB_LIB.T6G(SCH_1):PAGE91
   J16  246 VSS107 SCONN288_DDR506112002KQ-SCONN288_DDR506112002KQ,SMA   I177 @T6G_MB_LIB.T6G(SCH_1):PAGE91
   J16  248 VSS108 SCONN288_DDR506112002KQ-SCONN288_DDR506112002KQ,SMA   I177 @T6G_MB_LIB.T6G(SCH_1):PAGE91
   J16  251 VSS109 SCONN288_DDR506112002KQ-SCONN288_DDR506112002KQ,SMA   I177 @T6G_MB_LIB.T6G(SCH_1):PAGE91
   J16  253 VSS110 SCONN288_DDR506112002KQ-SCONN288_DDR506112002KQ,SMA   I177 @T6G_MB_LIB.T6G(SCH_1):PAGE91
   J16  255 VSS111 SCONN288_DDR506112002KQ-SCONN288_DDR506112002KQ,SMA   I177 @T6G_MB_LIB.T6G(SCH_1):PAGE91
   J16  257 VSS112 SCONN288_DDR506112002KQ-SCONN288_DDR506112002KQ,SMA   I177 @T6G_MB_LIB.T6G(SCH_1):PAGE91
   J16  259 VSS113 SCONN288_DDR506112002KQ-SCONN288_DDR506112002KQ,SMA   I177 @T6G_MB_LIB.T6G(SCH_1):PAGE91
   J16  262 VSS114 SCONN288_DDR506112002KQ-SCONN288_DDR506112002KQ,SMA   I177 @T6G_MB_LIB.T6G(SCH_1):PAGE91
   J16  264 VSS115 SCONN288_DDR506112002KQ-SCONN288_DDR506112002KQ,SMA   I177 @T6G_MB_LIB.T6G(SCH_1):PAGE91
   J16  266 VSS116 SCONN288_DDR506112002KQ-SCONN288_DDR506112002KQ,SMA   I177 @T6G_MB_LIB.T6G(SCH_1):PAGE91
   J16  268 VSS117 SCONN288_DDR506112002KQ-SCONN288_DDR506112002KQ,SMA   I177 @T6G_MB_LIB.T6G(SCH_1):PAGE91
   J16  270 VSS118 SCONN288_DDR506112002KQ-SCONN288_DDR506112002KQ,SMA   I177 @T6G_MB_LIB.T6G(SCH_1):PAGE91
   J16  273 VSS119 SCONN288_DDR506112002KQ-SCONN288_DDR506112002KQ,SMA   I177 @T6G_MB_LIB.T6G(SCH_1):PAGE91
   J16  275 VSS120 SCONN288_DDR506112002KQ-SCONN288_DDR506112002KQ,SMA   I177 @T6G_MB_LIB.T6G(SCH_1):PAGE91
   J16  277 VSS121 SCONN288_DDR506112002KQ-SCONN288_DDR506112002KQ,SMA   I177 @T6G_MB_LIB.T6G(SCH_1):PAGE91
   J16  279 VSS122 SCONN288_DDR506112002KQ-SCONN288_DDR506112002KQ,SMA   I177 @T6G_MB_LIB.T6G(SCH_1):PAGE91
   J16  281 VSS123 SCONN288_DDR506112002KQ-SCONN288_DDR506112002KQ,SMA   I177 @T6G_MB_LIB.T6G(SCH_1):PAGE91
   J16  284 VSS124 SCONN288_DDR506112002KQ-SCONN288_DDR506112002KQ,SMA   I177 @T6G_MB_LIB.T6G(SCH_1):PAGE91
   J16  286 VSS125 SCONN288_DDR506112002KQ-SCONN288_DDR506112002KQ,SMA   I177 @T6G_MB_LIB.T6G(SCH_1):PAGE91
   J16  288 VSS126 SCONN288_DDR506112002KQ-SCONN288_DDR506112002KQ,SMA   I177 @T6G_MB_LIB.T6G(SCH_1):PAGE91
  C112    2      B Q_CAP_0402-0.1UF,25V,10%,X7R,CH4104K1B00   I183 @T6G_MB_LIB.T6G(SCH_1):PAGE91
  C157    2      B Q_CAP_C0805-10UF,25V,10%,X6S,CH6104KEA00   I238 @T6G_MB_LIB.T6G(SCH_1):PAGE91
  C158    2      B Q_CAP_C0805-10UF,25V,10%,X6S,CH6104KEA00   I239 @T6G_MB_LIB.T6G(SCH_1):PAGE91
  R765    2      B Q_RES_0402LF-15.4K,1%,1/16W,CHIP,CS31542FB02   I129 @T6G_MB_LIB.T6G(SCH_1):PAGE92
   J69   G1     G1 SCONN288_DDR506112002KQ-SCONN288_DDR506112002KQ,SMA   I177 @T6G_MB_LIB.T6G(SCH_1):PAGE92
   J69   G2     G2 SCONN288_DDR506112002KQ-SCONN288_DDR506112002KQ,SMA   I177 @T6G_MB_LIB.T6G(SCH_1):PAGE92
   J69   G3     G3 SCONN288_DDR506112002KQ-SCONN288_DDR506112002KQ,SMA   I177 @T6G_MB_LIB.T6G(SCH_1):PAGE92
   J69    6   VSS0 SCONN288_DDR506112002KQ-SCONN288_DDR506112002KQ,SMA   I177 @T6G_MB_LIB.T6G(SCH_1):PAGE92
   J69    8   VSS1 SCONN288_DDR506112002KQ-SCONN288_DDR506112002KQ,SMA   I177 @T6G_MB_LIB.T6G(SCH_1):PAGE92
   J69   10   VSS2 SCONN288_DDR506112002KQ-SCONN288_DDR506112002KQ,SMA   I177 @T6G_MB_LIB.T6G(SCH_1):PAGE92
   J69   13   VSS3 SCONN288_DDR506112002KQ-SCONN288_DDR506112002KQ,SMA   I177 @T6G_MB_LIB.T6G(SCH_1):PAGE92
   J69   15   VSS4 SCONN288_DDR506112002KQ-SCONN288_DDR506112002KQ,SMA   I177 @T6G_MB_LIB.T6G(SCH_1):PAGE92
   J69   17   VSS5 SCONN288_DDR506112002KQ-SCONN288_DDR506112002KQ,SMA   I177 @T6G_MB_LIB.T6G(SCH_1):PAGE92
   J69   19   VSS6 SCONN288_DDR506112002KQ-SCONN288_DDR506112002KQ,SMA   I177 @T6G_MB_LIB.T6G(SCH_1):PAGE92
   J69   21   VSS7 SCONN288_DDR506112002KQ-SCONN288_DDR506112002KQ,SMA   I177 @T6G_MB_LIB.T6G(SCH_1):PAGE92
   J69   24   VSS8 SCONN288_DDR506112002KQ-SCONN288_DDR506112002KQ,SMA   I177 @T6G_MB_LIB.T6G(SCH_1):PAGE92
   J69   26   VSS9 SCONN288_DDR506112002KQ-SCONN288_DDR506112002KQ,SMA   I177 @T6G_MB_LIB.T6G(SCH_1):PAGE92
   J69   28  VSS10 SCONN288_DDR506112002KQ-SCONN288_DDR506112002KQ,SMA   I177 @T6G_MB_LIB.T6G(SCH_1):PAGE92
   J69   30  VSS11 SCONN288_DDR506112002KQ-SCONN288_DDR506112002KQ,SMA   I177 @T6G_MB_LIB.T6G(SCH_1):PAGE92
   J69   32  VSS12 SCONN288_DDR506112002KQ-SCONN288_DDR506112002KQ,SMA   I177 @T6G_MB_LIB.T6G(SCH_1):PAGE92
   J69   35  VSS13 SCONN288_DDR506112002KQ-SCONN288_DDR506112002KQ,SMA   I177 @T6G_MB_LIB.T6G(SCH_1):PAGE92
   J69   37  VSS14 SCONN288_DDR506112002KQ-SCONN288_DDR506112002KQ,SMA   I177 @T6G_MB_LIB.T6G(SCH_1):PAGE92
   J69   39  VSS15 SCONN288_DDR506112002KQ-SCONN288_DDR506112002KQ,SMA   I177 @T6G_MB_LIB.T6G(SCH_1):PAGE92
   J69   41  VSS16 SCONN288_DDR506112002KQ-SCONN288_DDR506112002KQ,SMA   I177 @T6G_MB_LIB.T6G(SCH_1):PAGE92
   J69   43  VSS17 SCONN288_DDR506112002KQ-SCONN288_DDR506112002KQ,SMA   I177 @T6G_MB_LIB.T6G(SCH_1):PAGE92
   J69   46  VSS18 SCONN288_DDR506112002KQ-SCONN288_DDR506112002KQ,SMA   I177 @T6G_MB_LIB.T6G(SCH_1):PAGE92
   J69   48  VSS19 SCONN288_DDR506112002KQ-SCONN288_DDR506112002KQ,SMA   I177 @T6G_MB_LIB.T6G(SCH_1):PAGE92
   J69   50  VSS20 SCONN288_DDR506112002KQ-SCONN288_DDR506112002KQ,SMA   I177 @T6G_MB_LIB.T6G(SCH_1):PAGE92
   J69   52  VSS21 SCONN288_DDR506112002KQ-SCONN288_DDR506112002KQ,SMA   I177 @T6G_MB_LIB.T6G(SCH_1):PAGE92
   J69   54  VSS22 SCONN288_DDR506112002KQ-SCONN288_DDR506112002KQ,SMA   I177 @T6G_MB_LIB.T6G(SCH_1):PAGE92
   J69   57  VSS23 SCONN288_DDR506112002KQ-SCONN288_DDR506112002KQ,SMA   I177 @T6G_MB_LIB.T6G(SCH_1):PAGE92
   J69   59  VSS24 SCONN288_DDR506112002KQ-SCONN288_DDR506112002KQ,SMA   I177 @T6G_MB_LIB.T6G(SCH_1):PAGE92
   J69   61  VSS25 SCONN288_DDR506112002KQ-SCONN288_DDR506112002KQ,SMA   I177 @T6G_MB_LIB.T6G(SCH_1):PAGE92
   J69   63  VSS26 SCONN288_DDR506112002KQ-SCONN288_DDR506112002KQ,SMA   I177 @T6G_MB_LIB.T6G(SCH_1):PAGE92
   J69   65  VSS27 SCONN288_DDR506112002KQ-SCONN288_DDR506112002KQ,SMA   I177 @T6G_MB_LIB.T6G(SCH_1):PAGE92
   J69   67  VSS28 SCONN288_DDR506112002KQ-SCONN288_DDR506112002KQ,SMA   I177 @T6G_MB_LIB.T6G(SCH_1):PAGE92
   J69   69  VSS29 SCONN288_DDR506112002KQ-SCONN288_DDR506112002KQ,SMA   I177 @T6G_MB_LIB.T6G(SCH_1):PAGE92
   J69   71  VSS30 SCONN288_DDR506112002KQ-SCONN288_DDR506112002KQ,SMA   I177 @T6G_MB_LIB.T6G(SCH_1):PAGE92
   J69   73  VSS31 SCONN288_DDR506112002KQ-SCONN288_DDR506112002KQ,SMA   I177 @T6G_MB_LIB.T6G(SCH_1):PAGE92
   J69   75  VSS32 SCONN288_DDR506112002KQ-SCONN288_DDR506112002KQ,SMA   I177 @T6G_MB_LIB.T6G(SCH_1):PAGE92
   J69   77  VSS33 SCONN288_DDR506112002KQ-SCONN288_DDR506112002KQ,SMA   I177 @T6G_MB_LIB.T6G(SCH_1):PAGE92
   J69   79  VSS34 SCONN288_DDR506112002KQ-SCONN288_DDR506112002KQ,SMA   I177 @T6G_MB_LIB.T6G(SCH_1):PAGE92
   J69   81  VSS35 SCONN288_DDR506112002KQ-SCONN288_DDR506112002KQ,SMA   I177 @T6G_MB_LIB.T6G(SCH_1):PAGE92
   J69   83  VSS36 SCONN288_DDR506112002KQ-SCONN288_DDR506112002KQ,SMA   I177 @T6G_MB_LIB.T6G(SCH_1):PAGE92
   J69   85  VSS37 SCONN288_DDR506112002KQ-SCONN288_DDR506112002KQ,SMA   I177 @T6G_MB_LIB.T6G(SCH_1):PAGE92
   J69   88  VSS38 SCONN288_DDR506112002KQ-SCONN288_DDR506112002KQ,SMA   I177 @T6G_MB_LIB.T6G(SCH_1):PAGE92
   J69   90  VSS39 SCONN288_DDR506112002KQ-SCONN288_DDR506112002KQ,SMA   I177 @T6G_MB_LIB.T6G(SCH_1):PAGE92
   J69   92  VSS40 SCONN288_DDR506112002KQ-SCONN288_DDR506112002KQ,SMA   I177 @T6G_MB_LIB.T6G(SCH_1):PAGE92
   J69   95  VSS41 SCONN288_DDR506112002KQ-SCONN288_DDR506112002KQ,SMA   I177 @T6G_MB_LIB.T6G(SCH_1):PAGE92
   J69   97  VSS42 SCONN288_DDR506112002KQ-SCONN288_DDR506112002KQ,SMA   I177 @T6G_MB_LIB.T6G(SCH_1):PAGE92
   J69   99  VSS43 SCONN288_DDR506112002KQ-SCONN288_DDR506112002KQ,SMA   I177 @T6G_MB_LIB.T6G(SCH_1):PAGE92
   J69  101  VSS44 SCONN288_DDR506112002KQ-SCONN288_DDR506112002KQ,SMA   I177 @T6G_MB_LIB.T6G(SCH_1):PAGE92
   J69  103  VSS45 SCONN288_DDR506112002KQ-SCONN288_DDR506112002KQ,SMA   I177 @T6G_MB_LIB.T6G(SCH_1):PAGE92
   J69  106  VSS46 SCONN288_DDR506112002KQ-SCONN288_DDR506112002KQ,SMA   I177 @T6G_MB_LIB.T6G(SCH_1):PAGE92
   J69  108  VSS47 SCONN288_DDR506112002KQ-SCONN288_DDR506112002KQ,SMA   I177 @T6G_MB_LIB.T6G(SCH_1):PAGE92
   J69  110  VSS48 SCONN288_DDR506112002KQ-SCONN288_DDR506112002KQ,SMA   I177 @T6G_MB_LIB.T6G(SCH_1):PAGE92
   J69  112  VSS49 SCONN288_DDR506112002KQ-SCONN288_DDR506112002KQ,SMA   I177 @T6G_MB_LIB.T6G(SCH_1):PAGE92
   J69  114  VSS50 SCONN288_DDR506112002KQ-SCONN288_DDR506112002KQ,SMA   I177 @T6G_MB_LIB.T6G(SCH_1):PAGE92
   J69  117  VSS51 SCONN288_DDR506112002KQ-SCONN288_DDR506112002KQ,SMA   I177 @T6G_MB_LIB.T6G(SCH_1):PAGE92
   J69  119  VSS52 SCONN288_DDR506112002KQ-SCONN288_DDR506112002KQ,SMA   I177 @T6G_MB_LIB.T6G(SCH_1):PAGE92
   J69  121  VSS53 SCONN288_DDR506112002KQ-SCONN288_DDR506112002KQ,SMA   I177 @T6G_MB_LIB.T6G(SCH_1):PAGE92
   J69  123  VSS54 SCONN288_DDR506112002KQ-SCONN288_DDR506112002KQ,SMA   I177 @T6G_MB_LIB.T6G(SCH_1):PAGE92
   J69  125  VSS55 SCONN288_DDR506112002KQ-SCONN288_DDR506112002KQ,SMA   I177 @T6G_MB_LIB.T6G(SCH_1):PAGE92
   J69  128  VSS56 SCONN288_DDR506112002KQ-SCONN288_DDR506112002KQ,SMA   I177 @T6G_MB_LIB.T6G(SCH_1):PAGE92
   J69  130  VSS57 SCONN288_DDR506112002KQ-SCONN288_DDR506112002KQ,SMA   I177 @T6G_MB_LIB.T6G(SCH_1):PAGE92
   J69  132  VSS58 SCONN288_DDR506112002KQ-SCONN288_DDR506112002KQ,SMA   I177 @T6G_MB_LIB.T6G(SCH_1):PAGE92
   J69  134  VSS59 SCONN288_DDR506112002KQ-SCONN288_DDR506112002KQ,SMA   I177 @T6G_MB_LIB.T6G(SCH_1):PAGE92
   J69  136  VSS60 SCONN288_DDR506112002KQ-SCONN288_DDR506112002KQ,SMA   I177 @T6G_MB_LIB.T6G(SCH_1):PAGE92
   J69  139  VSS61 SCONN288_DDR506112002KQ-SCONN288_DDR506112002KQ,SMA   I177 @T6G_MB_LIB.T6G(SCH_1):PAGE92
   J69  141  VSS62 SCONN288_DDR506112002KQ-SCONN288_DDR506112002KQ,SMA   I177 @T6G_MB_LIB.T6G(SCH_1):PAGE92
   J69  143  VSS63 SCONN288_DDR506112002KQ-SCONN288_DDR506112002KQ,SMA   I177 @T6G_MB_LIB.T6G(SCH_1):PAGE92
   J69  151  VSS64 SCONN288_DDR506112002KQ-SCONN288_DDR506112002KQ,SMA   I177 @T6G_MB_LIB.T6G(SCH_1):PAGE92
   J69  153  VSS65 SCONN288_DDR506112002KQ-SCONN288_DDR506112002KQ,SMA   I177 @T6G_MB_LIB.T6G(SCH_1):PAGE92
   J69  155  VSS66 SCONN288_DDR506112002KQ-SCONN288_DDR506112002KQ,SMA   I177 @T6G_MB_LIB.T6G(SCH_1):PAGE92
   J69  158  VSS67 SCONN288_DDR506112002KQ-SCONN288_DDR506112002KQ,SMA   I177 @T6G_MB_LIB.T6G(SCH_1):PAGE92
   J69  160  VSS68 SCONN288_DDR506112002KQ-SCONN288_DDR506112002KQ,SMA   I177 @T6G_MB_LIB.T6G(SCH_1):PAGE92
   J69  162  VSS69 SCONN288_DDR506112002KQ-SCONN288_DDR506112002KQ,SMA   I177 @T6G_MB_LIB.T6G(SCH_1):PAGE92
   J69  164  VSS70 SCONN288_DDR506112002KQ-SCONN288_DDR506112002KQ,SMA   I177 @T6G_MB_LIB.T6G(SCH_1):PAGE92
   J69  166  VSS71 SCONN288_DDR506112002KQ-SCONN288_DDR506112002KQ,SMA   I177 @T6G_MB_LIB.T6G(SCH_1):PAGE92
   J69  169  VSS72 SCONN288_DDR506112002KQ-SCONN288_DDR506112002KQ,SMA   I177 @T6G_MB_LIB.T6G(SCH_1):PAGE92
   J69  171  VSS73 SCONN288_DDR506112002KQ-SCONN288_DDR506112002KQ,SMA   I177 @T6G_MB_LIB.T6G(SCH_1):PAGE92
   J69  173  VSS74 SCONN288_DDR506112002KQ-SCONN288_DDR506112002KQ,SMA   I177 @T6G_MB_LIB.T6G(SCH_1):PAGE92
   J69  175  VSS75 SCONN288_DDR506112002KQ-SCONN288_DDR506112002KQ,SMA   I177 @T6G_MB_LIB.T6G(SCH_1):PAGE92
   J69  177  VSS76 SCONN288_DDR506112002KQ-SCONN288_DDR506112002KQ,SMA   I177 @T6G_MB_LIB.T6G(SCH_1):PAGE92
   J69  180  VSS77 SCONN288_DDR506112002KQ-SCONN288_DDR506112002KQ,SMA   I177 @T6G_MB_LIB.T6G(SCH_1):PAGE92
   J69  182  VSS78 SCONN288_DDR506112002KQ-SCONN288_DDR506112002KQ,SMA   I177 @T6G_MB_LIB.T6G(SCH_1):PAGE92
   J69  184  VSS79 SCONN288_DDR506112002KQ-SCONN288_DDR506112002KQ,SMA   I177 @T6G_MB_LIB.T6G(SCH_1):PAGE92
   J69  186  VSS80 SCONN288_DDR506112002KQ-SCONN288_DDR506112002KQ,SMA   I177 @T6G_MB_LIB.T6G(SCH_1):PAGE92
   J69  188  VSS81 SCONN288_DDR506112002KQ-SCONN288_DDR506112002KQ,SMA   I177 @T6G_MB_LIB.T6G(SCH_1):PAGE92
   J69  191  VSS82 SCONN288_DDR506112002KQ-SCONN288_DDR506112002KQ,SMA   I177 @T6G_MB_LIB.T6G(SCH_1):PAGE92
   J69  193  VSS83 SCONN288_DDR506112002KQ-SCONN288_DDR506112002KQ,SMA   I177 @T6G_MB_LIB.T6G(SCH_1):PAGE92
   J69  195  VSS84 SCONN288_DDR506112002KQ-SCONN288_DDR506112002KQ,SMA   I177 @T6G_MB_LIB.T6G(SCH_1):PAGE92
   J69  197  VSS85 SCONN288_DDR506112002KQ-SCONN288_DDR506112002KQ,SMA   I177 @T6G_MB_LIB.T6G(SCH_1):PAGE92
   J69  199  VSS86 SCONN288_DDR506112002KQ-SCONN288_DDR506112002KQ,SMA   I177 @T6G_MB_LIB.T6G(SCH_1):PAGE92
   J69  202  VSS87 SCONN288_DDR506112002KQ-SCONN288_DDR506112002KQ,SMA   I177 @T6G_MB_LIB.T6G(SCH_1):PAGE92
   J69  204  VSS88 SCONN288_DDR506112002KQ-SCONN288_DDR506112002KQ,SMA   I177 @T6G_MB_LIB.T6G(SCH_1):PAGE92
   J69  206  VSS89 SCONN288_DDR506112002KQ-SCONN288_DDR506112002KQ,SMA   I177 @T6G_MB_LIB.T6G(SCH_1):PAGE92
   J69  208  VSS90 SCONN288_DDR506112002KQ-SCONN288_DDR506112002KQ,SMA   I177 @T6G_MB_LIB.T6G(SCH_1):PAGE92
   J69  210  VSS91 SCONN288_DDR506112002KQ-SCONN288_DDR506112002KQ,SMA   I177 @T6G_MB_LIB.T6G(SCH_1):PAGE92
   J69  212  VSS92 SCONN288_DDR506112002KQ-SCONN288_DDR506112002KQ,SMA   I177 @T6G_MB_LIB.T6G(SCH_1):PAGE92
   J69  214  VSS93 SCONN288_DDR506112002KQ-SCONN288_DDR506112002KQ,SMA   I177 @T6G_MB_LIB.T6G(SCH_1):PAGE92
   J69  216  VSS94 SCONN288_DDR506112002KQ-SCONN288_DDR506112002KQ,SMA   I177 @T6G_MB_LIB.T6G(SCH_1):PAGE92
   J69  219  VSS95 SCONN288_DDR506112002KQ-SCONN288_DDR506112002KQ,SMA   I177 @T6G_MB_LIB.T6G(SCH_1):PAGE92
   J69  222  VSS96 SCONN288_DDR506112002KQ-SCONN288_DDR506112002KQ,SMA   I177 @T6G_MB_LIB.T6G(SCH_1):PAGE92
   J69  224  VSS97 SCONN288_DDR506112002KQ-SCONN288_DDR506112002KQ,SMA   I177 @T6G_MB_LIB.T6G(SCH_1):PAGE92
   J69  226  VSS98 SCONN288_DDR506112002KQ-SCONN288_DDR506112002KQ,SMA   I177 @T6G_MB_LIB.T6G(SCH_1):PAGE92
   J69  228  VSS99 SCONN288_DDR506112002KQ-SCONN288_DDR506112002KQ,SMA   I177 @T6G_MB_LIB.T6G(SCH_1):PAGE92
   J69  230 VSS100 SCONN288_DDR506112002KQ-SCONN288_DDR506112002KQ,SMA   I177 @T6G_MB_LIB.T6G(SCH_1):PAGE92
   J69  233 VSS101 SCONN288_DDR506112002KQ-SCONN288_DDR506112002KQ,SMA   I177 @T6G_MB_LIB.T6G(SCH_1):PAGE92
   J69  235 VSS102 SCONN288_DDR506112002KQ-SCONN288_DDR506112002KQ,SMA   I177 @T6G_MB_LIB.T6G(SCH_1):PAGE92
   J69  237 VSS103 SCONN288_DDR506112002KQ-SCONN288_DDR506112002KQ,SMA   I177 @T6G_MB_LIB.T6G(SCH_1):PAGE92
   J69  240 VSS104 SCONN288_DDR506112002KQ-SCONN288_DDR506112002KQ,SMA   I177 @T6G_MB_LIB.T6G(SCH_1):PAGE92
   J69  242 VSS105 SCONN288_DDR506112002KQ-SCONN288_DDR506112002KQ,SMA   I177 @T6G_MB_LIB.T6G(SCH_1):PAGE92
   J69  244 VSS106 SCONN288_DDR506112002KQ-SCONN288_DDR506112002KQ,SMA   I177 @T6G_MB_LIB.T6G(SCH_1):PAGE92
   J69  246 VSS107 SCONN288_DDR506112002KQ-SCONN288_DDR506112002KQ,SMA   I177 @T6G_MB_LIB.T6G(SCH_1):PAGE92
   J69  248 VSS108 SCONN288_DDR506112002KQ-SCONN288_DDR506112002KQ,SMA   I177 @T6G_MB_LIB.T6G(SCH_1):PAGE92
   J69  251 VSS109 SCONN288_DDR506112002KQ-SCONN288_DDR506112002KQ,SMA   I177 @T6G_MB_LIB.T6G(SCH_1):PAGE92
   J69  253 VSS110 SCONN288_DDR506112002KQ-SCONN288_DDR506112002KQ,SMA   I177 @T6G_MB_LIB.T6G(SCH_1):PAGE92
   J69  255 VSS111 SCONN288_DDR506112002KQ-SCONN288_DDR506112002KQ,SMA   I177 @T6G_MB_LIB.T6G(SCH_1):PAGE92
   J69  257 VSS112 SCONN288_DDR506112002KQ-SCONN288_DDR506112002KQ,SMA   I177 @T6G_MB_LIB.T6G(SCH_1):PAGE92
   J69  259 VSS113 SCONN288_DDR506112002KQ-SCONN288_DDR506112002KQ,SMA   I177 @T6G_MB_LIB.T6G(SCH_1):PAGE92
   J69  262 VSS114 SCONN288_DDR506112002KQ-SCONN288_DDR506112002KQ,SMA   I177 @T6G_MB_LIB.T6G(SCH_1):PAGE92
   J69  264 VSS115 SCONN288_DDR506112002KQ-SCONN288_DDR506112002KQ,SMA   I177 @T6G_MB_LIB.T6G(SCH_1):PAGE92
   J69  266 VSS116 SCONN288_DDR506112002KQ-SCONN288_DDR506112002KQ,SMA   I177 @T6G_MB_LIB.T6G(SCH_1):PAGE92
   J69  268 VSS117 SCONN288_DDR506112002KQ-SCONN288_DDR506112002KQ,SMA   I177 @T6G_MB_LIB.T6G(SCH_1):PAGE92
   J69  270 VSS118 SCONN288_DDR506112002KQ-SCONN288_DDR506112002KQ,SMA   I177 @T6G_MB_LIB.T6G(SCH_1):PAGE92
   J69  273 VSS119 SCONN288_DDR506112002KQ-SCONN288_DDR506112002KQ,SMA   I177 @T6G_MB_LIB.T6G(SCH_1):PAGE92
   J69  275 VSS120 SCONN288_DDR506112002KQ-SCONN288_DDR506112002KQ,SMA   I177 @T6G_MB_LIB.T6G(SCH_1):PAGE92
   J69  277 VSS121 SCONN288_DDR506112002KQ-SCONN288_DDR506112002KQ,SMA   I177 @T6G_MB_LIB.T6G(SCH_1):PAGE92
   J69  279 VSS122 SCONN288_DDR506112002KQ-SCONN288_DDR506112002KQ,SMA   I177 @T6G_MB_LIB.T6G(SCH_1):PAGE92
   J69  281 VSS123 SCONN288_DDR506112002KQ-SCONN288_DDR506112002KQ,SMA   I177 @T6G_MB_LIB.T6G(SCH_1):PAGE92
   J69  284 VSS124 SCONN288_DDR506112002KQ-SCONN288_DDR506112002KQ,SMA   I177 @T6G_MB_LIB.T6G(SCH_1):PAGE92
   J69  286 VSS125 SCONN288_DDR506112002KQ-SCONN288_DDR506112002KQ,SMA   I177 @T6G_MB_LIB.T6G(SCH_1):PAGE92
   J69  288 VSS126 SCONN288_DDR506112002KQ-SCONN288_DDR506112002KQ,SMA   I177 @T6G_MB_LIB.T6G(SCH_1):PAGE92
  C116    2      B Q_CAP_0402-0.1UF,25V,10%,X7R,CH4104K1B00   I186 @T6G_MB_LIB.T6G(SCH_1):PAGE92
  C159    2      B Q_CAP_C0805-10UF,25V,10%,X6S,CH6104KEA00   I239 @T6G_MB_LIB.T6G(SCH_1):PAGE92
  C161    2      B Q_CAP_C0805-10UF,25V,10%,X6S,CH6104KEA00   I240 @T6G_MB_LIB.T6G(SCH_1):PAGE92
  R766    2      B Q_RES_0402LF-23.2K,1%,1/16W,CHIP,CS32322FB03   I128 @T6G_MB_LIB.T6G(SCH_1):PAGE93
   J18   G1     G1 SCONN288_DDR506112002KQ-SCONN288_DDR506112002KQ,SMA   I143 @T6G_MB_LIB.T6G(SCH_1):PAGE93
   J18   G2     G2 SCONN288_DDR506112002KQ-SCONN288_DDR506112002KQ,SMA   I143 @T6G_MB_LIB.T6G(SCH_1):PAGE93
   J18   G3     G3 SCONN288_DDR506112002KQ-SCONN288_DDR506112002KQ,SMA   I143 @T6G_MB_LIB.T6G(SCH_1):PAGE93
   J18    6   VSS0 SCONN288_DDR506112002KQ-SCONN288_DDR506112002KQ,SMA   I143 @T6G_MB_LIB.T6G(SCH_1):PAGE93
   J18    8   VSS1 SCONN288_DDR506112002KQ-SCONN288_DDR506112002KQ,SMA   I143 @T6G_MB_LIB.T6G(SCH_1):PAGE93
   J18   10   VSS2 SCONN288_DDR506112002KQ-SCONN288_DDR506112002KQ,SMA   I143 @T6G_MB_LIB.T6G(SCH_1):PAGE93
   J18   13   VSS3 SCONN288_DDR506112002KQ-SCONN288_DDR506112002KQ,SMA   I143 @T6G_MB_LIB.T6G(SCH_1):PAGE93
   J18   15   VSS4 SCONN288_DDR506112002KQ-SCONN288_DDR506112002KQ,SMA   I143 @T6G_MB_LIB.T6G(SCH_1):PAGE93
   J18   17   VSS5 SCONN288_DDR506112002KQ-SCONN288_DDR506112002KQ,SMA   I143 @T6G_MB_LIB.T6G(SCH_1):PAGE93
   J18   19   VSS6 SCONN288_DDR506112002KQ-SCONN288_DDR506112002KQ,SMA   I143 @T6G_MB_LIB.T6G(SCH_1):PAGE93
   J18   21   VSS7 SCONN288_DDR506112002KQ-SCONN288_DDR506112002KQ,SMA   I143 @T6G_MB_LIB.T6G(SCH_1):PAGE93
   J18   24   VSS8 SCONN288_DDR506112002KQ-SCONN288_DDR506112002KQ,SMA   I143 @T6G_MB_LIB.T6G(SCH_1):PAGE93
   J18   26   VSS9 SCONN288_DDR506112002KQ-SCONN288_DDR506112002KQ,SMA   I143 @T6G_MB_LIB.T6G(SCH_1):PAGE93
   J18   28  VSS10 SCONN288_DDR506112002KQ-SCONN288_DDR506112002KQ,SMA   I143 @T6G_MB_LIB.T6G(SCH_1):PAGE93
   J18   30  VSS11 SCONN288_DDR506112002KQ-SCONN288_DDR506112002KQ,SMA   I143 @T6G_MB_LIB.T6G(SCH_1):PAGE93
   J18   32  VSS12 SCONN288_DDR506112002KQ-SCONN288_DDR506112002KQ,SMA   I143 @T6G_MB_LIB.T6G(SCH_1):PAGE93
   J18   35  VSS13 SCONN288_DDR506112002KQ-SCONN288_DDR506112002KQ,SMA   I143 @T6G_MB_LIB.T6G(SCH_1):PAGE93
   J18   37  VSS14 SCONN288_DDR506112002KQ-SCONN288_DDR506112002KQ,SMA   I143 @T6G_MB_LIB.T6G(SCH_1):PAGE93
   J18   39  VSS15 SCONN288_DDR506112002KQ-SCONN288_DDR506112002KQ,SMA   I143 @T6G_MB_LIB.T6G(SCH_1):PAGE93
   J18   41  VSS16 SCONN288_DDR506112002KQ-SCONN288_DDR506112002KQ,SMA   I143 @T6G_MB_LIB.T6G(SCH_1):PAGE93
   J18   43  VSS17 SCONN288_DDR506112002KQ-SCONN288_DDR506112002KQ,SMA   I143 @T6G_MB_LIB.T6G(SCH_1):PAGE93
   J18   46  VSS18 SCONN288_DDR506112002KQ-SCONN288_DDR506112002KQ,SMA   I143 @T6G_MB_LIB.T6G(SCH_1):PAGE93
   J18   48  VSS19 SCONN288_DDR506112002KQ-SCONN288_DDR506112002KQ,SMA   I143 @T6G_MB_LIB.T6G(SCH_1):PAGE93
   J18   50  VSS20 SCONN288_DDR506112002KQ-SCONN288_DDR506112002KQ,SMA   I143 @T6G_MB_LIB.T6G(SCH_1):PAGE93
   J18   52  VSS21 SCONN288_DDR506112002KQ-SCONN288_DDR506112002KQ,SMA   I143 @T6G_MB_LIB.T6G(SCH_1):PAGE93
   J18   54  VSS22 SCONN288_DDR506112002KQ-SCONN288_DDR506112002KQ,SMA   I143 @T6G_MB_LIB.T6G(SCH_1):PAGE93
   J18   57  VSS23 SCONN288_DDR506112002KQ-SCONN288_DDR506112002KQ,SMA   I143 @T6G_MB_LIB.T6G(SCH_1):PAGE93
   J18   59  VSS24 SCONN288_DDR506112002KQ-SCONN288_DDR506112002KQ,SMA   I143 @T6G_MB_LIB.T6G(SCH_1):PAGE93
   J18   61  VSS25 SCONN288_DDR506112002KQ-SCONN288_DDR506112002KQ,SMA   I143 @T6G_MB_LIB.T6G(SCH_1):PAGE93
   J18   63  VSS26 SCONN288_DDR506112002KQ-SCONN288_DDR506112002KQ,SMA   I143 @T6G_MB_LIB.T6G(SCH_1):PAGE93
   J18   65  VSS27 SCONN288_DDR506112002KQ-SCONN288_DDR506112002KQ,SMA   I143 @T6G_MB_LIB.T6G(SCH_1):PAGE93
   J18   67  VSS28 SCONN288_DDR506112002KQ-SCONN288_DDR506112002KQ,SMA   I143 @T6G_MB_LIB.T6G(SCH_1):PAGE93
   J18   69  VSS29 SCONN288_DDR506112002KQ-SCONN288_DDR506112002KQ,SMA   I143 @T6G_MB_LIB.T6G(SCH_1):PAGE93
   J18   71  VSS30 SCONN288_DDR506112002KQ-SCONN288_DDR506112002KQ,SMA   I143 @T6G_MB_LIB.T6G(SCH_1):PAGE93
   J18   73  VSS31 SCONN288_DDR506112002KQ-SCONN288_DDR506112002KQ,SMA   I143 @T6G_MB_LIB.T6G(SCH_1):PAGE93
   J18   75  VSS32 SCONN288_DDR506112002KQ-SCONN288_DDR506112002KQ,SMA   I143 @T6G_MB_LIB.T6G(SCH_1):PAGE93
   J18   77  VSS33 SCONN288_DDR506112002KQ-SCONN288_DDR506112002KQ,SMA   I143 @T6G_MB_LIB.T6G(SCH_1):PAGE93
   J18   79  VSS34 SCONN288_DDR506112002KQ-SCONN288_DDR506112002KQ,SMA   I143 @T6G_MB_LIB.T6G(SCH_1):PAGE93
   J18   81  VSS35 SCONN288_DDR506112002KQ-SCONN288_DDR506112002KQ,SMA   I143 @T6G_MB_LIB.T6G(SCH_1):PAGE93
   J18   83  VSS36 SCONN288_DDR506112002KQ-SCONN288_DDR506112002KQ,SMA   I143 @T6G_MB_LIB.T6G(SCH_1):PAGE93
   J18   85  VSS37 SCONN288_DDR506112002KQ-SCONN288_DDR506112002KQ,SMA   I143 @T6G_MB_LIB.T6G(SCH_1):PAGE93
   J18   88  VSS38 SCONN288_DDR506112002KQ-SCONN288_DDR506112002KQ,SMA   I143 @T6G_MB_LIB.T6G(SCH_1):PAGE93
   J18   90  VSS39 SCONN288_DDR506112002KQ-SCONN288_DDR506112002KQ,SMA   I143 @T6G_MB_LIB.T6G(SCH_1):PAGE93
   J18   92  VSS40 SCONN288_DDR506112002KQ-SCONN288_DDR506112002KQ,SMA   I143 @T6G_MB_LIB.T6G(SCH_1):PAGE93
   J18   95  VSS41 SCONN288_DDR506112002KQ-SCONN288_DDR506112002KQ,SMA   I143 @T6G_MB_LIB.T6G(SCH_1):PAGE93
   J18   97  VSS42 SCONN288_DDR506112002KQ-SCONN288_DDR506112002KQ,SMA   I143 @T6G_MB_LIB.T6G(SCH_1):PAGE93
   J18   99  VSS43 SCONN288_DDR506112002KQ-SCONN288_DDR506112002KQ,SMA   I143 @T6G_MB_LIB.T6G(SCH_1):PAGE93
   J18  101  VSS44 SCONN288_DDR506112002KQ-SCONN288_DDR506112002KQ,SMA   I143 @T6G_MB_LIB.T6G(SCH_1):PAGE93
   J18  103  VSS45 SCONN288_DDR506112002KQ-SCONN288_DDR506112002KQ,SMA   I143 @T6G_MB_LIB.T6G(SCH_1):PAGE93
   J18  106  VSS46 SCONN288_DDR506112002KQ-SCONN288_DDR506112002KQ,SMA   I143 @T6G_MB_LIB.T6G(SCH_1):PAGE93
   J18  108  VSS47 SCONN288_DDR506112002KQ-SCONN288_DDR506112002KQ,SMA   I143 @T6G_MB_LIB.T6G(SCH_1):PAGE93
   J18  110  VSS48 SCONN288_DDR506112002KQ-SCONN288_DDR506112002KQ,SMA   I143 @T6G_MB_LIB.T6G(SCH_1):PAGE93
   J18  112  VSS49 SCONN288_DDR506112002KQ-SCONN288_DDR506112002KQ,SMA   I143 @T6G_MB_LIB.T6G(SCH_1):PAGE93
   J18  114  VSS50 SCONN288_DDR506112002KQ-SCONN288_DDR506112002KQ,SMA   I143 @T6G_MB_LIB.T6G(SCH_1):PAGE93
   J18  117  VSS51 SCONN288_DDR506112002KQ-SCONN288_DDR506112002KQ,SMA   I143 @T6G_MB_LIB.T6G(SCH_1):PAGE93
   J18  119  VSS52 SCONN288_DDR506112002KQ-SCONN288_DDR506112002KQ,SMA   I143 @T6G_MB_LIB.T6G(SCH_1):PAGE93
   J18  121  VSS53 SCONN288_DDR506112002KQ-SCONN288_DDR506112002KQ,SMA   I143 @T6G_MB_LIB.T6G(SCH_1):PAGE93
   J18  123  VSS54 SCONN288_DDR506112002KQ-SCONN288_DDR506112002KQ,SMA   I143 @T6G_MB_LIB.T6G(SCH_1):PAGE93
   J18  125  VSS55 SCONN288_DDR506112002KQ-SCONN288_DDR506112002KQ,SMA   I143 @T6G_MB_LIB.T6G(SCH_1):PAGE93
   J18  128  VSS56 SCONN288_DDR506112002KQ-SCONN288_DDR506112002KQ,SMA   I143 @T6G_MB_LIB.T6G(SCH_1):PAGE93
   J18  130  VSS57 SCONN288_DDR506112002KQ-SCONN288_DDR506112002KQ,SMA   I143 @T6G_MB_LIB.T6G(SCH_1):PAGE93
   J18  132  VSS58 SCONN288_DDR506112002KQ-SCONN288_DDR506112002KQ,SMA   I143 @T6G_MB_LIB.T6G(SCH_1):PAGE93
   J18  134  VSS59 SCONN288_DDR506112002KQ-SCONN288_DDR506112002KQ,SMA   I143 @T6G_MB_LIB.T6G(SCH_1):PAGE93
   J18  136  VSS60 SCONN288_DDR506112002KQ-SCONN288_DDR506112002KQ,SMA   I143 @T6G_MB_LIB.T6G(SCH_1):PAGE93
   J18  139  VSS61 SCONN288_DDR506112002KQ-SCONN288_DDR506112002KQ,SMA   I143 @T6G_MB_LIB.T6G(SCH_1):PAGE93
   J18  141  VSS62 SCONN288_DDR506112002KQ-SCONN288_DDR506112002KQ,SMA   I143 @T6G_MB_LIB.T6G(SCH_1):PAGE93
   J18  143  VSS63 SCONN288_DDR506112002KQ-SCONN288_DDR506112002KQ,SMA   I143 @T6G_MB_LIB.T6G(SCH_1):PAGE93
   J18  151  VSS64 SCONN288_DDR506112002KQ-SCONN288_DDR506112002KQ,SMA   I143 @T6G_MB_LIB.T6G(SCH_1):PAGE93
   J18  153  VSS65 SCONN288_DDR506112002KQ-SCONN288_DDR506112002KQ,SMA   I143 @T6G_MB_LIB.T6G(SCH_1):PAGE93
   J18  155  VSS66 SCONN288_DDR506112002KQ-SCONN288_DDR506112002KQ,SMA   I143 @T6G_MB_LIB.T6G(SCH_1):PAGE93
   J18  158  VSS67 SCONN288_DDR506112002KQ-SCONN288_DDR506112002KQ,SMA   I143 @T6G_MB_LIB.T6G(SCH_1):PAGE93
   J18  160  VSS68 SCONN288_DDR506112002KQ-SCONN288_DDR506112002KQ,SMA   I143 @T6G_MB_LIB.T6G(SCH_1):PAGE93
   J18  162  VSS69 SCONN288_DDR506112002KQ-SCONN288_DDR506112002KQ,SMA   I143 @T6G_MB_LIB.T6G(SCH_1):PAGE93
   J18  164  VSS70 SCONN288_DDR506112002KQ-SCONN288_DDR506112002KQ,SMA   I143 @T6G_MB_LIB.T6G(SCH_1):PAGE93
   J18  166  VSS71 SCONN288_DDR506112002KQ-SCONN288_DDR506112002KQ,SMA   I143 @T6G_MB_LIB.T6G(SCH_1):PAGE93
   J18  169  VSS72 SCONN288_DDR506112002KQ-SCONN288_DDR506112002KQ,SMA   I143 @T6G_MB_LIB.T6G(SCH_1):PAGE93
   J18  171  VSS73 SCONN288_DDR506112002KQ-SCONN288_DDR506112002KQ,SMA   I143 @T6G_MB_LIB.T6G(SCH_1):PAGE93
   J18  173  VSS74 SCONN288_DDR506112002KQ-SCONN288_DDR506112002KQ,SMA   I143 @T6G_MB_LIB.T6G(SCH_1):PAGE93
   J18  175  VSS75 SCONN288_DDR506112002KQ-SCONN288_DDR506112002KQ,SMA   I143 @T6G_MB_LIB.T6G(SCH_1):PAGE93
   J18  177  VSS76 SCONN288_DDR506112002KQ-SCONN288_DDR506112002KQ,SMA   I143 @T6G_MB_LIB.T6G(SCH_1):PAGE93
   J18  180  VSS77 SCONN288_DDR506112002KQ-SCONN288_DDR506112002KQ,SMA   I143 @T6G_MB_LIB.T6G(SCH_1):PAGE93
   J18  182  VSS78 SCONN288_DDR506112002KQ-SCONN288_DDR506112002KQ,SMA   I143 @T6G_MB_LIB.T6G(SCH_1):PAGE93
   J18  184  VSS79 SCONN288_DDR506112002KQ-SCONN288_DDR506112002KQ,SMA   I143 @T6G_MB_LIB.T6G(SCH_1):PAGE93
   J18  186  VSS80 SCONN288_DDR506112002KQ-SCONN288_DDR506112002KQ,SMA   I143 @T6G_MB_LIB.T6G(SCH_1):PAGE93
   J18  188  VSS81 SCONN288_DDR506112002KQ-SCONN288_DDR506112002KQ,SMA   I143 @T6G_MB_LIB.T6G(SCH_1):PAGE93
   J18  191  VSS82 SCONN288_DDR506112002KQ-SCONN288_DDR506112002KQ,SMA   I143 @T6G_MB_LIB.T6G(SCH_1):PAGE93
   J18  193  VSS83 SCONN288_DDR506112002KQ-SCONN288_DDR506112002KQ,SMA   I143 @T6G_MB_LIB.T6G(SCH_1):PAGE93
   J18  195  VSS84 SCONN288_DDR506112002KQ-SCONN288_DDR506112002KQ,SMA   I143 @T6G_MB_LIB.T6G(SCH_1):PAGE93
   J18  197  VSS85 SCONN288_DDR506112002KQ-SCONN288_DDR506112002KQ,SMA   I143 @T6G_MB_LIB.T6G(SCH_1):PAGE93
   J18  199  VSS86 SCONN288_DDR506112002KQ-SCONN288_DDR506112002KQ,SMA   I143 @T6G_MB_LIB.T6G(SCH_1):PAGE93
   J18  202  VSS87 SCONN288_DDR506112002KQ-SCONN288_DDR506112002KQ,SMA   I143 @T6G_MB_LIB.T6G(SCH_1):PAGE93
   J18  204  VSS88 SCONN288_DDR506112002KQ-SCONN288_DDR506112002KQ,SMA   I143 @T6G_MB_LIB.T6G(SCH_1):PAGE93
   J18  206  VSS89 SCONN288_DDR506112002KQ-SCONN288_DDR506112002KQ,SMA   I143 @T6G_MB_LIB.T6G(SCH_1):PAGE93
   J18  208  VSS90 SCONN288_DDR506112002KQ-SCONN288_DDR506112002KQ,SMA   I143 @T6G_MB_LIB.T6G(SCH_1):PAGE93
   J18  210  VSS91 SCONN288_DDR506112002KQ-SCONN288_DDR506112002KQ,SMA   I143 @T6G_MB_LIB.T6G(SCH_1):PAGE93
   J18  212  VSS92 SCONN288_DDR506112002KQ-SCONN288_DDR506112002KQ,SMA   I143 @T6G_MB_LIB.T6G(SCH_1):PAGE93
   J18  214  VSS93 SCONN288_DDR506112002KQ-SCONN288_DDR506112002KQ,SMA   I143 @T6G_MB_LIB.T6G(SCH_1):PAGE93
   J18  216  VSS94 SCONN288_DDR506112002KQ-SCONN288_DDR506112002KQ,SMA   I143 @T6G_MB_LIB.T6G(SCH_1):PAGE93
   J18  219  VSS95 SCONN288_DDR506112002KQ-SCONN288_DDR506112002KQ,SMA   I143 @T6G_MB_LIB.T6G(SCH_1):PAGE93
   J18  222  VSS96 SCONN288_DDR506112002KQ-SCONN288_DDR506112002KQ,SMA   I143 @T6G_MB_LIB.T6G(SCH_1):PAGE93
   J18  224  VSS97 SCONN288_DDR506112002KQ-SCONN288_DDR506112002KQ,SMA   I143 @T6G_MB_LIB.T6G(SCH_1):PAGE93
   J18  226  VSS98 SCONN288_DDR506112002KQ-SCONN288_DDR506112002KQ,SMA   I143 @T6G_MB_LIB.T6G(SCH_1):PAGE93
   J18  228  VSS99 SCONN288_DDR506112002KQ-SCONN288_DDR506112002KQ,SMA   I143 @T6G_MB_LIB.T6G(SCH_1):PAGE93
   J18  230 VSS100 SCONN288_DDR506112002KQ-SCONN288_DDR506112002KQ,SMA   I143 @T6G_MB_LIB.T6G(SCH_1):PAGE93
   J18  233 VSS101 SCONN288_DDR506112002KQ-SCONN288_DDR506112002KQ,SMA   I143 @T6G_MB_LIB.T6G(SCH_1):PAGE93
   J18  235 VSS102 SCONN288_DDR506112002KQ-SCONN288_DDR506112002KQ,SMA   I143 @T6G_MB_LIB.T6G(SCH_1):PAGE93
   J18  237 VSS103 SCONN288_DDR506112002KQ-SCONN288_DDR506112002KQ,SMA   I143 @T6G_MB_LIB.T6G(SCH_1):PAGE93
   J18  240 VSS104 SCONN288_DDR506112002KQ-SCONN288_DDR506112002KQ,SMA   I143 @T6G_MB_LIB.T6G(SCH_1):PAGE93
   J18  242 VSS105 SCONN288_DDR506112002KQ-SCONN288_DDR506112002KQ,SMA   I143 @T6G_MB_LIB.T6G(SCH_1):PAGE93
   J18  244 VSS106 SCONN288_DDR506112002KQ-SCONN288_DDR506112002KQ,SMA   I143 @T6G_MB_LIB.T6G(SCH_1):PAGE93
   J18  246 VSS107 SCONN288_DDR506112002KQ-SCONN288_DDR506112002KQ,SMA   I143 @T6G_MB_LIB.T6G(SCH_1):PAGE93
   J18  248 VSS108 SCONN288_DDR506112002KQ-SCONN288_DDR506112002KQ,SMA   I143 @T6G_MB_LIB.T6G(SCH_1):PAGE93
   J18  251 VSS109 SCONN288_DDR506112002KQ-SCONN288_DDR506112002KQ,SMA   I143 @T6G_MB_LIB.T6G(SCH_1):PAGE93
   J18  253 VSS110 SCONN288_DDR506112002KQ-SCONN288_DDR506112002KQ,SMA   I143 @T6G_MB_LIB.T6G(SCH_1):PAGE93
   J18  255 VSS111 SCONN288_DDR506112002KQ-SCONN288_DDR506112002KQ,SMA   I143 @T6G_MB_LIB.T6G(SCH_1):PAGE93
   J18  257 VSS112 SCONN288_DDR506112002KQ-SCONN288_DDR506112002KQ,SMA   I143 @T6G_MB_LIB.T6G(SCH_1):PAGE93
   J18  259 VSS113 SCONN288_DDR506112002KQ-SCONN288_DDR506112002KQ,SMA   I143 @T6G_MB_LIB.T6G(SCH_1):PAGE93
   J18  262 VSS114 SCONN288_DDR506112002KQ-SCONN288_DDR506112002KQ,SMA   I143 @T6G_MB_LIB.T6G(SCH_1):PAGE93
   J18  264 VSS115 SCONN288_DDR506112002KQ-SCONN288_DDR506112002KQ,SMA   I143 @T6G_MB_LIB.T6G(SCH_1):PAGE93
   J18  266 VSS116 SCONN288_DDR506112002KQ-SCONN288_DDR506112002KQ,SMA   I143 @T6G_MB_LIB.T6G(SCH_1):PAGE93
   J18  268 VSS117 SCONN288_DDR506112002KQ-SCONN288_DDR506112002KQ,SMA   I143 @T6G_MB_LIB.T6G(SCH_1):PAGE93
   J18  270 VSS118 SCONN288_DDR506112002KQ-SCONN288_DDR506112002KQ,SMA   I143 @T6G_MB_LIB.T6G(SCH_1):PAGE93
   J18  273 VSS119 SCONN288_DDR506112002KQ-SCONN288_DDR506112002KQ,SMA   I143 @T6G_MB_LIB.T6G(SCH_1):PAGE93
   J18  275 VSS120 SCONN288_DDR506112002KQ-SCONN288_DDR506112002KQ,SMA   I143 @T6G_MB_LIB.T6G(SCH_1):PAGE93
   J18  277 VSS121 SCONN288_DDR506112002KQ-SCONN288_DDR506112002KQ,SMA   I143 @T6G_MB_LIB.T6G(SCH_1):PAGE93
   J18  279 VSS122 SCONN288_DDR506112002KQ-SCONN288_DDR506112002KQ,SMA   I143 @T6G_MB_LIB.T6G(SCH_1):PAGE93
   J18  281 VSS123 SCONN288_DDR506112002KQ-SCONN288_DDR506112002KQ,SMA   I143 @T6G_MB_LIB.T6G(SCH_1):PAGE93
   J18  284 VSS124 SCONN288_DDR506112002KQ-SCONN288_DDR506112002KQ,SMA   I143 @T6G_MB_LIB.T6G(SCH_1):PAGE93
   J18  286 VSS125 SCONN288_DDR506112002KQ-SCONN288_DDR506112002KQ,SMA   I143 @T6G_MB_LIB.T6G(SCH_1):PAGE93
   J18  288 VSS126 SCONN288_DDR506112002KQ-SCONN288_DDR506112002KQ,SMA   I143 @T6G_MB_LIB.T6G(SCH_1):PAGE93
  C120    2      B Q_CAP_0402-0.1UF,25V,10%,X7R,CH4104K1B00   I185 @T6G_MB_LIB.T6G(SCH_1):PAGE93
  C162    2      B Q_CAP_C0805-10UF,25V,10%,X6S,CH6104KEA00   I238 @T6G_MB_LIB.T6G(SCH_1):PAGE93
  C163    2      B Q_CAP_C0805-10UF,25V,10%,X6S,CH6104KEA00   I239 @T6G_MB_LIB.T6G(SCH_1):PAGE93
  R767    2      B Q_RES_0402LF-35.7K,1%,1/16W,CHIP,CS33572FB01   I129 @T6G_MB_LIB.T6G(SCH_1):PAGE94
   J68   G1     G1 SCONN288_DDR506112002KQ-SCONN288_DDR506112002KQ,SMA   I177 @T6G_MB_LIB.T6G(SCH_1):PAGE94
   J68   G2     G2 SCONN288_DDR506112002KQ-SCONN288_DDR506112002KQ,SMA   I177 @T6G_MB_LIB.T6G(SCH_1):PAGE94
   J68   G3     G3 SCONN288_DDR506112002KQ-SCONN288_DDR506112002KQ,SMA   I177 @T6G_MB_LIB.T6G(SCH_1):PAGE94
   J68    6   VSS0 SCONN288_DDR506112002KQ-SCONN288_DDR506112002KQ,SMA   I177 @T6G_MB_LIB.T6G(SCH_1):PAGE94
   J68    8   VSS1 SCONN288_DDR506112002KQ-SCONN288_DDR506112002KQ,SMA   I177 @T6G_MB_LIB.T6G(SCH_1):PAGE94
   J68   10   VSS2 SCONN288_DDR506112002KQ-SCONN288_DDR506112002KQ,SMA   I177 @T6G_MB_LIB.T6G(SCH_1):PAGE94
   J68   13   VSS3 SCONN288_DDR506112002KQ-SCONN288_DDR506112002KQ,SMA   I177 @T6G_MB_LIB.T6G(SCH_1):PAGE94
   J68   15   VSS4 SCONN288_DDR506112002KQ-SCONN288_DDR506112002KQ,SMA   I177 @T6G_MB_LIB.T6G(SCH_1):PAGE94
   J68   17   VSS5 SCONN288_DDR506112002KQ-SCONN288_DDR506112002KQ,SMA   I177 @T6G_MB_LIB.T6G(SCH_1):PAGE94
   J68   19   VSS6 SCONN288_DDR506112002KQ-SCONN288_DDR506112002KQ,SMA   I177 @T6G_MB_LIB.T6G(SCH_1):PAGE94
   J68   21   VSS7 SCONN288_DDR506112002KQ-SCONN288_DDR506112002KQ,SMA   I177 @T6G_MB_LIB.T6G(SCH_1):PAGE94
   J68   24   VSS8 SCONN288_DDR506112002KQ-SCONN288_DDR506112002KQ,SMA   I177 @T6G_MB_LIB.T6G(SCH_1):PAGE94
   J68   26   VSS9 SCONN288_DDR506112002KQ-SCONN288_DDR506112002KQ,SMA   I177 @T6G_MB_LIB.T6G(SCH_1):PAGE94
   J68   28  VSS10 SCONN288_DDR506112002KQ-SCONN288_DDR506112002KQ,SMA   I177 @T6G_MB_LIB.T6G(SCH_1):PAGE94
   J68   30  VSS11 SCONN288_DDR506112002KQ-SCONN288_DDR506112002KQ,SMA   I177 @T6G_MB_LIB.T6G(SCH_1):PAGE94
   J68   32  VSS12 SCONN288_DDR506112002KQ-SCONN288_DDR506112002KQ,SMA   I177 @T6G_MB_LIB.T6G(SCH_1):PAGE94
   J68   35  VSS13 SCONN288_DDR506112002KQ-SCONN288_DDR506112002KQ,SMA   I177 @T6G_MB_LIB.T6G(SCH_1):PAGE94
   J68   37  VSS14 SCONN288_DDR506112002KQ-SCONN288_DDR506112002KQ,SMA   I177 @T6G_MB_LIB.T6G(SCH_1):PAGE94
   J68   39  VSS15 SCONN288_DDR506112002KQ-SCONN288_DDR506112002KQ,SMA   I177 @T6G_MB_LIB.T6G(SCH_1):PAGE94
   J68   41  VSS16 SCONN288_DDR506112002KQ-SCONN288_DDR506112002KQ,SMA   I177 @T6G_MB_LIB.T6G(SCH_1):PAGE94
   J68   43  VSS17 SCONN288_DDR506112002KQ-SCONN288_DDR506112002KQ,SMA   I177 @T6G_MB_LIB.T6G(SCH_1):PAGE94
   J68   46  VSS18 SCONN288_DDR506112002KQ-SCONN288_DDR506112002KQ,SMA   I177 @T6G_MB_LIB.T6G(SCH_1):PAGE94
   J68   48  VSS19 SCONN288_DDR506112002KQ-SCONN288_DDR506112002KQ,SMA   I177 @T6G_MB_LIB.T6G(SCH_1):PAGE94
   J68   50  VSS20 SCONN288_DDR506112002KQ-SCONN288_DDR506112002KQ,SMA   I177 @T6G_MB_LIB.T6G(SCH_1):PAGE94
   J68   52  VSS21 SCONN288_DDR506112002KQ-SCONN288_DDR506112002KQ,SMA   I177 @T6G_MB_LIB.T6G(SCH_1):PAGE94
   J68   54  VSS22 SCONN288_DDR506112002KQ-SCONN288_DDR506112002KQ,SMA   I177 @T6G_MB_LIB.T6G(SCH_1):PAGE94
   J68   57  VSS23 SCONN288_DDR506112002KQ-SCONN288_DDR506112002KQ,SMA   I177 @T6G_MB_LIB.T6G(SCH_1):PAGE94
   J68   59  VSS24 SCONN288_DDR506112002KQ-SCONN288_DDR506112002KQ,SMA   I177 @T6G_MB_LIB.T6G(SCH_1):PAGE94
   J68   61  VSS25 SCONN288_DDR506112002KQ-SCONN288_DDR506112002KQ,SMA   I177 @T6G_MB_LIB.T6G(SCH_1):PAGE94
   J68   63  VSS26 SCONN288_DDR506112002KQ-SCONN288_DDR506112002KQ,SMA   I177 @T6G_MB_LIB.T6G(SCH_1):PAGE94
   J68   65  VSS27 SCONN288_DDR506112002KQ-SCONN288_DDR506112002KQ,SMA   I177 @T6G_MB_LIB.T6G(SCH_1):PAGE94
   J68   67  VSS28 SCONN288_DDR506112002KQ-SCONN288_DDR506112002KQ,SMA   I177 @T6G_MB_LIB.T6G(SCH_1):PAGE94
   J68   69  VSS29 SCONN288_DDR506112002KQ-SCONN288_DDR506112002KQ,SMA   I177 @T6G_MB_LIB.T6G(SCH_1):PAGE94
   J68   71  VSS30 SCONN288_DDR506112002KQ-SCONN288_DDR506112002KQ,SMA   I177 @T6G_MB_LIB.T6G(SCH_1):PAGE94
   J68   73  VSS31 SCONN288_DDR506112002KQ-SCONN288_DDR506112002KQ,SMA   I177 @T6G_MB_LIB.T6G(SCH_1):PAGE94
   J68   75  VSS32 SCONN288_DDR506112002KQ-SCONN288_DDR506112002KQ,SMA   I177 @T6G_MB_LIB.T6G(SCH_1):PAGE94
   J68   77  VSS33 SCONN288_DDR506112002KQ-SCONN288_DDR506112002KQ,SMA   I177 @T6G_MB_LIB.T6G(SCH_1):PAGE94
   J68   79  VSS34 SCONN288_DDR506112002KQ-SCONN288_DDR506112002KQ,SMA   I177 @T6G_MB_LIB.T6G(SCH_1):PAGE94
   J68   81  VSS35 SCONN288_DDR506112002KQ-SCONN288_DDR506112002KQ,SMA   I177 @T6G_MB_LIB.T6G(SCH_1):PAGE94
   J68   83  VSS36 SCONN288_DDR506112002KQ-SCONN288_DDR506112002KQ,SMA   I177 @T6G_MB_LIB.T6G(SCH_1):PAGE94
   J68   85  VSS37 SCONN288_DDR506112002KQ-SCONN288_DDR506112002KQ,SMA   I177 @T6G_MB_LIB.T6G(SCH_1):PAGE94
   J68   88  VSS38 SCONN288_DDR506112002KQ-SCONN288_DDR506112002KQ,SMA   I177 @T6G_MB_LIB.T6G(SCH_1):PAGE94
   J68   90  VSS39 SCONN288_DDR506112002KQ-SCONN288_DDR506112002KQ,SMA   I177 @T6G_MB_LIB.T6G(SCH_1):PAGE94
   J68   92  VSS40 SCONN288_DDR506112002KQ-SCONN288_DDR506112002KQ,SMA   I177 @T6G_MB_LIB.T6G(SCH_1):PAGE94
   J68   95  VSS41 SCONN288_DDR506112002KQ-SCONN288_DDR506112002KQ,SMA   I177 @T6G_MB_LIB.T6G(SCH_1):PAGE94
   J68   97  VSS42 SCONN288_DDR506112002KQ-SCONN288_DDR506112002KQ,SMA   I177 @T6G_MB_LIB.T6G(SCH_1):PAGE94
   J68   99  VSS43 SCONN288_DDR506112002KQ-SCONN288_DDR506112002KQ,SMA   I177 @T6G_MB_LIB.T6G(SCH_1):PAGE94
   J68  101  VSS44 SCONN288_DDR506112002KQ-SCONN288_DDR506112002KQ,SMA   I177 @T6G_MB_LIB.T6G(SCH_1):PAGE94
   J68  103  VSS45 SCONN288_DDR506112002KQ-SCONN288_DDR506112002KQ,SMA   I177 @T6G_MB_LIB.T6G(SCH_1):PAGE94
   J68  106  VSS46 SCONN288_DDR506112002KQ-SCONN288_DDR506112002KQ,SMA   I177 @T6G_MB_LIB.T6G(SCH_1):PAGE94
   J68  108  VSS47 SCONN288_DDR506112002KQ-SCONN288_DDR506112002KQ,SMA   I177 @T6G_MB_LIB.T6G(SCH_1):PAGE94
   J68  110  VSS48 SCONN288_DDR506112002KQ-SCONN288_DDR506112002KQ,SMA   I177 @T6G_MB_LIB.T6G(SCH_1):PAGE94
   J68  112  VSS49 SCONN288_DDR506112002KQ-SCONN288_DDR506112002KQ,SMA   I177 @T6G_MB_LIB.T6G(SCH_1):PAGE94
   J68  114  VSS50 SCONN288_DDR506112002KQ-SCONN288_DDR506112002KQ,SMA   I177 @T6G_MB_LIB.T6G(SCH_1):PAGE94
   J68  117  VSS51 SCONN288_DDR506112002KQ-SCONN288_DDR506112002KQ,SMA   I177 @T6G_MB_LIB.T6G(SCH_1):PAGE94
   J68  119  VSS52 SCONN288_DDR506112002KQ-SCONN288_DDR506112002KQ,SMA   I177 @T6G_MB_LIB.T6G(SCH_1):PAGE94
   J68  121  VSS53 SCONN288_DDR506112002KQ-SCONN288_DDR506112002KQ,SMA   I177 @T6G_MB_LIB.T6G(SCH_1):PAGE94
   J68  123  VSS54 SCONN288_DDR506112002KQ-SCONN288_DDR506112002KQ,SMA   I177 @T6G_MB_LIB.T6G(SCH_1):PAGE94
   J68  125  VSS55 SCONN288_DDR506112002KQ-SCONN288_DDR506112002KQ,SMA   I177 @T6G_MB_LIB.T6G(SCH_1):PAGE94
   J68  128  VSS56 SCONN288_DDR506112002KQ-SCONN288_DDR506112002KQ,SMA   I177 @T6G_MB_LIB.T6G(SCH_1):PAGE94
   J68  130  VSS57 SCONN288_DDR506112002KQ-SCONN288_DDR506112002KQ,SMA   I177 @T6G_MB_LIB.T6G(SCH_1):PAGE94
   J68  132  VSS58 SCONN288_DDR506112002KQ-SCONN288_DDR506112002KQ,SMA   I177 @T6G_MB_LIB.T6G(SCH_1):PAGE94
   J68  134  VSS59 SCONN288_DDR506112002KQ-SCONN288_DDR506112002KQ,SMA   I177 @T6G_MB_LIB.T6G(SCH_1):PAGE94
   J68  136  VSS60 SCONN288_DDR506112002KQ-SCONN288_DDR506112002KQ,SMA   I177 @T6G_MB_LIB.T6G(SCH_1):PAGE94
   J68  139  VSS61 SCONN288_DDR506112002KQ-SCONN288_DDR506112002KQ,SMA   I177 @T6G_MB_LIB.T6G(SCH_1):PAGE94
   J68  141  VSS62 SCONN288_DDR506112002KQ-SCONN288_DDR506112002KQ,SMA   I177 @T6G_MB_LIB.T6G(SCH_1):PAGE94
   J68  143  VSS63 SCONN288_DDR506112002KQ-SCONN288_DDR506112002KQ,SMA   I177 @T6G_MB_LIB.T6G(SCH_1):PAGE94
   J68  151  VSS64 SCONN288_DDR506112002KQ-SCONN288_DDR506112002KQ,SMA   I177 @T6G_MB_LIB.T6G(SCH_1):PAGE94
   J68  153  VSS65 SCONN288_DDR506112002KQ-SCONN288_DDR506112002KQ,SMA   I177 @T6G_MB_LIB.T6G(SCH_1):PAGE94
   J68  155  VSS66 SCONN288_DDR506112002KQ-SCONN288_DDR506112002KQ,SMA   I177 @T6G_MB_LIB.T6G(SCH_1):PAGE94
   J68  158  VSS67 SCONN288_DDR506112002KQ-SCONN288_DDR506112002KQ,SMA   I177 @T6G_MB_LIB.T6G(SCH_1):PAGE94
   J68  160  VSS68 SCONN288_DDR506112002KQ-SCONN288_DDR506112002KQ,SMA   I177 @T6G_MB_LIB.T6G(SCH_1):PAGE94
   J68  162  VSS69 SCONN288_DDR506112002KQ-SCONN288_DDR506112002KQ,SMA   I177 @T6G_MB_LIB.T6G(SCH_1):PAGE94
   J68  164  VSS70 SCONN288_DDR506112002KQ-SCONN288_DDR506112002KQ,SMA   I177 @T6G_MB_LIB.T6G(SCH_1):PAGE94
   J68  166  VSS71 SCONN288_DDR506112002KQ-SCONN288_DDR506112002KQ,SMA   I177 @T6G_MB_LIB.T6G(SCH_1):PAGE94
   J68  169  VSS72 SCONN288_DDR506112002KQ-SCONN288_DDR506112002KQ,SMA   I177 @T6G_MB_LIB.T6G(SCH_1):PAGE94
   J68  171  VSS73 SCONN288_DDR506112002KQ-SCONN288_DDR506112002KQ,SMA   I177 @T6G_MB_LIB.T6G(SCH_1):PAGE94
   J68  173  VSS74 SCONN288_DDR506112002KQ-SCONN288_DDR506112002KQ,SMA   I177 @T6G_MB_LIB.T6G(SCH_1):PAGE94
   J68  175  VSS75 SCONN288_DDR506112002KQ-SCONN288_DDR506112002KQ,SMA   I177 @T6G_MB_LIB.T6G(SCH_1):PAGE94
   J68  177  VSS76 SCONN288_DDR506112002KQ-SCONN288_DDR506112002KQ,SMA   I177 @T6G_MB_LIB.T6G(SCH_1):PAGE94
   J68  180  VSS77 SCONN288_DDR506112002KQ-SCONN288_DDR506112002KQ,SMA   I177 @T6G_MB_LIB.T6G(SCH_1):PAGE94
   J68  182  VSS78 SCONN288_DDR506112002KQ-SCONN288_DDR506112002KQ,SMA   I177 @T6G_MB_LIB.T6G(SCH_1):PAGE94
   J68  184  VSS79 SCONN288_DDR506112002KQ-SCONN288_DDR506112002KQ,SMA   I177 @T6G_MB_LIB.T6G(SCH_1):PAGE94
   J68  186  VSS80 SCONN288_DDR506112002KQ-SCONN288_DDR506112002KQ,SMA   I177 @T6G_MB_LIB.T6G(SCH_1):PAGE94
   J68  188  VSS81 SCONN288_DDR506112002KQ-SCONN288_DDR506112002KQ,SMA   I177 @T6G_MB_LIB.T6G(SCH_1):PAGE94
   J68  191  VSS82 SCONN288_DDR506112002KQ-SCONN288_DDR506112002KQ,SMA   I177 @T6G_MB_LIB.T6G(SCH_1):PAGE94
   J68  193  VSS83 SCONN288_DDR506112002KQ-SCONN288_DDR506112002KQ,SMA   I177 @T6G_MB_LIB.T6G(SCH_1):PAGE94
   J68  195  VSS84 SCONN288_DDR506112002KQ-SCONN288_DDR506112002KQ,SMA   I177 @T6G_MB_LIB.T6G(SCH_1):PAGE94
   J68  197  VSS85 SCONN288_DDR506112002KQ-SCONN288_DDR506112002KQ,SMA   I177 @T6G_MB_LIB.T6G(SCH_1):PAGE94
   J68  199  VSS86 SCONN288_DDR506112002KQ-SCONN288_DDR506112002KQ,SMA   I177 @T6G_MB_LIB.T6G(SCH_1):PAGE94
   J68  202  VSS87 SCONN288_DDR506112002KQ-SCONN288_DDR506112002KQ,SMA   I177 @T6G_MB_LIB.T6G(SCH_1):PAGE94
   J68  204  VSS88 SCONN288_DDR506112002KQ-SCONN288_DDR506112002KQ,SMA   I177 @T6G_MB_LIB.T6G(SCH_1):PAGE94
   J68  206  VSS89 SCONN288_DDR506112002KQ-SCONN288_DDR506112002KQ,SMA   I177 @T6G_MB_LIB.T6G(SCH_1):PAGE94
   J68  208  VSS90 SCONN288_DDR506112002KQ-SCONN288_DDR506112002KQ,SMA   I177 @T6G_MB_LIB.T6G(SCH_1):PAGE94
   J68  210  VSS91 SCONN288_DDR506112002KQ-SCONN288_DDR506112002KQ,SMA   I177 @T6G_MB_LIB.T6G(SCH_1):PAGE94
   J68  212  VSS92 SCONN288_DDR506112002KQ-SCONN288_DDR506112002KQ,SMA   I177 @T6G_MB_LIB.T6G(SCH_1):PAGE94
   J68  214  VSS93 SCONN288_DDR506112002KQ-SCONN288_DDR506112002KQ,SMA   I177 @T6G_MB_LIB.T6G(SCH_1):PAGE94
   J68  216  VSS94 SCONN288_DDR506112002KQ-SCONN288_DDR506112002KQ,SMA   I177 @T6G_MB_LIB.T6G(SCH_1):PAGE94
   J68  219  VSS95 SCONN288_DDR506112002KQ-SCONN288_DDR506112002KQ,SMA   I177 @T6G_MB_LIB.T6G(SCH_1):PAGE94
   J68  222  VSS96 SCONN288_DDR506112002KQ-SCONN288_DDR506112002KQ,SMA   I177 @T6G_MB_LIB.T6G(SCH_1):PAGE94
   J68  224  VSS97 SCONN288_DDR506112002KQ-SCONN288_DDR506112002KQ,SMA   I177 @T6G_MB_LIB.T6G(SCH_1):PAGE94
   J68  226  VSS98 SCONN288_DDR506112002KQ-SCONN288_DDR506112002KQ,SMA   I177 @T6G_MB_LIB.T6G(SCH_1):PAGE94
   J68  228  VSS99 SCONN288_DDR506112002KQ-SCONN288_DDR506112002KQ,SMA   I177 @T6G_MB_LIB.T6G(SCH_1):PAGE94
   J68  230 VSS100 SCONN288_DDR506112002KQ-SCONN288_DDR506112002KQ,SMA   I177 @T6G_MB_LIB.T6G(SCH_1):PAGE94
   J68  233 VSS101 SCONN288_DDR506112002KQ-SCONN288_DDR506112002KQ,SMA   I177 @T6G_MB_LIB.T6G(SCH_1):PAGE94
   J68  235 VSS102 SCONN288_DDR506112002KQ-SCONN288_DDR506112002KQ,SMA   I177 @T6G_MB_LIB.T6G(SCH_1):PAGE94
   J68  237 VSS103 SCONN288_DDR506112002KQ-SCONN288_DDR506112002KQ,SMA   I177 @T6G_MB_LIB.T6G(SCH_1):PAGE94
   J68  240 VSS104 SCONN288_DDR506112002KQ-SCONN288_DDR506112002KQ,SMA   I177 @T6G_MB_LIB.T6G(SCH_1):PAGE94
   J68  242 VSS105 SCONN288_DDR506112002KQ-SCONN288_DDR506112002KQ,SMA   I177 @T6G_MB_LIB.T6G(SCH_1):PAGE94
   J68  244 VSS106 SCONN288_DDR506112002KQ-SCONN288_DDR506112002KQ,SMA   I177 @T6G_MB_LIB.T6G(SCH_1):PAGE94
   J68  246 VSS107 SCONN288_DDR506112002KQ-SCONN288_DDR506112002KQ,SMA   I177 @T6G_MB_LIB.T6G(SCH_1):PAGE94
   J68  248 VSS108 SCONN288_DDR506112002KQ-SCONN288_DDR506112002KQ,SMA   I177 @T6G_MB_LIB.T6G(SCH_1):PAGE94
   J68  251 VSS109 SCONN288_DDR506112002KQ-SCONN288_DDR506112002KQ,SMA   I177 @T6G_MB_LIB.T6G(SCH_1):PAGE94
   J68  253 VSS110 SCONN288_DDR506112002KQ-SCONN288_DDR506112002KQ,SMA   I177 @T6G_MB_LIB.T6G(SCH_1):PAGE94
   J68  255 VSS111 SCONN288_DDR506112002KQ-SCONN288_DDR506112002KQ,SMA   I177 @T6G_MB_LIB.T6G(SCH_1):PAGE94
   J68  257 VSS112 SCONN288_DDR506112002KQ-SCONN288_DDR506112002KQ,SMA   I177 @T6G_MB_LIB.T6G(SCH_1):PAGE94
   J68  259 VSS113 SCONN288_DDR506112002KQ-SCONN288_DDR506112002KQ,SMA   I177 @T6G_MB_LIB.T6G(SCH_1):PAGE94
   J68  262 VSS114 SCONN288_DDR506112002KQ-SCONN288_DDR506112002KQ,SMA   I177 @T6G_MB_LIB.T6G(SCH_1):PAGE94
   J68  264 VSS115 SCONN288_DDR506112002KQ-SCONN288_DDR506112002KQ,SMA   I177 @T6G_MB_LIB.T6G(SCH_1):PAGE94
   J68  266 VSS116 SCONN288_DDR506112002KQ-SCONN288_DDR506112002KQ,SMA   I177 @T6G_MB_LIB.T6G(SCH_1):PAGE94
   J68  268 VSS117 SCONN288_DDR506112002KQ-SCONN288_DDR506112002KQ,SMA   I177 @T6G_MB_LIB.T6G(SCH_1):PAGE94
   J68  270 VSS118 SCONN288_DDR506112002KQ-SCONN288_DDR506112002KQ,SMA   I177 @T6G_MB_LIB.T6G(SCH_1):PAGE94
   J68  273 VSS119 SCONN288_DDR506112002KQ-SCONN288_DDR506112002KQ,SMA   I177 @T6G_MB_LIB.T6G(SCH_1):PAGE94
   J68  275 VSS120 SCONN288_DDR506112002KQ-SCONN288_DDR506112002KQ,SMA   I177 @T6G_MB_LIB.T6G(SCH_1):PAGE94
   J68  277 VSS121 SCONN288_DDR506112002KQ-SCONN288_DDR506112002KQ,SMA   I177 @T6G_MB_LIB.T6G(SCH_1):PAGE94
   J68  279 VSS122 SCONN288_DDR506112002KQ-SCONN288_DDR506112002KQ,SMA   I177 @T6G_MB_LIB.T6G(SCH_1):PAGE94
   J68  281 VSS123 SCONN288_DDR506112002KQ-SCONN288_DDR506112002KQ,SMA   I177 @T6G_MB_LIB.T6G(SCH_1):PAGE94
   J68  284 VSS124 SCONN288_DDR506112002KQ-SCONN288_DDR506112002KQ,SMA   I177 @T6G_MB_LIB.T6G(SCH_1):PAGE94
   J68  286 VSS125 SCONN288_DDR506112002KQ-SCONN288_DDR506112002KQ,SMA   I177 @T6G_MB_LIB.T6G(SCH_1):PAGE94
   J68  288 VSS126 SCONN288_DDR506112002KQ-SCONN288_DDR506112002KQ,SMA   I177 @T6G_MB_LIB.T6G(SCH_1):PAGE94
  C124    2      B Q_CAP_0402-0.1UF,25V,10%,X7R,CH4104K1B00   I185 @T6G_MB_LIB.T6G(SCH_1):PAGE94
  C165    2      B Q_CAP_C0805-10UF,25V,10%,X6S,CH6104KEA00   I238 @T6G_MB_LIB.T6G(SCH_1):PAGE94
  C166    2      B Q_CAP_C0805-10UF,25V,10%,X6S,CH6104KEA00   I239 @T6G_MB_LIB.T6G(SCH_1):PAGE94
  R768    2      B Q_RES_0402LF-54.9K,1%,1/16W,CHIP,CS35492FB03   I129 @T6G_MB_LIB.T6G(SCH_1):PAGE95
   J20   G1     G1 SCONN288_DDR506112002KQ-SCONN288_DDR506112002KQ,SMA   I177 @T6G_MB_LIB.T6G(SCH_1):PAGE95
   J20   G2     G2 SCONN288_DDR506112002KQ-SCONN288_DDR506112002KQ,SMA   I177 @T6G_MB_LIB.T6G(SCH_1):PAGE95
   J20   G3     G3 SCONN288_DDR506112002KQ-SCONN288_DDR506112002KQ,SMA   I177 @T6G_MB_LIB.T6G(SCH_1):PAGE95
   J20    6   VSS0 SCONN288_DDR506112002KQ-SCONN288_DDR506112002KQ,SMA   I177 @T6G_MB_LIB.T6G(SCH_1):PAGE95
   J20    8   VSS1 SCONN288_DDR506112002KQ-SCONN288_DDR506112002KQ,SMA   I177 @T6G_MB_LIB.T6G(SCH_1):PAGE95
   J20   10   VSS2 SCONN288_DDR506112002KQ-SCONN288_DDR506112002KQ,SMA   I177 @T6G_MB_LIB.T6G(SCH_1):PAGE95
   J20   13   VSS3 SCONN288_DDR506112002KQ-SCONN288_DDR506112002KQ,SMA   I177 @T6G_MB_LIB.T6G(SCH_1):PAGE95
   J20   15   VSS4 SCONN288_DDR506112002KQ-SCONN288_DDR506112002KQ,SMA   I177 @T6G_MB_LIB.T6G(SCH_1):PAGE95
   J20   17   VSS5 SCONN288_DDR506112002KQ-SCONN288_DDR506112002KQ,SMA   I177 @T6G_MB_LIB.T6G(SCH_1):PAGE95
   J20   19   VSS6 SCONN288_DDR506112002KQ-SCONN288_DDR506112002KQ,SMA   I177 @T6G_MB_LIB.T6G(SCH_1):PAGE95
   J20   21   VSS7 SCONN288_DDR506112002KQ-SCONN288_DDR506112002KQ,SMA   I177 @T6G_MB_LIB.T6G(SCH_1):PAGE95
   J20   24   VSS8 SCONN288_DDR506112002KQ-SCONN288_DDR506112002KQ,SMA   I177 @T6G_MB_LIB.T6G(SCH_1):PAGE95
   J20   26   VSS9 SCONN288_DDR506112002KQ-SCONN288_DDR506112002KQ,SMA   I177 @T6G_MB_LIB.T6G(SCH_1):PAGE95
   J20   28  VSS10 SCONN288_DDR506112002KQ-SCONN288_DDR506112002KQ,SMA   I177 @T6G_MB_LIB.T6G(SCH_1):PAGE95
   J20   30  VSS11 SCONN288_DDR506112002KQ-SCONN288_DDR506112002KQ,SMA   I177 @T6G_MB_LIB.T6G(SCH_1):PAGE95
   J20   32  VSS12 SCONN288_DDR506112002KQ-SCONN288_DDR506112002KQ,SMA   I177 @T6G_MB_LIB.T6G(SCH_1):PAGE95
   J20   35  VSS13 SCONN288_DDR506112002KQ-SCONN288_DDR506112002KQ,SMA   I177 @T6G_MB_LIB.T6G(SCH_1):PAGE95
   J20   37  VSS14 SCONN288_DDR506112002KQ-SCONN288_DDR506112002KQ,SMA   I177 @T6G_MB_LIB.T6G(SCH_1):PAGE95
   J20   39  VSS15 SCONN288_DDR506112002KQ-SCONN288_DDR506112002KQ,SMA   I177 @T6G_MB_LIB.T6G(SCH_1):PAGE95
   J20   41  VSS16 SCONN288_DDR506112002KQ-SCONN288_DDR506112002KQ,SMA   I177 @T6G_MB_LIB.T6G(SCH_1):PAGE95
   J20   43  VSS17 SCONN288_DDR506112002KQ-SCONN288_DDR506112002KQ,SMA   I177 @T6G_MB_LIB.T6G(SCH_1):PAGE95
   J20   46  VSS18 SCONN288_DDR506112002KQ-SCONN288_DDR506112002KQ,SMA   I177 @T6G_MB_LIB.T6G(SCH_1):PAGE95
   J20   48  VSS19 SCONN288_DDR506112002KQ-SCONN288_DDR506112002KQ,SMA   I177 @T6G_MB_LIB.T6G(SCH_1):PAGE95
   J20   50  VSS20 SCONN288_DDR506112002KQ-SCONN288_DDR506112002KQ,SMA   I177 @T6G_MB_LIB.T6G(SCH_1):PAGE95
   J20   52  VSS21 SCONN288_DDR506112002KQ-SCONN288_DDR506112002KQ,SMA   I177 @T6G_MB_LIB.T6G(SCH_1):PAGE95
   J20   54  VSS22 SCONN288_DDR506112002KQ-SCONN288_DDR506112002KQ,SMA   I177 @T6G_MB_LIB.T6G(SCH_1):PAGE95
   J20   57  VSS23 SCONN288_DDR506112002KQ-SCONN288_DDR506112002KQ,SMA   I177 @T6G_MB_LIB.T6G(SCH_1):PAGE95
   J20   59  VSS24 SCONN288_DDR506112002KQ-SCONN288_DDR506112002KQ,SMA   I177 @T6G_MB_LIB.T6G(SCH_1):PAGE95
   J20   61  VSS25 SCONN288_DDR506112002KQ-SCONN288_DDR506112002KQ,SMA   I177 @T6G_MB_LIB.T6G(SCH_1):PAGE95
   J20   63  VSS26 SCONN288_DDR506112002KQ-SCONN288_DDR506112002KQ,SMA   I177 @T6G_MB_LIB.T6G(SCH_1):PAGE95
   J20   65  VSS27 SCONN288_DDR506112002KQ-SCONN288_DDR506112002KQ,SMA   I177 @T6G_MB_LIB.T6G(SCH_1):PAGE95
   J20   67  VSS28 SCONN288_DDR506112002KQ-SCONN288_DDR506112002KQ,SMA   I177 @T6G_MB_LIB.T6G(SCH_1):PAGE95
   J20   69  VSS29 SCONN288_DDR506112002KQ-SCONN288_DDR506112002KQ,SMA   I177 @T6G_MB_LIB.T6G(SCH_1):PAGE95
   J20   71  VSS30 SCONN288_DDR506112002KQ-SCONN288_DDR506112002KQ,SMA   I177 @T6G_MB_LIB.T6G(SCH_1):PAGE95
   J20   73  VSS31 SCONN288_DDR506112002KQ-SCONN288_DDR506112002KQ,SMA   I177 @T6G_MB_LIB.T6G(SCH_1):PAGE95
   J20   75  VSS32 SCONN288_DDR506112002KQ-SCONN288_DDR506112002KQ,SMA   I177 @T6G_MB_LIB.T6G(SCH_1):PAGE95
   J20   77  VSS33 SCONN288_DDR506112002KQ-SCONN288_DDR506112002KQ,SMA   I177 @T6G_MB_LIB.T6G(SCH_1):PAGE95
   J20   79  VSS34 SCONN288_DDR506112002KQ-SCONN288_DDR506112002KQ,SMA   I177 @T6G_MB_LIB.T6G(SCH_1):PAGE95
   J20   81  VSS35 SCONN288_DDR506112002KQ-SCONN288_DDR506112002KQ,SMA   I177 @T6G_MB_LIB.T6G(SCH_1):PAGE95
   J20   83  VSS36 SCONN288_DDR506112002KQ-SCONN288_DDR506112002KQ,SMA   I177 @T6G_MB_LIB.T6G(SCH_1):PAGE95
   J20   85  VSS37 SCONN288_DDR506112002KQ-SCONN288_DDR506112002KQ,SMA   I177 @T6G_MB_LIB.T6G(SCH_1):PAGE95
   J20   88  VSS38 SCONN288_DDR506112002KQ-SCONN288_DDR506112002KQ,SMA   I177 @T6G_MB_LIB.T6G(SCH_1):PAGE95
   J20   90  VSS39 SCONN288_DDR506112002KQ-SCONN288_DDR506112002KQ,SMA   I177 @T6G_MB_LIB.T6G(SCH_1):PAGE95
   J20   92  VSS40 SCONN288_DDR506112002KQ-SCONN288_DDR506112002KQ,SMA   I177 @T6G_MB_LIB.T6G(SCH_1):PAGE95
   J20   95  VSS41 SCONN288_DDR506112002KQ-SCONN288_DDR506112002KQ,SMA   I177 @T6G_MB_LIB.T6G(SCH_1):PAGE95
   J20   97  VSS42 SCONN288_DDR506112002KQ-SCONN288_DDR506112002KQ,SMA   I177 @T6G_MB_LIB.T6G(SCH_1):PAGE95
   J20   99  VSS43 SCONN288_DDR506112002KQ-SCONN288_DDR506112002KQ,SMA   I177 @T6G_MB_LIB.T6G(SCH_1):PAGE95
   J20  101  VSS44 SCONN288_DDR506112002KQ-SCONN288_DDR506112002KQ,SMA   I177 @T6G_MB_LIB.T6G(SCH_1):PAGE95
   J20  103  VSS45 SCONN288_DDR506112002KQ-SCONN288_DDR506112002KQ,SMA   I177 @T6G_MB_LIB.T6G(SCH_1):PAGE95
   J20  106  VSS46 SCONN288_DDR506112002KQ-SCONN288_DDR506112002KQ,SMA   I177 @T6G_MB_LIB.T6G(SCH_1):PAGE95
   J20  108  VSS47 SCONN288_DDR506112002KQ-SCONN288_DDR506112002KQ,SMA   I177 @T6G_MB_LIB.T6G(SCH_1):PAGE95
   J20  110  VSS48 SCONN288_DDR506112002KQ-SCONN288_DDR506112002KQ,SMA   I177 @T6G_MB_LIB.T6G(SCH_1):PAGE95
   J20  112  VSS49 SCONN288_DDR506112002KQ-SCONN288_DDR506112002KQ,SMA   I177 @T6G_MB_LIB.T6G(SCH_1):PAGE95
   J20  114  VSS50 SCONN288_DDR506112002KQ-SCONN288_DDR506112002KQ,SMA   I177 @T6G_MB_LIB.T6G(SCH_1):PAGE95
   J20  117  VSS51 SCONN288_DDR506112002KQ-SCONN288_DDR506112002KQ,SMA   I177 @T6G_MB_LIB.T6G(SCH_1):PAGE95
   J20  119  VSS52 SCONN288_DDR506112002KQ-SCONN288_DDR506112002KQ,SMA   I177 @T6G_MB_LIB.T6G(SCH_1):PAGE95
   J20  121  VSS53 SCONN288_DDR506112002KQ-SCONN288_DDR506112002KQ,SMA   I177 @T6G_MB_LIB.T6G(SCH_1):PAGE95
   J20  123  VSS54 SCONN288_DDR506112002KQ-SCONN288_DDR506112002KQ,SMA   I177 @T6G_MB_LIB.T6G(SCH_1):PAGE95
   J20  125  VSS55 SCONN288_DDR506112002KQ-SCONN288_DDR506112002KQ,SMA   I177 @T6G_MB_LIB.T6G(SCH_1):PAGE95
   J20  128  VSS56 SCONN288_DDR506112002KQ-SCONN288_DDR506112002KQ,SMA   I177 @T6G_MB_LIB.T6G(SCH_1):PAGE95
   J20  130  VSS57 SCONN288_DDR506112002KQ-SCONN288_DDR506112002KQ,SMA   I177 @T6G_MB_LIB.T6G(SCH_1):PAGE95
   J20  132  VSS58 SCONN288_DDR506112002KQ-SCONN288_DDR506112002KQ,SMA   I177 @T6G_MB_LIB.T6G(SCH_1):PAGE95
   J20  134  VSS59 SCONN288_DDR506112002KQ-SCONN288_DDR506112002KQ,SMA   I177 @T6G_MB_LIB.T6G(SCH_1):PAGE95
   J20  136  VSS60 SCONN288_DDR506112002KQ-SCONN288_DDR506112002KQ,SMA   I177 @T6G_MB_LIB.T6G(SCH_1):PAGE95
   J20  139  VSS61 SCONN288_DDR506112002KQ-SCONN288_DDR506112002KQ,SMA   I177 @T6G_MB_LIB.T6G(SCH_1):PAGE95
   J20  141  VSS62 SCONN288_DDR506112002KQ-SCONN288_DDR506112002KQ,SMA   I177 @T6G_MB_LIB.T6G(SCH_1):PAGE95
   J20  143  VSS63 SCONN288_DDR506112002KQ-SCONN288_DDR506112002KQ,SMA   I177 @T6G_MB_LIB.T6G(SCH_1):PAGE95
   J20  151  VSS64 SCONN288_DDR506112002KQ-SCONN288_DDR506112002KQ,SMA   I177 @T6G_MB_LIB.T6G(SCH_1):PAGE95
   J20  153  VSS65 SCONN288_DDR506112002KQ-SCONN288_DDR506112002KQ,SMA   I177 @T6G_MB_LIB.T6G(SCH_1):PAGE95
   J20  155  VSS66 SCONN288_DDR506112002KQ-SCONN288_DDR506112002KQ,SMA   I177 @T6G_MB_LIB.T6G(SCH_1):PAGE95
   J20  158  VSS67 SCONN288_DDR506112002KQ-SCONN288_DDR506112002KQ,SMA   I177 @T6G_MB_LIB.T6G(SCH_1):PAGE95
   J20  160  VSS68 SCONN288_DDR506112002KQ-SCONN288_DDR506112002KQ,SMA   I177 @T6G_MB_LIB.T6G(SCH_1):PAGE95
   J20  162  VSS69 SCONN288_DDR506112002KQ-SCONN288_DDR506112002KQ,SMA   I177 @T6G_MB_LIB.T6G(SCH_1):PAGE95
   J20  164  VSS70 SCONN288_DDR506112002KQ-SCONN288_DDR506112002KQ,SMA   I177 @T6G_MB_LIB.T6G(SCH_1):PAGE95
   J20  166  VSS71 SCONN288_DDR506112002KQ-SCONN288_DDR506112002KQ,SMA   I177 @T6G_MB_LIB.T6G(SCH_1):PAGE95
   J20  169  VSS72 SCONN288_DDR506112002KQ-SCONN288_DDR506112002KQ,SMA   I177 @T6G_MB_LIB.T6G(SCH_1):PAGE95
   J20  171  VSS73 SCONN288_DDR506112002KQ-SCONN288_DDR506112002KQ,SMA   I177 @T6G_MB_LIB.T6G(SCH_1):PAGE95
   J20  173  VSS74 SCONN288_DDR506112002KQ-SCONN288_DDR506112002KQ,SMA   I177 @T6G_MB_LIB.T6G(SCH_1):PAGE95
   J20  175  VSS75 SCONN288_DDR506112002KQ-SCONN288_DDR506112002KQ,SMA   I177 @T6G_MB_LIB.T6G(SCH_1):PAGE95
   J20  177  VSS76 SCONN288_DDR506112002KQ-SCONN288_DDR506112002KQ,SMA   I177 @T6G_MB_LIB.T6G(SCH_1):PAGE95
   J20  180  VSS77 SCONN288_DDR506112002KQ-SCONN288_DDR506112002KQ,SMA   I177 @T6G_MB_LIB.T6G(SCH_1):PAGE95
   J20  182  VSS78 SCONN288_DDR506112002KQ-SCONN288_DDR506112002KQ,SMA   I177 @T6G_MB_LIB.T6G(SCH_1):PAGE95
   J20  184  VSS79 SCONN288_DDR506112002KQ-SCONN288_DDR506112002KQ,SMA   I177 @T6G_MB_LIB.T6G(SCH_1):PAGE95
   J20  186  VSS80 SCONN288_DDR506112002KQ-SCONN288_DDR506112002KQ,SMA   I177 @T6G_MB_LIB.T6G(SCH_1):PAGE95
   J20  188  VSS81 SCONN288_DDR506112002KQ-SCONN288_DDR506112002KQ,SMA   I177 @T6G_MB_LIB.T6G(SCH_1):PAGE95
   J20  191  VSS82 SCONN288_DDR506112002KQ-SCONN288_DDR506112002KQ,SMA   I177 @T6G_MB_LIB.T6G(SCH_1):PAGE95
   J20  193  VSS83 SCONN288_DDR506112002KQ-SCONN288_DDR506112002KQ,SMA   I177 @T6G_MB_LIB.T6G(SCH_1):PAGE95
   J20  195  VSS84 SCONN288_DDR506112002KQ-SCONN288_DDR506112002KQ,SMA   I177 @T6G_MB_LIB.T6G(SCH_1):PAGE95
   J20  197  VSS85 SCONN288_DDR506112002KQ-SCONN288_DDR506112002KQ,SMA   I177 @T6G_MB_LIB.T6G(SCH_1):PAGE95
   J20  199  VSS86 SCONN288_DDR506112002KQ-SCONN288_DDR506112002KQ,SMA   I177 @T6G_MB_LIB.T6G(SCH_1):PAGE95
   J20  202  VSS87 SCONN288_DDR506112002KQ-SCONN288_DDR506112002KQ,SMA   I177 @T6G_MB_LIB.T6G(SCH_1):PAGE95
   J20  204  VSS88 SCONN288_DDR506112002KQ-SCONN288_DDR506112002KQ,SMA   I177 @T6G_MB_LIB.T6G(SCH_1):PAGE95
   J20  206  VSS89 SCONN288_DDR506112002KQ-SCONN288_DDR506112002KQ,SMA   I177 @T6G_MB_LIB.T6G(SCH_1):PAGE95
   J20  208  VSS90 SCONN288_DDR506112002KQ-SCONN288_DDR506112002KQ,SMA   I177 @T6G_MB_LIB.T6G(SCH_1):PAGE95
   J20  210  VSS91 SCONN288_DDR506112002KQ-SCONN288_DDR506112002KQ,SMA   I177 @T6G_MB_LIB.T6G(SCH_1):PAGE95
   J20  212  VSS92 SCONN288_DDR506112002KQ-SCONN288_DDR506112002KQ,SMA   I177 @T6G_MB_LIB.T6G(SCH_1):PAGE95
   J20  214  VSS93 SCONN288_DDR506112002KQ-SCONN288_DDR506112002KQ,SMA   I177 @T6G_MB_LIB.T6G(SCH_1):PAGE95
   J20  216  VSS94 SCONN288_DDR506112002KQ-SCONN288_DDR506112002KQ,SMA   I177 @T6G_MB_LIB.T6G(SCH_1):PAGE95
   J20  219  VSS95 SCONN288_DDR506112002KQ-SCONN288_DDR506112002KQ,SMA   I177 @T6G_MB_LIB.T6G(SCH_1):PAGE95
   J20  222  VSS96 SCONN288_DDR506112002KQ-SCONN288_DDR506112002KQ,SMA   I177 @T6G_MB_LIB.T6G(SCH_1):PAGE95
   J20  224  VSS97 SCONN288_DDR506112002KQ-SCONN288_DDR506112002KQ,SMA   I177 @T6G_MB_LIB.T6G(SCH_1):PAGE95
   J20  226  VSS98 SCONN288_DDR506112002KQ-SCONN288_DDR506112002KQ,SMA   I177 @T6G_MB_LIB.T6G(SCH_1):PAGE95
   J20  228  VSS99 SCONN288_DDR506112002KQ-SCONN288_DDR506112002KQ,SMA   I177 @T6G_MB_LIB.T6G(SCH_1):PAGE95
   J20  230 VSS100 SCONN288_DDR506112002KQ-SCONN288_DDR506112002KQ,SMA   I177 @T6G_MB_LIB.T6G(SCH_1):PAGE95
   J20  233 VSS101 SCONN288_DDR506112002KQ-SCONN288_DDR506112002KQ,SMA   I177 @T6G_MB_LIB.T6G(SCH_1):PAGE95
   J20  235 VSS102 SCONN288_DDR506112002KQ-SCONN288_DDR506112002KQ,SMA   I177 @T6G_MB_LIB.T6G(SCH_1):PAGE95
   J20  237 VSS103 SCONN288_DDR506112002KQ-SCONN288_DDR506112002KQ,SMA   I177 @T6G_MB_LIB.T6G(SCH_1):PAGE95
   J20  240 VSS104 SCONN288_DDR506112002KQ-SCONN288_DDR506112002KQ,SMA   I177 @T6G_MB_LIB.T6G(SCH_1):PAGE95
   J20  242 VSS105 SCONN288_DDR506112002KQ-SCONN288_DDR506112002KQ,SMA   I177 @T6G_MB_LIB.T6G(SCH_1):PAGE95
   J20  244 VSS106 SCONN288_DDR506112002KQ-SCONN288_DDR506112002KQ,SMA   I177 @T6G_MB_LIB.T6G(SCH_1):PAGE95
   J20  246 VSS107 SCONN288_DDR506112002KQ-SCONN288_DDR506112002KQ,SMA   I177 @T6G_MB_LIB.T6G(SCH_1):PAGE95
   J20  248 VSS108 SCONN288_DDR506112002KQ-SCONN288_DDR506112002KQ,SMA   I177 @T6G_MB_LIB.T6G(SCH_1):PAGE95
   J20  251 VSS109 SCONN288_DDR506112002KQ-SCONN288_DDR506112002KQ,SMA   I177 @T6G_MB_LIB.T6G(SCH_1):PAGE95
   J20  253 VSS110 SCONN288_DDR506112002KQ-SCONN288_DDR506112002KQ,SMA   I177 @T6G_MB_LIB.T6G(SCH_1):PAGE95
   J20  255 VSS111 SCONN288_DDR506112002KQ-SCONN288_DDR506112002KQ,SMA   I177 @T6G_MB_LIB.T6G(SCH_1):PAGE95
   J20  257 VSS112 SCONN288_DDR506112002KQ-SCONN288_DDR506112002KQ,SMA   I177 @T6G_MB_LIB.T6G(SCH_1):PAGE95
   J20  259 VSS113 SCONN288_DDR506112002KQ-SCONN288_DDR506112002KQ,SMA   I177 @T6G_MB_LIB.T6G(SCH_1):PAGE95
   J20  262 VSS114 SCONN288_DDR506112002KQ-SCONN288_DDR506112002KQ,SMA   I177 @T6G_MB_LIB.T6G(SCH_1):PAGE95
   J20  264 VSS115 SCONN288_DDR506112002KQ-SCONN288_DDR506112002KQ,SMA   I177 @T6G_MB_LIB.T6G(SCH_1):PAGE95
   J20  266 VSS116 SCONN288_DDR506112002KQ-SCONN288_DDR506112002KQ,SMA   I177 @T6G_MB_LIB.T6G(SCH_1):PAGE95
   J20  268 VSS117 SCONN288_DDR506112002KQ-SCONN288_DDR506112002KQ,SMA   I177 @T6G_MB_LIB.T6G(SCH_1):PAGE95
   J20  270 VSS118 SCONN288_DDR506112002KQ-SCONN288_DDR506112002KQ,SMA   I177 @T6G_MB_LIB.T6G(SCH_1):PAGE95
   J20  273 VSS119 SCONN288_DDR506112002KQ-SCONN288_DDR506112002KQ,SMA   I177 @T6G_MB_LIB.T6G(SCH_1):PAGE95
   J20  275 VSS120 SCONN288_DDR506112002KQ-SCONN288_DDR506112002KQ,SMA   I177 @T6G_MB_LIB.T6G(SCH_1):PAGE95
   J20  277 VSS121 SCONN288_DDR506112002KQ-SCONN288_DDR506112002KQ,SMA   I177 @T6G_MB_LIB.T6G(SCH_1):PAGE95
   J20  279 VSS122 SCONN288_DDR506112002KQ-SCONN288_DDR506112002KQ,SMA   I177 @T6G_MB_LIB.T6G(SCH_1):PAGE95
   J20  281 VSS123 SCONN288_DDR506112002KQ-SCONN288_DDR506112002KQ,SMA   I177 @T6G_MB_LIB.T6G(SCH_1):PAGE95
   J20  284 VSS124 SCONN288_DDR506112002KQ-SCONN288_DDR506112002KQ,SMA   I177 @T6G_MB_LIB.T6G(SCH_1):PAGE95
   J20  286 VSS125 SCONN288_DDR506112002KQ-SCONN288_DDR506112002KQ,SMA   I177 @T6G_MB_LIB.T6G(SCH_1):PAGE95
   J20  288 VSS126 SCONN288_DDR506112002KQ-SCONN288_DDR506112002KQ,SMA   I177 @T6G_MB_LIB.T6G(SCH_1):PAGE95
  C128    2      B Q_CAP_0402-0.1UF,25V,10%,X7R,CH4104K1B00   I185 @T6G_MB_LIB.T6G(SCH_1):PAGE95
  C167    2      B Q_CAP_C0805-10UF,25V,10%,X6S,CH6104KEA00   I238 @T6G_MB_LIB.T6G(SCH_1):PAGE95
  C169    2      B Q_CAP_C0805-10UF,25V,10%,X6S,CH6104KEA00   I239 @T6G_MB_LIB.T6G(SCH_1):PAGE95
  R769    2      B Q_RES_0402LF-84.5K,1%,1/16W,CHIP,CS38452FB05   I127 @T6G_MB_LIB.T6G(SCH_1):PAGE96
   J67   G1     G1 SCONN288_DDR506112002KQ-SCONN288_DDR506112002KQ,SMA   I140 @T6G_MB_LIB.T6G(SCH_1):PAGE96
   J67   G2     G2 SCONN288_DDR506112002KQ-SCONN288_DDR506112002KQ,SMA   I140 @T6G_MB_LIB.T6G(SCH_1):PAGE96
   J67   G3     G3 SCONN288_DDR506112002KQ-SCONN288_DDR506112002KQ,SMA   I140 @T6G_MB_LIB.T6G(SCH_1):PAGE96
   J67    6   VSS0 SCONN288_DDR506112002KQ-SCONN288_DDR506112002KQ,SMA   I140 @T6G_MB_LIB.T6G(SCH_1):PAGE96
   J67    8   VSS1 SCONN288_DDR506112002KQ-SCONN288_DDR506112002KQ,SMA   I140 @T6G_MB_LIB.T6G(SCH_1):PAGE96
   J67   10   VSS2 SCONN288_DDR506112002KQ-SCONN288_DDR506112002KQ,SMA   I140 @T6G_MB_LIB.T6G(SCH_1):PAGE96
   J67   13   VSS3 SCONN288_DDR506112002KQ-SCONN288_DDR506112002KQ,SMA   I140 @T6G_MB_LIB.T6G(SCH_1):PAGE96
   J67   15   VSS4 SCONN288_DDR506112002KQ-SCONN288_DDR506112002KQ,SMA   I140 @T6G_MB_LIB.T6G(SCH_1):PAGE96
   J67   17   VSS5 SCONN288_DDR506112002KQ-SCONN288_DDR506112002KQ,SMA   I140 @T6G_MB_LIB.T6G(SCH_1):PAGE96
   J67   19   VSS6 SCONN288_DDR506112002KQ-SCONN288_DDR506112002KQ,SMA   I140 @T6G_MB_LIB.T6G(SCH_1):PAGE96
   J67   21   VSS7 SCONN288_DDR506112002KQ-SCONN288_DDR506112002KQ,SMA   I140 @T6G_MB_LIB.T6G(SCH_1):PAGE96
   J67   24   VSS8 SCONN288_DDR506112002KQ-SCONN288_DDR506112002KQ,SMA   I140 @T6G_MB_LIB.T6G(SCH_1):PAGE96
   J67   26   VSS9 SCONN288_DDR506112002KQ-SCONN288_DDR506112002KQ,SMA   I140 @T6G_MB_LIB.T6G(SCH_1):PAGE96
   J67   28  VSS10 SCONN288_DDR506112002KQ-SCONN288_DDR506112002KQ,SMA   I140 @T6G_MB_LIB.T6G(SCH_1):PAGE96
   J67   30  VSS11 SCONN288_DDR506112002KQ-SCONN288_DDR506112002KQ,SMA   I140 @T6G_MB_LIB.T6G(SCH_1):PAGE96
   J67   32  VSS12 SCONN288_DDR506112002KQ-SCONN288_DDR506112002KQ,SMA   I140 @T6G_MB_LIB.T6G(SCH_1):PAGE96
   J67   35  VSS13 SCONN288_DDR506112002KQ-SCONN288_DDR506112002KQ,SMA   I140 @T6G_MB_LIB.T6G(SCH_1):PAGE96
   J67   37  VSS14 SCONN288_DDR506112002KQ-SCONN288_DDR506112002KQ,SMA   I140 @T6G_MB_LIB.T6G(SCH_1):PAGE96
   J67   39  VSS15 SCONN288_DDR506112002KQ-SCONN288_DDR506112002KQ,SMA   I140 @T6G_MB_LIB.T6G(SCH_1):PAGE96
   J67   41  VSS16 SCONN288_DDR506112002KQ-SCONN288_DDR506112002KQ,SMA   I140 @T6G_MB_LIB.T6G(SCH_1):PAGE96
   J67   43  VSS17 SCONN288_DDR506112002KQ-SCONN288_DDR506112002KQ,SMA   I140 @T6G_MB_LIB.T6G(SCH_1):PAGE96
   J67   46  VSS18 SCONN288_DDR506112002KQ-SCONN288_DDR506112002KQ,SMA   I140 @T6G_MB_LIB.T6G(SCH_1):PAGE96
   J67   48  VSS19 SCONN288_DDR506112002KQ-SCONN288_DDR506112002KQ,SMA   I140 @T6G_MB_LIB.T6G(SCH_1):PAGE96
   J67   50  VSS20 SCONN288_DDR506112002KQ-SCONN288_DDR506112002KQ,SMA   I140 @T6G_MB_LIB.T6G(SCH_1):PAGE96
   J67   52  VSS21 SCONN288_DDR506112002KQ-SCONN288_DDR506112002KQ,SMA   I140 @T6G_MB_LIB.T6G(SCH_1):PAGE96
   J67   54  VSS22 SCONN288_DDR506112002KQ-SCONN288_DDR506112002KQ,SMA   I140 @T6G_MB_LIB.T6G(SCH_1):PAGE96
   J67   57  VSS23 SCONN288_DDR506112002KQ-SCONN288_DDR506112002KQ,SMA   I140 @T6G_MB_LIB.T6G(SCH_1):PAGE96
   J67   59  VSS24 SCONN288_DDR506112002KQ-SCONN288_DDR506112002KQ,SMA   I140 @T6G_MB_LIB.T6G(SCH_1):PAGE96
   J67   61  VSS25 SCONN288_DDR506112002KQ-SCONN288_DDR506112002KQ,SMA   I140 @T6G_MB_LIB.T6G(SCH_1):PAGE96
   J67   63  VSS26 SCONN288_DDR506112002KQ-SCONN288_DDR506112002KQ,SMA   I140 @T6G_MB_LIB.T6G(SCH_1):PAGE96
   J67   65  VSS27 SCONN288_DDR506112002KQ-SCONN288_DDR506112002KQ,SMA   I140 @T6G_MB_LIB.T6G(SCH_1):PAGE96
   J67   67  VSS28 SCONN288_DDR506112002KQ-SCONN288_DDR506112002KQ,SMA   I140 @T6G_MB_LIB.T6G(SCH_1):PAGE96
   J67   69  VSS29 SCONN288_DDR506112002KQ-SCONN288_DDR506112002KQ,SMA   I140 @T6G_MB_LIB.T6G(SCH_1):PAGE96
   J67   71  VSS30 SCONN288_DDR506112002KQ-SCONN288_DDR506112002KQ,SMA   I140 @T6G_MB_LIB.T6G(SCH_1):PAGE96
   J67   73  VSS31 SCONN288_DDR506112002KQ-SCONN288_DDR506112002KQ,SMA   I140 @T6G_MB_LIB.T6G(SCH_1):PAGE96
   J67   75  VSS32 SCONN288_DDR506112002KQ-SCONN288_DDR506112002KQ,SMA   I140 @T6G_MB_LIB.T6G(SCH_1):PAGE96
   J67   77  VSS33 SCONN288_DDR506112002KQ-SCONN288_DDR506112002KQ,SMA   I140 @T6G_MB_LIB.T6G(SCH_1):PAGE96
   J67   79  VSS34 SCONN288_DDR506112002KQ-SCONN288_DDR506112002KQ,SMA   I140 @T6G_MB_LIB.T6G(SCH_1):PAGE96
   J67   81  VSS35 SCONN288_DDR506112002KQ-SCONN288_DDR506112002KQ,SMA   I140 @T6G_MB_LIB.T6G(SCH_1):PAGE96
   J67   83  VSS36 SCONN288_DDR506112002KQ-SCONN288_DDR506112002KQ,SMA   I140 @T6G_MB_LIB.T6G(SCH_1):PAGE96
   J67   85  VSS37 SCONN288_DDR506112002KQ-SCONN288_DDR506112002KQ,SMA   I140 @T6G_MB_LIB.T6G(SCH_1):PAGE96
   J67   88  VSS38 SCONN288_DDR506112002KQ-SCONN288_DDR506112002KQ,SMA   I140 @T6G_MB_LIB.T6G(SCH_1):PAGE96
   J67   90  VSS39 SCONN288_DDR506112002KQ-SCONN288_DDR506112002KQ,SMA   I140 @T6G_MB_LIB.T6G(SCH_1):PAGE96
   J67   92  VSS40 SCONN288_DDR506112002KQ-SCONN288_DDR506112002KQ,SMA   I140 @T6G_MB_LIB.T6G(SCH_1):PAGE96
   J67   95  VSS41 SCONN288_DDR506112002KQ-SCONN288_DDR506112002KQ,SMA   I140 @T6G_MB_LIB.T6G(SCH_1):PAGE96
   J67   97  VSS42 SCONN288_DDR506112002KQ-SCONN288_DDR506112002KQ,SMA   I140 @T6G_MB_LIB.T6G(SCH_1):PAGE96
   J67   99  VSS43 SCONN288_DDR506112002KQ-SCONN288_DDR506112002KQ,SMA   I140 @T6G_MB_LIB.T6G(SCH_1):PAGE96
   J67  101  VSS44 SCONN288_DDR506112002KQ-SCONN288_DDR506112002KQ,SMA   I140 @T6G_MB_LIB.T6G(SCH_1):PAGE96
   J67  103  VSS45 SCONN288_DDR506112002KQ-SCONN288_DDR506112002KQ,SMA   I140 @T6G_MB_LIB.T6G(SCH_1):PAGE96
   J67  106  VSS46 SCONN288_DDR506112002KQ-SCONN288_DDR506112002KQ,SMA   I140 @T6G_MB_LIB.T6G(SCH_1):PAGE96
   J67  108  VSS47 SCONN288_DDR506112002KQ-SCONN288_DDR506112002KQ,SMA   I140 @T6G_MB_LIB.T6G(SCH_1):PAGE96
   J67  110  VSS48 SCONN288_DDR506112002KQ-SCONN288_DDR506112002KQ,SMA   I140 @T6G_MB_LIB.T6G(SCH_1):PAGE96
   J67  112  VSS49 SCONN288_DDR506112002KQ-SCONN288_DDR506112002KQ,SMA   I140 @T6G_MB_LIB.T6G(SCH_1):PAGE96
   J67  114  VSS50 SCONN288_DDR506112002KQ-SCONN288_DDR506112002KQ,SMA   I140 @T6G_MB_LIB.T6G(SCH_1):PAGE96
   J67  117  VSS51 SCONN288_DDR506112002KQ-SCONN288_DDR506112002KQ,SMA   I140 @T6G_MB_LIB.T6G(SCH_1):PAGE96
   J67  119  VSS52 SCONN288_DDR506112002KQ-SCONN288_DDR506112002KQ,SMA   I140 @T6G_MB_LIB.T6G(SCH_1):PAGE96
   J67  121  VSS53 SCONN288_DDR506112002KQ-SCONN288_DDR506112002KQ,SMA   I140 @T6G_MB_LIB.T6G(SCH_1):PAGE96
   J67  123  VSS54 SCONN288_DDR506112002KQ-SCONN288_DDR506112002KQ,SMA   I140 @T6G_MB_LIB.T6G(SCH_1):PAGE96
   J67  125  VSS55 SCONN288_DDR506112002KQ-SCONN288_DDR506112002KQ,SMA   I140 @T6G_MB_LIB.T6G(SCH_1):PAGE96
   J67  128  VSS56 SCONN288_DDR506112002KQ-SCONN288_DDR506112002KQ,SMA   I140 @T6G_MB_LIB.T6G(SCH_1):PAGE96
   J67  130  VSS57 SCONN288_DDR506112002KQ-SCONN288_DDR506112002KQ,SMA   I140 @T6G_MB_LIB.T6G(SCH_1):PAGE96
   J67  132  VSS58 SCONN288_DDR506112002KQ-SCONN288_DDR506112002KQ,SMA   I140 @T6G_MB_LIB.T6G(SCH_1):PAGE96
   J67  134  VSS59 SCONN288_DDR506112002KQ-SCONN288_DDR506112002KQ,SMA   I140 @T6G_MB_LIB.T6G(SCH_1):PAGE96
   J67  136  VSS60 SCONN288_DDR506112002KQ-SCONN288_DDR506112002KQ,SMA   I140 @T6G_MB_LIB.T6G(SCH_1):PAGE96
   J67  139  VSS61 SCONN288_DDR506112002KQ-SCONN288_DDR506112002KQ,SMA   I140 @T6G_MB_LIB.T6G(SCH_1):PAGE96
   J67  141  VSS62 SCONN288_DDR506112002KQ-SCONN288_DDR506112002KQ,SMA   I140 @T6G_MB_LIB.T6G(SCH_1):PAGE96
   J67  143  VSS63 SCONN288_DDR506112002KQ-SCONN288_DDR506112002KQ,SMA   I140 @T6G_MB_LIB.T6G(SCH_1):PAGE96
   J67  151  VSS64 SCONN288_DDR506112002KQ-SCONN288_DDR506112002KQ,SMA   I140 @T6G_MB_LIB.T6G(SCH_1):PAGE96
   J67  153  VSS65 SCONN288_DDR506112002KQ-SCONN288_DDR506112002KQ,SMA   I140 @T6G_MB_LIB.T6G(SCH_1):PAGE96
   J67  155  VSS66 SCONN288_DDR506112002KQ-SCONN288_DDR506112002KQ,SMA   I140 @T6G_MB_LIB.T6G(SCH_1):PAGE96
   J67  158  VSS67 SCONN288_DDR506112002KQ-SCONN288_DDR506112002KQ,SMA   I140 @T6G_MB_LIB.T6G(SCH_1):PAGE96
   J67  160  VSS68 SCONN288_DDR506112002KQ-SCONN288_DDR506112002KQ,SMA   I140 @T6G_MB_LIB.T6G(SCH_1):PAGE96
   J67  162  VSS69 SCONN288_DDR506112002KQ-SCONN288_DDR506112002KQ,SMA   I140 @T6G_MB_LIB.T6G(SCH_1):PAGE96
   J67  164  VSS70 SCONN288_DDR506112002KQ-SCONN288_DDR506112002KQ,SMA   I140 @T6G_MB_LIB.T6G(SCH_1):PAGE96
   J67  166  VSS71 SCONN288_DDR506112002KQ-SCONN288_DDR506112002KQ,SMA   I140 @T6G_MB_LIB.T6G(SCH_1):PAGE96
   J67  169  VSS72 SCONN288_DDR506112002KQ-SCONN288_DDR506112002KQ,SMA   I140 @T6G_MB_LIB.T6G(SCH_1):PAGE96
   J67  171  VSS73 SCONN288_DDR506112002KQ-SCONN288_DDR506112002KQ,SMA   I140 @T6G_MB_LIB.T6G(SCH_1):PAGE96
   J67  173  VSS74 SCONN288_DDR506112002KQ-SCONN288_DDR506112002KQ,SMA   I140 @T6G_MB_LIB.T6G(SCH_1):PAGE96
   J67  175  VSS75 SCONN288_DDR506112002KQ-SCONN288_DDR506112002KQ,SMA   I140 @T6G_MB_LIB.T6G(SCH_1):PAGE96
   J67  177  VSS76 SCONN288_DDR506112002KQ-SCONN288_DDR506112002KQ,SMA   I140 @T6G_MB_LIB.T6G(SCH_1):PAGE96
   J67  180  VSS77 SCONN288_DDR506112002KQ-SCONN288_DDR506112002KQ,SMA   I140 @T6G_MB_LIB.T6G(SCH_1):PAGE96
   J67  182  VSS78 SCONN288_DDR506112002KQ-SCONN288_DDR506112002KQ,SMA   I140 @T6G_MB_LIB.T6G(SCH_1):PAGE96
   J67  184  VSS79 SCONN288_DDR506112002KQ-SCONN288_DDR506112002KQ,SMA   I140 @T6G_MB_LIB.T6G(SCH_1):PAGE96
   J67  186  VSS80 SCONN288_DDR506112002KQ-SCONN288_DDR506112002KQ,SMA   I140 @T6G_MB_LIB.T6G(SCH_1):PAGE96
   J67  188  VSS81 SCONN288_DDR506112002KQ-SCONN288_DDR506112002KQ,SMA   I140 @T6G_MB_LIB.T6G(SCH_1):PAGE96
   J67  191  VSS82 SCONN288_DDR506112002KQ-SCONN288_DDR506112002KQ,SMA   I140 @T6G_MB_LIB.T6G(SCH_1):PAGE96
   J67  193  VSS83 SCONN288_DDR506112002KQ-SCONN288_DDR506112002KQ,SMA   I140 @T6G_MB_LIB.T6G(SCH_1):PAGE96
   J67  195  VSS84 SCONN288_DDR506112002KQ-SCONN288_DDR506112002KQ,SMA   I140 @T6G_MB_LIB.T6G(SCH_1):PAGE96
   J67  197  VSS85 SCONN288_DDR506112002KQ-SCONN288_DDR506112002KQ,SMA   I140 @T6G_MB_LIB.T6G(SCH_1):PAGE96
   J67  199  VSS86 SCONN288_DDR506112002KQ-SCONN288_DDR506112002KQ,SMA   I140 @T6G_MB_LIB.T6G(SCH_1):PAGE96
   J67  202  VSS87 SCONN288_DDR506112002KQ-SCONN288_DDR506112002KQ,SMA   I140 @T6G_MB_LIB.T6G(SCH_1):PAGE96
   J67  204  VSS88 SCONN288_DDR506112002KQ-SCONN288_DDR506112002KQ,SMA   I140 @T6G_MB_LIB.T6G(SCH_1):PAGE96
   J67  206  VSS89 SCONN288_DDR506112002KQ-SCONN288_DDR506112002KQ,SMA   I140 @T6G_MB_LIB.T6G(SCH_1):PAGE96
   J67  208  VSS90 SCONN288_DDR506112002KQ-SCONN288_DDR506112002KQ,SMA   I140 @T6G_MB_LIB.T6G(SCH_1):PAGE96
   J67  210  VSS91 SCONN288_DDR506112002KQ-SCONN288_DDR506112002KQ,SMA   I140 @T6G_MB_LIB.T6G(SCH_1):PAGE96
   J67  212  VSS92 SCONN288_DDR506112002KQ-SCONN288_DDR506112002KQ,SMA   I140 @T6G_MB_LIB.T6G(SCH_1):PAGE96
   J67  214  VSS93 SCONN288_DDR506112002KQ-SCONN288_DDR506112002KQ,SMA   I140 @T6G_MB_LIB.T6G(SCH_1):PAGE96
   J67  216  VSS94 SCONN288_DDR506112002KQ-SCONN288_DDR506112002KQ,SMA   I140 @T6G_MB_LIB.T6G(SCH_1):PAGE96
   J67  219  VSS95 SCONN288_DDR506112002KQ-SCONN288_DDR506112002KQ,SMA   I140 @T6G_MB_LIB.T6G(SCH_1):PAGE96
   J67  222  VSS96 SCONN288_DDR506112002KQ-SCONN288_DDR506112002KQ,SMA   I140 @T6G_MB_LIB.T6G(SCH_1):PAGE96
   J67  224  VSS97 SCONN288_DDR506112002KQ-SCONN288_DDR506112002KQ,SMA   I140 @T6G_MB_LIB.T6G(SCH_1):PAGE96
   J67  226  VSS98 SCONN288_DDR506112002KQ-SCONN288_DDR506112002KQ,SMA   I140 @T6G_MB_LIB.T6G(SCH_1):PAGE96
   J67  228  VSS99 SCONN288_DDR506112002KQ-SCONN288_DDR506112002KQ,SMA   I140 @T6G_MB_LIB.T6G(SCH_1):PAGE96
   J67  230 VSS100 SCONN288_DDR506112002KQ-SCONN288_DDR506112002KQ,SMA   I140 @T6G_MB_LIB.T6G(SCH_1):PAGE96
   J67  233 VSS101 SCONN288_DDR506112002KQ-SCONN288_DDR506112002KQ,SMA   I140 @T6G_MB_LIB.T6G(SCH_1):PAGE96
   J67  235 VSS102 SCONN288_DDR506112002KQ-SCONN288_DDR506112002KQ,SMA   I140 @T6G_MB_LIB.T6G(SCH_1):PAGE96
   J67  237 VSS103 SCONN288_DDR506112002KQ-SCONN288_DDR506112002KQ,SMA   I140 @T6G_MB_LIB.T6G(SCH_1):PAGE96
   J67  240 VSS104 SCONN288_DDR506112002KQ-SCONN288_DDR506112002KQ,SMA   I140 @T6G_MB_LIB.T6G(SCH_1):PAGE96
   J67  242 VSS105 SCONN288_DDR506112002KQ-SCONN288_DDR506112002KQ,SMA   I140 @T6G_MB_LIB.T6G(SCH_1):PAGE96
   J67  244 VSS106 SCONN288_DDR506112002KQ-SCONN288_DDR506112002KQ,SMA   I140 @T6G_MB_LIB.T6G(SCH_1):PAGE96
   J67  246 VSS107 SCONN288_DDR506112002KQ-SCONN288_DDR506112002KQ,SMA   I140 @T6G_MB_LIB.T6G(SCH_1):PAGE96
   J67  248 VSS108 SCONN288_DDR506112002KQ-SCONN288_DDR506112002KQ,SMA   I140 @T6G_MB_LIB.T6G(SCH_1):PAGE96
   J67  251 VSS109 SCONN288_DDR506112002KQ-SCONN288_DDR506112002KQ,SMA   I140 @T6G_MB_LIB.T6G(SCH_1):PAGE96
   J67  253 VSS110 SCONN288_DDR506112002KQ-SCONN288_DDR506112002KQ,SMA   I140 @T6G_MB_LIB.T6G(SCH_1):PAGE96
   J67  255 VSS111 SCONN288_DDR506112002KQ-SCONN288_DDR506112002KQ,SMA   I140 @T6G_MB_LIB.T6G(SCH_1):PAGE96
   J67  257 VSS112 SCONN288_DDR506112002KQ-SCONN288_DDR506112002KQ,SMA   I140 @T6G_MB_LIB.T6G(SCH_1):PAGE96
   J67  259 VSS113 SCONN288_DDR506112002KQ-SCONN288_DDR506112002KQ,SMA   I140 @T6G_MB_LIB.T6G(SCH_1):PAGE96
   J67  262 VSS114 SCONN288_DDR506112002KQ-SCONN288_DDR506112002KQ,SMA   I140 @T6G_MB_LIB.T6G(SCH_1):PAGE96
   J67  264 VSS115 SCONN288_DDR506112002KQ-SCONN288_DDR506112002KQ,SMA   I140 @T6G_MB_LIB.T6G(SCH_1):PAGE96
   J67  266 VSS116 SCONN288_DDR506112002KQ-SCONN288_DDR506112002KQ,SMA   I140 @T6G_MB_LIB.T6G(SCH_1):PAGE96
   J67  268 VSS117 SCONN288_DDR506112002KQ-SCONN288_DDR506112002KQ,SMA   I140 @T6G_MB_LIB.T6G(SCH_1):PAGE96
   J67  270 VSS118 SCONN288_DDR506112002KQ-SCONN288_DDR506112002KQ,SMA   I140 @T6G_MB_LIB.T6G(SCH_1):PAGE96
   J67  273 VSS119 SCONN288_DDR506112002KQ-SCONN288_DDR506112002KQ,SMA   I140 @T6G_MB_LIB.T6G(SCH_1):PAGE96
   J67  275 VSS120 SCONN288_DDR506112002KQ-SCONN288_DDR506112002KQ,SMA   I140 @T6G_MB_LIB.T6G(SCH_1):PAGE96
   J67  277 VSS121 SCONN288_DDR506112002KQ-SCONN288_DDR506112002KQ,SMA   I140 @T6G_MB_LIB.T6G(SCH_1):PAGE96
   J67  279 VSS122 SCONN288_DDR506112002KQ-SCONN288_DDR506112002KQ,SMA   I140 @T6G_MB_LIB.T6G(SCH_1):PAGE96
   J67  281 VSS123 SCONN288_DDR506112002KQ-SCONN288_DDR506112002KQ,SMA   I140 @T6G_MB_LIB.T6G(SCH_1):PAGE96
   J67  284 VSS124 SCONN288_DDR506112002KQ-SCONN288_DDR506112002KQ,SMA   I140 @T6G_MB_LIB.T6G(SCH_1):PAGE96
   J67  286 VSS125 SCONN288_DDR506112002KQ-SCONN288_DDR506112002KQ,SMA   I140 @T6G_MB_LIB.T6G(SCH_1):PAGE96
   J67  288 VSS126 SCONN288_DDR506112002KQ-SCONN288_DDR506112002KQ,SMA   I140 @T6G_MB_LIB.T6G(SCH_1):PAGE96
  C132    2      B Q_CAP_0402-0.1UF,25V,10%,X7R,CH4104K1B00   I185 @T6G_MB_LIB.T6G(SCH_1):PAGE96
  C170    2      B Q_CAP_C0805-10UF,25V,10%,X6S,CH6104KEA00   I238 @T6G_MB_LIB.T6G(SCH_1):PAGE96
  C171    2      B Q_CAP_C0805-10UF,25V,10%,X6S,CH6104KEA00   I239 @T6G_MB_LIB.T6G(SCH_1):PAGE96
   R36    2      B Q_RES_0402LF-10K,1%,1/16W,CHIP,CS31002FB08   I129 @T6G_MB_LIB.T6G(SCH_1):PAGE97
   J24   G1     G1 SCONN288_DDR506112002KQ-SCONN288_DDR506112002KQ,SMA   I177 @T6G_MB_LIB.T6G(SCH_1):PAGE97
   J24   G2     G2 SCONN288_DDR506112002KQ-SCONN288_DDR506112002KQ,SMA   I177 @T6G_MB_LIB.T6G(SCH_1):PAGE97
   J24   G3     G3 SCONN288_DDR506112002KQ-SCONN288_DDR506112002KQ,SMA   I177 @T6G_MB_LIB.T6G(SCH_1):PAGE97
   J24    6   VSS0 SCONN288_DDR506112002KQ-SCONN288_DDR506112002KQ,SMA   I177 @T6G_MB_LIB.T6G(SCH_1):PAGE97
   J24    8   VSS1 SCONN288_DDR506112002KQ-SCONN288_DDR506112002KQ,SMA   I177 @T6G_MB_LIB.T6G(SCH_1):PAGE97
   J24   10   VSS2 SCONN288_DDR506112002KQ-SCONN288_DDR506112002KQ,SMA   I177 @T6G_MB_LIB.T6G(SCH_1):PAGE97
   J24   13   VSS3 SCONN288_DDR506112002KQ-SCONN288_DDR506112002KQ,SMA   I177 @T6G_MB_LIB.T6G(SCH_1):PAGE97
   J24   15   VSS4 SCONN288_DDR506112002KQ-SCONN288_DDR506112002KQ,SMA   I177 @T6G_MB_LIB.T6G(SCH_1):PAGE97
   J24   17   VSS5 SCONN288_DDR506112002KQ-SCONN288_DDR506112002KQ,SMA   I177 @T6G_MB_LIB.T6G(SCH_1):PAGE97
   J24   19   VSS6 SCONN288_DDR506112002KQ-SCONN288_DDR506112002KQ,SMA   I177 @T6G_MB_LIB.T6G(SCH_1):PAGE97
   J24   21   VSS7 SCONN288_DDR506112002KQ-SCONN288_DDR506112002KQ,SMA   I177 @T6G_MB_LIB.T6G(SCH_1):PAGE97
   J24   24   VSS8 SCONN288_DDR506112002KQ-SCONN288_DDR506112002KQ,SMA   I177 @T6G_MB_LIB.T6G(SCH_1):PAGE97
   J24   26   VSS9 SCONN288_DDR506112002KQ-SCONN288_DDR506112002KQ,SMA   I177 @T6G_MB_LIB.T6G(SCH_1):PAGE97
   J24   28  VSS10 SCONN288_DDR506112002KQ-SCONN288_DDR506112002KQ,SMA   I177 @T6G_MB_LIB.T6G(SCH_1):PAGE97
   J24   30  VSS11 SCONN288_DDR506112002KQ-SCONN288_DDR506112002KQ,SMA   I177 @T6G_MB_LIB.T6G(SCH_1):PAGE97
   J24   32  VSS12 SCONN288_DDR506112002KQ-SCONN288_DDR506112002KQ,SMA   I177 @T6G_MB_LIB.T6G(SCH_1):PAGE97
   J24   35  VSS13 SCONN288_DDR506112002KQ-SCONN288_DDR506112002KQ,SMA   I177 @T6G_MB_LIB.T6G(SCH_1):PAGE97
   J24   37  VSS14 SCONN288_DDR506112002KQ-SCONN288_DDR506112002KQ,SMA   I177 @T6G_MB_LIB.T6G(SCH_1):PAGE97
   J24   39  VSS15 SCONN288_DDR506112002KQ-SCONN288_DDR506112002KQ,SMA   I177 @T6G_MB_LIB.T6G(SCH_1):PAGE97
   J24   41  VSS16 SCONN288_DDR506112002KQ-SCONN288_DDR506112002KQ,SMA   I177 @T6G_MB_LIB.T6G(SCH_1):PAGE97
   J24   43  VSS17 SCONN288_DDR506112002KQ-SCONN288_DDR506112002KQ,SMA   I177 @T6G_MB_LIB.T6G(SCH_1):PAGE97
   J24   46  VSS18 SCONN288_DDR506112002KQ-SCONN288_DDR506112002KQ,SMA   I177 @T6G_MB_LIB.T6G(SCH_1):PAGE97
   J24   48  VSS19 SCONN288_DDR506112002KQ-SCONN288_DDR506112002KQ,SMA   I177 @T6G_MB_LIB.T6G(SCH_1):PAGE97
   J24   50  VSS20 SCONN288_DDR506112002KQ-SCONN288_DDR506112002KQ,SMA   I177 @T6G_MB_LIB.T6G(SCH_1):PAGE97
   J24   52  VSS21 SCONN288_DDR506112002KQ-SCONN288_DDR506112002KQ,SMA   I177 @T6G_MB_LIB.T6G(SCH_1):PAGE97
   J24   54  VSS22 SCONN288_DDR506112002KQ-SCONN288_DDR506112002KQ,SMA   I177 @T6G_MB_LIB.T6G(SCH_1):PAGE97
   J24   57  VSS23 SCONN288_DDR506112002KQ-SCONN288_DDR506112002KQ,SMA   I177 @T6G_MB_LIB.T6G(SCH_1):PAGE97
   J24   59  VSS24 SCONN288_DDR506112002KQ-SCONN288_DDR506112002KQ,SMA   I177 @T6G_MB_LIB.T6G(SCH_1):PAGE97
   J24   61  VSS25 SCONN288_DDR506112002KQ-SCONN288_DDR506112002KQ,SMA   I177 @T6G_MB_LIB.T6G(SCH_1):PAGE97
   J24   63  VSS26 SCONN288_DDR506112002KQ-SCONN288_DDR506112002KQ,SMA   I177 @T6G_MB_LIB.T6G(SCH_1):PAGE97
   J24   65  VSS27 SCONN288_DDR506112002KQ-SCONN288_DDR506112002KQ,SMA   I177 @T6G_MB_LIB.T6G(SCH_1):PAGE97
   J24   67  VSS28 SCONN288_DDR506112002KQ-SCONN288_DDR506112002KQ,SMA   I177 @T6G_MB_LIB.T6G(SCH_1):PAGE97
   J24   69  VSS29 SCONN288_DDR506112002KQ-SCONN288_DDR506112002KQ,SMA   I177 @T6G_MB_LIB.T6G(SCH_1):PAGE97
   J24   71  VSS30 SCONN288_DDR506112002KQ-SCONN288_DDR506112002KQ,SMA   I177 @T6G_MB_LIB.T6G(SCH_1):PAGE97
   J24   73  VSS31 SCONN288_DDR506112002KQ-SCONN288_DDR506112002KQ,SMA   I177 @T6G_MB_LIB.T6G(SCH_1):PAGE97
   J24   75  VSS32 SCONN288_DDR506112002KQ-SCONN288_DDR506112002KQ,SMA   I177 @T6G_MB_LIB.T6G(SCH_1):PAGE97
   J24   77  VSS33 SCONN288_DDR506112002KQ-SCONN288_DDR506112002KQ,SMA   I177 @T6G_MB_LIB.T6G(SCH_1):PAGE97
   J24   79  VSS34 SCONN288_DDR506112002KQ-SCONN288_DDR506112002KQ,SMA   I177 @T6G_MB_LIB.T6G(SCH_1):PAGE97
   J24   81  VSS35 SCONN288_DDR506112002KQ-SCONN288_DDR506112002KQ,SMA   I177 @T6G_MB_LIB.T6G(SCH_1):PAGE97
   J24   83  VSS36 SCONN288_DDR506112002KQ-SCONN288_DDR506112002KQ,SMA   I177 @T6G_MB_LIB.T6G(SCH_1):PAGE97
   J24   85  VSS37 SCONN288_DDR506112002KQ-SCONN288_DDR506112002KQ,SMA   I177 @T6G_MB_LIB.T6G(SCH_1):PAGE97
   J24   88  VSS38 SCONN288_DDR506112002KQ-SCONN288_DDR506112002KQ,SMA   I177 @T6G_MB_LIB.T6G(SCH_1):PAGE97
   J24   90  VSS39 SCONN288_DDR506112002KQ-SCONN288_DDR506112002KQ,SMA   I177 @T6G_MB_LIB.T6G(SCH_1):PAGE97
   J24   92  VSS40 SCONN288_DDR506112002KQ-SCONN288_DDR506112002KQ,SMA   I177 @T6G_MB_LIB.T6G(SCH_1):PAGE97
   J24   95  VSS41 SCONN288_DDR506112002KQ-SCONN288_DDR506112002KQ,SMA   I177 @T6G_MB_LIB.T6G(SCH_1):PAGE97
   J24   97  VSS42 SCONN288_DDR506112002KQ-SCONN288_DDR506112002KQ,SMA   I177 @T6G_MB_LIB.T6G(SCH_1):PAGE97
   J24   99  VSS43 SCONN288_DDR506112002KQ-SCONN288_DDR506112002KQ,SMA   I177 @T6G_MB_LIB.T6G(SCH_1):PAGE97
   J24  101  VSS44 SCONN288_DDR506112002KQ-SCONN288_DDR506112002KQ,SMA   I177 @T6G_MB_LIB.T6G(SCH_1):PAGE97
   J24  103  VSS45 SCONN288_DDR506112002KQ-SCONN288_DDR506112002KQ,SMA   I177 @T6G_MB_LIB.T6G(SCH_1):PAGE97
   J24  106  VSS46 SCONN288_DDR506112002KQ-SCONN288_DDR506112002KQ,SMA   I177 @T6G_MB_LIB.T6G(SCH_1):PAGE97
   J24  108  VSS47 SCONN288_DDR506112002KQ-SCONN288_DDR506112002KQ,SMA   I177 @T6G_MB_LIB.T6G(SCH_1):PAGE97
   J24  110  VSS48 SCONN288_DDR506112002KQ-SCONN288_DDR506112002KQ,SMA   I177 @T6G_MB_LIB.T6G(SCH_1):PAGE97
   J24  112  VSS49 SCONN288_DDR506112002KQ-SCONN288_DDR506112002KQ,SMA   I177 @T6G_MB_LIB.T6G(SCH_1):PAGE97
   J24  114  VSS50 SCONN288_DDR506112002KQ-SCONN288_DDR506112002KQ,SMA   I177 @T6G_MB_LIB.T6G(SCH_1):PAGE97
   J24  117  VSS51 SCONN288_DDR506112002KQ-SCONN288_DDR506112002KQ,SMA   I177 @T6G_MB_LIB.T6G(SCH_1):PAGE97
   J24  119  VSS52 SCONN288_DDR506112002KQ-SCONN288_DDR506112002KQ,SMA   I177 @T6G_MB_LIB.T6G(SCH_1):PAGE97
   J24  121  VSS53 SCONN288_DDR506112002KQ-SCONN288_DDR506112002KQ,SMA   I177 @T6G_MB_LIB.T6G(SCH_1):PAGE97
   J24  123  VSS54 SCONN288_DDR506112002KQ-SCONN288_DDR506112002KQ,SMA   I177 @T6G_MB_LIB.T6G(SCH_1):PAGE97
   J24  125  VSS55 SCONN288_DDR506112002KQ-SCONN288_DDR506112002KQ,SMA   I177 @T6G_MB_LIB.T6G(SCH_1):PAGE97
   J24  128  VSS56 SCONN288_DDR506112002KQ-SCONN288_DDR506112002KQ,SMA   I177 @T6G_MB_LIB.T6G(SCH_1):PAGE97
   J24  130  VSS57 SCONN288_DDR506112002KQ-SCONN288_DDR506112002KQ,SMA   I177 @T6G_MB_LIB.T6G(SCH_1):PAGE97
   J24  132  VSS58 SCONN288_DDR506112002KQ-SCONN288_DDR506112002KQ,SMA   I177 @T6G_MB_LIB.T6G(SCH_1):PAGE97
   J24  134  VSS59 SCONN288_DDR506112002KQ-SCONN288_DDR506112002KQ,SMA   I177 @T6G_MB_LIB.T6G(SCH_1):PAGE97
   J24  136  VSS60 SCONN288_DDR506112002KQ-SCONN288_DDR506112002KQ,SMA   I177 @T6G_MB_LIB.T6G(SCH_1):PAGE97
   J24  139  VSS61 SCONN288_DDR506112002KQ-SCONN288_DDR506112002KQ,SMA   I177 @T6G_MB_LIB.T6G(SCH_1):PAGE97
   J24  141  VSS62 SCONN288_DDR506112002KQ-SCONN288_DDR506112002KQ,SMA   I177 @T6G_MB_LIB.T6G(SCH_1):PAGE97
   J24  143  VSS63 SCONN288_DDR506112002KQ-SCONN288_DDR506112002KQ,SMA   I177 @T6G_MB_LIB.T6G(SCH_1):PAGE97
   J24  151  VSS64 SCONN288_DDR506112002KQ-SCONN288_DDR506112002KQ,SMA   I177 @T6G_MB_LIB.T6G(SCH_1):PAGE97
   J24  153  VSS65 SCONN288_DDR506112002KQ-SCONN288_DDR506112002KQ,SMA   I177 @T6G_MB_LIB.T6G(SCH_1):PAGE97
   J24  155  VSS66 SCONN288_DDR506112002KQ-SCONN288_DDR506112002KQ,SMA   I177 @T6G_MB_LIB.T6G(SCH_1):PAGE97
   J24  158  VSS67 SCONN288_DDR506112002KQ-SCONN288_DDR506112002KQ,SMA   I177 @T6G_MB_LIB.T6G(SCH_1):PAGE97
   J24  160  VSS68 SCONN288_DDR506112002KQ-SCONN288_DDR506112002KQ,SMA   I177 @T6G_MB_LIB.T6G(SCH_1):PAGE97
   J24  162  VSS69 SCONN288_DDR506112002KQ-SCONN288_DDR506112002KQ,SMA   I177 @T6G_MB_LIB.T6G(SCH_1):PAGE97
   J24  164  VSS70 SCONN288_DDR506112002KQ-SCONN288_DDR506112002KQ,SMA   I177 @T6G_MB_LIB.T6G(SCH_1):PAGE97
   J24  166  VSS71 SCONN288_DDR506112002KQ-SCONN288_DDR506112002KQ,SMA   I177 @T6G_MB_LIB.T6G(SCH_1):PAGE97
   J24  169  VSS72 SCONN288_DDR506112002KQ-SCONN288_DDR506112002KQ,SMA   I177 @T6G_MB_LIB.T6G(SCH_1):PAGE97
   J24  171  VSS73 SCONN288_DDR506112002KQ-SCONN288_DDR506112002KQ,SMA   I177 @T6G_MB_LIB.T6G(SCH_1):PAGE97
   J24  173  VSS74 SCONN288_DDR506112002KQ-SCONN288_DDR506112002KQ,SMA   I177 @T6G_MB_LIB.T6G(SCH_1):PAGE97
   J24  175  VSS75 SCONN288_DDR506112002KQ-SCONN288_DDR506112002KQ,SMA   I177 @T6G_MB_LIB.T6G(SCH_1):PAGE97
   J24  177  VSS76 SCONN288_DDR506112002KQ-SCONN288_DDR506112002KQ,SMA   I177 @T6G_MB_LIB.T6G(SCH_1):PAGE97
   J24  180  VSS77 SCONN288_DDR506112002KQ-SCONN288_DDR506112002KQ,SMA   I177 @T6G_MB_LIB.T6G(SCH_1):PAGE97
   J24  182  VSS78 SCONN288_DDR506112002KQ-SCONN288_DDR506112002KQ,SMA   I177 @T6G_MB_LIB.T6G(SCH_1):PAGE97
   J24  184  VSS79 SCONN288_DDR506112002KQ-SCONN288_DDR506112002KQ,SMA   I177 @T6G_MB_LIB.T6G(SCH_1):PAGE97
   J24  186  VSS80 SCONN288_DDR506112002KQ-SCONN288_DDR506112002KQ,SMA   I177 @T6G_MB_LIB.T6G(SCH_1):PAGE97
   J24  188  VSS81 SCONN288_DDR506112002KQ-SCONN288_DDR506112002KQ,SMA   I177 @T6G_MB_LIB.T6G(SCH_1):PAGE97
   J24  191  VSS82 SCONN288_DDR506112002KQ-SCONN288_DDR506112002KQ,SMA   I177 @T6G_MB_LIB.T6G(SCH_1):PAGE97
   J24  193  VSS83 SCONN288_DDR506112002KQ-SCONN288_DDR506112002KQ,SMA   I177 @T6G_MB_LIB.T6G(SCH_1):PAGE97
   J24  195  VSS84 SCONN288_DDR506112002KQ-SCONN288_DDR506112002KQ,SMA   I177 @T6G_MB_LIB.T6G(SCH_1):PAGE97
   J24  197  VSS85 SCONN288_DDR506112002KQ-SCONN288_DDR506112002KQ,SMA   I177 @T6G_MB_LIB.T6G(SCH_1):PAGE97
   J24  199  VSS86 SCONN288_DDR506112002KQ-SCONN288_DDR506112002KQ,SMA   I177 @T6G_MB_LIB.T6G(SCH_1):PAGE97
   J24  202  VSS87 SCONN288_DDR506112002KQ-SCONN288_DDR506112002KQ,SMA   I177 @T6G_MB_LIB.T6G(SCH_1):PAGE97
   J24  204  VSS88 SCONN288_DDR506112002KQ-SCONN288_DDR506112002KQ,SMA   I177 @T6G_MB_LIB.T6G(SCH_1):PAGE97
   J24  206  VSS89 SCONN288_DDR506112002KQ-SCONN288_DDR506112002KQ,SMA   I177 @T6G_MB_LIB.T6G(SCH_1):PAGE97
   J24  208  VSS90 SCONN288_DDR506112002KQ-SCONN288_DDR506112002KQ,SMA   I177 @T6G_MB_LIB.T6G(SCH_1):PAGE97
   J24  210  VSS91 SCONN288_DDR506112002KQ-SCONN288_DDR506112002KQ,SMA   I177 @T6G_MB_LIB.T6G(SCH_1):PAGE97
   J24  212  VSS92 SCONN288_DDR506112002KQ-SCONN288_DDR506112002KQ,SMA   I177 @T6G_MB_LIB.T6G(SCH_1):PAGE97
   J24  214  VSS93 SCONN288_DDR506112002KQ-SCONN288_DDR506112002KQ,SMA   I177 @T6G_MB_LIB.T6G(SCH_1):PAGE97
   J24  216  VSS94 SCONN288_DDR506112002KQ-SCONN288_DDR506112002KQ,SMA   I177 @T6G_MB_LIB.T6G(SCH_1):PAGE97
   J24  219  VSS95 SCONN288_DDR506112002KQ-SCONN288_DDR506112002KQ,SMA   I177 @T6G_MB_LIB.T6G(SCH_1):PAGE97
   J24  222  VSS96 SCONN288_DDR506112002KQ-SCONN288_DDR506112002KQ,SMA   I177 @T6G_MB_LIB.T6G(SCH_1):PAGE97
   J24  224  VSS97 SCONN288_DDR506112002KQ-SCONN288_DDR506112002KQ,SMA   I177 @T6G_MB_LIB.T6G(SCH_1):PAGE97
   J24  226  VSS98 SCONN288_DDR506112002KQ-SCONN288_DDR506112002KQ,SMA   I177 @T6G_MB_LIB.T6G(SCH_1):PAGE97
   J24  228  VSS99 SCONN288_DDR506112002KQ-SCONN288_DDR506112002KQ,SMA   I177 @T6G_MB_LIB.T6G(SCH_1):PAGE97
   J24  230 VSS100 SCONN288_DDR506112002KQ-SCONN288_DDR506112002KQ,SMA   I177 @T6G_MB_LIB.T6G(SCH_1):PAGE97
   J24  233 VSS101 SCONN288_DDR506112002KQ-SCONN288_DDR506112002KQ,SMA   I177 @T6G_MB_LIB.T6G(SCH_1):PAGE97
   J24  235 VSS102 SCONN288_DDR506112002KQ-SCONN288_DDR506112002KQ,SMA   I177 @T6G_MB_LIB.T6G(SCH_1):PAGE97
   J24  237 VSS103 SCONN288_DDR506112002KQ-SCONN288_DDR506112002KQ,SMA   I177 @T6G_MB_LIB.T6G(SCH_1):PAGE97
   J24  240 VSS104 SCONN288_DDR506112002KQ-SCONN288_DDR506112002KQ,SMA   I177 @T6G_MB_LIB.T6G(SCH_1):PAGE97
   J24  242 VSS105 SCONN288_DDR506112002KQ-SCONN288_DDR506112002KQ,SMA   I177 @T6G_MB_LIB.T6G(SCH_1):PAGE97
   J24  244 VSS106 SCONN288_DDR506112002KQ-SCONN288_DDR506112002KQ,SMA   I177 @T6G_MB_LIB.T6G(SCH_1):PAGE97
   J24  246 VSS107 SCONN288_DDR506112002KQ-SCONN288_DDR506112002KQ,SMA   I177 @T6G_MB_LIB.T6G(SCH_1):PAGE97
   J24  248 VSS108 SCONN288_DDR506112002KQ-SCONN288_DDR506112002KQ,SMA   I177 @T6G_MB_LIB.T6G(SCH_1):PAGE97
   J24  251 VSS109 SCONN288_DDR506112002KQ-SCONN288_DDR506112002KQ,SMA   I177 @T6G_MB_LIB.T6G(SCH_1):PAGE97
   J24  253 VSS110 SCONN288_DDR506112002KQ-SCONN288_DDR506112002KQ,SMA   I177 @T6G_MB_LIB.T6G(SCH_1):PAGE97
   J24  255 VSS111 SCONN288_DDR506112002KQ-SCONN288_DDR506112002KQ,SMA   I177 @T6G_MB_LIB.T6G(SCH_1):PAGE97
   J24  257 VSS112 SCONN288_DDR506112002KQ-SCONN288_DDR506112002KQ,SMA   I177 @T6G_MB_LIB.T6G(SCH_1):PAGE97
   J24  259 VSS113 SCONN288_DDR506112002KQ-SCONN288_DDR506112002KQ,SMA   I177 @T6G_MB_LIB.T6G(SCH_1):PAGE97
   J24  262 VSS114 SCONN288_DDR506112002KQ-SCONN288_DDR506112002KQ,SMA   I177 @T6G_MB_LIB.T6G(SCH_1):PAGE97
   J24  264 VSS115 SCONN288_DDR506112002KQ-SCONN288_DDR506112002KQ,SMA   I177 @T6G_MB_LIB.T6G(SCH_1):PAGE97
   J24  266 VSS116 SCONN288_DDR506112002KQ-SCONN288_DDR506112002KQ,SMA   I177 @T6G_MB_LIB.T6G(SCH_1):PAGE97
   J24  268 VSS117 SCONN288_DDR506112002KQ-SCONN288_DDR506112002KQ,SMA   I177 @T6G_MB_LIB.T6G(SCH_1):PAGE97
   J24  270 VSS118 SCONN288_DDR506112002KQ-SCONN288_DDR506112002KQ,SMA   I177 @T6G_MB_LIB.T6G(SCH_1):PAGE97
   J24  273 VSS119 SCONN288_DDR506112002KQ-SCONN288_DDR506112002KQ,SMA   I177 @T6G_MB_LIB.T6G(SCH_1):PAGE97
   J24  275 VSS120 SCONN288_DDR506112002KQ-SCONN288_DDR506112002KQ,SMA   I177 @T6G_MB_LIB.T6G(SCH_1):PAGE97
   J24  277 VSS121 SCONN288_DDR506112002KQ-SCONN288_DDR506112002KQ,SMA   I177 @T6G_MB_LIB.T6G(SCH_1):PAGE97
   J24  279 VSS122 SCONN288_DDR506112002KQ-SCONN288_DDR506112002KQ,SMA   I177 @T6G_MB_LIB.T6G(SCH_1):PAGE97
   J24  281 VSS123 SCONN288_DDR506112002KQ-SCONN288_DDR506112002KQ,SMA   I177 @T6G_MB_LIB.T6G(SCH_1):PAGE97
   J24  284 VSS124 SCONN288_DDR506112002KQ-SCONN288_DDR506112002KQ,SMA   I177 @T6G_MB_LIB.T6G(SCH_1):PAGE97
   J24  286 VSS125 SCONN288_DDR506112002KQ-SCONN288_DDR506112002KQ,SMA   I177 @T6G_MB_LIB.T6G(SCH_1):PAGE97
   J24  288 VSS126 SCONN288_DDR506112002KQ-SCONN288_DDR506112002KQ,SMA   I177 @T6G_MB_LIB.T6G(SCH_1):PAGE97
  C136    2      B Q_CAP_0402-0.1UF,25V,10%,X7R,CH4104K1B00   I185 @T6G_MB_LIB.T6G(SCH_1):PAGE97
  C173    2      B Q_CAP_C0805-10UF,25V,10%,X6S,CH6104KEA00   I240 @T6G_MB_LIB.T6G(SCH_1):PAGE97
  C174    2      B Q_CAP_C0805-10UF,25V,10%,X6S,CH6104KEA00   I241 @T6G_MB_LIB.T6G(SCH_1):PAGE97
  R770    2      B Q_RES_0402LF-15.4K,1%,1/16W,CHIP,CS31542FB02   I127 @T6G_MB_LIB.T6G(SCH_1):PAGE98
   J26   G1     G1 SCONN288_DDR506112002KQ-SCONN288_DDR506112002KQ,SMA   I160 @T6G_MB_LIB.T6G(SCH_1):PAGE98
   J26   G2     G2 SCONN288_DDR506112002KQ-SCONN288_DDR506112002KQ,SMA   I160 @T6G_MB_LIB.T6G(SCH_1):PAGE98
   J26   G3     G3 SCONN288_DDR506112002KQ-SCONN288_DDR506112002KQ,SMA   I160 @T6G_MB_LIB.T6G(SCH_1):PAGE98
   J26    6   VSS0 SCONN288_DDR506112002KQ-SCONN288_DDR506112002KQ,SMA   I160 @T6G_MB_LIB.T6G(SCH_1):PAGE98
   J26    8   VSS1 SCONN288_DDR506112002KQ-SCONN288_DDR506112002KQ,SMA   I160 @T6G_MB_LIB.T6G(SCH_1):PAGE98
   J26   10   VSS2 SCONN288_DDR506112002KQ-SCONN288_DDR506112002KQ,SMA   I160 @T6G_MB_LIB.T6G(SCH_1):PAGE98
   J26   13   VSS3 SCONN288_DDR506112002KQ-SCONN288_DDR506112002KQ,SMA   I160 @T6G_MB_LIB.T6G(SCH_1):PAGE98
   J26   15   VSS4 SCONN288_DDR506112002KQ-SCONN288_DDR506112002KQ,SMA   I160 @T6G_MB_LIB.T6G(SCH_1):PAGE98
   J26   17   VSS5 SCONN288_DDR506112002KQ-SCONN288_DDR506112002KQ,SMA   I160 @T6G_MB_LIB.T6G(SCH_1):PAGE98
   J26   19   VSS6 SCONN288_DDR506112002KQ-SCONN288_DDR506112002KQ,SMA   I160 @T6G_MB_LIB.T6G(SCH_1):PAGE98
   J26   21   VSS7 SCONN288_DDR506112002KQ-SCONN288_DDR506112002KQ,SMA   I160 @T6G_MB_LIB.T6G(SCH_1):PAGE98
   J26   24   VSS8 SCONN288_DDR506112002KQ-SCONN288_DDR506112002KQ,SMA   I160 @T6G_MB_LIB.T6G(SCH_1):PAGE98
   J26   26   VSS9 SCONN288_DDR506112002KQ-SCONN288_DDR506112002KQ,SMA   I160 @T6G_MB_LIB.T6G(SCH_1):PAGE98
   J26   28  VSS10 SCONN288_DDR506112002KQ-SCONN288_DDR506112002KQ,SMA   I160 @T6G_MB_LIB.T6G(SCH_1):PAGE98
   J26   30  VSS11 SCONN288_DDR506112002KQ-SCONN288_DDR506112002KQ,SMA   I160 @T6G_MB_LIB.T6G(SCH_1):PAGE98
   J26   32  VSS12 SCONN288_DDR506112002KQ-SCONN288_DDR506112002KQ,SMA   I160 @T6G_MB_LIB.T6G(SCH_1):PAGE98
   J26   35  VSS13 SCONN288_DDR506112002KQ-SCONN288_DDR506112002KQ,SMA   I160 @T6G_MB_LIB.T6G(SCH_1):PAGE98
   J26   37  VSS14 SCONN288_DDR506112002KQ-SCONN288_DDR506112002KQ,SMA   I160 @T6G_MB_LIB.T6G(SCH_1):PAGE98
   J26   39  VSS15 SCONN288_DDR506112002KQ-SCONN288_DDR506112002KQ,SMA   I160 @T6G_MB_LIB.T6G(SCH_1):PAGE98
   J26   41  VSS16 SCONN288_DDR506112002KQ-SCONN288_DDR506112002KQ,SMA   I160 @T6G_MB_LIB.T6G(SCH_1):PAGE98
   J26   43  VSS17 SCONN288_DDR506112002KQ-SCONN288_DDR506112002KQ,SMA   I160 @T6G_MB_LIB.T6G(SCH_1):PAGE98
   J26   46  VSS18 SCONN288_DDR506112002KQ-SCONN288_DDR506112002KQ,SMA   I160 @T6G_MB_LIB.T6G(SCH_1):PAGE98
   J26   48  VSS19 SCONN288_DDR506112002KQ-SCONN288_DDR506112002KQ,SMA   I160 @T6G_MB_LIB.T6G(SCH_1):PAGE98
   J26   50  VSS20 SCONN288_DDR506112002KQ-SCONN288_DDR506112002KQ,SMA   I160 @T6G_MB_LIB.T6G(SCH_1):PAGE98
   J26   52  VSS21 SCONN288_DDR506112002KQ-SCONN288_DDR506112002KQ,SMA   I160 @T6G_MB_LIB.T6G(SCH_1):PAGE98
   J26   54  VSS22 SCONN288_DDR506112002KQ-SCONN288_DDR506112002KQ,SMA   I160 @T6G_MB_LIB.T6G(SCH_1):PAGE98
   J26   57  VSS23 SCONN288_DDR506112002KQ-SCONN288_DDR506112002KQ,SMA   I160 @T6G_MB_LIB.T6G(SCH_1):PAGE98
   J26   59  VSS24 SCONN288_DDR506112002KQ-SCONN288_DDR506112002KQ,SMA   I160 @T6G_MB_LIB.T6G(SCH_1):PAGE98
   J26   61  VSS25 SCONN288_DDR506112002KQ-SCONN288_DDR506112002KQ,SMA   I160 @T6G_MB_LIB.T6G(SCH_1):PAGE98
   J26   63  VSS26 SCONN288_DDR506112002KQ-SCONN288_DDR506112002KQ,SMA   I160 @T6G_MB_LIB.T6G(SCH_1):PAGE98
   J26   65  VSS27 SCONN288_DDR506112002KQ-SCONN288_DDR506112002KQ,SMA   I160 @T6G_MB_LIB.T6G(SCH_1):PAGE98
   J26   67  VSS28 SCONN288_DDR506112002KQ-SCONN288_DDR506112002KQ,SMA   I160 @T6G_MB_LIB.T6G(SCH_1):PAGE98
   J26   69  VSS29 SCONN288_DDR506112002KQ-SCONN288_DDR506112002KQ,SMA   I160 @T6G_MB_LIB.T6G(SCH_1):PAGE98
   J26   71  VSS30 SCONN288_DDR506112002KQ-SCONN288_DDR506112002KQ,SMA   I160 @T6G_MB_LIB.T6G(SCH_1):PAGE98
   J26   73  VSS31 SCONN288_DDR506112002KQ-SCONN288_DDR506112002KQ,SMA   I160 @T6G_MB_LIB.T6G(SCH_1):PAGE98
   J26   75  VSS32 SCONN288_DDR506112002KQ-SCONN288_DDR506112002KQ,SMA   I160 @T6G_MB_LIB.T6G(SCH_1):PAGE98
   J26   77  VSS33 SCONN288_DDR506112002KQ-SCONN288_DDR506112002KQ,SMA   I160 @T6G_MB_LIB.T6G(SCH_1):PAGE98
   J26   79  VSS34 SCONN288_DDR506112002KQ-SCONN288_DDR506112002KQ,SMA   I160 @T6G_MB_LIB.T6G(SCH_1):PAGE98
   J26   81  VSS35 SCONN288_DDR506112002KQ-SCONN288_DDR506112002KQ,SMA   I160 @T6G_MB_LIB.T6G(SCH_1):PAGE98
   J26   83  VSS36 SCONN288_DDR506112002KQ-SCONN288_DDR506112002KQ,SMA   I160 @T6G_MB_LIB.T6G(SCH_1):PAGE98
   J26   85  VSS37 SCONN288_DDR506112002KQ-SCONN288_DDR506112002KQ,SMA   I160 @T6G_MB_LIB.T6G(SCH_1):PAGE98
   J26   88  VSS38 SCONN288_DDR506112002KQ-SCONN288_DDR506112002KQ,SMA   I160 @T6G_MB_LIB.T6G(SCH_1):PAGE98
   J26   90  VSS39 SCONN288_DDR506112002KQ-SCONN288_DDR506112002KQ,SMA   I160 @T6G_MB_LIB.T6G(SCH_1):PAGE98
   J26   92  VSS40 SCONN288_DDR506112002KQ-SCONN288_DDR506112002KQ,SMA   I160 @T6G_MB_LIB.T6G(SCH_1):PAGE98
   J26   95  VSS41 SCONN288_DDR506112002KQ-SCONN288_DDR506112002KQ,SMA   I160 @T6G_MB_LIB.T6G(SCH_1):PAGE98
   J26   97  VSS42 SCONN288_DDR506112002KQ-SCONN288_DDR506112002KQ,SMA   I160 @T6G_MB_LIB.T6G(SCH_1):PAGE98
   J26   99  VSS43 SCONN288_DDR506112002KQ-SCONN288_DDR506112002KQ,SMA   I160 @T6G_MB_LIB.T6G(SCH_1):PAGE98
   J26  101  VSS44 SCONN288_DDR506112002KQ-SCONN288_DDR506112002KQ,SMA   I160 @T6G_MB_LIB.T6G(SCH_1):PAGE98
   J26  103  VSS45 SCONN288_DDR506112002KQ-SCONN288_DDR506112002KQ,SMA   I160 @T6G_MB_LIB.T6G(SCH_1):PAGE98
   J26  106  VSS46 SCONN288_DDR506112002KQ-SCONN288_DDR506112002KQ,SMA   I160 @T6G_MB_LIB.T6G(SCH_1):PAGE98
   J26  108  VSS47 SCONN288_DDR506112002KQ-SCONN288_DDR506112002KQ,SMA   I160 @T6G_MB_LIB.T6G(SCH_1):PAGE98
   J26  110  VSS48 SCONN288_DDR506112002KQ-SCONN288_DDR506112002KQ,SMA   I160 @T6G_MB_LIB.T6G(SCH_1):PAGE98
   J26  112  VSS49 SCONN288_DDR506112002KQ-SCONN288_DDR506112002KQ,SMA   I160 @T6G_MB_LIB.T6G(SCH_1):PAGE98
   J26  114  VSS50 SCONN288_DDR506112002KQ-SCONN288_DDR506112002KQ,SMA   I160 @T6G_MB_LIB.T6G(SCH_1):PAGE98
   J26  117  VSS51 SCONN288_DDR506112002KQ-SCONN288_DDR506112002KQ,SMA   I160 @T6G_MB_LIB.T6G(SCH_1):PAGE98
   J26  119  VSS52 SCONN288_DDR506112002KQ-SCONN288_DDR506112002KQ,SMA   I160 @T6G_MB_LIB.T6G(SCH_1):PAGE98
   J26  121  VSS53 SCONN288_DDR506112002KQ-SCONN288_DDR506112002KQ,SMA   I160 @T6G_MB_LIB.T6G(SCH_1):PAGE98
   J26  123  VSS54 SCONN288_DDR506112002KQ-SCONN288_DDR506112002KQ,SMA   I160 @T6G_MB_LIB.T6G(SCH_1):PAGE98
   J26  125  VSS55 SCONN288_DDR506112002KQ-SCONN288_DDR506112002KQ,SMA   I160 @T6G_MB_LIB.T6G(SCH_1):PAGE98
   J26  128  VSS56 SCONN288_DDR506112002KQ-SCONN288_DDR506112002KQ,SMA   I160 @T6G_MB_LIB.T6G(SCH_1):PAGE98
   J26  130  VSS57 SCONN288_DDR506112002KQ-SCONN288_DDR506112002KQ,SMA   I160 @T6G_MB_LIB.T6G(SCH_1):PAGE98
   J26  132  VSS58 SCONN288_DDR506112002KQ-SCONN288_DDR506112002KQ,SMA   I160 @T6G_MB_LIB.T6G(SCH_1):PAGE98
   J26  134  VSS59 SCONN288_DDR506112002KQ-SCONN288_DDR506112002KQ,SMA   I160 @T6G_MB_LIB.T6G(SCH_1):PAGE98
   J26  136  VSS60 SCONN288_DDR506112002KQ-SCONN288_DDR506112002KQ,SMA   I160 @T6G_MB_LIB.T6G(SCH_1):PAGE98
   J26  139  VSS61 SCONN288_DDR506112002KQ-SCONN288_DDR506112002KQ,SMA   I160 @T6G_MB_LIB.T6G(SCH_1):PAGE98
   J26  141  VSS62 SCONN288_DDR506112002KQ-SCONN288_DDR506112002KQ,SMA   I160 @T6G_MB_LIB.T6G(SCH_1):PAGE98
   J26  143  VSS63 SCONN288_DDR506112002KQ-SCONN288_DDR506112002KQ,SMA   I160 @T6G_MB_LIB.T6G(SCH_1):PAGE98
   J26  151  VSS64 SCONN288_DDR506112002KQ-SCONN288_DDR506112002KQ,SMA   I160 @T6G_MB_LIB.T6G(SCH_1):PAGE98
   J26  153  VSS65 SCONN288_DDR506112002KQ-SCONN288_DDR506112002KQ,SMA   I160 @T6G_MB_LIB.T6G(SCH_1):PAGE98
   J26  155  VSS66 SCONN288_DDR506112002KQ-SCONN288_DDR506112002KQ,SMA   I160 @T6G_MB_LIB.T6G(SCH_1):PAGE98
   J26  158  VSS67 SCONN288_DDR506112002KQ-SCONN288_DDR506112002KQ,SMA   I160 @T6G_MB_LIB.T6G(SCH_1):PAGE98
   J26  160  VSS68 SCONN288_DDR506112002KQ-SCONN288_DDR506112002KQ,SMA   I160 @T6G_MB_LIB.T6G(SCH_1):PAGE98
   J26  162  VSS69 SCONN288_DDR506112002KQ-SCONN288_DDR506112002KQ,SMA   I160 @T6G_MB_LIB.T6G(SCH_1):PAGE98
   J26  164  VSS70 SCONN288_DDR506112002KQ-SCONN288_DDR506112002KQ,SMA   I160 @T6G_MB_LIB.T6G(SCH_1):PAGE98
   J26  166  VSS71 SCONN288_DDR506112002KQ-SCONN288_DDR506112002KQ,SMA   I160 @T6G_MB_LIB.T6G(SCH_1):PAGE98
   J26  169  VSS72 SCONN288_DDR506112002KQ-SCONN288_DDR506112002KQ,SMA   I160 @T6G_MB_LIB.T6G(SCH_1):PAGE98
   J26  171  VSS73 SCONN288_DDR506112002KQ-SCONN288_DDR506112002KQ,SMA   I160 @T6G_MB_LIB.T6G(SCH_1):PAGE98
   J26  173  VSS74 SCONN288_DDR506112002KQ-SCONN288_DDR506112002KQ,SMA   I160 @T6G_MB_LIB.T6G(SCH_1):PAGE98
   J26  175  VSS75 SCONN288_DDR506112002KQ-SCONN288_DDR506112002KQ,SMA   I160 @T6G_MB_LIB.T6G(SCH_1):PAGE98
   J26  177  VSS76 SCONN288_DDR506112002KQ-SCONN288_DDR506112002KQ,SMA   I160 @T6G_MB_LIB.T6G(SCH_1):PAGE98
   J26  180  VSS77 SCONN288_DDR506112002KQ-SCONN288_DDR506112002KQ,SMA   I160 @T6G_MB_LIB.T6G(SCH_1):PAGE98
   J26  182  VSS78 SCONN288_DDR506112002KQ-SCONN288_DDR506112002KQ,SMA   I160 @T6G_MB_LIB.T6G(SCH_1):PAGE98
   J26  184  VSS79 SCONN288_DDR506112002KQ-SCONN288_DDR506112002KQ,SMA   I160 @T6G_MB_LIB.T6G(SCH_1):PAGE98
   J26  186  VSS80 SCONN288_DDR506112002KQ-SCONN288_DDR506112002KQ,SMA   I160 @T6G_MB_LIB.T6G(SCH_1):PAGE98
   J26  188  VSS81 SCONN288_DDR506112002KQ-SCONN288_DDR506112002KQ,SMA   I160 @T6G_MB_LIB.T6G(SCH_1):PAGE98
   J26  191  VSS82 SCONN288_DDR506112002KQ-SCONN288_DDR506112002KQ,SMA   I160 @T6G_MB_LIB.T6G(SCH_1):PAGE98
   J26  193  VSS83 SCONN288_DDR506112002KQ-SCONN288_DDR506112002KQ,SMA   I160 @T6G_MB_LIB.T6G(SCH_1):PAGE98
   J26  195  VSS84 SCONN288_DDR506112002KQ-SCONN288_DDR506112002KQ,SMA   I160 @T6G_MB_LIB.T6G(SCH_1):PAGE98
   J26  197  VSS85 SCONN288_DDR506112002KQ-SCONN288_DDR506112002KQ,SMA   I160 @T6G_MB_LIB.T6G(SCH_1):PAGE98
   J26  199  VSS86 SCONN288_DDR506112002KQ-SCONN288_DDR506112002KQ,SMA   I160 @T6G_MB_LIB.T6G(SCH_1):PAGE98
   J26  202  VSS87 SCONN288_DDR506112002KQ-SCONN288_DDR506112002KQ,SMA   I160 @T6G_MB_LIB.T6G(SCH_1):PAGE98
   J26  204  VSS88 SCONN288_DDR506112002KQ-SCONN288_DDR506112002KQ,SMA   I160 @T6G_MB_LIB.T6G(SCH_1):PAGE98
   J26  206  VSS89 SCONN288_DDR506112002KQ-SCONN288_DDR506112002KQ,SMA   I160 @T6G_MB_LIB.T6G(SCH_1):PAGE98
   J26  208  VSS90 SCONN288_DDR506112002KQ-SCONN288_DDR506112002KQ,SMA   I160 @T6G_MB_LIB.T6G(SCH_1):PAGE98
   J26  210  VSS91 SCONN288_DDR506112002KQ-SCONN288_DDR506112002KQ,SMA   I160 @T6G_MB_LIB.T6G(SCH_1):PAGE98
   J26  212  VSS92 SCONN288_DDR506112002KQ-SCONN288_DDR506112002KQ,SMA   I160 @T6G_MB_LIB.T6G(SCH_1):PAGE98
   J26  214  VSS93 SCONN288_DDR506112002KQ-SCONN288_DDR506112002KQ,SMA   I160 @T6G_MB_LIB.T6G(SCH_1):PAGE98
   J26  216  VSS94 SCONN288_DDR506112002KQ-SCONN288_DDR506112002KQ,SMA   I160 @T6G_MB_LIB.T6G(SCH_1):PAGE98
   J26  219  VSS95 SCONN288_DDR506112002KQ-SCONN288_DDR506112002KQ,SMA   I160 @T6G_MB_LIB.T6G(SCH_1):PAGE98
   J26  222  VSS96 SCONN288_DDR506112002KQ-SCONN288_DDR506112002KQ,SMA   I160 @T6G_MB_LIB.T6G(SCH_1):PAGE98
   J26  224  VSS97 SCONN288_DDR506112002KQ-SCONN288_DDR506112002KQ,SMA   I160 @T6G_MB_LIB.T6G(SCH_1):PAGE98
   J26  226  VSS98 SCONN288_DDR506112002KQ-SCONN288_DDR506112002KQ,SMA   I160 @T6G_MB_LIB.T6G(SCH_1):PAGE98
   J26  228  VSS99 SCONN288_DDR506112002KQ-SCONN288_DDR506112002KQ,SMA   I160 @T6G_MB_LIB.T6G(SCH_1):PAGE98
   J26  230 VSS100 SCONN288_DDR506112002KQ-SCONN288_DDR506112002KQ,SMA   I160 @T6G_MB_LIB.T6G(SCH_1):PAGE98
   J26  233 VSS101 SCONN288_DDR506112002KQ-SCONN288_DDR506112002KQ,SMA   I160 @T6G_MB_LIB.T6G(SCH_1):PAGE98
   J26  235 VSS102 SCONN288_DDR506112002KQ-SCONN288_DDR506112002KQ,SMA   I160 @T6G_MB_LIB.T6G(SCH_1):PAGE98
   J26  237 VSS103 SCONN288_DDR506112002KQ-SCONN288_DDR506112002KQ,SMA   I160 @T6G_MB_LIB.T6G(SCH_1):PAGE98
   J26  240 VSS104 SCONN288_DDR506112002KQ-SCONN288_DDR506112002KQ,SMA   I160 @T6G_MB_LIB.T6G(SCH_1):PAGE98
   J26  242 VSS105 SCONN288_DDR506112002KQ-SCONN288_DDR506112002KQ,SMA   I160 @T6G_MB_LIB.T6G(SCH_1):PAGE98
   J26  244 VSS106 SCONN288_DDR506112002KQ-SCONN288_DDR506112002KQ,SMA   I160 @T6G_MB_LIB.T6G(SCH_1):PAGE98
   J26  246 VSS107 SCONN288_DDR506112002KQ-SCONN288_DDR506112002KQ,SMA   I160 @T6G_MB_LIB.T6G(SCH_1):PAGE98
   J26  248 VSS108 SCONN288_DDR506112002KQ-SCONN288_DDR506112002KQ,SMA   I160 @T6G_MB_LIB.T6G(SCH_1):PAGE98
   J26  251 VSS109 SCONN288_DDR506112002KQ-SCONN288_DDR506112002KQ,SMA   I160 @T6G_MB_LIB.T6G(SCH_1):PAGE98
   J26  253 VSS110 SCONN288_DDR506112002KQ-SCONN288_DDR506112002KQ,SMA   I160 @T6G_MB_LIB.T6G(SCH_1):PAGE98
   J26  255 VSS111 SCONN288_DDR506112002KQ-SCONN288_DDR506112002KQ,SMA   I160 @T6G_MB_LIB.T6G(SCH_1):PAGE98
   J26  257 VSS112 SCONN288_DDR506112002KQ-SCONN288_DDR506112002KQ,SMA   I160 @T6G_MB_LIB.T6G(SCH_1):PAGE98
   J26  259 VSS113 SCONN288_DDR506112002KQ-SCONN288_DDR506112002KQ,SMA   I160 @T6G_MB_LIB.T6G(SCH_1):PAGE98
   J26  262 VSS114 SCONN288_DDR506112002KQ-SCONN288_DDR506112002KQ,SMA   I160 @T6G_MB_LIB.T6G(SCH_1):PAGE98
   J26  264 VSS115 SCONN288_DDR506112002KQ-SCONN288_DDR506112002KQ,SMA   I160 @T6G_MB_LIB.T6G(SCH_1):PAGE98
   J26  266 VSS116 SCONN288_DDR506112002KQ-SCONN288_DDR506112002KQ,SMA   I160 @T6G_MB_LIB.T6G(SCH_1):PAGE98
   J26  268 VSS117 SCONN288_DDR506112002KQ-SCONN288_DDR506112002KQ,SMA   I160 @T6G_MB_LIB.T6G(SCH_1):PAGE98
   J26  270 VSS118 SCONN288_DDR506112002KQ-SCONN288_DDR506112002KQ,SMA   I160 @T6G_MB_LIB.T6G(SCH_1):PAGE98
   J26  273 VSS119 SCONN288_DDR506112002KQ-SCONN288_DDR506112002KQ,SMA   I160 @T6G_MB_LIB.T6G(SCH_1):PAGE98
   J26  275 VSS120 SCONN288_DDR506112002KQ-SCONN288_DDR506112002KQ,SMA   I160 @T6G_MB_LIB.T6G(SCH_1):PAGE98
   J26  277 VSS121 SCONN288_DDR506112002KQ-SCONN288_DDR506112002KQ,SMA   I160 @T6G_MB_LIB.T6G(SCH_1):PAGE98
   J26  279 VSS122 SCONN288_DDR506112002KQ-SCONN288_DDR506112002KQ,SMA   I160 @T6G_MB_LIB.T6G(SCH_1):PAGE98
   J26  281 VSS123 SCONN288_DDR506112002KQ-SCONN288_DDR506112002KQ,SMA   I160 @T6G_MB_LIB.T6G(SCH_1):PAGE98
   J26  284 VSS124 SCONN288_DDR506112002KQ-SCONN288_DDR506112002KQ,SMA   I160 @T6G_MB_LIB.T6G(SCH_1):PAGE98
   J26  286 VSS125 SCONN288_DDR506112002KQ-SCONN288_DDR506112002KQ,SMA   I160 @T6G_MB_LIB.T6G(SCH_1):PAGE98
   J26  288 VSS126 SCONN288_DDR506112002KQ-SCONN288_DDR506112002KQ,SMA   I160 @T6G_MB_LIB.T6G(SCH_1):PAGE98
  C140    2      B Q_CAP_0402-0.1UF,25V,10%,X7R,CH4104K1B00   I185 @T6G_MB_LIB.T6G(SCH_1):PAGE98
  C175    2      B Q_CAP_C0805-10UF,25V,10%,X6S,CH6104KEA00   I238 @T6G_MB_LIB.T6G(SCH_1):PAGE98
  C177    2      B Q_CAP_C0805-10UF,25V,10%,X6S,CH6104KEA00   I239 @T6G_MB_LIB.T6G(SCH_1):PAGE98
  R771    2      B Q_RES_0402LF-23.2K,1%,1/16W,CHIP,CS32322FB03   I148 @T6G_MB_LIB.T6G(SCH_1):PAGE99
   J28   G1     G1 SCONN288_DDR506112002KQ-SCONN288_DDR506112002KQ,SMA   I155 @T6G_MB_LIB.T6G(SCH_1):PAGE99
   J28   G2     G2 SCONN288_DDR506112002KQ-SCONN288_DDR506112002KQ,SMA   I155 @T6G_MB_LIB.T6G(SCH_1):PAGE99
   J28   G3     G3 SCONN288_DDR506112002KQ-SCONN288_DDR506112002KQ,SMA   I155 @T6G_MB_LIB.T6G(SCH_1):PAGE99
   J28    6   VSS0 SCONN288_DDR506112002KQ-SCONN288_DDR506112002KQ,SMA   I155 @T6G_MB_LIB.T6G(SCH_1):PAGE99
   J28    8   VSS1 SCONN288_DDR506112002KQ-SCONN288_DDR506112002KQ,SMA   I155 @T6G_MB_LIB.T6G(SCH_1):PAGE99
   J28   10   VSS2 SCONN288_DDR506112002KQ-SCONN288_DDR506112002KQ,SMA   I155 @T6G_MB_LIB.T6G(SCH_1):PAGE99
   J28   13   VSS3 SCONN288_DDR506112002KQ-SCONN288_DDR506112002KQ,SMA   I155 @T6G_MB_LIB.T6G(SCH_1):PAGE99
   J28   15   VSS4 SCONN288_DDR506112002KQ-SCONN288_DDR506112002KQ,SMA   I155 @T6G_MB_LIB.T6G(SCH_1):PAGE99
   J28   17   VSS5 SCONN288_DDR506112002KQ-SCONN288_DDR506112002KQ,SMA   I155 @T6G_MB_LIB.T6G(SCH_1):PAGE99
   J28   19   VSS6 SCONN288_DDR506112002KQ-SCONN288_DDR506112002KQ,SMA   I155 @T6G_MB_LIB.T6G(SCH_1):PAGE99
   J28   21   VSS7 SCONN288_DDR506112002KQ-SCONN288_DDR506112002KQ,SMA   I155 @T6G_MB_LIB.T6G(SCH_1):PAGE99
   J28   24   VSS8 SCONN288_DDR506112002KQ-SCONN288_DDR506112002KQ,SMA   I155 @T6G_MB_LIB.T6G(SCH_1):PAGE99
   J28   26   VSS9 SCONN288_DDR506112002KQ-SCONN288_DDR506112002KQ,SMA   I155 @T6G_MB_LIB.T6G(SCH_1):PAGE99
   J28   28  VSS10 SCONN288_DDR506112002KQ-SCONN288_DDR506112002KQ,SMA   I155 @T6G_MB_LIB.T6G(SCH_1):PAGE99
   J28   30  VSS11 SCONN288_DDR506112002KQ-SCONN288_DDR506112002KQ,SMA   I155 @T6G_MB_LIB.T6G(SCH_1):PAGE99
   J28   32  VSS12 SCONN288_DDR506112002KQ-SCONN288_DDR506112002KQ,SMA   I155 @T6G_MB_LIB.T6G(SCH_1):PAGE99
   J28   35  VSS13 SCONN288_DDR506112002KQ-SCONN288_DDR506112002KQ,SMA   I155 @T6G_MB_LIB.T6G(SCH_1):PAGE99
   J28   37  VSS14 SCONN288_DDR506112002KQ-SCONN288_DDR506112002KQ,SMA   I155 @T6G_MB_LIB.T6G(SCH_1):PAGE99
   J28   39  VSS15 SCONN288_DDR506112002KQ-SCONN288_DDR506112002KQ,SMA   I155 @T6G_MB_LIB.T6G(SCH_1):PAGE99
   J28   41  VSS16 SCONN288_DDR506112002KQ-SCONN288_DDR506112002KQ,SMA   I155 @T6G_MB_LIB.T6G(SCH_1):PAGE99
   J28   43  VSS17 SCONN288_DDR506112002KQ-SCONN288_DDR506112002KQ,SMA   I155 @T6G_MB_LIB.T6G(SCH_1):PAGE99
   J28   46  VSS18 SCONN288_DDR506112002KQ-SCONN288_DDR506112002KQ,SMA   I155 @T6G_MB_LIB.T6G(SCH_1):PAGE99
   J28   48  VSS19 SCONN288_DDR506112002KQ-SCONN288_DDR506112002KQ,SMA   I155 @T6G_MB_LIB.T6G(SCH_1):PAGE99
   J28   50  VSS20 SCONN288_DDR506112002KQ-SCONN288_DDR506112002KQ,SMA   I155 @T6G_MB_LIB.T6G(SCH_1):PAGE99
   J28   52  VSS21 SCONN288_DDR506112002KQ-SCONN288_DDR506112002KQ,SMA   I155 @T6G_MB_LIB.T6G(SCH_1):PAGE99
   J28   54  VSS22 SCONN288_DDR506112002KQ-SCONN288_DDR506112002KQ,SMA   I155 @T6G_MB_LIB.T6G(SCH_1):PAGE99
   J28   57  VSS23 SCONN288_DDR506112002KQ-SCONN288_DDR506112002KQ,SMA   I155 @T6G_MB_LIB.T6G(SCH_1):PAGE99
   J28   59  VSS24 SCONN288_DDR506112002KQ-SCONN288_DDR506112002KQ,SMA   I155 @T6G_MB_LIB.T6G(SCH_1):PAGE99
   J28   61  VSS25 SCONN288_DDR506112002KQ-SCONN288_DDR506112002KQ,SMA   I155 @T6G_MB_LIB.T6G(SCH_1):PAGE99
   J28   63  VSS26 SCONN288_DDR506112002KQ-SCONN288_DDR506112002KQ,SMA   I155 @T6G_MB_LIB.T6G(SCH_1):PAGE99
   J28   65  VSS27 SCONN288_DDR506112002KQ-SCONN288_DDR506112002KQ,SMA   I155 @T6G_MB_LIB.T6G(SCH_1):PAGE99
   J28   67  VSS28 SCONN288_DDR506112002KQ-SCONN288_DDR506112002KQ,SMA   I155 @T6G_MB_LIB.T6G(SCH_1):PAGE99
   J28   69  VSS29 SCONN288_DDR506112002KQ-SCONN288_DDR506112002KQ,SMA   I155 @T6G_MB_LIB.T6G(SCH_1):PAGE99
   J28   71  VSS30 SCONN288_DDR506112002KQ-SCONN288_DDR506112002KQ,SMA   I155 @T6G_MB_LIB.T6G(SCH_1):PAGE99
   J28   73  VSS31 SCONN288_DDR506112002KQ-SCONN288_DDR506112002KQ,SMA   I155 @T6G_MB_LIB.T6G(SCH_1):PAGE99
   J28   75  VSS32 SCONN288_DDR506112002KQ-SCONN288_DDR506112002KQ,SMA   I155 @T6G_MB_LIB.T6G(SCH_1):PAGE99
   J28   77  VSS33 SCONN288_DDR506112002KQ-SCONN288_DDR506112002KQ,SMA   I155 @T6G_MB_LIB.T6G(SCH_1):PAGE99
   J28   79  VSS34 SCONN288_DDR506112002KQ-SCONN288_DDR506112002KQ,SMA   I155 @T6G_MB_LIB.T6G(SCH_1):PAGE99
   J28   81  VSS35 SCONN288_DDR506112002KQ-SCONN288_DDR506112002KQ,SMA   I155 @T6G_MB_LIB.T6G(SCH_1):PAGE99
   J28   83  VSS36 SCONN288_DDR506112002KQ-SCONN288_DDR506112002KQ,SMA   I155 @T6G_MB_LIB.T6G(SCH_1):PAGE99
   J28   85  VSS37 SCONN288_DDR506112002KQ-SCONN288_DDR506112002KQ,SMA   I155 @T6G_MB_LIB.T6G(SCH_1):PAGE99
   J28   88  VSS38 SCONN288_DDR506112002KQ-SCONN288_DDR506112002KQ,SMA   I155 @T6G_MB_LIB.T6G(SCH_1):PAGE99
   J28   90  VSS39 SCONN288_DDR506112002KQ-SCONN288_DDR506112002KQ,SMA   I155 @T6G_MB_LIB.T6G(SCH_1):PAGE99
   J28   92  VSS40 SCONN288_DDR506112002KQ-SCONN288_DDR506112002KQ,SMA   I155 @T6G_MB_LIB.T6G(SCH_1):PAGE99
   J28   95  VSS41 SCONN288_DDR506112002KQ-SCONN288_DDR506112002KQ,SMA   I155 @T6G_MB_LIB.T6G(SCH_1):PAGE99
   J28   97  VSS42 SCONN288_DDR506112002KQ-SCONN288_DDR506112002KQ,SMA   I155 @T6G_MB_LIB.T6G(SCH_1):PAGE99
   J28   99  VSS43 SCONN288_DDR506112002KQ-SCONN288_DDR506112002KQ,SMA   I155 @T6G_MB_LIB.T6G(SCH_1):PAGE99
   J28  101  VSS44 SCONN288_DDR506112002KQ-SCONN288_DDR506112002KQ,SMA   I155 @T6G_MB_LIB.T6G(SCH_1):PAGE99
   J28  103  VSS45 SCONN288_DDR506112002KQ-SCONN288_DDR506112002KQ,SMA   I155 @T6G_MB_LIB.T6G(SCH_1):PAGE99
   J28  106  VSS46 SCONN288_DDR506112002KQ-SCONN288_DDR506112002KQ,SMA   I155 @T6G_MB_LIB.T6G(SCH_1):PAGE99
   J28  108  VSS47 SCONN288_DDR506112002KQ-SCONN288_DDR506112002KQ,SMA   I155 @T6G_MB_LIB.T6G(SCH_1):PAGE99
   J28  110  VSS48 SCONN288_DDR506112002KQ-SCONN288_DDR506112002KQ,SMA   I155 @T6G_MB_LIB.T6G(SCH_1):PAGE99
   J28  112  VSS49 SCONN288_DDR506112002KQ-SCONN288_DDR506112002KQ,SMA   I155 @T6G_MB_LIB.T6G(SCH_1):PAGE99
   J28  114  VSS50 SCONN288_DDR506112002KQ-SCONN288_DDR506112002KQ,SMA   I155 @T6G_MB_LIB.T6G(SCH_1):PAGE99
   J28  117  VSS51 SCONN288_DDR506112002KQ-SCONN288_DDR506112002KQ,SMA   I155 @T6G_MB_LIB.T6G(SCH_1):PAGE99
   J28  119  VSS52 SCONN288_DDR506112002KQ-SCONN288_DDR506112002KQ,SMA   I155 @T6G_MB_LIB.T6G(SCH_1):PAGE99
   J28  121  VSS53 SCONN288_DDR506112002KQ-SCONN288_DDR506112002KQ,SMA   I155 @T6G_MB_LIB.T6G(SCH_1):PAGE99
   J28  123  VSS54 SCONN288_DDR506112002KQ-SCONN288_DDR506112002KQ,SMA   I155 @T6G_MB_LIB.T6G(SCH_1):PAGE99
   J28  125  VSS55 SCONN288_DDR506112002KQ-SCONN288_DDR506112002KQ,SMA   I155 @T6G_MB_LIB.T6G(SCH_1):PAGE99
   J28  128  VSS56 SCONN288_DDR506112002KQ-SCONN288_DDR506112002KQ,SMA   I155 @T6G_MB_LIB.T6G(SCH_1):PAGE99
   J28  130  VSS57 SCONN288_DDR506112002KQ-SCONN288_DDR506112002KQ,SMA   I155 @T6G_MB_LIB.T6G(SCH_1):PAGE99
   J28  132  VSS58 SCONN288_DDR506112002KQ-SCONN288_DDR506112002KQ,SMA   I155 @T6G_MB_LIB.T6G(SCH_1):PAGE99
   J28  134  VSS59 SCONN288_DDR506112002KQ-SCONN288_DDR506112002KQ,SMA   I155 @T6G_MB_LIB.T6G(SCH_1):PAGE99
   J28  136  VSS60 SCONN288_DDR506112002KQ-SCONN288_DDR506112002KQ,SMA   I155 @T6G_MB_LIB.T6G(SCH_1):PAGE99
   J28  139  VSS61 SCONN288_DDR506112002KQ-SCONN288_DDR506112002KQ,SMA   I155 @T6G_MB_LIB.T6G(SCH_1):PAGE99
   J28  141  VSS62 SCONN288_DDR506112002KQ-SCONN288_DDR506112002KQ,SMA   I155 @T6G_MB_LIB.T6G(SCH_1):PAGE99
   J28  143  VSS63 SCONN288_DDR506112002KQ-SCONN288_DDR506112002KQ,SMA   I155 @T6G_MB_LIB.T6G(SCH_1):PAGE99
   J28  151  VSS64 SCONN288_DDR506112002KQ-SCONN288_DDR506112002KQ,SMA   I155 @T6G_MB_LIB.T6G(SCH_1):PAGE99
   J28  153  VSS65 SCONN288_DDR506112002KQ-SCONN288_DDR506112002KQ,SMA   I155 @T6G_MB_LIB.T6G(SCH_1):PAGE99
   J28  155  VSS66 SCONN288_DDR506112002KQ-SCONN288_DDR506112002KQ,SMA   I155 @T6G_MB_LIB.T6G(SCH_1):PAGE99
   J28  158  VSS67 SCONN288_DDR506112002KQ-SCONN288_DDR506112002KQ,SMA   I155 @T6G_MB_LIB.T6G(SCH_1):PAGE99
   J28  160  VSS68 SCONN288_DDR506112002KQ-SCONN288_DDR506112002KQ,SMA   I155 @T6G_MB_LIB.T6G(SCH_1):PAGE99
   J28  162  VSS69 SCONN288_DDR506112002KQ-SCONN288_DDR506112002KQ,SMA   I155 @T6G_MB_LIB.T6G(SCH_1):PAGE99
   J28  164  VSS70 SCONN288_DDR506112002KQ-SCONN288_DDR506112002KQ,SMA   I155 @T6G_MB_LIB.T6G(SCH_1):PAGE99
   J28  166  VSS71 SCONN288_DDR506112002KQ-SCONN288_DDR506112002KQ,SMA   I155 @T6G_MB_LIB.T6G(SCH_1):PAGE99
   J28  169  VSS72 SCONN288_DDR506112002KQ-SCONN288_DDR506112002KQ,SMA   I155 @T6G_MB_LIB.T6G(SCH_1):PAGE99
   J28  171  VSS73 SCONN288_DDR506112002KQ-SCONN288_DDR506112002KQ,SMA   I155 @T6G_MB_LIB.T6G(SCH_1):PAGE99
   J28  173  VSS74 SCONN288_DDR506112002KQ-SCONN288_DDR506112002KQ,SMA   I155 @T6G_MB_LIB.T6G(SCH_1):PAGE99
   J28  175  VSS75 SCONN288_DDR506112002KQ-SCONN288_DDR506112002KQ,SMA   I155 @T6G_MB_LIB.T6G(SCH_1):PAGE99
   J28  177  VSS76 SCONN288_DDR506112002KQ-SCONN288_DDR506112002KQ,SMA   I155 @T6G_MB_LIB.T6G(SCH_1):PAGE99
   J28  180  VSS77 SCONN288_DDR506112002KQ-SCONN288_DDR506112002KQ,SMA   I155 @T6G_MB_LIB.T6G(SCH_1):PAGE99
   J28  182  VSS78 SCONN288_DDR506112002KQ-SCONN288_DDR506112002KQ,SMA   I155 @T6G_MB_LIB.T6G(SCH_1):PAGE99
   J28  184  VSS79 SCONN288_DDR506112002KQ-SCONN288_DDR506112002KQ,SMA   I155 @T6G_MB_LIB.T6G(SCH_1):PAGE99
   J28  186  VSS80 SCONN288_DDR506112002KQ-SCONN288_DDR506112002KQ,SMA   I155 @T6G_MB_LIB.T6G(SCH_1):PAGE99
   J28  188  VSS81 SCONN288_DDR506112002KQ-SCONN288_DDR506112002KQ,SMA   I155 @T6G_MB_LIB.T6G(SCH_1):PAGE99
   J28  191  VSS82 SCONN288_DDR506112002KQ-SCONN288_DDR506112002KQ,SMA   I155 @T6G_MB_LIB.T6G(SCH_1):PAGE99
   J28  193  VSS83 SCONN288_DDR506112002KQ-SCONN288_DDR506112002KQ,SMA   I155 @T6G_MB_LIB.T6G(SCH_1):PAGE99
   J28  195  VSS84 SCONN288_DDR506112002KQ-SCONN288_DDR506112002KQ,SMA   I155 @T6G_MB_LIB.T6G(SCH_1):PAGE99
   J28  197  VSS85 SCONN288_DDR506112002KQ-SCONN288_DDR506112002KQ,SMA   I155 @T6G_MB_LIB.T6G(SCH_1):PAGE99
   J28  199  VSS86 SCONN288_DDR506112002KQ-SCONN288_DDR506112002KQ,SMA   I155 @T6G_MB_LIB.T6G(SCH_1):PAGE99
   J28  202  VSS87 SCONN288_DDR506112002KQ-SCONN288_DDR506112002KQ,SMA   I155 @T6G_MB_LIB.T6G(SCH_1):PAGE99
   J28  204  VSS88 SCONN288_DDR506112002KQ-SCONN288_DDR506112002KQ,SMA   I155 @T6G_MB_LIB.T6G(SCH_1):PAGE99
   J28  206  VSS89 SCONN288_DDR506112002KQ-SCONN288_DDR506112002KQ,SMA   I155 @T6G_MB_LIB.T6G(SCH_1):PAGE99
   J28  208  VSS90 SCONN288_DDR506112002KQ-SCONN288_DDR506112002KQ,SMA   I155 @T6G_MB_LIB.T6G(SCH_1):PAGE99
   J28  210  VSS91 SCONN288_DDR506112002KQ-SCONN288_DDR506112002KQ,SMA   I155 @T6G_MB_LIB.T6G(SCH_1):PAGE99
   J28  212  VSS92 SCONN288_DDR506112002KQ-SCONN288_DDR506112002KQ,SMA   I155 @T6G_MB_LIB.T6G(SCH_1):PAGE99
   J28  214  VSS93 SCONN288_DDR506112002KQ-SCONN288_DDR506112002KQ,SMA   I155 @T6G_MB_LIB.T6G(SCH_1):PAGE99
   J28  216  VSS94 SCONN288_DDR506112002KQ-SCONN288_DDR506112002KQ,SMA   I155 @T6G_MB_LIB.T6G(SCH_1):PAGE99
   J28  219  VSS95 SCONN288_DDR506112002KQ-SCONN288_DDR506112002KQ,SMA   I155 @T6G_MB_LIB.T6G(SCH_1):PAGE99
   J28  222  VSS96 SCONN288_DDR506112002KQ-SCONN288_DDR506112002KQ,SMA   I155 @T6G_MB_LIB.T6G(SCH_1):PAGE99
   J28  224  VSS97 SCONN288_DDR506112002KQ-SCONN288_DDR506112002KQ,SMA   I155 @T6G_MB_LIB.T6G(SCH_1):PAGE99
   J28  226  VSS98 SCONN288_DDR506112002KQ-SCONN288_DDR506112002KQ,SMA   I155 @T6G_MB_LIB.T6G(SCH_1):PAGE99
   J28  228  VSS99 SCONN288_DDR506112002KQ-SCONN288_DDR506112002KQ,SMA   I155 @T6G_MB_LIB.T6G(SCH_1):PAGE99
   J28  230 VSS100 SCONN288_DDR506112002KQ-SCONN288_DDR506112002KQ,SMA   I155 @T6G_MB_LIB.T6G(SCH_1):PAGE99
   J28  233 VSS101 SCONN288_DDR506112002KQ-SCONN288_DDR506112002KQ,SMA   I155 @T6G_MB_LIB.T6G(SCH_1):PAGE99
   J28  235 VSS102 SCONN288_DDR506112002KQ-SCONN288_DDR506112002KQ,SMA   I155 @T6G_MB_LIB.T6G(SCH_1):PAGE99
   J28  237 VSS103 SCONN288_DDR506112002KQ-SCONN288_DDR506112002KQ,SMA   I155 @T6G_MB_LIB.T6G(SCH_1):PAGE99
   J28  240 VSS104 SCONN288_DDR506112002KQ-SCONN288_DDR506112002KQ,SMA   I155 @T6G_MB_LIB.T6G(SCH_1):PAGE99
   J28  242 VSS105 SCONN288_DDR506112002KQ-SCONN288_DDR506112002KQ,SMA   I155 @T6G_MB_LIB.T6G(SCH_1):PAGE99
   J28  244 VSS106 SCONN288_DDR506112002KQ-SCONN288_DDR506112002KQ,SMA   I155 @T6G_MB_LIB.T6G(SCH_1):PAGE99
   J28  246 VSS107 SCONN288_DDR506112002KQ-SCONN288_DDR506112002KQ,SMA   I155 @T6G_MB_LIB.T6G(SCH_1):PAGE99
   J28  248 VSS108 SCONN288_DDR506112002KQ-SCONN288_DDR506112002KQ,SMA   I155 @T6G_MB_LIB.T6G(SCH_1):PAGE99
   J28  251 VSS109 SCONN288_DDR506112002KQ-SCONN288_DDR506112002KQ,SMA   I155 @T6G_MB_LIB.T6G(SCH_1):PAGE99
   J28  253 VSS110 SCONN288_DDR506112002KQ-SCONN288_DDR506112002KQ,SMA   I155 @T6G_MB_LIB.T6G(SCH_1):PAGE99
   J28  255 VSS111 SCONN288_DDR506112002KQ-SCONN288_DDR506112002KQ,SMA   I155 @T6G_MB_LIB.T6G(SCH_1):PAGE99
   J28  257 VSS112 SCONN288_DDR506112002KQ-SCONN288_DDR506112002KQ,SMA   I155 @T6G_MB_LIB.T6G(SCH_1):PAGE99
   J28  259 VSS113 SCONN288_DDR506112002KQ-SCONN288_DDR506112002KQ,SMA   I155 @T6G_MB_LIB.T6G(SCH_1):PAGE99
   J28  262 VSS114 SCONN288_DDR506112002KQ-SCONN288_DDR506112002KQ,SMA   I155 @T6G_MB_LIB.T6G(SCH_1):PAGE99
   J28  264 VSS115 SCONN288_DDR506112002KQ-SCONN288_DDR506112002KQ,SMA   I155 @T6G_MB_LIB.T6G(SCH_1):PAGE99
   J28  266 VSS116 SCONN288_DDR506112002KQ-SCONN288_DDR506112002KQ,SMA   I155 @T6G_MB_LIB.T6G(SCH_1):PAGE99
   J28  268 VSS117 SCONN288_DDR506112002KQ-SCONN288_DDR506112002KQ,SMA   I155 @T6G_MB_LIB.T6G(SCH_1):PAGE99
   J28  270 VSS118 SCONN288_DDR506112002KQ-SCONN288_DDR506112002KQ,SMA   I155 @T6G_MB_LIB.T6G(SCH_1):PAGE99
   J28  273 VSS119 SCONN288_DDR506112002KQ-SCONN288_DDR506112002KQ,SMA   I155 @T6G_MB_LIB.T6G(SCH_1):PAGE99
   J28  275 VSS120 SCONN288_DDR506112002KQ-SCONN288_DDR506112002KQ,SMA   I155 @T6G_MB_LIB.T6G(SCH_1):PAGE99
   J28  277 VSS121 SCONN288_DDR506112002KQ-SCONN288_DDR506112002KQ,SMA   I155 @T6G_MB_LIB.T6G(SCH_1):PAGE99
   J28  279 VSS122 SCONN288_DDR506112002KQ-SCONN288_DDR506112002KQ,SMA   I155 @T6G_MB_LIB.T6G(SCH_1):PAGE99
   J28  281 VSS123 SCONN288_DDR506112002KQ-SCONN288_DDR506112002KQ,SMA   I155 @T6G_MB_LIB.T6G(SCH_1):PAGE99
   J28  284 VSS124 SCONN288_DDR506112002KQ-SCONN288_DDR506112002KQ,SMA   I155 @T6G_MB_LIB.T6G(SCH_1):PAGE99
   J28  286 VSS125 SCONN288_DDR506112002KQ-SCONN288_DDR506112002KQ,SMA   I155 @T6G_MB_LIB.T6G(SCH_1):PAGE99
   J28  288 VSS126 SCONN288_DDR506112002KQ-SCONN288_DDR506112002KQ,SMA   I155 @T6G_MB_LIB.T6G(SCH_1):PAGE99
  C144    2      B Q_CAP_0402-0.1UF,25V,10%,X7R,CH4104K1B00   I185 @T6G_MB_LIB.T6G(SCH_1):PAGE99
  C178    2      B Q_CAP_C0805-10UF,25V,10%,X6S,CH6104KEA00   I238 @T6G_MB_LIB.T6G(SCH_1):PAGE99
  C179    2      B Q_CAP_C0805-10UF,25V,10%,X6S,CH6104KEA00   I239 @T6G_MB_LIB.T6G(SCH_1):PAGE99
  R772    2      B Q_RES_0402LF-35.7K,1%,1/16W,CHIP,CS33572FB01   I146 @T6G_MB_LIB.T6G(SCH_1):PAGE100
   J30   G1     G1 SCONN288_DDR506112002KQ-SCONN288_DDR506112002KQ,SMA   I161 @T6G_MB_LIB.T6G(SCH_1):PAGE100
   J30   G2     G2 SCONN288_DDR506112002KQ-SCONN288_DDR506112002KQ,SMA   I161 @T6G_MB_LIB.T6G(SCH_1):PAGE100
   J30   G3     G3 SCONN288_DDR506112002KQ-SCONN288_DDR506112002KQ,SMA   I161 @T6G_MB_LIB.T6G(SCH_1):PAGE100
   J30    6   VSS0 SCONN288_DDR506112002KQ-SCONN288_DDR506112002KQ,SMA   I161 @T6G_MB_LIB.T6G(SCH_1):PAGE100
   J30    8   VSS1 SCONN288_DDR506112002KQ-SCONN288_DDR506112002KQ,SMA   I161 @T6G_MB_LIB.T6G(SCH_1):PAGE100
   J30   10   VSS2 SCONN288_DDR506112002KQ-SCONN288_DDR506112002KQ,SMA   I161 @T6G_MB_LIB.T6G(SCH_1):PAGE100
   J30   13   VSS3 SCONN288_DDR506112002KQ-SCONN288_DDR506112002KQ,SMA   I161 @T6G_MB_LIB.T6G(SCH_1):PAGE100
   J30   15   VSS4 SCONN288_DDR506112002KQ-SCONN288_DDR506112002KQ,SMA   I161 @T6G_MB_LIB.T6G(SCH_1):PAGE100
   J30   17   VSS5 SCONN288_DDR506112002KQ-SCONN288_DDR506112002KQ,SMA   I161 @T6G_MB_LIB.T6G(SCH_1):PAGE100
   J30   19   VSS6 SCONN288_DDR506112002KQ-SCONN288_DDR506112002KQ,SMA   I161 @T6G_MB_LIB.T6G(SCH_1):PAGE100
   J30   21   VSS7 SCONN288_DDR506112002KQ-SCONN288_DDR506112002KQ,SMA   I161 @T6G_MB_LIB.T6G(SCH_1):PAGE100
   J30   24   VSS8 SCONN288_DDR506112002KQ-SCONN288_DDR506112002KQ,SMA   I161 @T6G_MB_LIB.T6G(SCH_1):PAGE100
   J30   26   VSS9 SCONN288_DDR506112002KQ-SCONN288_DDR506112002KQ,SMA   I161 @T6G_MB_LIB.T6G(SCH_1):PAGE100
   J30   28  VSS10 SCONN288_DDR506112002KQ-SCONN288_DDR506112002KQ,SMA   I161 @T6G_MB_LIB.T6G(SCH_1):PAGE100
   J30   30  VSS11 SCONN288_DDR506112002KQ-SCONN288_DDR506112002KQ,SMA   I161 @T6G_MB_LIB.T6G(SCH_1):PAGE100
   J30   32  VSS12 SCONN288_DDR506112002KQ-SCONN288_DDR506112002KQ,SMA   I161 @T6G_MB_LIB.T6G(SCH_1):PAGE100
   J30   35  VSS13 SCONN288_DDR506112002KQ-SCONN288_DDR506112002KQ,SMA   I161 @T6G_MB_LIB.T6G(SCH_1):PAGE100
   J30   37  VSS14 SCONN288_DDR506112002KQ-SCONN288_DDR506112002KQ,SMA   I161 @T6G_MB_LIB.T6G(SCH_1):PAGE100
   J30   39  VSS15 SCONN288_DDR506112002KQ-SCONN288_DDR506112002KQ,SMA   I161 @T6G_MB_LIB.T6G(SCH_1):PAGE100
   J30   41  VSS16 SCONN288_DDR506112002KQ-SCONN288_DDR506112002KQ,SMA   I161 @T6G_MB_LIB.T6G(SCH_1):PAGE100
   J30   43  VSS17 SCONN288_DDR506112002KQ-SCONN288_DDR506112002KQ,SMA   I161 @T6G_MB_LIB.T6G(SCH_1):PAGE100
   J30   46  VSS18 SCONN288_DDR506112002KQ-SCONN288_DDR506112002KQ,SMA   I161 @T6G_MB_LIB.T6G(SCH_1):PAGE100
   J30   48  VSS19 SCONN288_DDR506112002KQ-SCONN288_DDR506112002KQ,SMA   I161 @T6G_MB_LIB.T6G(SCH_1):PAGE100
   J30   50  VSS20 SCONN288_DDR506112002KQ-SCONN288_DDR506112002KQ,SMA   I161 @T6G_MB_LIB.T6G(SCH_1):PAGE100
   J30   52  VSS21 SCONN288_DDR506112002KQ-SCONN288_DDR506112002KQ,SMA   I161 @T6G_MB_LIB.T6G(SCH_1):PAGE100
   J30   54  VSS22 SCONN288_DDR506112002KQ-SCONN288_DDR506112002KQ,SMA   I161 @T6G_MB_LIB.T6G(SCH_1):PAGE100
   J30   57  VSS23 SCONN288_DDR506112002KQ-SCONN288_DDR506112002KQ,SMA   I161 @T6G_MB_LIB.T6G(SCH_1):PAGE100
   J30   59  VSS24 SCONN288_DDR506112002KQ-SCONN288_DDR506112002KQ,SMA   I161 @T6G_MB_LIB.T6G(SCH_1):PAGE100
   J30   61  VSS25 SCONN288_DDR506112002KQ-SCONN288_DDR506112002KQ,SMA   I161 @T6G_MB_LIB.T6G(SCH_1):PAGE100
   J30   63  VSS26 SCONN288_DDR506112002KQ-SCONN288_DDR506112002KQ,SMA   I161 @T6G_MB_LIB.T6G(SCH_1):PAGE100
   J30   65  VSS27 SCONN288_DDR506112002KQ-SCONN288_DDR506112002KQ,SMA   I161 @T6G_MB_LIB.T6G(SCH_1):PAGE100
   J30   67  VSS28 SCONN288_DDR506112002KQ-SCONN288_DDR506112002KQ,SMA   I161 @T6G_MB_LIB.T6G(SCH_1):PAGE100
   J30   69  VSS29 SCONN288_DDR506112002KQ-SCONN288_DDR506112002KQ,SMA   I161 @T6G_MB_LIB.T6G(SCH_1):PAGE100
   J30   71  VSS30 SCONN288_DDR506112002KQ-SCONN288_DDR506112002KQ,SMA   I161 @T6G_MB_LIB.T6G(SCH_1):PAGE100
   J30   73  VSS31 SCONN288_DDR506112002KQ-SCONN288_DDR506112002KQ,SMA   I161 @T6G_MB_LIB.T6G(SCH_1):PAGE100
   J30   75  VSS32 SCONN288_DDR506112002KQ-SCONN288_DDR506112002KQ,SMA   I161 @T6G_MB_LIB.T6G(SCH_1):PAGE100
   J30   77  VSS33 SCONN288_DDR506112002KQ-SCONN288_DDR506112002KQ,SMA   I161 @T6G_MB_LIB.T6G(SCH_1):PAGE100
   J30   79  VSS34 SCONN288_DDR506112002KQ-SCONN288_DDR506112002KQ,SMA   I161 @T6G_MB_LIB.T6G(SCH_1):PAGE100
   J30   81  VSS35 SCONN288_DDR506112002KQ-SCONN288_DDR506112002KQ,SMA   I161 @T6G_MB_LIB.T6G(SCH_1):PAGE100
   J30   83  VSS36 SCONN288_DDR506112002KQ-SCONN288_DDR506112002KQ,SMA   I161 @T6G_MB_LIB.T6G(SCH_1):PAGE100
   J30   85  VSS37 SCONN288_DDR506112002KQ-SCONN288_DDR506112002KQ,SMA   I161 @T6G_MB_LIB.T6G(SCH_1):PAGE100
   J30   88  VSS38 SCONN288_DDR506112002KQ-SCONN288_DDR506112002KQ,SMA   I161 @T6G_MB_LIB.T6G(SCH_1):PAGE100
   J30   90  VSS39 SCONN288_DDR506112002KQ-SCONN288_DDR506112002KQ,SMA   I161 @T6G_MB_LIB.T6G(SCH_1):PAGE100
   J30   92  VSS40 SCONN288_DDR506112002KQ-SCONN288_DDR506112002KQ,SMA   I161 @T6G_MB_LIB.T6G(SCH_1):PAGE100
   J30   95  VSS41 SCONN288_DDR506112002KQ-SCONN288_DDR506112002KQ,SMA   I161 @T6G_MB_LIB.T6G(SCH_1):PAGE100
   J30   97  VSS42 SCONN288_DDR506112002KQ-SCONN288_DDR506112002KQ,SMA   I161 @T6G_MB_LIB.T6G(SCH_1):PAGE100
   J30   99  VSS43 SCONN288_DDR506112002KQ-SCONN288_DDR506112002KQ,SMA   I161 @T6G_MB_LIB.T6G(SCH_1):PAGE100
   J30  101  VSS44 SCONN288_DDR506112002KQ-SCONN288_DDR506112002KQ,SMA   I161 @T6G_MB_LIB.T6G(SCH_1):PAGE100
   J30  103  VSS45 SCONN288_DDR506112002KQ-SCONN288_DDR506112002KQ,SMA   I161 @T6G_MB_LIB.T6G(SCH_1):PAGE100
   J30  106  VSS46 SCONN288_DDR506112002KQ-SCONN288_DDR506112002KQ,SMA   I161 @T6G_MB_LIB.T6G(SCH_1):PAGE100
   J30  108  VSS47 SCONN288_DDR506112002KQ-SCONN288_DDR506112002KQ,SMA   I161 @T6G_MB_LIB.T6G(SCH_1):PAGE100
   J30  110  VSS48 SCONN288_DDR506112002KQ-SCONN288_DDR506112002KQ,SMA   I161 @T6G_MB_LIB.T6G(SCH_1):PAGE100
   J30  112  VSS49 SCONN288_DDR506112002KQ-SCONN288_DDR506112002KQ,SMA   I161 @T6G_MB_LIB.T6G(SCH_1):PAGE100
   J30  114  VSS50 SCONN288_DDR506112002KQ-SCONN288_DDR506112002KQ,SMA   I161 @T6G_MB_LIB.T6G(SCH_1):PAGE100
   J30  117  VSS51 SCONN288_DDR506112002KQ-SCONN288_DDR506112002KQ,SMA   I161 @T6G_MB_LIB.T6G(SCH_1):PAGE100
   J30  119  VSS52 SCONN288_DDR506112002KQ-SCONN288_DDR506112002KQ,SMA   I161 @T6G_MB_LIB.T6G(SCH_1):PAGE100
   J30  121  VSS53 SCONN288_DDR506112002KQ-SCONN288_DDR506112002KQ,SMA   I161 @T6G_MB_LIB.T6G(SCH_1):PAGE100
   J30  123  VSS54 SCONN288_DDR506112002KQ-SCONN288_DDR506112002KQ,SMA   I161 @T6G_MB_LIB.T6G(SCH_1):PAGE100
   J30  125  VSS55 SCONN288_DDR506112002KQ-SCONN288_DDR506112002KQ,SMA   I161 @T6G_MB_LIB.T6G(SCH_1):PAGE100
   J30  128  VSS56 SCONN288_DDR506112002KQ-SCONN288_DDR506112002KQ,SMA   I161 @T6G_MB_LIB.T6G(SCH_1):PAGE100
   J30  130  VSS57 SCONN288_DDR506112002KQ-SCONN288_DDR506112002KQ,SMA   I161 @T6G_MB_LIB.T6G(SCH_1):PAGE100
   J30  132  VSS58 SCONN288_DDR506112002KQ-SCONN288_DDR506112002KQ,SMA   I161 @T6G_MB_LIB.T6G(SCH_1):PAGE100
   J30  134  VSS59 SCONN288_DDR506112002KQ-SCONN288_DDR506112002KQ,SMA   I161 @T6G_MB_LIB.T6G(SCH_1):PAGE100
   J30  136  VSS60 SCONN288_DDR506112002KQ-SCONN288_DDR506112002KQ,SMA   I161 @T6G_MB_LIB.T6G(SCH_1):PAGE100
   J30  139  VSS61 SCONN288_DDR506112002KQ-SCONN288_DDR506112002KQ,SMA   I161 @T6G_MB_LIB.T6G(SCH_1):PAGE100
   J30  141  VSS62 SCONN288_DDR506112002KQ-SCONN288_DDR506112002KQ,SMA   I161 @T6G_MB_LIB.T6G(SCH_1):PAGE100
   J30  143  VSS63 SCONN288_DDR506112002KQ-SCONN288_DDR506112002KQ,SMA   I161 @T6G_MB_LIB.T6G(SCH_1):PAGE100
   J30  151  VSS64 SCONN288_DDR506112002KQ-SCONN288_DDR506112002KQ,SMA   I161 @T6G_MB_LIB.T6G(SCH_1):PAGE100
   J30  153  VSS65 SCONN288_DDR506112002KQ-SCONN288_DDR506112002KQ,SMA   I161 @T6G_MB_LIB.T6G(SCH_1):PAGE100
   J30  155  VSS66 SCONN288_DDR506112002KQ-SCONN288_DDR506112002KQ,SMA   I161 @T6G_MB_LIB.T6G(SCH_1):PAGE100
   J30  158  VSS67 SCONN288_DDR506112002KQ-SCONN288_DDR506112002KQ,SMA   I161 @T6G_MB_LIB.T6G(SCH_1):PAGE100
   J30  160  VSS68 SCONN288_DDR506112002KQ-SCONN288_DDR506112002KQ,SMA   I161 @T6G_MB_LIB.T6G(SCH_1):PAGE100
   J30  162  VSS69 SCONN288_DDR506112002KQ-SCONN288_DDR506112002KQ,SMA   I161 @T6G_MB_LIB.T6G(SCH_1):PAGE100
   J30  164  VSS70 SCONN288_DDR506112002KQ-SCONN288_DDR506112002KQ,SMA   I161 @T6G_MB_LIB.T6G(SCH_1):PAGE100
   J30  166  VSS71 SCONN288_DDR506112002KQ-SCONN288_DDR506112002KQ,SMA   I161 @T6G_MB_LIB.T6G(SCH_1):PAGE100
   J30  169  VSS72 SCONN288_DDR506112002KQ-SCONN288_DDR506112002KQ,SMA   I161 @T6G_MB_LIB.T6G(SCH_1):PAGE100
   J30  171  VSS73 SCONN288_DDR506112002KQ-SCONN288_DDR506112002KQ,SMA   I161 @T6G_MB_LIB.T6G(SCH_1):PAGE100
   J30  173  VSS74 SCONN288_DDR506112002KQ-SCONN288_DDR506112002KQ,SMA   I161 @T6G_MB_LIB.T6G(SCH_1):PAGE100
   J30  175  VSS75 SCONN288_DDR506112002KQ-SCONN288_DDR506112002KQ,SMA   I161 @T6G_MB_LIB.T6G(SCH_1):PAGE100
   J30  177  VSS76 SCONN288_DDR506112002KQ-SCONN288_DDR506112002KQ,SMA   I161 @T6G_MB_LIB.T6G(SCH_1):PAGE100
   J30  180  VSS77 SCONN288_DDR506112002KQ-SCONN288_DDR506112002KQ,SMA   I161 @T6G_MB_LIB.T6G(SCH_1):PAGE100
   J30  182  VSS78 SCONN288_DDR506112002KQ-SCONN288_DDR506112002KQ,SMA   I161 @T6G_MB_LIB.T6G(SCH_1):PAGE100
   J30  184  VSS79 SCONN288_DDR506112002KQ-SCONN288_DDR506112002KQ,SMA   I161 @T6G_MB_LIB.T6G(SCH_1):PAGE100
   J30  186  VSS80 SCONN288_DDR506112002KQ-SCONN288_DDR506112002KQ,SMA   I161 @T6G_MB_LIB.T6G(SCH_1):PAGE100
   J30  188  VSS81 SCONN288_DDR506112002KQ-SCONN288_DDR506112002KQ,SMA   I161 @T6G_MB_LIB.T6G(SCH_1):PAGE100
   J30  191  VSS82 SCONN288_DDR506112002KQ-SCONN288_DDR506112002KQ,SMA   I161 @T6G_MB_LIB.T6G(SCH_1):PAGE100
   J30  193  VSS83 SCONN288_DDR506112002KQ-SCONN288_DDR506112002KQ,SMA   I161 @T6G_MB_LIB.T6G(SCH_1):PAGE100
   J30  195  VSS84 SCONN288_DDR506112002KQ-SCONN288_DDR506112002KQ,SMA   I161 @T6G_MB_LIB.T6G(SCH_1):PAGE100
   J30  197  VSS85 SCONN288_DDR506112002KQ-SCONN288_DDR506112002KQ,SMA   I161 @T6G_MB_LIB.T6G(SCH_1):PAGE100
   J30  199  VSS86 SCONN288_DDR506112002KQ-SCONN288_DDR506112002KQ,SMA   I161 @T6G_MB_LIB.T6G(SCH_1):PAGE100
   J30  202  VSS87 SCONN288_DDR506112002KQ-SCONN288_DDR506112002KQ,SMA   I161 @T6G_MB_LIB.T6G(SCH_1):PAGE100
   J30  204  VSS88 SCONN288_DDR506112002KQ-SCONN288_DDR506112002KQ,SMA   I161 @T6G_MB_LIB.T6G(SCH_1):PAGE100
   J30  206  VSS89 SCONN288_DDR506112002KQ-SCONN288_DDR506112002KQ,SMA   I161 @T6G_MB_LIB.T6G(SCH_1):PAGE100
   J30  208  VSS90 SCONN288_DDR506112002KQ-SCONN288_DDR506112002KQ,SMA   I161 @T6G_MB_LIB.T6G(SCH_1):PAGE100
   J30  210  VSS91 SCONN288_DDR506112002KQ-SCONN288_DDR506112002KQ,SMA   I161 @T6G_MB_LIB.T6G(SCH_1):PAGE100
   J30  212  VSS92 SCONN288_DDR506112002KQ-SCONN288_DDR506112002KQ,SMA   I161 @T6G_MB_LIB.T6G(SCH_1):PAGE100
   J30  214  VSS93 SCONN288_DDR506112002KQ-SCONN288_DDR506112002KQ,SMA   I161 @T6G_MB_LIB.T6G(SCH_1):PAGE100
   J30  216  VSS94 SCONN288_DDR506112002KQ-SCONN288_DDR506112002KQ,SMA   I161 @T6G_MB_LIB.T6G(SCH_1):PAGE100
   J30  219  VSS95 SCONN288_DDR506112002KQ-SCONN288_DDR506112002KQ,SMA   I161 @T6G_MB_LIB.T6G(SCH_1):PAGE100
   J30  222  VSS96 SCONN288_DDR506112002KQ-SCONN288_DDR506112002KQ,SMA   I161 @T6G_MB_LIB.T6G(SCH_1):PAGE100
   J30  224  VSS97 SCONN288_DDR506112002KQ-SCONN288_DDR506112002KQ,SMA   I161 @T6G_MB_LIB.T6G(SCH_1):PAGE100
   J30  226  VSS98 SCONN288_DDR506112002KQ-SCONN288_DDR506112002KQ,SMA   I161 @T6G_MB_LIB.T6G(SCH_1):PAGE100
   J30  228  VSS99 SCONN288_DDR506112002KQ-SCONN288_DDR506112002KQ,SMA   I161 @T6G_MB_LIB.T6G(SCH_1):PAGE100
   J30  230 VSS100 SCONN288_DDR506112002KQ-SCONN288_DDR506112002KQ,SMA   I161 @T6G_MB_LIB.T6G(SCH_1):PAGE100
   J30  233 VSS101 SCONN288_DDR506112002KQ-SCONN288_DDR506112002KQ,SMA   I161 @T6G_MB_LIB.T6G(SCH_1):PAGE100
   J30  235 VSS102 SCONN288_DDR506112002KQ-SCONN288_DDR506112002KQ,SMA   I161 @T6G_MB_LIB.T6G(SCH_1):PAGE100
   J30  237 VSS103 SCONN288_DDR506112002KQ-SCONN288_DDR506112002KQ,SMA   I161 @T6G_MB_LIB.T6G(SCH_1):PAGE100
   J30  240 VSS104 SCONN288_DDR506112002KQ-SCONN288_DDR506112002KQ,SMA   I161 @T6G_MB_LIB.T6G(SCH_1):PAGE100
   J30  242 VSS105 SCONN288_DDR506112002KQ-SCONN288_DDR506112002KQ,SMA   I161 @T6G_MB_LIB.T6G(SCH_1):PAGE100
   J30  244 VSS106 SCONN288_DDR506112002KQ-SCONN288_DDR506112002KQ,SMA   I161 @T6G_MB_LIB.T6G(SCH_1):PAGE100
   J30  246 VSS107 SCONN288_DDR506112002KQ-SCONN288_DDR506112002KQ,SMA   I161 @T6G_MB_LIB.T6G(SCH_1):PAGE100
   J30  248 VSS108 SCONN288_DDR506112002KQ-SCONN288_DDR506112002KQ,SMA   I161 @T6G_MB_LIB.T6G(SCH_1):PAGE100
   J30  251 VSS109 SCONN288_DDR506112002KQ-SCONN288_DDR506112002KQ,SMA   I161 @T6G_MB_LIB.T6G(SCH_1):PAGE100
   J30  253 VSS110 SCONN288_DDR506112002KQ-SCONN288_DDR506112002KQ,SMA   I161 @T6G_MB_LIB.T6G(SCH_1):PAGE100
   J30  255 VSS111 SCONN288_DDR506112002KQ-SCONN288_DDR506112002KQ,SMA   I161 @T6G_MB_LIB.T6G(SCH_1):PAGE100
   J30  257 VSS112 SCONN288_DDR506112002KQ-SCONN288_DDR506112002KQ,SMA   I161 @T6G_MB_LIB.T6G(SCH_1):PAGE100
   J30  259 VSS113 SCONN288_DDR506112002KQ-SCONN288_DDR506112002KQ,SMA   I161 @T6G_MB_LIB.T6G(SCH_1):PAGE100
   J30  262 VSS114 SCONN288_DDR506112002KQ-SCONN288_DDR506112002KQ,SMA   I161 @T6G_MB_LIB.T6G(SCH_1):PAGE100
   J30  264 VSS115 SCONN288_DDR506112002KQ-SCONN288_DDR506112002KQ,SMA   I161 @T6G_MB_LIB.T6G(SCH_1):PAGE100
   J30  266 VSS116 SCONN288_DDR506112002KQ-SCONN288_DDR506112002KQ,SMA   I161 @T6G_MB_LIB.T6G(SCH_1):PAGE100
   J30  268 VSS117 SCONN288_DDR506112002KQ-SCONN288_DDR506112002KQ,SMA   I161 @T6G_MB_LIB.T6G(SCH_1):PAGE100
   J30  270 VSS118 SCONN288_DDR506112002KQ-SCONN288_DDR506112002KQ,SMA   I161 @T6G_MB_LIB.T6G(SCH_1):PAGE100
   J30  273 VSS119 SCONN288_DDR506112002KQ-SCONN288_DDR506112002KQ,SMA   I161 @T6G_MB_LIB.T6G(SCH_1):PAGE100
   J30  275 VSS120 SCONN288_DDR506112002KQ-SCONN288_DDR506112002KQ,SMA   I161 @T6G_MB_LIB.T6G(SCH_1):PAGE100
   J30  277 VSS121 SCONN288_DDR506112002KQ-SCONN288_DDR506112002KQ,SMA   I161 @T6G_MB_LIB.T6G(SCH_1):PAGE100
   J30  279 VSS122 SCONN288_DDR506112002KQ-SCONN288_DDR506112002KQ,SMA   I161 @T6G_MB_LIB.T6G(SCH_1):PAGE100
   J30  281 VSS123 SCONN288_DDR506112002KQ-SCONN288_DDR506112002KQ,SMA   I161 @T6G_MB_LIB.T6G(SCH_1):PAGE100
   J30  284 VSS124 SCONN288_DDR506112002KQ-SCONN288_DDR506112002KQ,SMA   I161 @T6G_MB_LIB.T6G(SCH_1):PAGE100
   J30  286 VSS125 SCONN288_DDR506112002KQ-SCONN288_DDR506112002KQ,SMA   I161 @T6G_MB_LIB.T6G(SCH_1):PAGE100
   J30  288 VSS126 SCONN288_DDR506112002KQ-SCONN288_DDR506112002KQ,SMA   I161 @T6G_MB_LIB.T6G(SCH_1):PAGE100
  C148    2      B Q_CAP_0402-0.1UF,25V,10%,X7R,CH4104K1B00   I185 @T6G_MB_LIB.T6G(SCH_1):PAGE100
  C181    2      B Q_CAP_C0805-10UF,25V,10%,X6S,CH6104KEA00   I238 @T6G_MB_LIB.T6G(SCH_1):PAGE100
  C182    2      B Q_CAP_C0805-10UF,25V,10%,X6S,CH6104KEA00   I239 @T6G_MB_LIB.T6G(SCH_1):PAGE100
    R6    2      B Q_RES_0402LF-54.9K,1%,1/16W,CHIP,CS35492FB03   I127 @T6G_MB_LIB.T6G(SCH_1):PAGE101
   J32   G1     G1 SCONN288_DDR506112002KQ-SCONN288_DDR506112002KQ,SMA   I175 @T6G_MB_LIB.T6G(SCH_1):PAGE101
   J32   G2     G2 SCONN288_DDR506112002KQ-SCONN288_DDR506112002KQ,SMA   I175 @T6G_MB_LIB.T6G(SCH_1):PAGE101
   J32   G3     G3 SCONN288_DDR506112002KQ-SCONN288_DDR506112002KQ,SMA   I175 @T6G_MB_LIB.T6G(SCH_1):PAGE101
   J32    6   VSS0 SCONN288_DDR506112002KQ-SCONN288_DDR506112002KQ,SMA   I175 @T6G_MB_LIB.T6G(SCH_1):PAGE101
   J32    8   VSS1 SCONN288_DDR506112002KQ-SCONN288_DDR506112002KQ,SMA   I175 @T6G_MB_LIB.T6G(SCH_1):PAGE101
   J32   10   VSS2 SCONN288_DDR506112002KQ-SCONN288_DDR506112002KQ,SMA   I175 @T6G_MB_LIB.T6G(SCH_1):PAGE101
   J32   13   VSS3 SCONN288_DDR506112002KQ-SCONN288_DDR506112002KQ,SMA   I175 @T6G_MB_LIB.T6G(SCH_1):PAGE101
   J32   15   VSS4 SCONN288_DDR506112002KQ-SCONN288_DDR506112002KQ,SMA   I175 @T6G_MB_LIB.T6G(SCH_1):PAGE101
   J32   17   VSS5 SCONN288_DDR506112002KQ-SCONN288_DDR506112002KQ,SMA   I175 @T6G_MB_LIB.T6G(SCH_1):PAGE101
   J32   19   VSS6 SCONN288_DDR506112002KQ-SCONN288_DDR506112002KQ,SMA   I175 @T6G_MB_LIB.T6G(SCH_1):PAGE101
   J32   21   VSS7 SCONN288_DDR506112002KQ-SCONN288_DDR506112002KQ,SMA   I175 @T6G_MB_LIB.T6G(SCH_1):PAGE101
   J32   24   VSS8 SCONN288_DDR506112002KQ-SCONN288_DDR506112002KQ,SMA   I175 @T6G_MB_LIB.T6G(SCH_1):PAGE101
   J32   26   VSS9 SCONN288_DDR506112002KQ-SCONN288_DDR506112002KQ,SMA   I175 @T6G_MB_LIB.T6G(SCH_1):PAGE101
   J32   28  VSS10 SCONN288_DDR506112002KQ-SCONN288_DDR506112002KQ,SMA   I175 @T6G_MB_LIB.T6G(SCH_1):PAGE101
   J32   30  VSS11 SCONN288_DDR506112002KQ-SCONN288_DDR506112002KQ,SMA   I175 @T6G_MB_LIB.T6G(SCH_1):PAGE101
   J32   32  VSS12 SCONN288_DDR506112002KQ-SCONN288_DDR506112002KQ,SMA   I175 @T6G_MB_LIB.T6G(SCH_1):PAGE101
   J32   35  VSS13 SCONN288_DDR506112002KQ-SCONN288_DDR506112002KQ,SMA   I175 @T6G_MB_LIB.T6G(SCH_1):PAGE101
   J32   37  VSS14 SCONN288_DDR506112002KQ-SCONN288_DDR506112002KQ,SMA   I175 @T6G_MB_LIB.T6G(SCH_1):PAGE101
   J32   39  VSS15 SCONN288_DDR506112002KQ-SCONN288_DDR506112002KQ,SMA   I175 @T6G_MB_LIB.T6G(SCH_1):PAGE101
   J32   41  VSS16 SCONN288_DDR506112002KQ-SCONN288_DDR506112002KQ,SMA   I175 @T6G_MB_LIB.T6G(SCH_1):PAGE101
   J32   43  VSS17 SCONN288_DDR506112002KQ-SCONN288_DDR506112002KQ,SMA   I175 @T6G_MB_LIB.T6G(SCH_1):PAGE101
   J32   46  VSS18 SCONN288_DDR506112002KQ-SCONN288_DDR506112002KQ,SMA   I175 @T6G_MB_LIB.T6G(SCH_1):PAGE101
   J32   48  VSS19 SCONN288_DDR506112002KQ-SCONN288_DDR506112002KQ,SMA   I175 @T6G_MB_LIB.T6G(SCH_1):PAGE101
   J32   50  VSS20 SCONN288_DDR506112002KQ-SCONN288_DDR506112002KQ,SMA   I175 @T6G_MB_LIB.T6G(SCH_1):PAGE101
   J32   52  VSS21 SCONN288_DDR506112002KQ-SCONN288_DDR506112002KQ,SMA   I175 @T6G_MB_LIB.T6G(SCH_1):PAGE101
   J32   54  VSS22 SCONN288_DDR506112002KQ-SCONN288_DDR506112002KQ,SMA   I175 @T6G_MB_LIB.T6G(SCH_1):PAGE101
   J32   57  VSS23 SCONN288_DDR506112002KQ-SCONN288_DDR506112002KQ,SMA   I175 @T6G_MB_LIB.T6G(SCH_1):PAGE101
   J32   59  VSS24 SCONN288_DDR506112002KQ-SCONN288_DDR506112002KQ,SMA   I175 @T6G_MB_LIB.T6G(SCH_1):PAGE101
   J32   61  VSS25 SCONN288_DDR506112002KQ-SCONN288_DDR506112002KQ,SMA   I175 @T6G_MB_LIB.T6G(SCH_1):PAGE101
   J32   63  VSS26 SCONN288_DDR506112002KQ-SCONN288_DDR506112002KQ,SMA   I175 @T6G_MB_LIB.T6G(SCH_1):PAGE101
   J32   65  VSS27 SCONN288_DDR506112002KQ-SCONN288_DDR506112002KQ,SMA   I175 @T6G_MB_LIB.T6G(SCH_1):PAGE101
   J32   67  VSS28 SCONN288_DDR506112002KQ-SCONN288_DDR506112002KQ,SMA   I175 @T6G_MB_LIB.T6G(SCH_1):PAGE101
   J32   69  VSS29 SCONN288_DDR506112002KQ-SCONN288_DDR506112002KQ,SMA   I175 @T6G_MB_LIB.T6G(SCH_1):PAGE101
   J32   71  VSS30 SCONN288_DDR506112002KQ-SCONN288_DDR506112002KQ,SMA   I175 @T6G_MB_LIB.T6G(SCH_1):PAGE101
   J32   73  VSS31 SCONN288_DDR506112002KQ-SCONN288_DDR506112002KQ,SMA   I175 @T6G_MB_LIB.T6G(SCH_1):PAGE101
   J32   75  VSS32 SCONN288_DDR506112002KQ-SCONN288_DDR506112002KQ,SMA   I175 @T6G_MB_LIB.T6G(SCH_1):PAGE101
   J32   77  VSS33 SCONN288_DDR506112002KQ-SCONN288_DDR506112002KQ,SMA   I175 @T6G_MB_LIB.T6G(SCH_1):PAGE101
   J32   79  VSS34 SCONN288_DDR506112002KQ-SCONN288_DDR506112002KQ,SMA   I175 @T6G_MB_LIB.T6G(SCH_1):PAGE101
   J32   81  VSS35 SCONN288_DDR506112002KQ-SCONN288_DDR506112002KQ,SMA   I175 @T6G_MB_LIB.T6G(SCH_1):PAGE101
   J32   83  VSS36 SCONN288_DDR506112002KQ-SCONN288_DDR506112002KQ,SMA   I175 @T6G_MB_LIB.T6G(SCH_1):PAGE101
   J32   85  VSS37 SCONN288_DDR506112002KQ-SCONN288_DDR506112002KQ,SMA   I175 @T6G_MB_LIB.T6G(SCH_1):PAGE101
   J32   88  VSS38 SCONN288_DDR506112002KQ-SCONN288_DDR506112002KQ,SMA   I175 @T6G_MB_LIB.T6G(SCH_1):PAGE101
   J32   90  VSS39 SCONN288_DDR506112002KQ-SCONN288_DDR506112002KQ,SMA   I175 @T6G_MB_LIB.T6G(SCH_1):PAGE101
   J32   92  VSS40 SCONN288_DDR506112002KQ-SCONN288_DDR506112002KQ,SMA   I175 @T6G_MB_LIB.T6G(SCH_1):PAGE101
   J32   95  VSS41 SCONN288_DDR506112002KQ-SCONN288_DDR506112002KQ,SMA   I175 @T6G_MB_LIB.T6G(SCH_1):PAGE101
   J32   97  VSS42 SCONN288_DDR506112002KQ-SCONN288_DDR506112002KQ,SMA   I175 @T6G_MB_LIB.T6G(SCH_1):PAGE101
   J32   99  VSS43 SCONN288_DDR506112002KQ-SCONN288_DDR506112002KQ,SMA   I175 @T6G_MB_LIB.T6G(SCH_1):PAGE101
   J32  101  VSS44 SCONN288_DDR506112002KQ-SCONN288_DDR506112002KQ,SMA   I175 @T6G_MB_LIB.T6G(SCH_1):PAGE101
   J32  103  VSS45 SCONN288_DDR506112002KQ-SCONN288_DDR506112002KQ,SMA   I175 @T6G_MB_LIB.T6G(SCH_1):PAGE101
   J32  106  VSS46 SCONN288_DDR506112002KQ-SCONN288_DDR506112002KQ,SMA   I175 @T6G_MB_LIB.T6G(SCH_1):PAGE101
   J32  108  VSS47 SCONN288_DDR506112002KQ-SCONN288_DDR506112002KQ,SMA   I175 @T6G_MB_LIB.T6G(SCH_1):PAGE101
   J32  110  VSS48 SCONN288_DDR506112002KQ-SCONN288_DDR506112002KQ,SMA   I175 @T6G_MB_LIB.T6G(SCH_1):PAGE101
   J32  112  VSS49 SCONN288_DDR506112002KQ-SCONN288_DDR506112002KQ,SMA   I175 @T6G_MB_LIB.T6G(SCH_1):PAGE101
   J32  114  VSS50 SCONN288_DDR506112002KQ-SCONN288_DDR506112002KQ,SMA   I175 @T6G_MB_LIB.T6G(SCH_1):PAGE101
   J32  117  VSS51 SCONN288_DDR506112002KQ-SCONN288_DDR506112002KQ,SMA   I175 @T6G_MB_LIB.T6G(SCH_1):PAGE101
   J32  119  VSS52 SCONN288_DDR506112002KQ-SCONN288_DDR506112002KQ,SMA   I175 @T6G_MB_LIB.T6G(SCH_1):PAGE101
   J32  121  VSS53 SCONN288_DDR506112002KQ-SCONN288_DDR506112002KQ,SMA   I175 @T6G_MB_LIB.T6G(SCH_1):PAGE101
   J32  123  VSS54 SCONN288_DDR506112002KQ-SCONN288_DDR506112002KQ,SMA   I175 @T6G_MB_LIB.T6G(SCH_1):PAGE101
   J32  125  VSS55 SCONN288_DDR506112002KQ-SCONN288_DDR506112002KQ,SMA   I175 @T6G_MB_LIB.T6G(SCH_1):PAGE101
   J32  128  VSS56 SCONN288_DDR506112002KQ-SCONN288_DDR506112002KQ,SMA   I175 @T6G_MB_LIB.T6G(SCH_1):PAGE101
   J32  130  VSS57 SCONN288_DDR506112002KQ-SCONN288_DDR506112002KQ,SMA   I175 @T6G_MB_LIB.T6G(SCH_1):PAGE101
   J32  132  VSS58 SCONN288_DDR506112002KQ-SCONN288_DDR506112002KQ,SMA   I175 @T6G_MB_LIB.T6G(SCH_1):PAGE101
   J32  134  VSS59 SCONN288_DDR506112002KQ-SCONN288_DDR506112002KQ,SMA   I175 @T6G_MB_LIB.T6G(SCH_1):PAGE101
   J32  136  VSS60 SCONN288_DDR506112002KQ-SCONN288_DDR506112002KQ,SMA   I175 @T6G_MB_LIB.T6G(SCH_1):PAGE101
   J32  139  VSS61 SCONN288_DDR506112002KQ-SCONN288_DDR506112002KQ,SMA   I175 @T6G_MB_LIB.T6G(SCH_1):PAGE101
   J32  141  VSS62 SCONN288_DDR506112002KQ-SCONN288_DDR506112002KQ,SMA   I175 @T6G_MB_LIB.T6G(SCH_1):PAGE101
   J32  143  VSS63 SCONN288_DDR506112002KQ-SCONN288_DDR506112002KQ,SMA   I175 @T6G_MB_LIB.T6G(SCH_1):PAGE101
   J32  151  VSS64 SCONN288_DDR506112002KQ-SCONN288_DDR506112002KQ,SMA   I175 @T6G_MB_LIB.T6G(SCH_1):PAGE101
   J32  153  VSS65 SCONN288_DDR506112002KQ-SCONN288_DDR506112002KQ,SMA   I175 @T6G_MB_LIB.T6G(SCH_1):PAGE101
   J32  155  VSS66 SCONN288_DDR506112002KQ-SCONN288_DDR506112002KQ,SMA   I175 @T6G_MB_LIB.T6G(SCH_1):PAGE101
   J32  158  VSS67 SCONN288_DDR506112002KQ-SCONN288_DDR506112002KQ,SMA   I175 @T6G_MB_LIB.T6G(SCH_1):PAGE101
   J32  160  VSS68 SCONN288_DDR506112002KQ-SCONN288_DDR506112002KQ,SMA   I175 @T6G_MB_LIB.T6G(SCH_1):PAGE101
   J32  162  VSS69 SCONN288_DDR506112002KQ-SCONN288_DDR506112002KQ,SMA   I175 @T6G_MB_LIB.T6G(SCH_1):PAGE101
   J32  164  VSS70 SCONN288_DDR506112002KQ-SCONN288_DDR506112002KQ,SMA   I175 @T6G_MB_LIB.T6G(SCH_1):PAGE101
   J32  166  VSS71 SCONN288_DDR506112002KQ-SCONN288_DDR506112002KQ,SMA   I175 @T6G_MB_LIB.T6G(SCH_1):PAGE101
   J32  169  VSS72 SCONN288_DDR506112002KQ-SCONN288_DDR506112002KQ,SMA   I175 @T6G_MB_LIB.T6G(SCH_1):PAGE101
   J32  171  VSS73 SCONN288_DDR506112002KQ-SCONN288_DDR506112002KQ,SMA   I175 @T6G_MB_LIB.T6G(SCH_1):PAGE101
   J32  173  VSS74 SCONN288_DDR506112002KQ-SCONN288_DDR506112002KQ,SMA   I175 @T6G_MB_LIB.T6G(SCH_1):PAGE101
   J32  175  VSS75 SCONN288_DDR506112002KQ-SCONN288_DDR506112002KQ,SMA   I175 @T6G_MB_LIB.T6G(SCH_1):PAGE101
   J32  177  VSS76 SCONN288_DDR506112002KQ-SCONN288_DDR506112002KQ,SMA   I175 @T6G_MB_LIB.T6G(SCH_1):PAGE101
   J32  180  VSS77 SCONN288_DDR506112002KQ-SCONN288_DDR506112002KQ,SMA   I175 @T6G_MB_LIB.T6G(SCH_1):PAGE101
   J32  182  VSS78 SCONN288_DDR506112002KQ-SCONN288_DDR506112002KQ,SMA   I175 @T6G_MB_LIB.T6G(SCH_1):PAGE101
   J32  184  VSS79 SCONN288_DDR506112002KQ-SCONN288_DDR506112002KQ,SMA   I175 @T6G_MB_LIB.T6G(SCH_1):PAGE101
   J32  186  VSS80 SCONN288_DDR506112002KQ-SCONN288_DDR506112002KQ,SMA   I175 @T6G_MB_LIB.T6G(SCH_1):PAGE101
   J32  188  VSS81 SCONN288_DDR506112002KQ-SCONN288_DDR506112002KQ,SMA   I175 @T6G_MB_LIB.T6G(SCH_1):PAGE101
   J32  191  VSS82 SCONN288_DDR506112002KQ-SCONN288_DDR506112002KQ,SMA   I175 @T6G_MB_LIB.T6G(SCH_1):PAGE101
   J32  193  VSS83 SCONN288_DDR506112002KQ-SCONN288_DDR506112002KQ,SMA   I175 @T6G_MB_LIB.T6G(SCH_1):PAGE101
   J32  195  VSS84 SCONN288_DDR506112002KQ-SCONN288_DDR506112002KQ,SMA   I175 @T6G_MB_LIB.T6G(SCH_1):PAGE101
   J32  197  VSS85 SCONN288_DDR506112002KQ-SCONN288_DDR506112002KQ,SMA   I175 @T6G_MB_LIB.T6G(SCH_1):PAGE101
   J32  199  VSS86 SCONN288_DDR506112002KQ-SCONN288_DDR506112002KQ,SMA   I175 @T6G_MB_LIB.T6G(SCH_1):PAGE101
   J32  202  VSS87 SCONN288_DDR506112002KQ-SCONN288_DDR506112002KQ,SMA   I175 @T6G_MB_LIB.T6G(SCH_1):PAGE101
   J32  204  VSS88 SCONN288_DDR506112002KQ-SCONN288_DDR506112002KQ,SMA   I175 @T6G_MB_LIB.T6G(SCH_1):PAGE101
   J32  206  VSS89 SCONN288_DDR506112002KQ-SCONN288_DDR506112002KQ,SMA   I175 @T6G_MB_LIB.T6G(SCH_1):PAGE101
   J32  208  VSS90 SCONN288_DDR506112002KQ-SCONN288_DDR506112002KQ,SMA   I175 @T6G_MB_LIB.T6G(SCH_1):PAGE101
   J32  210  VSS91 SCONN288_DDR506112002KQ-SCONN288_DDR506112002KQ,SMA   I175 @T6G_MB_LIB.T6G(SCH_1):PAGE101
   J32  212  VSS92 SCONN288_DDR506112002KQ-SCONN288_DDR506112002KQ,SMA   I175 @T6G_MB_LIB.T6G(SCH_1):PAGE101
   J32  214  VSS93 SCONN288_DDR506112002KQ-SCONN288_DDR506112002KQ,SMA   I175 @T6G_MB_LIB.T6G(SCH_1):PAGE101
   J32  216  VSS94 SCONN288_DDR506112002KQ-SCONN288_DDR506112002KQ,SMA   I175 @T6G_MB_LIB.T6G(SCH_1):PAGE101
   J32  219  VSS95 SCONN288_DDR506112002KQ-SCONN288_DDR506112002KQ,SMA   I175 @T6G_MB_LIB.T6G(SCH_1):PAGE101
   J32  222  VSS96 SCONN288_DDR506112002KQ-SCONN288_DDR506112002KQ,SMA   I175 @T6G_MB_LIB.T6G(SCH_1):PAGE101
   J32  224  VSS97 SCONN288_DDR506112002KQ-SCONN288_DDR506112002KQ,SMA   I175 @T6G_MB_LIB.T6G(SCH_1):PAGE101
   J32  226  VSS98 SCONN288_DDR506112002KQ-SCONN288_DDR506112002KQ,SMA   I175 @T6G_MB_LIB.T6G(SCH_1):PAGE101
   J32  228  VSS99 SCONN288_DDR506112002KQ-SCONN288_DDR506112002KQ,SMA   I175 @T6G_MB_LIB.T6G(SCH_1):PAGE101
   J32  230 VSS100 SCONN288_DDR506112002KQ-SCONN288_DDR506112002KQ,SMA   I175 @T6G_MB_LIB.T6G(SCH_1):PAGE101
   J32  233 VSS101 SCONN288_DDR506112002KQ-SCONN288_DDR506112002KQ,SMA   I175 @T6G_MB_LIB.T6G(SCH_1):PAGE101
   J32  235 VSS102 SCONN288_DDR506112002KQ-SCONN288_DDR506112002KQ,SMA   I175 @T6G_MB_LIB.T6G(SCH_1):PAGE101
   J32  237 VSS103 SCONN288_DDR506112002KQ-SCONN288_DDR506112002KQ,SMA   I175 @T6G_MB_LIB.T6G(SCH_1):PAGE101
   J32  240 VSS104 SCONN288_DDR506112002KQ-SCONN288_DDR506112002KQ,SMA   I175 @T6G_MB_LIB.T6G(SCH_1):PAGE101
   J32  242 VSS105 SCONN288_DDR506112002KQ-SCONN288_DDR506112002KQ,SMA   I175 @T6G_MB_LIB.T6G(SCH_1):PAGE101
   J32  244 VSS106 SCONN288_DDR506112002KQ-SCONN288_DDR506112002KQ,SMA   I175 @T6G_MB_LIB.T6G(SCH_1):PAGE101
   J32  246 VSS107 SCONN288_DDR506112002KQ-SCONN288_DDR506112002KQ,SMA   I175 @T6G_MB_LIB.T6G(SCH_1):PAGE101
   J32  248 VSS108 SCONN288_DDR506112002KQ-SCONN288_DDR506112002KQ,SMA   I175 @T6G_MB_LIB.T6G(SCH_1):PAGE101
   J32  251 VSS109 SCONN288_DDR506112002KQ-SCONN288_DDR506112002KQ,SMA   I175 @T6G_MB_LIB.T6G(SCH_1):PAGE101
   J32  253 VSS110 SCONN288_DDR506112002KQ-SCONN288_DDR506112002KQ,SMA   I175 @T6G_MB_LIB.T6G(SCH_1):PAGE101
   J32  255 VSS111 SCONN288_DDR506112002KQ-SCONN288_DDR506112002KQ,SMA   I175 @T6G_MB_LIB.T6G(SCH_1):PAGE101
   J32  257 VSS112 SCONN288_DDR506112002KQ-SCONN288_DDR506112002KQ,SMA   I175 @T6G_MB_LIB.T6G(SCH_1):PAGE101
   J32  259 VSS113 SCONN288_DDR506112002KQ-SCONN288_DDR506112002KQ,SMA   I175 @T6G_MB_LIB.T6G(SCH_1):PAGE101
   J32  262 VSS114 SCONN288_DDR506112002KQ-SCONN288_DDR506112002KQ,SMA   I175 @T6G_MB_LIB.T6G(SCH_1):PAGE101
   J32  264 VSS115 SCONN288_DDR506112002KQ-SCONN288_DDR506112002KQ,SMA   I175 @T6G_MB_LIB.T6G(SCH_1):PAGE101
   J32  266 VSS116 SCONN288_DDR506112002KQ-SCONN288_DDR506112002KQ,SMA   I175 @T6G_MB_LIB.T6G(SCH_1):PAGE101
   J32  268 VSS117 SCONN288_DDR506112002KQ-SCONN288_DDR506112002KQ,SMA   I175 @T6G_MB_LIB.T6G(SCH_1):PAGE101
   J32  270 VSS118 SCONN288_DDR506112002KQ-SCONN288_DDR506112002KQ,SMA   I175 @T6G_MB_LIB.T6G(SCH_1):PAGE101
   J32  273 VSS119 SCONN288_DDR506112002KQ-SCONN288_DDR506112002KQ,SMA   I175 @T6G_MB_LIB.T6G(SCH_1):PAGE101
   J32  275 VSS120 SCONN288_DDR506112002KQ-SCONN288_DDR506112002KQ,SMA   I175 @T6G_MB_LIB.T6G(SCH_1):PAGE101
   J32  277 VSS121 SCONN288_DDR506112002KQ-SCONN288_DDR506112002KQ,SMA   I175 @T6G_MB_LIB.T6G(SCH_1):PAGE101
   J32  279 VSS122 SCONN288_DDR506112002KQ-SCONN288_DDR506112002KQ,SMA   I175 @T6G_MB_LIB.T6G(SCH_1):PAGE101
   J32  281 VSS123 SCONN288_DDR506112002KQ-SCONN288_DDR506112002KQ,SMA   I175 @T6G_MB_LIB.T6G(SCH_1):PAGE101
   J32  284 VSS124 SCONN288_DDR506112002KQ-SCONN288_DDR506112002KQ,SMA   I175 @T6G_MB_LIB.T6G(SCH_1):PAGE101
   J32  286 VSS125 SCONN288_DDR506112002KQ-SCONN288_DDR506112002KQ,SMA   I175 @T6G_MB_LIB.T6G(SCH_1):PAGE101
   J32  288 VSS126 SCONN288_DDR506112002KQ-SCONN288_DDR506112002KQ,SMA   I175 @T6G_MB_LIB.T6G(SCH_1):PAGE101
  C152    2      B Q_CAP_0402-0.1UF,25V,10%,X7R,CH4104K1B00   I185 @T6G_MB_LIB.T6G(SCH_1):PAGE101
  C183    2      B Q_CAP_C0805-10UF,25V,10%,X6S,CH6104KEA00   I238 @T6G_MB_LIB.T6G(SCH_1):PAGE101
  C509    2      B Q_CAP_C0805-10UF,25V,10%,X6S,CH6104KEA00   I239 @T6G_MB_LIB.T6G(SCH_1):PAGE101
  R773    2      B Q_RES_0402LF-84.5K,1%,1/16W,CHIP,CS38452FB05   I129 @T6G_MB_LIB.T6G(SCH_1):PAGE102
   J33   G1     G1 SCONN288_DDR506112002KQ-SCONN288_DDR506112002KQ,SMA   I142 @T6G_MB_LIB.T6G(SCH_1):PAGE102
   J33   G2     G2 SCONN288_DDR506112002KQ-SCONN288_DDR506112002KQ,SMA   I142 @T6G_MB_LIB.T6G(SCH_1):PAGE102
   J33   G3     G3 SCONN288_DDR506112002KQ-SCONN288_DDR506112002KQ,SMA   I142 @T6G_MB_LIB.T6G(SCH_1):PAGE102
   J33    6   VSS0 SCONN288_DDR506112002KQ-SCONN288_DDR506112002KQ,SMA   I142 @T6G_MB_LIB.T6G(SCH_1):PAGE102
   J33    8   VSS1 SCONN288_DDR506112002KQ-SCONN288_DDR506112002KQ,SMA   I142 @T6G_MB_LIB.T6G(SCH_1):PAGE102
   J33   10   VSS2 SCONN288_DDR506112002KQ-SCONN288_DDR506112002KQ,SMA   I142 @T6G_MB_LIB.T6G(SCH_1):PAGE102
   J33   13   VSS3 SCONN288_DDR506112002KQ-SCONN288_DDR506112002KQ,SMA   I142 @T6G_MB_LIB.T6G(SCH_1):PAGE102
   J33   15   VSS4 SCONN288_DDR506112002KQ-SCONN288_DDR506112002KQ,SMA   I142 @T6G_MB_LIB.T6G(SCH_1):PAGE102
   J33   17   VSS5 SCONN288_DDR506112002KQ-SCONN288_DDR506112002KQ,SMA   I142 @T6G_MB_LIB.T6G(SCH_1):PAGE102
   J33   19   VSS6 SCONN288_DDR506112002KQ-SCONN288_DDR506112002KQ,SMA   I142 @T6G_MB_LIB.T6G(SCH_1):PAGE102
   J33   21   VSS7 SCONN288_DDR506112002KQ-SCONN288_DDR506112002KQ,SMA   I142 @T6G_MB_LIB.T6G(SCH_1):PAGE102
   J33   24   VSS8 SCONN288_DDR506112002KQ-SCONN288_DDR506112002KQ,SMA   I142 @T6G_MB_LIB.T6G(SCH_1):PAGE102
   J33   26   VSS9 SCONN288_DDR506112002KQ-SCONN288_DDR506112002KQ,SMA   I142 @T6G_MB_LIB.T6G(SCH_1):PAGE102
   J33   28  VSS10 SCONN288_DDR506112002KQ-SCONN288_DDR506112002KQ,SMA   I142 @T6G_MB_LIB.T6G(SCH_1):PAGE102
   J33   30  VSS11 SCONN288_DDR506112002KQ-SCONN288_DDR506112002KQ,SMA   I142 @T6G_MB_LIB.T6G(SCH_1):PAGE102
   J33   32  VSS12 SCONN288_DDR506112002KQ-SCONN288_DDR506112002KQ,SMA   I142 @T6G_MB_LIB.T6G(SCH_1):PAGE102
   J33   35  VSS13 SCONN288_DDR506112002KQ-SCONN288_DDR506112002KQ,SMA   I142 @T6G_MB_LIB.T6G(SCH_1):PAGE102
   J33   37  VSS14 SCONN288_DDR506112002KQ-SCONN288_DDR506112002KQ,SMA   I142 @T6G_MB_LIB.T6G(SCH_1):PAGE102
   J33   39  VSS15 SCONN288_DDR506112002KQ-SCONN288_DDR506112002KQ,SMA   I142 @T6G_MB_LIB.T6G(SCH_1):PAGE102
   J33   41  VSS16 SCONN288_DDR506112002KQ-SCONN288_DDR506112002KQ,SMA   I142 @T6G_MB_LIB.T6G(SCH_1):PAGE102
   J33   43  VSS17 SCONN288_DDR506112002KQ-SCONN288_DDR506112002KQ,SMA   I142 @T6G_MB_LIB.T6G(SCH_1):PAGE102
   J33   46  VSS18 SCONN288_DDR506112002KQ-SCONN288_DDR506112002KQ,SMA   I142 @T6G_MB_LIB.T6G(SCH_1):PAGE102
   J33   48  VSS19 SCONN288_DDR506112002KQ-SCONN288_DDR506112002KQ,SMA   I142 @T6G_MB_LIB.T6G(SCH_1):PAGE102
   J33   50  VSS20 SCONN288_DDR506112002KQ-SCONN288_DDR506112002KQ,SMA   I142 @T6G_MB_LIB.T6G(SCH_1):PAGE102
   J33   52  VSS21 SCONN288_DDR506112002KQ-SCONN288_DDR506112002KQ,SMA   I142 @T6G_MB_LIB.T6G(SCH_1):PAGE102
   J33   54  VSS22 SCONN288_DDR506112002KQ-SCONN288_DDR506112002KQ,SMA   I142 @T6G_MB_LIB.T6G(SCH_1):PAGE102
   J33   57  VSS23 SCONN288_DDR506112002KQ-SCONN288_DDR506112002KQ,SMA   I142 @T6G_MB_LIB.T6G(SCH_1):PAGE102
   J33   59  VSS24 SCONN288_DDR506112002KQ-SCONN288_DDR506112002KQ,SMA   I142 @T6G_MB_LIB.T6G(SCH_1):PAGE102
   J33   61  VSS25 SCONN288_DDR506112002KQ-SCONN288_DDR506112002KQ,SMA   I142 @T6G_MB_LIB.T6G(SCH_1):PAGE102
   J33   63  VSS26 SCONN288_DDR506112002KQ-SCONN288_DDR506112002KQ,SMA   I142 @T6G_MB_LIB.T6G(SCH_1):PAGE102
   J33   65  VSS27 SCONN288_DDR506112002KQ-SCONN288_DDR506112002KQ,SMA   I142 @T6G_MB_LIB.T6G(SCH_1):PAGE102
   J33   67  VSS28 SCONN288_DDR506112002KQ-SCONN288_DDR506112002KQ,SMA   I142 @T6G_MB_LIB.T6G(SCH_1):PAGE102
   J33   69  VSS29 SCONN288_DDR506112002KQ-SCONN288_DDR506112002KQ,SMA   I142 @T6G_MB_LIB.T6G(SCH_1):PAGE102
   J33   71  VSS30 SCONN288_DDR506112002KQ-SCONN288_DDR506112002KQ,SMA   I142 @T6G_MB_LIB.T6G(SCH_1):PAGE102
   J33   73  VSS31 SCONN288_DDR506112002KQ-SCONN288_DDR506112002KQ,SMA   I142 @T6G_MB_LIB.T6G(SCH_1):PAGE102
   J33   75  VSS32 SCONN288_DDR506112002KQ-SCONN288_DDR506112002KQ,SMA   I142 @T6G_MB_LIB.T6G(SCH_1):PAGE102
   J33   77  VSS33 SCONN288_DDR506112002KQ-SCONN288_DDR506112002KQ,SMA   I142 @T6G_MB_LIB.T6G(SCH_1):PAGE102
   J33   79  VSS34 SCONN288_DDR506112002KQ-SCONN288_DDR506112002KQ,SMA   I142 @T6G_MB_LIB.T6G(SCH_1):PAGE102
   J33   81  VSS35 SCONN288_DDR506112002KQ-SCONN288_DDR506112002KQ,SMA   I142 @T6G_MB_LIB.T6G(SCH_1):PAGE102
   J33   83  VSS36 SCONN288_DDR506112002KQ-SCONN288_DDR506112002KQ,SMA   I142 @T6G_MB_LIB.T6G(SCH_1):PAGE102
   J33   85  VSS37 SCONN288_DDR506112002KQ-SCONN288_DDR506112002KQ,SMA   I142 @T6G_MB_LIB.T6G(SCH_1):PAGE102
   J33   88  VSS38 SCONN288_DDR506112002KQ-SCONN288_DDR506112002KQ,SMA   I142 @T6G_MB_LIB.T6G(SCH_1):PAGE102
   J33   90  VSS39 SCONN288_DDR506112002KQ-SCONN288_DDR506112002KQ,SMA   I142 @T6G_MB_LIB.T6G(SCH_1):PAGE102
   J33   92  VSS40 SCONN288_DDR506112002KQ-SCONN288_DDR506112002KQ,SMA   I142 @T6G_MB_LIB.T6G(SCH_1):PAGE102
   J33   95  VSS41 SCONN288_DDR506112002KQ-SCONN288_DDR506112002KQ,SMA   I142 @T6G_MB_LIB.T6G(SCH_1):PAGE102
   J33   97  VSS42 SCONN288_DDR506112002KQ-SCONN288_DDR506112002KQ,SMA   I142 @T6G_MB_LIB.T6G(SCH_1):PAGE102
   J33   99  VSS43 SCONN288_DDR506112002KQ-SCONN288_DDR506112002KQ,SMA   I142 @T6G_MB_LIB.T6G(SCH_1):PAGE102
   J33  101  VSS44 SCONN288_DDR506112002KQ-SCONN288_DDR506112002KQ,SMA   I142 @T6G_MB_LIB.T6G(SCH_1):PAGE102
   J33  103  VSS45 SCONN288_DDR506112002KQ-SCONN288_DDR506112002KQ,SMA   I142 @T6G_MB_LIB.T6G(SCH_1):PAGE102
   J33  106  VSS46 SCONN288_DDR506112002KQ-SCONN288_DDR506112002KQ,SMA   I142 @T6G_MB_LIB.T6G(SCH_1):PAGE102
   J33  108  VSS47 SCONN288_DDR506112002KQ-SCONN288_DDR506112002KQ,SMA   I142 @T6G_MB_LIB.T6G(SCH_1):PAGE102
   J33  110  VSS48 SCONN288_DDR506112002KQ-SCONN288_DDR506112002KQ,SMA   I142 @T6G_MB_LIB.T6G(SCH_1):PAGE102
   J33  112  VSS49 SCONN288_DDR506112002KQ-SCONN288_DDR506112002KQ,SMA   I142 @T6G_MB_LIB.T6G(SCH_1):PAGE102
   J33  114  VSS50 SCONN288_DDR506112002KQ-SCONN288_DDR506112002KQ,SMA   I142 @T6G_MB_LIB.T6G(SCH_1):PAGE102
   J33  117  VSS51 SCONN288_DDR506112002KQ-SCONN288_DDR506112002KQ,SMA   I142 @T6G_MB_LIB.T6G(SCH_1):PAGE102
   J33  119  VSS52 SCONN288_DDR506112002KQ-SCONN288_DDR506112002KQ,SMA   I142 @T6G_MB_LIB.T6G(SCH_1):PAGE102
   J33  121  VSS53 SCONN288_DDR506112002KQ-SCONN288_DDR506112002KQ,SMA   I142 @T6G_MB_LIB.T6G(SCH_1):PAGE102
   J33  123  VSS54 SCONN288_DDR506112002KQ-SCONN288_DDR506112002KQ,SMA   I142 @T6G_MB_LIB.T6G(SCH_1):PAGE102
   J33  125  VSS55 SCONN288_DDR506112002KQ-SCONN288_DDR506112002KQ,SMA   I142 @T6G_MB_LIB.T6G(SCH_1):PAGE102
   J33  128  VSS56 SCONN288_DDR506112002KQ-SCONN288_DDR506112002KQ,SMA   I142 @T6G_MB_LIB.T6G(SCH_1):PAGE102
   J33  130  VSS57 SCONN288_DDR506112002KQ-SCONN288_DDR506112002KQ,SMA   I142 @T6G_MB_LIB.T6G(SCH_1):PAGE102
   J33  132  VSS58 SCONN288_DDR506112002KQ-SCONN288_DDR506112002KQ,SMA   I142 @T6G_MB_LIB.T6G(SCH_1):PAGE102
   J33  134  VSS59 SCONN288_DDR506112002KQ-SCONN288_DDR506112002KQ,SMA   I142 @T6G_MB_LIB.T6G(SCH_1):PAGE102
   J33  136  VSS60 SCONN288_DDR506112002KQ-SCONN288_DDR506112002KQ,SMA   I142 @T6G_MB_LIB.T6G(SCH_1):PAGE102
   J33  139  VSS61 SCONN288_DDR506112002KQ-SCONN288_DDR506112002KQ,SMA   I142 @T6G_MB_LIB.T6G(SCH_1):PAGE102
   J33  141  VSS62 SCONN288_DDR506112002KQ-SCONN288_DDR506112002KQ,SMA   I142 @T6G_MB_LIB.T6G(SCH_1):PAGE102
   J33  143  VSS63 SCONN288_DDR506112002KQ-SCONN288_DDR506112002KQ,SMA   I142 @T6G_MB_LIB.T6G(SCH_1):PAGE102
   J33  151  VSS64 SCONN288_DDR506112002KQ-SCONN288_DDR506112002KQ,SMA   I142 @T6G_MB_LIB.T6G(SCH_1):PAGE102
   J33  153  VSS65 SCONN288_DDR506112002KQ-SCONN288_DDR506112002KQ,SMA   I142 @T6G_MB_LIB.T6G(SCH_1):PAGE102
   J33  155  VSS66 SCONN288_DDR506112002KQ-SCONN288_DDR506112002KQ,SMA   I142 @T6G_MB_LIB.T6G(SCH_1):PAGE102
   J33  158  VSS67 SCONN288_DDR506112002KQ-SCONN288_DDR506112002KQ,SMA   I142 @T6G_MB_LIB.T6G(SCH_1):PAGE102
   J33  160  VSS68 SCONN288_DDR506112002KQ-SCONN288_DDR506112002KQ,SMA   I142 @T6G_MB_LIB.T6G(SCH_1):PAGE102
   J33  162  VSS69 SCONN288_DDR506112002KQ-SCONN288_DDR506112002KQ,SMA   I142 @T6G_MB_LIB.T6G(SCH_1):PAGE102
   J33  164  VSS70 SCONN288_DDR506112002KQ-SCONN288_DDR506112002KQ,SMA   I142 @T6G_MB_LIB.T6G(SCH_1):PAGE102
   J33  166  VSS71 SCONN288_DDR506112002KQ-SCONN288_DDR506112002KQ,SMA   I142 @T6G_MB_LIB.T6G(SCH_1):PAGE102
   J33  169  VSS72 SCONN288_DDR506112002KQ-SCONN288_DDR506112002KQ,SMA   I142 @T6G_MB_LIB.T6G(SCH_1):PAGE102
   J33  171  VSS73 SCONN288_DDR506112002KQ-SCONN288_DDR506112002KQ,SMA   I142 @T6G_MB_LIB.T6G(SCH_1):PAGE102
   J33  173  VSS74 SCONN288_DDR506112002KQ-SCONN288_DDR506112002KQ,SMA   I142 @T6G_MB_LIB.T6G(SCH_1):PAGE102
   J33  175  VSS75 SCONN288_DDR506112002KQ-SCONN288_DDR506112002KQ,SMA   I142 @T6G_MB_LIB.T6G(SCH_1):PAGE102
   J33  177  VSS76 SCONN288_DDR506112002KQ-SCONN288_DDR506112002KQ,SMA   I142 @T6G_MB_LIB.T6G(SCH_1):PAGE102
   J33  180  VSS77 SCONN288_DDR506112002KQ-SCONN288_DDR506112002KQ,SMA   I142 @T6G_MB_LIB.T6G(SCH_1):PAGE102
   J33  182  VSS78 SCONN288_DDR506112002KQ-SCONN288_DDR506112002KQ,SMA   I142 @T6G_MB_LIB.T6G(SCH_1):PAGE102
   J33  184  VSS79 SCONN288_DDR506112002KQ-SCONN288_DDR506112002KQ,SMA   I142 @T6G_MB_LIB.T6G(SCH_1):PAGE102
   J33  186  VSS80 SCONN288_DDR506112002KQ-SCONN288_DDR506112002KQ,SMA   I142 @T6G_MB_LIB.T6G(SCH_1):PAGE102
   J33  188  VSS81 SCONN288_DDR506112002KQ-SCONN288_DDR506112002KQ,SMA   I142 @T6G_MB_LIB.T6G(SCH_1):PAGE102
   J33  191  VSS82 SCONN288_DDR506112002KQ-SCONN288_DDR506112002KQ,SMA   I142 @T6G_MB_LIB.T6G(SCH_1):PAGE102
   J33  193  VSS83 SCONN288_DDR506112002KQ-SCONN288_DDR506112002KQ,SMA   I142 @T6G_MB_LIB.T6G(SCH_1):PAGE102
   J33  195  VSS84 SCONN288_DDR506112002KQ-SCONN288_DDR506112002KQ,SMA   I142 @T6G_MB_LIB.T6G(SCH_1):PAGE102
   J33  197  VSS85 SCONN288_DDR506112002KQ-SCONN288_DDR506112002KQ,SMA   I142 @T6G_MB_LIB.T6G(SCH_1):PAGE102
   J33  199  VSS86 SCONN288_DDR506112002KQ-SCONN288_DDR506112002KQ,SMA   I142 @T6G_MB_LIB.T6G(SCH_1):PAGE102
   J33  202  VSS87 SCONN288_DDR506112002KQ-SCONN288_DDR506112002KQ,SMA   I142 @T6G_MB_LIB.T6G(SCH_1):PAGE102
   J33  204  VSS88 SCONN288_DDR506112002KQ-SCONN288_DDR506112002KQ,SMA   I142 @T6G_MB_LIB.T6G(SCH_1):PAGE102
   J33  206  VSS89 SCONN288_DDR506112002KQ-SCONN288_DDR506112002KQ,SMA   I142 @T6G_MB_LIB.T6G(SCH_1):PAGE102
   J33  208  VSS90 SCONN288_DDR506112002KQ-SCONN288_DDR506112002KQ,SMA   I142 @T6G_MB_LIB.T6G(SCH_1):PAGE102
   J33  210  VSS91 SCONN288_DDR506112002KQ-SCONN288_DDR506112002KQ,SMA   I142 @T6G_MB_LIB.T6G(SCH_1):PAGE102
   J33  212  VSS92 SCONN288_DDR506112002KQ-SCONN288_DDR506112002KQ,SMA   I142 @T6G_MB_LIB.T6G(SCH_1):PAGE102
   J33  214  VSS93 SCONN288_DDR506112002KQ-SCONN288_DDR506112002KQ,SMA   I142 @T6G_MB_LIB.T6G(SCH_1):PAGE102
   J33  216  VSS94 SCONN288_DDR506112002KQ-SCONN288_DDR506112002KQ,SMA   I142 @T6G_MB_LIB.T6G(SCH_1):PAGE102
   J33  219  VSS95 SCONN288_DDR506112002KQ-SCONN288_DDR506112002KQ,SMA   I142 @T6G_MB_LIB.T6G(SCH_1):PAGE102
   J33  222  VSS96 SCONN288_DDR506112002KQ-SCONN288_DDR506112002KQ,SMA   I142 @T6G_MB_LIB.T6G(SCH_1):PAGE102
   J33  224  VSS97 SCONN288_DDR506112002KQ-SCONN288_DDR506112002KQ,SMA   I142 @T6G_MB_LIB.T6G(SCH_1):PAGE102
   J33  226  VSS98 SCONN288_DDR506112002KQ-SCONN288_DDR506112002KQ,SMA   I142 @T6G_MB_LIB.T6G(SCH_1):PAGE102
   J33  228  VSS99 SCONN288_DDR506112002KQ-SCONN288_DDR506112002KQ,SMA   I142 @T6G_MB_LIB.T6G(SCH_1):PAGE102
   J33  230 VSS100 SCONN288_DDR506112002KQ-SCONN288_DDR506112002KQ,SMA   I142 @T6G_MB_LIB.T6G(SCH_1):PAGE102
   J33  233 VSS101 SCONN288_DDR506112002KQ-SCONN288_DDR506112002KQ,SMA   I142 @T6G_MB_LIB.T6G(SCH_1):PAGE102
   J33  235 VSS102 SCONN288_DDR506112002KQ-SCONN288_DDR506112002KQ,SMA   I142 @T6G_MB_LIB.T6G(SCH_1):PAGE102
   J33  237 VSS103 SCONN288_DDR506112002KQ-SCONN288_DDR506112002KQ,SMA   I142 @T6G_MB_LIB.T6G(SCH_1):PAGE102
   J33  240 VSS104 SCONN288_DDR506112002KQ-SCONN288_DDR506112002KQ,SMA   I142 @T6G_MB_LIB.T6G(SCH_1):PAGE102
   J33  242 VSS105 SCONN288_DDR506112002KQ-SCONN288_DDR506112002KQ,SMA   I142 @T6G_MB_LIB.T6G(SCH_1):PAGE102
   J33  244 VSS106 SCONN288_DDR506112002KQ-SCONN288_DDR506112002KQ,SMA   I142 @T6G_MB_LIB.T6G(SCH_1):PAGE102
   J33  246 VSS107 SCONN288_DDR506112002KQ-SCONN288_DDR506112002KQ,SMA   I142 @T6G_MB_LIB.T6G(SCH_1):PAGE102
   J33  248 VSS108 SCONN288_DDR506112002KQ-SCONN288_DDR506112002KQ,SMA   I142 @T6G_MB_LIB.T6G(SCH_1):PAGE102
   J33  251 VSS109 SCONN288_DDR506112002KQ-SCONN288_DDR506112002KQ,SMA   I142 @T6G_MB_LIB.T6G(SCH_1):PAGE102
   J33  253 VSS110 SCONN288_DDR506112002KQ-SCONN288_DDR506112002KQ,SMA   I142 @T6G_MB_LIB.T6G(SCH_1):PAGE102
   J33  255 VSS111 SCONN288_DDR506112002KQ-SCONN288_DDR506112002KQ,SMA   I142 @T6G_MB_LIB.T6G(SCH_1):PAGE102
   J33  257 VSS112 SCONN288_DDR506112002KQ-SCONN288_DDR506112002KQ,SMA   I142 @T6G_MB_LIB.T6G(SCH_1):PAGE102
   J33  259 VSS113 SCONN288_DDR506112002KQ-SCONN288_DDR506112002KQ,SMA   I142 @T6G_MB_LIB.T6G(SCH_1):PAGE102
   J33  262 VSS114 SCONN288_DDR506112002KQ-SCONN288_DDR506112002KQ,SMA   I142 @T6G_MB_LIB.T6G(SCH_1):PAGE102
   J33  264 VSS115 SCONN288_DDR506112002KQ-SCONN288_DDR506112002KQ,SMA   I142 @T6G_MB_LIB.T6G(SCH_1):PAGE102
   J33  266 VSS116 SCONN288_DDR506112002KQ-SCONN288_DDR506112002KQ,SMA   I142 @T6G_MB_LIB.T6G(SCH_1):PAGE102
   J33  268 VSS117 SCONN288_DDR506112002KQ-SCONN288_DDR506112002KQ,SMA   I142 @T6G_MB_LIB.T6G(SCH_1):PAGE102
   J33  270 VSS118 SCONN288_DDR506112002KQ-SCONN288_DDR506112002KQ,SMA   I142 @T6G_MB_LIB.T6G(SCH_1):PAGE102
   J33  273 VSS119 SCONN288_DDR506112002KQ-SCONN288_DDR506112002KQ,SMA   I142 @T6G_MB_LIB.T6G(SCH_1):PAGE102
   J33  275 VSS120 SCONN288_DDR506112002KQ-SCONN288_DDR506112002KQ,SMA   I142 @T6G_MB_LIB.T6G(SCH_1):PAGE102
   J33  277 VSS121 SCONN288_DDR506112002KQ-SCONN288_DDR506112002KQ,SMA   I142 @T6G_MB_LIB.T6G(SCH_1):PAGE102
   J33  279 VSS122 SCONN288_DDR506112002KQ-SCONN288_DDR506112002KQ,SMA   I142 @T6G_MB_LIB.T6G(SCH_1):PAGE102
   J33  281 VSS123 SCONN288_DDR506112002KQ-SCONN288_DDR506112002KQ,SMA   I142 @T6G_MB_LIB.T6G(SCH_1):PAGE102
   J33  284 VSS124 SCONN288_DDR506112002KQ-SCONN288_DDR506112002KQ,SMA   I142 @T6G_MB_LIB.T6G(SCH_1):PAGE102
   J33  286 VSS125 SCONN288_DDR506112002KQ-SCONN288_DDR506112002KQ,SMA   I142 @T6G_MB_LIB.T6G(SCH_1):PAGE102
   J33  288 VSS126 SCONN288_DDR506112002KQ-SCONN288_DDR506112002KQ,SMA   I142 @T6G_MB_LIB.T6G(SCH_1):PAGE102
  C156    2      B Q_CAP_0402-0.1UF,25V,10%,X7R,CH4104K1B00   I185 @T6G_MB_LIB.T6G(SCH_1):PAGE102
  C518    2      B Q_CAP_C0805-10UF,25V,10%,X6S,CH6104KEA00   I238 @T6G_MB_LIB.T6G(SCH_1):PAGE102
  C527    2      B Q_CAP_C0805-10UF,25V,10%,X6S,CH6104KEA00   I239 @T6G_MB_LIB.T6G(SCH_1):PAGE102
   R37    2      B Q_RES_0402LF-10K,1%,1/16W,CHIP,CS31002FB08   I129 @T6G_MB_LIB.T6G(SCH_1):PAGE103
  J102   G1     G1 SCONN288_DDR506112002KQ-SCONN288_DDR506112002KQ,SMA   I142 @T6G_MB_LIB.T6G(SCH_1):PAGE103
  J102   G2     G2 SCONN288_DDR506112002KQ-SCONN288_DDR506112002KQ,SMA   I142 @T6G_MB_LIB.T6G(SCH_1):PAGE103
  J102   G3     G3 SCONN288_DDR506112002KQ-SCONN288_DDR506112002KQ,SMA   I142 @T6G_MB_LIB.T6G(SCH_1):PAGE103
  J102    6   VSS0 SCONN288_DDR506112002KQ-SCONN288_DDR506112002KQ,SMA   I142 @T6G_MB_LIB.T6G(SCH_1):PAGE103
  J102    8   VSS1 SCONN288_DDR506112002KQ-SCONN288_DDR506112002KQ,SMA   I142 @T6G_MB_LIB.T6G(SCH_1):PAGE103
  J102   10   VSS2 SCONN288_DDR506112002KQ-SCONN288_DDR506112002KQ,SMA   I142 @T6G_MB_LIB.T6G(SCH_1):PAGE103
  J102   13   VSS3 SCONN288_DDR506112002KQ-SCONN288_DDR506112002KQ,SMA   I142 @T6G_MB_LIB.T6G(SCH_1):PAGE103
  J102   15   VSS4 SCONN288_DDR506112002KQ-SCONN288_DDR506112002KQ,SMA   I142 @T6G_MB_LIB.T6G(SCH_1):PAGE103
  J102   17   VSS5 SCONN288_DDR506112002KQ-SCONN288_DDR506112002KQ,SMA   I142 @T6G_MB_LIB.T6G(SCH_1):PAGE103
  J102   19   VSS6 SCONN288_DDR506112002KQ-SCONN288_DDR506112002KQ,SMA   I142 @T6G_MB_LIB.T6G(SCH_1):PAGE103
  J102   21   VSS7 SCONN288_DDR506112002KQ-SCONN288_DDR506112002KQ,SMA   I142 @T6G_MB_LIB.T6G(SCH_1):PAGE103
  J102   24   VSS8 SCONN288_DDR506112002KQ-SCONN288_DDR506112002KQ,SMA   I142 @T6G_MB_LIB.T6G(SCH_1):PAGE103
  J102   26   VSS9 SCONN288_DDR506112002KQ-SCONN288_DDR506112002KQ,SMA   I142 @T6G_MB_LIB.T6G(SCH_1):PAGE103
  J102   28  VSS10 SCONN288_DDR506112002KQ-SCONN288_DDR506112002KQ,SMA   I142 @T6G_MB_LIB.T6G(SCH_1):PAGE103
  J102   30  VSS11 SCONN288_DDR506112002KQ-SCONN288_DDR506112002KQ,SMA   I142 @T6G_MB_LIB.T6G(SCH_1):PAGE103
  J102   32  VSS12 SCONN288_DDR506112002KQ-SCONN288_DDR506112002KQ,SMA   I142 @T6G_MB_LIB.T6G(SCH_1):PAGE103
  J102   35  VSS13 SCONN288_DDR506112002KQ-SCONN288_DDR506112002KQ,SMA   I142 @T6G_MB_LIB.T6G(SCH_1):PAGE103
  J102   37  VSS14 SCONN288_DDR506112002KQ-SCONN288_DDR506112002KQ,SMA   I142 @T6G_MB_LIB.T6G(SCH_1):PAGE103
  J102   39  VSS15 SCONN288_DDR506112002KQ-SCONN288_DDR506112002KQ,SMA   I142 @T6G_MB_LIB.T6G(SCH_1):PAGE103
  J102   41  VSS16 SCONN288_DDR506112002KQ-SCONN288_DDR506112002KQ,SMA   I142 @T6G_MB_LIB.T6G(SCH_1):PAGE103
  J102   43  VSS17 SCONN288_DDR506112002KQ-SCONN288_DDR506112002KQ,SMA   I142 @T6G_MB_LIB.T6G(SCH_1):PAGE103
  J102   46  VSS18 SCONN288_DDR506112002KQ-SCONN288_DDR506112002KQ,SMA   I142 @T6G_MB_LIB.T6G(SCH_1):PAGE103
  J102   48  VSS19 SCONN288_DDR506112002KQ-SCONN288_DDR506112002KQ,SMA   I142 @T6G_MB_LIB.T6G(SCH_1):PAGE103
  J102   50  VSS20 SCONN288_DDR506112002KQ-SCONN288_DDR506112002KQ,SMA   I142 @T6G_MB_LIB.T6G(SCH_1):PAGE103
  J102   52  VSS21 SCONN288_DDR506112002KQ-SCONN288_DDR506112002KQ,SMA   I142 @T6G_MB_LIB.T6G(SCH_1):PAGE103
  J102   54  VSS22 SCONN288_DDR506112002KQ-SCONN288_DDR506112002KQ,SMA   I142 @T6G_MB_LIB.T6G(SCH_1):PAGE103
  J102   57  VSS23 SCONN288_DDR506112002KQ-SCONN288_DDR506112002KQ,SMA   I142 @T6G_MB_LIB.T6G(SCH_1):PAGE103
  J102   59  VSS24 SCONN288_DDR506112002KQ-SCONN288_DDR506112002KQ,SMA   I142 @T6G_MB_LIB.T6G(SCH_1):PAGE103
  J102   61  VSS25 SCONN288_DDR506112002KQ-SCONN288_DDR506112002KQ,SMA   I142 @T6G_MB_LIB.T6G(SCH_1):PAGE103
  J102   63  VSS26 SCONN288_DDR506112002KQ-SCONN288_DDR506112002KQ,SMA   I142 @T6G_MB_LIB.T6G(SCH_1):PAGE103
  J102   65  VSS27 SCONN288_DDR506112002KQ-SCONN288_DDR506112002KQ,SMA   I142 @T6G_MB_LIB.T6G(SCH_1):PAGE103
  J102   67  VSS28 SCONN288_DDR506112002KQ-SCONN288_DDR506112002KQ,SMA   I142 @T6G_MB_LIB.T6G(SCH_1):PAGE103
  J102   69  VSS29 SCONN288_DDR506112002KQ-SCONN288_DDR506112002KQ,SMA   I142 @T6G_MB_LIB.T6G(SCH_1):PAGE103
  J102   71  VSS30 SCONN288_DDR506112002KQ-SCONN288_DDR506112002KQ,SMA   I142 @T6G_MB_LIB.T6G(SCH_1):PAGE103
  J102   73  VSS31 SCONN288_DDR506112002KQ-SCONN288_DDR506112002KQ,SMA   I142 @T6G_MB_LIB.T6G(SCH_1):PAGE103
  J102   75  VSS32 SCONN288_DDR506112002KQ-SCONN288_DDR506112002KQ,SMA   I142 @T6G_MB_LIB.T6G(SCH_1):PAGE103
  J102   77  VSS33 SCONN288_DDR506112002KQ-SCONN288_DDR506112002KQ,SMA   I142 @T6G_MB_LIB.T6G(SCH_1):PAGE103
  J102   79  VSS34 SCONN288_DDR506112002KQ-SCONN288_DDR506112002KQ,SMA   I142 @T6G_MB_LIB.T6G(SCH_1):PAGE103
  J102   81  VSS35 SCONN288_DDR506112002KQ-SCONN288_DDR506112002KQ,SMA   I142 @T6G_MB_LIB.T6G(SCH_1):PAGE103
  J102   83  VSS36 SCONN288_DDR506112002KQ-SCONN288_DDR506112002KQ,SMA   I142 @T6G_MB_LIB.T6G(SCH_1):PAGE103
  J102   85  VSS37 SCONN288_DDR506112002KQ-SCONN288_DDR506112002KQ,SMA   I142 @T6G_MB_LIB.T6G(SCH_1):PAGE103
  J102   88  VSS38 SCONN288_DDR506112002KQ-SCONN288_DDR506112002KQ,SMA   I142 @T6G_MB_LIB.T6G(SCH_1):PAGE103
  J102   90  VSS39 SCONN288_DDR506112002KQ-SCONN288_DDR506112002KQ,SMA   I142 @T6G_MB_LIB.T6G(SCH_1):PAGE103
  J102   92  VSS40 SCONN288_DDR506112002KQ-SCONN288_DDR506112002KQ,SMA   I142 @T6G_MB_LIB.T6G(SCH_1):PAGE103
  J102   95  VSS41 SCONN288_DDR506112002KQ-SCONN288_DDR506112002KQ,SMA   I142 @T6G_MB_LIB.T6G(SCH_1):PAGE103
  J102   97  VSS42 SCONN288_DDR506112002KQ-SCONN288_DDR506112002KQ,SMA   I142 @T6G_MB_LIB.T6G(SCH_1):PAGE103
  J102   99  VSS43 SCONN288_DDR506112002KQ-SCONN288_DDR506112002KQ,SMA   I142 @T6G_MB_LIB.T6G(SCH_1):PAGE103
  J102  101  VSS44 SCONN288_DDR506112002KQ-SCONN288_DDR506112002KQ,SMA   I142 @T6G_MB_LIB.T6G(SCH_1):PAGE103
  J102  103  VSS45 SCONN288_DDR506112002KQ-SCONN288_DDR506112002KQ,SMA   I142 @T6G_MB_LIB.T6G(SCH_1):PAGE103
  J102  106  VSS46 SCONN288_DDR506112002KQ-SCONN288_DDR506112002KQ,SMA   I142 @T6G_MB_LIB.T6G(SCH_1):PAGE103
  J102  108  VSS47 SCONN288_DDR506112002KQ-SCONN288_DDR506112002KQ,SMA   I142 @T6G_MB_LIB.T6G(SCH_1):PAGE103
  J102  110  VSS48 SCONN288_DDR506112002KQ-SCONN288_DDR506112002KQ,SMA   I142 @T6G_MB_LIB.T6G(SCH_1):PAGE103
  J102  112  VSS49 SCONN288_DDR506112002KQ-SCONN288_DDR506112002KQ,SMA   I142 @T6G_MB_LIB.T6G(SCH_1):PAGE103
  J102  114  VSS50 SCONN288_DDR506112002KQ-SCONN288_DDR506112002KQ,SMA   I142 @T6G_MB_LIB.T6G(SCH_1):PAGE103
  J102  117  VSS51 SCONN288_DDR506112002KQ-SCONN288_DDR506112002KQ,SMA   I142 @T6G_MB_LIB.T6G(SCH_1):PAGE103
  J102  119  VSS52 SCONN288_DDR506112002KQ-SCONN288_DDR506112002KQ,SMA   I142 @T6G_MB_LIB.T6G(SCH_1):PAGE103
  J102  121  VSS53 SCONN288_DDR506112002KQ-SCONN288_DDR506112002KQ,SMA   I142 @T6G_MB_LIB.T6G(SCH_1):PAGE103
  J102  123  VSS54 SCONN288_DDR506112002KQ-SCONN288_DDR506112002KQ,SMA   I142 @T6G_MB_LIB.T6G(SCH_1):PAGE103
  J102  125  VSS55 SCONN288_DDR506112002KQ-SCONN288_DDR506112002KQ,SMA   I142 @T6G_MB_LIB.T6G(SCH_1):PAGE103
  J102  128  VSS56 SCONN288_DDR506112002KQ-SCONN288_DDR506112002KQ,SMA   I142 @T6G_MB_LIB.T6G(SCH_1):PAGE103
  J102  130  VSS57 SCONN288_DDR506112002KQ-SCONN288_DDR506112002KQ,SMA   I142 @T6G_MB_LIB.T6G(SCH_1):PAGE103
  J102  132  VSS58 SCONN288_DDR506112002KQ-SCONN288_DDR506112002KQ,SMA   I142 @T6G_MB_LIB.T6G(SCH_1):PAGE103
  J102  134  VSS59 SCONN288_DDR506112002KQ-SCONN288_DDR506112002KQ,SMA   I142 @T6G_MB_LIB.T6G(SCH_1):PAGE103
  J102  136  VSS60 SCONN288_DDR506112002KQ-SCONN288_DDR506112002KQ,SMA   I142 @T6G_MB_LIB.T6G(SCH_1):PAGE103
  J102  139  VSS61 SCONN288_DDR506112002KQ-SCONN288_DDR506112002KQ,SMA   I142 @T6G_MB_LIB.T6G(SCH_1):PAGE103
  J102  141  VSS62 SCONN288_DDR506112002KQ-SCONN288_DDR506112002KQ,SMA   I142 @T6G_MB_LIB.T6G(SCH_1):PAGE103
  J102  143  VSS63 SCONN288_DDR506112002KQ-SCONN288_DDR506112002KQ,SMA   I142 @T6G_MB_LIB.T6G(SCH_1):PAGE103
  J102  151  VSS64 SCONN288_DDR506112002KQ-SCONN288_DDR506112002KQ,SMA   I142 @T6G_MB_LIB.T6G(SCH_1):PAGE103
  J102  153  VSS65 SCONN288_DDR506112002KQ-SCONN288_DDR506112002KQ,SMA   I142 @T6G_MB_LIB.T6G(SCH_1):PAGE103
  J102  155  VSS66 SCONN288_DDR506112002KQ-SCONN288_DDR506112002KQ,SMA   I142 @T6G_MB_LIB.T6G(SCH_1):PAGE103
  J102  158  VSS67 SCONN288_DDR506112002KQ-SCONN288_DDR506112002KQ,SMA   I142 @T6G_MB_LIB.T6G(SCH_1):PAGE103
  J102  160  VSS68 SCONN288_DDR506112002KQ-SCONN288_DDR506112002KQ,SMA   I142 @T6G_MB_LIB.T6G(SCH_1):PAGE103
  J102  162  VSS69 SCONN288_DDR506112002KQ-SCONN288_DDR506112002KQ,SMA   I142 @T6G_MB_LIB.T6G(SCH_1):PAGE103
  J102  164  VSS70 SCONN288_DDR506112002KQ-SCONN288_DDR506112002KQ,SMA   I142 @T6G_MB_LIB.T6G(SCH_1):PAGE103
  J102  166  VSS71 SCONN288_DDR506112002KQ-SCONN288_DDR506112002KQ,SMA   I142 @T6G_MB_LIB.T6G(SCH_1):PAGE103
  J102  169  VSS72 SCONN288_DDR506112002KQ-SCONN288_DDR506112002KQ,SMA   I142 @T6G_MB_LIB.T6G(SCH_1):PAGE103
  J102  171  VSS73 SCONN288_DDR506112002KQ-SCONN288_DDR506112002KQ,SMA   I142 @T6G_MB_LIB.T6G(SCH_1):PAGE103
  J102  173  VSS74 SCONN288_DDR506112002KQ-SCONN288_DDR506112002KQ,SMA   I142 @T6G_MB_LIB.T6G(SCH_1):PAGE103
  J102  175  VSS75 SCONN288_DDR506112002KQ-SCONN288_DDR506112002KQ,SMA   I142 @T6G_MB_LIB.T6G(SCH_1):PAGE103
  J102  177  VSS76 SCONN288_DDR506112002KQ-SCONN288_DDR506112002KQ,SMA   I142 @T6G_MB_LIB.T6G(SCH_1):PAGE103
  J102  180  VSS77 SCONN288_DDR506112002KQ-SCONN288_DDR506112002KQ,SMA   I142 @T6G_MB_LIB.T6G(SCH_1):PAGE103
  J102  182  VSS78 SCONN288_DDR506112002KQ-SCONN288_DDR506112002KQ,SMA   I142 @T6G_MB_LIB.T6G(SCH_1):PAGE103
  J102  184  VSS79 SCONN288_DDR506112002KQ-SCONN288_DDR506112002KQ,SMA   I142 @T6G_MB_LIB.T6G(SCH_1):PAGE103
  J102  186  VSS80 SCONN288_DDR506112002KQ-SCONN288_DDR506112002KQ,SMA   I142 @T6G_MB_LIB.T6G(SCH_1):PAGE103
  J102  188  VSS81 SCONN288_DDR506112002KQ-SCONN288_DDR506112002KQ,SMA   I142 @T6G_MB_LIB.T6G(SCH_1):PAGE103
  J102  191  VSS82 SCONN288_DDR506112002KQ-SCONN288_DDR506112002KQ,SMA   I142 @T6G_MB_LIB.T6G(SCH_1):PAGE103
  J102  193  VSS83 SCONN288_DDR506112002KQ-SCONN288_DDR506112002KQ,SMA   I142 @T6G_MB_LIB.T6G(SCH_1):PAGE103
  J102  195  VSS84 SCONN288_DDR506112002KQ-SCONN288_DDR506112002KQ,SMA   I142 @T6G_MB_LIB.T6G(SCH_1):PAGE103
  J102  197  VSS85 SCONN288_DDR506112002KQ-SCONN288_DDR506112002KQ,SMA   I142 @T6G_MB_LIB.T6G(SCH_1):PAGE103
  J102  199  VSS86 SCONN288_DDR506112002KQ-SCONN288_DDR506112002KQ,SMA   I142 @T6G_MB_LIB.T6G(SCH_1):PAGE103
  J102  202  VSS87 SCONN288_DDR506112002KQ-SCONN288_DDR506112002KQ,SMA   I142 @T6G_MB_LIB.T6G(SCH_1):PAGE103
  J102  204  VSS88 SCONN288_DDR506112002KQ-SCONN288_DDR506112002KQ,SMA   I142 @T6G_MB_LIB.T6G(SCH_1):PAGE103
  J102  206  VSS89 SCONN288_DDR506112002KQ-SCONN288_DDR506112002KQ,SMA   I142 @T6G_MB_LIB.T6G(SCH_1):PAGE103
  J102  208  VSS90 SCONN288_DDR506112002KQ-SCONN288_DDR506112002KQ,SMA   I142 @T6G_MB_LIB.T6G(SCH_1):PAGE103
  J102  210  VSS91 SCONN288_DDR506112002KQ-SCONN288_DDR506112002KQ,SMA   I142 @T6G_MB_LIB.T6G(SCH_1):PAGE103
  J102  212  VSS92 SCONN288_DDR506112002KQ-SCONN288_DDR506112002KQ,SMA   I142 @T6G_MB_LIB.T6G(SCH_1):PAGE103
  J102  214  VSS93 SCONN288_DDR506112002KQ-SCONN288_DDR506112002KQ,SMA   I142 @T6G_MB_LIB.T6G(SCH_1):PAGE103
  J102  216  VSS94 SCONN288_DDR506112002KQ-SCONN288_DDR506112002KQ,SMA   I142 @T6G_MB_LIB.T6G(SCH_1):PAGE103
  J102  219  VSS95 SCONN288_DDR506112002KQ-SCONN288_DDR506112002KQ,SMA   I142 @T6G_MB_LIB.T6G(SCH_1):PAGE103
  J102  222  VSS96 SCONN288_DDR506112002KQ-SCONN288_DDR506112002KQ,SMA   I142 @T6G_MB_LIB.T6G(SCH_1):PAGE103
  J102  224  VSS97 SCONN288_DDR506112002KQ-SCONN288_DDR506112002KQ,SMA   I142 @T6G_MB_LIB.T6G(SCH_1):PAGE103
  J102  226  VSS98 SCONN288_DDR506112002KQ-SCONN288_DDR506112002KQ,SMA   I142 @T6G_MB_LIB.T6G(SCH_1):PAGE103
  J102  228  VSS99 SCONN288_DDR506112002KQ-SCONN288_DDR506112002KQ,SMA   I142 @T6G_MB_LIB.T6G(SCH_1):PAGE103
  J102  230 VSS100 SCONN288_DDR506112002KQ-SCONN288_DDR506112002KQ,SMA   I142 @T6G_MB_LIB.T6G(SCH_1):PAGE103
  J102  233 VSS101 SCONN288_DDR506112002KQ-SCONN288_DDR506112002KQ,SMA   I142 @T6G_MB_LIB.T6G(SCH_1):PAGE103
  J102  235 VSS102 SCONN288_DDR506112002KQ-SCONN288_DDR506112002KQ,SMA   I142 @T6G_MB_LIB.T6G(SCH_1):PAGE103
  J102  237 VSS103 SCONN288_DDR506112002KQ-SCONN288_DDR506112002KQ,SMA   I142 @T6G_MB_LIB.T6G(SCH_1):PAGE103
  J102  240 VSS104 SCONN288_DDR506112002KQ-SCONN288_DDR506112002KQ,SMA   I142 @T6G_MB_LIB.T6G(SCH_1):PAGE103
  J102  242 VSS105 SCONN288_DDR506112002KQ-SCONN288_DDR506112002KQ,SMA   I142 @T6G_MB_LIB.T6G(SCH_1):PAGE103
  J102  244 VSS106 SCONN288_DDR506112002KQ-SCONN288_DDR506112002KQ,SMA   I142 @T6G_MB_LIB.T6G(SCH_1):PAGE103
  J102  246 VSS107 SCONN288_DDR506112002KQ-SCONN288_DDR506112002KQ,SMA   I142 @T6G_MB_LIB.T6G(SCH_1):PAGE103
  J102  248 VSS108 SCONN288_DDR506112002KQ-SCONN288_DDR506112002KQ,SMA   I142 @T6G_MB_LIB.T6G(SCH_1):PAGE103
  J102  251 VSS109 SCONN288_DDR506112002KQ-SCONN288_DDR506112002KQ,SMA   I142 @T6G_MB_LIB.T6G(SCH_1):PAGE103
  J102  253 VSS110 SCONN288_DDR506112002KQ-SCONN288_DDR506112002KQ,SMA   I142 @T6G_MB_LIB.T6G(SCH_1):PAGE103
  J102  255 VSS111 SCONN288_DDR506112002KQ-SCONN288_DDR506112002KQ,SMA   I142 @T6G_MB_LIB.T6G(SCH_1):PAGE103
  J102  257 VSS112 SCONN288_DDR506112002KQ-SCONN288_DDR506112002KQ,SMA   I142 @T6G_MB_LIB.T6G(SCH_1):PAGE103
  J102  259 VSS113 SCONN288_DDR506112002KQ-SCONN288_DDR506112002KQ,SMA   I142 @T6G_MB_LIB.T6G(SCH_1):PAGE103
  J102  262 VSS114 SCONN288_DDR506112002KQ-SCONN288_DDR506112002KQ,SMA   I142 @T6G_MB_LIB.T6G(SCH_1):PAGE103
  J102  264 VSS115 SCONN288_DDR506112002KQ-SCONN288_DDR506112002KQ,SMA   I142 @T6G_MB_LIB.T6G(SCH_1):PAGE103
  J102  266 VSS116 SCONN288_DDR506112002KQ-SCONN288_DDR506112002KQ,SMA   I142 @T6G_MB_LIB.T6G(SCH_1):PAGE103
  J102  268 VSS117 SCONN288_DDR506112002KQ-SCONN288_DDR506112002KQ,SMA   I142 @T6G_MB_LIB.T6G(SCH_1):PAGE103
  J102  270 VSS118 SCONN288_DDR506112002KQ-SCONN288_DDR506112002KQ,SMA   I142 @T6G_MB_LIB.T6G(SCH_1):PAGE103
  J102  273 VSS119 SCONN288_DDR506112002KQ-SCONN288_DDR506112002KQ,SMA   I142 @T6G_MB_LIB.T6G(SCH_1):PAGE103
  J102  275 VSS120 SCONN288_DDR506112002KQ-SCONN288_DDR506112002KQ,SMA   I142 @T6G_MB_LIB.T6G(SCH_1):PAGE103
  J102  277 VSS121 SCONN288_DDR506112002KQ-SCONN288_DDR506112002KQ,SMA   I142 @T6G_MB_LIB.T6G(SCH_1):PAGE103
  J102  279 VSS122 SCONN288_DDR506112002KQ-SCONN288_DDR506112002KQ,SMA   I142 @T6G_MB_LIB.T6G(SCH_1):PAGE103
  J102  281 VSS123 SCONN288_DDR506112002KQ-SCONN288_DDR506112002KQ,SMA   I142 @T6G_MB_LIB.T6G(SCH_1):PAGE103
  J102  284 VSS124 SCONN288_DDR506112002KQ-SCONN288_DDR506112002KQ,SMA   I142 @T6G_MB_LIB.T6G(SCH_1):PAGE103
  J102  286 VSS125 SCONN288_DDR506112002KQ-SCONN288_DDR506112002KQ,SMA   I142 @T6G_MB_LIB.T6G(SCH_1):PAGE103
  J102  288 VSS126 SCONN288_DDR506112002KQ-SCONN288_DDR506112002KQ,SMA   I142 @T6G_MB_LIB.T6G(SCH_1):PAGE103
  C160    2      B Q_CAP_0402-0.1UF,25V,10%,X7R,CH4104K1B00   I185 @T6G_MB_LIB.T6G(SCH_1):PAGE103
  C530    2      B Q_CAP_C0805-10UF,25V,10%,X6S,CH6104KEA00   I240 @T6G_MB_LIB.T6G(SCH_1):PAGE103
  C531    2      B Q_CAP_C0805-10UF,25V,10%,X6S,CH6104KEA00   I241 @T6G_MB_LIB.T6G(SCH_1):PAGE103
  R774    2      B Q_RES_0402LF-15.4K,1%,1/16W,CHIP,CS31542FB02   I128 @T6G_MB_LIB.T6G(SCH_1):PAGE104
   J27   G1     G1 SCONN288_DDR506112002KQ-SCONN288_DDR506112002KQ,SMA   I174 @T6G_MB_LIB.T6G(SCH_1):PAGE104
   J27   G2     G2 SCONN288_DDR506112002KQ-SCONN288_DDR506112002KQ,SMA   I174 @T6G_MB_LIB.T6G(SCH_1):PAGE104
   J27   G3     G3 SCONN288_DDR506112002KQ-SCONN288_DDR506112002KQ,SMA   I174 @T6G_MB_LIB.T6G(SCH_1):PAGE104
   J27    6   VSS0 SCONN288_DDR506112002KQ-SCONN288_DDR506112002KQ,SMA   I174 @T6G_MB_LIB.T6G(SCH_1):PAGE104
   J27    8   VSS1 SCONN288_DDR506112002KQ-SCONN288_DDR506112002KQ,SMA   I174 @T6G_MB_LIB.T6G(SCH_1):PAGE104
   J27   10   VSS2 SCONN288_DDR506112002KQ-SCONN288_DDR506112002KQ,SMA   I174 @T6G_MB_LIB.T6G(SCH_1):PAGE104
   J27   13   VSS3 SCONN288_DDR506112002KQ-SCONN288_DDR506112002KQ,SMA   I174 @T6G_MB_LIB.T6G(SCH_1):PAGE104
   J27   15   VSS4 SCONN288_DDR506112002KQ-SCONN288_DDR506112002KQ,SMA   I174 @T6G_MB_LIB.T6G(SCH_1):PAGE104
   J27   17   VSS5 SCONN288_DDR506112002KQ-SCONN288_DDR506112002KQ,SMA   I174 @T6G_MB_LIB.T6G(SCH_1):PAGE104
   J27   19   VSS6 SCONN288_DDR506112002KQ-SCONN288_DDR506112002KQ,SMA   I174 @T6G_MB_LIB.T6G(SCH_1):PAGE104
   J27   21   VSS7 SCONN288_DDR506112002KQ-SCONN288_DDR506112002KQ,SMA   I174 @T6G_MB_LIB.T6G(SCH_1):PAGE104
   J27   24   VSS8 SCONN288_DDR506112002KQ-SCONN288_DDR506112002KQ,SMA   I174 @T6G_MB_LIB.T6G(SCH_1):PAGE104
   J27   26   VSS9 SCONN288_DDR506112002KQ-SCONN288_DDR506112002KQ,SMA   I174 @T6G_MB_LIB.T6G(SCH_1):PAGE104
   J27   28  VSS10 SCONN288_DDR506112002KQ-SCONN288_DDR506112002KQ,SMA   I174 @T6G_MB_LIB.T6G(SCH_1):PAGE104
   J27   30  VSS11 SCONN288_DDR506112002KQ-SCONN288_DDR506112002KQ,SMA   I174 @T6G_MB_LIB.T6G(SCH_1):PAGE104
   J27   32  VSS12 SCONN288_DDR506112002KQ-SCONN288_DDR506112002KQ,SMA   I174 @T6G_MB_LIB.T6G(SCH_1):PAGE104
   J27   35  VSS13 SCONN288_DDR506112002KQ-SCONN288_DDR506112002KQ,SMA   I174 @T6G_MB_LIB.T6G(SCH_1):PAGE104
   J27   37  VSS14 SCONN288_DDR506112002KQ-SCONN288_DDR506112002KQ,SMA   I174 @T6G_MB_LIB.T6G(SCH_1):PAGE104
   J27   39  VSS15 SCONN288_DDR506112002KQ-SCONN288_DDR506112002KQ,SMA   I174 @T6G_MB_LIB.T6G(SCH_1):PAGE104
   J27   41  VSS16 SCONN288_DDR506112002KQ-SCONN288_DDR506112002KQ,SMA   I174 @T6G_MB_LIB.T6G(SCH_1):PAGE104
   J27   43  VSS17 SCONN288_DDR506112002KQ-SCONN288_DDR506112002KQ,SMA   I174 @T6G_MB_LIB.T6G(SCH_1):PAGE104
   J27   46  VSS18 SCONN288_DDR506112002KQ-SCONN288_DDR506112002KQ,SMA   I174 @T6G_MB_LIB.T6G(SCH_1):PAGE104
   J27   48  VSS19 SCONN288_DDR506112002KQ-SCONN288_DDR506112002KQ,SMA   I174 @T6G_MB_LIB.T6G(SCH_1):PAGE104
   J27   50  VSS20 SCONN288_DDR506112002KQ-SCONN288_DDR506112002KQ,SMA   I174 @T6G_MB_LIB.T6G(SCH_1):PAGE104
   J27   52  VSS21 SCONN288_DDR506112002KQ-SCONN288_DDR506112002KQ,SMA   I174 @T6G_MB_LIB.T6G(SCH_1):PAGE104
   J27   54  VSS22 SCONN288_DDR506112002KQ-SCONN288_DDR506112002KQ,SMA   I174 @T6G_MB_LIB.T6G(SCH_1):PAGE104
   J27   57  VSS23 SCONN288_DDR506112002KQ-SCONN288_DDR506112002KQ,SMA   I174 @T6G_MB_LIB.T6G(SCH_1):PAGE104
   J27   59  VSS24 SCONN288_DDR506112002KQ-SCONN288_DDR506112002KQ,SMA   I174 @T6G_MB_LIB.T6G(SCH_1):PAGE104
   J27   61  VSS25 SCONN288_DDR506112002KQ-SCONN288_DDR506112002KQ,SMA   I174 @T6G_MB_LIB.T6G(SCH_1):PAGE104
   J27   63  VSS26 SCONN288_DDR506112002KQ-SCONN288_DDR506112002KQ,SMA   I174 @T6G_MB_LIB.T6G(SCH_1):PAGE104
   J27   65  VSS27 SCONN288_DDR506112002KQ-SCONN288_DDR506112002KQ,SMA   I174 @T6G_MB_LIB.T6G(SCH_1):PAGE104
   J27   67  VSS28 SCONN288_DDR506112002KQ-SCONN288_DDR506112002KQ,SMA   I174 @T6G_MB_LIB.T6G(SCH_1):PAGE104
   J27   69  VSS29 SCONN288_DDR506112002KQ-SCONN288_DDR506112002KQ,SMA   I174 @T6G_MB_LIB.T6G(SCH_1):PAGE104
   J27   71  VSS30 SCONN288_DDR506112002KQ-SCONN288_DDR506112002KQ,SMA   I174 @T6G_MB_LIB.T6G(SCH_1):PAGE104
   J27   73  VSS31 SCONN288_DDR506112002KQ-SCONN288_DDR506112002KQ,SMA   I174 @T6G_MB_LIB.T6G(SCH_1):PAGE104
   J27   75  VSS32 SCONN288_DDR506112002KQ-SCONN288_DDR506112002KQ,SMA   I174 @T6G_MB_LIB.T6G(SCH_1):PAGE104
   J27   77  VSS33 SCONN288_DDR506112002KQ-SCONN288_DDR506112002KQ,SMA   I174 @T6G_MB_LIB.T6G(SCH_1):PAGE104
   J27   79  VSS34 SCONN288_DDR506112002KQ-SCONN288_DDR506112002KQ,SMA   I174 @T6G_MB_LIB.T6G(SCH_1):PAGE104
   J27   81  VSS35 SCONN288_DDR506112002KQ-SCONN288_DDR506112002KQ,SMA   I174 @T6G_MB_LIB.T6G(SCH_1):PAGE104
   J27   83  VSS36 SCONN288_DDR506112002KQ-SCONN288_DDR506112002KQ,SMA   I174 @T6G_MB_LIB.T6G(SCH_1):PAGE104
   J27   85  VSS37 SCONN288_DDR506112002KQ-SCONN288_DDR506112002KQ,SMA   I174 @T6G_MB_LIB.T6G(SCH_1):PAGE104
   J27   88  VSS38 SCONN288_DDR506112002KQ-SCONN288_DDR506112002KQ,SMA   I174 @T6G_MB_LIB.T6G(SCH_1):PAGE104
   J27   90  VSS39 SCONN288_DDR506112002KQ-SCONN288_DDR506112002KQ,SMA   I174 @T6G_MB_LIB.T6G(SCH_1):PAGE104
   J27   92  VSS40 SCONN288_DDR506112002KQ-SCONN288_DDR506112002KQ,SMA   I174 @T6G_MB_LIB.T6G(SCH_1):PAGE104
   J27   95  VSS41 SCONN288_DDR506112002KQ-SCONN288_DDR506112002KQ,SMA   I174 @T6G_MB_LIB.T6G(SCH_1):PAGE104
   J27   97  VSS42 SCONN288_DDR506112002KQ-SCONN288_DDR506112002KQ,SMA   I174 @T6G_MB_LIB.T6G(SCH_1):PAGE104
   J27   99  VSS43 SCONN288_DDR506112002KQ-SCONN288_DDR506112002KQ,SMA   I174 @T6G_MB_LIB.T6G(SCH_1):PAGE104
   J27  101  VSS44 SCONN288_DDR506112002KQ-SCONN288_DDR506112002KQ,SMA   I174 @T6G_MB_LIB.T6G(SCH_1):PAGE104
   J27  103  VSS45 SCONN288_DDR506112002KQ-SCONN288_DDR506112002KQ,SMA   I174 @T6G_MB_LIB.T6G(SCH_1):PAGE104
   J27  106  VSS46 SCONN288_DDR506112002KQ-SCONN288_DDR506112002KQ,SMA   I174 @T6G_MB_LIB.T6G(SCH_1):PAGE104
   J27  108  VSS47 SCONN288_DDR506112002KQ-SCONN288_DDR506112002KQ,SMA   I174 @T6G_MB_LIB.T6G(SCH_1):PAGE104
   J27  110  VSS48 SCONN288_DDR506112002KQ-SCONN288_DDR506112002KQ,SMA   I174 @T6G_MB_LIB.T6G(SCH_1):PAGE104
   J27  112  VSS49 SCONN288_DDR506112002KQ-SCONN288_DDR506112002KQ,SMA   I174 @T6G_MB_LIB.T6G(SCH_1):PAGE104
   J27  114  VSS50 SCONN288_DDR506112002KQ-SCONN288_DDR506112002KQ,SMA   I174 @T6G_MB_LIB.T6G(SCH_1):PAGE104
   J27  117  VSS51 SCONN288_DDR506112002KQ-SCONN288_DDR506112002KQ,SMA   I174 @T6G_MB_LIB.T6G(SCH_1):PAGE104
   J27  119  VSS52 SCONN288_DDR506112002KQ-SCONN288_DDR506112002KQ,SMA   I174 @T6G_MB_LIB.T6G(SCH_1):PAGE104
   J27  121  VSS53 SCONN288_DDR506112002KQ-SCONN288_DDR506112002KQ,SMA   I174 @T6G_MB_LIB.T6G(SCH_1):PAGE104
   J27  123  VSS54 SCONN288_DDR506112002KQ-SCONN288_DDR506112002KQ,SMA   I174 @T6G_MB_LIB.T6G(SCH_1):PAGE104
   J27  125  VSS55 SCONN288_DDR506112002KQ-SCONN288_DDR506112002KQ,SMA   I174 @T6G_MB_LIB.T6G(SCH_1):PAGE104
   J27  128  VSS56 SCONN288_DDR506112002KQ-SCONN288_DDR506112002KQ,SMA   I174 @T6G_MB_LIB.T6G(SCH_1):PAGE104
   J27  130  VSS57 SCONN288_DDR506112002KQ-SCONN288_DDR506112002KQ,SMA   I174 @T6G_MB_LIB.T6G(SCH_1):PAGE104
   J27  132  VSS58 SCONN288_DDR506112002KQ-SCONN288_DDR506112002KQ,SMA   I174 @T6G_MB_LIB.T6G(SCH_1):PAGE104
   J27  134  VSS59 SCONN288_DDR506112002KQ-SCONN288_DDR506112002KQ,SMA   I174 @T6G_MB_LIB.T6G(SCH_1):PAGE104
   J27  136  VSS60 SCONN288_DDR506112002KQ-SCONN288_DDR506112002KQ,SMA   I174 @T6G_MB_LIB.T6G(SCH_1):PAGE104
   J27  139  VSS61 SCONN288_DDR506112002KQ-SCONN288_DDR506112002KQ,SMA   I174 @T6G_MB_LIB.T6G(SCH_1):PAGE104
   J27  141  VSS62 SCONN288_DDR506112002KQ-SCONN288_DDR506112002KQ,SMA   I174 @T6G_MB_LIB.T6G(SCH_1):PAGE104
   J27  143  VSS63 SCONN288_DDR506112002KQ-SCONN288_DDR506112002KQ,SMA   I174 @T6G_MB_LIB.T6G(SCH_1):PAGE104
   J27  151  VSS64 SCONN288_DDR506112002KQ-SCONN288_DDR506112002KQ,SMA   I174 @T6G_MB_LIB.T6G(SCH_1):PAGE104
   J27  153  VSS65 SCONN288_DDR506112002KQ-SCONN288_DDR506112002KQ,SMA   I174 @T6G_MB_LIB.T6G(SCH_1):PAGE104
   J27  155  VSS66 SCONN288_DDR506112002KQ-SCONN288_DDR506112002KQ,SMA   I174 @T6G_MB_LIB.T6G(SCH_1):PAGE104
   J27  158  VSS67 SCONN288_DDR506112002KQ-SCONN288_DDR506112002KQ,SMA   I174 @T6G_MB_LIB.T6G(SCH_1):PAGE104
   J27  160  VSS68 SCONN288_DDR506112002KQ-SCONN288_DDR506112002KQ,SMA   I174 @T6G_MB_LIB.T6G(SCH_1):PAGE104
   J27  162  VSS69 SCONN288_DDR506112002KQ-SCONN288_DDR506112002KQ,SMA   I174 @T6G_MB_LIB.T6G(SCH_1):PAGE104
   J27  164  VSS70 SCONN288_DDR506112002KQ-SCONN288_DDR506112002KQ,SMA   I174 @T6G_MB_LIB.T6G(SCH_1):PAGE104
   J27  166  VSS71 SCONN288_DDR506112002KQ-SCONN288_DDR506112002KQ,SMA   I174 @T6G_MB_LIB.T6G(SCH_1):PAGE104
   J27  169  VSS72 SCONN288_DDR506112002KQ-SCONN288_DDR506112002KQ,SMA   I174 @T6G_MB_LIB.T6G(SCH_1):PAGE104
   J27  171  VSS73 SCONN288_DDR506112002KQ-SCONN288_DDR506112002KQ,SMA   I174 @T6G_MB_LIB.T6G(SCH_1):PAGE104
   J27  173  VSS74 SCONN288_DDR506112002KQ-SCONN288_DDR506112002KQ,SMA   I174 @T6G_MB_LIB.T6G(SCH_1):PAGE104
   J27  175  VSS75 SCONN288_DDR506112002KQ-SCONN288_DDR506112002KQ,SMA   I174 @T6G_MB_LIB.T6G(SCH_1):PAGE104
   J27  177  VSS76 SCONN288_DDR506112002KQ-SCONN288_DDR506112002KQ,SMA   I174 @T6G_MB_LIB.T6G(SCH_1):PAGE104
   J27  180  VSS77 SCONN288_DDR506112002KQ-SCONN288_DDR506112002KQ,SMA   I174 @T6G_MB_LIB.T6G(SCH_1):PAGE104
   J27  182  VSS78 SCONN288_DDR506112002KQ-SCONN288_DDR506112002KQ,SMA   I174 @T6G_MB_LIB.T6G(SCH_1):PAGE104
   J27  184  VSS79 SCONN288_DDR506112002KQ-SCONN288_DDR506112002KQ,SMA   I174 @T6G_MB_LIB.T6G(SCH_1):PAGE104
   J27  186  VSS80 SCONN288_DDR506112002KQ-SCONN288_DDR506112002KQ,SMA   I174 @T6G_MB_LIB.T6G(SCH_1):PAGE104
   J27  188  VSS81 SCONN288_DDR506112002KQ-SCONN288_DDR506112002KQ,SMA   I174 @T6G_MB_LIB.T6G(SCH_1):PAGE104
   J27  191  VSS82 SCONN288_DDR506112002KQ-SCONN288_DDR506112002KQ,SMA   I174 @T6G_MB_LIB.T6G(SCH_1):PAGE104
   J27  193  VSS83 SCONN288_DDR506112002KQ-SCONN288_DDR506112002KQ,SMA   I174 @T6G_MB_LIB.T6G(SCH_1):PAGE104
   J27  195  VSS84 SCONN288_DDR506112002KQ-SCONN288_DDR506112002KQ,SMA   I174 @T6G_MB_LIB.T6G(SCH_1):PAGE104
   J27  197  VSS85 SCONN288_DDR506112002KQ-SCONN288_DDR506112002KQ,SMA   I174 @T6G_MB_LIB.T6G(SCH_1):PAGE104
   J27  199  VSS86 SCONN288_DDR506112002KQ-SCONN288_DDR506112002KQ,SMA   I174 @T6G_MB_LIB.T6G(SCH_1):PAGE104
   J27  202  VSS87 SCONN288_DDR506112002KQ-SCONN288_DDR506112002KQ,SMA   I174 @T6G_MB_LIB.T6G(SCH_1):PAGE104
   J27  204  VSS88 SCONN288_DDR506112002KQ-SCONN288_DDR506112002KQ,SMA   I174 @T6G_MB_LIB.T6G(SCH_1):PAGE104
   J27  206  VSS89 SCONN288_DDR506112002KQ-SCONN288_DDR506112002KQ,SMA   I174 @T6G_MB_LIB.T6G(SCH_1):PAGE104
   J27  208  VSS90 SCONN288_DDR506112002KQ-SCONN288_DDR506112002KQ,SMA   I174 @T6G_MB_LIB.T6G(SCH_1):PAGE104
   J27  210  VSS91 SCONN288_DDR506112002KQ-SCONN288_DDR506112002KQ,SMA   I174 @T6G_MB_LIB.T6G(SCH_1):PAGE104
   J27  212  VSS92 SCONN288_DDR506112002KQ-SCONN288_DDR506112002KQ,SMA   I174 @T6G_MB_LIB.T6G(SCH_1):PAGE104
   J27  214  VSS93 SCONN288_DDR506112002KQ-SCONN288_DDR506112002KQ,SMA   I174 @T6G_MB_LIB.T6G(SCH_1):PAGE104
   J27  216  VSS94 SCONN288_DDR506112002KQ-SCONN288_DDR506112002KQ,SMA   I174 @T6G_MB_LIB.T6G(SCH_1):PAGE104
   J27  219  VSS95 SCONN288_DDR506112002KQ-SCONN288_DDR506112002KQ,SMA   I174 @T6G_MB_LIB.T6G(SCH_1):PAGE104
   J27  222  VSS96 SCONN288_DDR506112002KQ-SCONN288_DDR506112002KQ,SMA   I174 @T6G_MB_LIB.T6G(SCH_1):PAGE104
   J27  224  VSS97 SCONN288_DDR506112002KQ-SCONN288_DDR506112002KQ,SMA   I174 @T6G_MB_LIB.T6G(SCH_1):PAGE104
   J27  226  VSS98 SCONN288_DDR506112002KQ-SCONN288_DDR506112002KQ,SMA   I174 @T6G_MB_LIB.T6G(SCH_1):PAGE104
   J27  228  VSS99 SCONN288_DDR506112002KQ-SCONN288_DDR506112002KQ,SMA   I174 @T6G_MB_LIB.T6G(SCH_1):PAGE104
   J27  230 VSS100 SCONN288_DDR506112002KQ-SCONN288_DDR506112002KQ,SMA   I174 @T6G_MB_LIB.T6G(SCH_1):PAGE104
   J27  233 VSS101 SCONN288_DDR506112002KQ-SCONN288_DDR506112002KQ,SMA   I174 @T6G_MB_LIB.T6G(SCH_1):PAGE104
   J27  235 VSS102 SCONN288_DDR506112002KQ-SCONN288_DDR506112002KQ,SMA   I174 @T6G_MB_LIB.T6G(SCH_1):PAGE104
   J27  237 VSS103 SCONN288_DDR506112002KQ-SCONN288_DDR506112002KQ,SMA   I174 @T6G_MB_LIB.T6G(SCH_1):PAGE104
   J27  240 VSS104 SCONN288_DDR506112002KQ-SCONN288_DDR506112002KQ,SMA   I174 @T6G_MB_LIB.T6G(SCH_1):PAGE104
   J27  242 VSS105 SCONN288_DDR506112002KQ-SCONN288_DDR506112002KQ,SMA   I174 @T6G_MB_LIB.T6G(SCH_1):PAGE104
   J27  244 VSS106 SCONN288_DDR506112002KQ-SCONN288_DDR506112002KQ,SMA   I174 @T6G_MB_LIB.T6G(SCH_1):PAGE104
   J27  246 VSS107 SCONN288_DDR506112002KQ-SCONN288_DDR506112002KQ,SMA   I174 @T6G_MB_LIB.T6G(SCH_1):PAGE104
   J27  248 VSS108 SCONN288_DDR506112002KQ-SCONN288_DDR506112002KQ,SMA   I174 @T6G_MB_LIB.T6G(SCH_1):PAGE104
   J27  251 VSS109 SCONN288_DDR506112002KQ-SCONN288_DDR506112002KQ,SMA   I174 @T6G_MB_LIB.T6G(SCH_1):PAGE104
   J27  253 VSS110 SCONN288_DDR506112002KQ-SCONN288_DDR506112002KQ,SMA   I174 @T6G_MB_LIB.T6G(SCH_1):PAGE104
   J27  255 VSS111 SCONN288_DDR506112002KQ-SCONN288_DDR506112002KQ,SMA   I174 @T6G_MB_LIB.T6G(SCH_1):PAGE104
   J27  257 VSS112 SCONN288_DDR506112002KQ-SCONN288_DDR506112002KQ,SMA   I174 @T6G_MB_LIB.T6G(SCH_1):PAGE104
   J27  259 VSS113 SCONN288_DDR506112002KQ-SCONN288_DDR506112002KQ,SMA   I174 @T6G_MB_LIB.T6G(SCH_1):PAGE104
   J27  262 VSS114 SCONN288_DDR506112002KQ-SCONN288_DDR506112002KQ,SMA   I174 @T6G_MB_LIB.T6G(SCH_1):PAGE104
   J27  264 VSS115 SCONN288_DDR506112002KQ-SCONN288_DDR506112002KQ,SMA   I174 @T6G_MB_LIB.T6G(SCH_1):PAGE104
   J27  266 VSS116 SCONN288_DDR506112002KQ-SCONN288_DDR506112002KQ,SMA   I174 @T6G_MB_LIB.T6G(SCH_1):PAGE104
   J27  268 VSS117 SCONN288_DDR506112002KQ-SCONN288_DDR506112002KQ,SMA   I174 @T6G_MB_LIB.T6G(SCH_1):PAGE104
   J27  270 VSS118 SCONN288_DDR506112002KQ-SCONN288_DDR506112002KQ,SMA   I174 @T6G_MB_LIB.T6G(SCH_1):PAGE104
   J27  273 VSS119 SCONN288_DDR506112002KQ-SCONN288_DDR506112002KQ,SMA   I174 @T6G_MB_LIB.T6G(SCH_1):PAGE104
   J27  275 VSS120 SCONN288_DDR506112002KQ-SCONN288_DDR506112002KQ,SMA   I174 @T6G_MB_LIB.T6G(SCH_1):PAGE104
   J27  277 VSS121 SCONN288_DDR506112002KQ-SCONN288_DDR506112002KQ,SMA   I174 @T6G_MB_LIB.T6G(SCH_1):PAGE104
   J27  279 VSS122 SCONN288_DDR506112002KQ-SCONN288_DDR506112002KQ,SMA   I174 @T6G_MB_LIB.T6G(SCH_1):PAGE104
   J27  281 VSS123 SCONN288_DDR506112002KQ-SCONN288_DDR506112002KQ,SMA   I174 @T6G_MB_LIB.T6G(SCH_1):PAGE104
   J27  284 VSS124 SCONN288_DDR506112002KQ-SCONN288_DDR506112002KQ,SMA   I174 @T6G_MB_LIB.T6G(SCH_1):PAGE104
   J27  286 VSS125 SCONN288_DDR506112002KQ-SCONN288_DDR506112002KQ,SMA   I174 @T6G_MB_LIB.T6G(SCH_1):PAGE104
   J27  288 VSS126 SCONN288_DDR506112002KQ-SCONN288_DDR506112002KQ,SMA   I174 @T6G_MB_LIB.T6G(SCH_1):PAGE104
  C164    2      B Q_CAP_0402-0.1UF,25V,10%,X7R,CH4104K1B00   I185 @T6G_MB_LIB.T6G(SCH_1):PAGE104
  C532    2      B Q_CAP_C0805-10UF,25V,10%,X6S,CH6104KEA00   I240 @T6G_MB_LIB.T6G(SCH_1):PAGE104
  C533    2      B Q_CAP_C0805-10UF,25V,10%,X6S,CH6104KEA00   I241 @T6G_MB_LIB.T6G(SCH_1):PAGE104
  R775    2      B Q_RES_0402LF-23.2K,1%,1/16W,CHIP,CS32322FB03   I128 @T6G_MB_LIB.T6G(SCH_1):PAGE105
  J100   G1     G1 SCONN288_DDR506112002KQ-SCONN288_DDR506112002KQ,SMA   I176 @T6G_MB_LIB.T6G(SCH_1):PAGE105
  J100   G2     G2 SCONN288_DDR506112002KQ-SCONN288_DDR506112002KQ,SMA   I176 @T6G_MB_LIB.T6G(SCH_1):PAGE105
  J100   G3     G3 SCONN288_DDR506112002KQ-SCONN288_DDR506112002KQ,SMA   I176 @T6G_MB_LIB.T6G(SCH_1):PAGE105
  J100    6   VSS0 SCONN288_DDR506112002KQ-SCONN288_DDR506112002KQ,SMA   I176 @T6G_MB_LIB.T6G(SCH_1):PAGE105
  J100    8   VSS1 SCONN288_DDR506112002KQ-SCONN288_DDR506112002KQ,SMA   I176 @T6G_MB_LIB.T6G(SCH_1):PAGE105
  J100   10   VSS2 SCONN288_DDR506112002KQ-SCONN288_DDR506112002KQ,SMA   I176 @T6G_MB_LIB.T6G(SCH_1):PAGE105
  J100   13   VSS3 SCONN288_DDR506112002KQ-SCONN288_DDR506112002KQ,SMA   I176 @T6G_MB_LIB.T6G(SCH_1):PAGE105
  J100   15   VSS4 SCONN288_DDR506112002KQ-SCONN288_DDR506112002KQ,SMA   I176 @T6G_MB_LIB.T6G(SCH_1):PAGE105
  J100   17   VSS5 SCONN288_DDR506112002KQ-SCONN288_DDR506112002KQ,SMA   I176 @T6G_MB_LIB.T6G(SCH_1):PAGE105
  J100   19   VSS6 SCONN288_DDR506112002KQ-SCONN288_DDR506112002KQ,SMA   I176 @T6G_MB_LIB.T6G(SCH_1):PAGE105
  J100   21   VSS7 SCONN288_DDR506112002KQ-SCONN288_DDR506112002KQ,SMA   I176 @T6G_MB_LIB.T6G(SCH_1):PAGE105
  J100   24   VSS8 SCONN288_DDR506112002KQ-SCONN288_DDR506112002KQ,SMA   I176 @T6G_MB_LIB.T6G(SCH_1):PAGE105
  J100   26   VSS9 SCONN288_DDR506112002KQ-SCONN288_DDR506112002KQ,SMA   I176 @T6G_MB_LIB.T6G(SCH_1):PAGE105
  J100   28  VSS10 SCONN288_DDR506112002KQ-SCONN288_DDR506112002KQ,SMA   I176 @T6G_MB_LIB.T6G(SCH_1):PAGE105
  J100   30  VSS11 SCONN288_DDR506112002KQ-SCONN288_DDR506112002KQ,SMA   I176 @T6G_MB_LIB.T6G(SCH_1):PAGE105
  J100   32  VSS12 SCONN288_DDR506112002KQ-SCONN288_DDR506112002KQ,SMA   I176 @T6G_MB_LIB.T6G(SCH_1):PAGE105
  J100   35  VSS13 SCONN288_DDR506112002KQ-SCONN288_DDR506112002KQ,SMA   I176 @T6G_MB_LIB.T6G(SCH_1):PAGE105
  J100   37  VSS14 SCONN288_DDR506112002KQ-SCONN288_DDR506112002KQ,SMA   I176 @T6G_MB_LIB.T6G(SCH_1):PAGE105
  J100   39  VSS15 SCONN288_DDR506112002KQ-SCONN288_DDR506112002KQ,SMA   I176 @T6G_MB_LIB.T6G(SCH_1):PAGE105
  J100   41  VSS16 SCONN288_DDR506112002KQ-SCONN288_DDR506112002KQ,SMA   I176 @T6G_MB_LIB.T6G(SCH_1):PAGE105
  J100   43  VSS17 SCONN288_DDR506112002KQ-SCONN288_DDR506112002KQ,SMA   I176 @T6G_MB_LIB.T6G(SCH_1):PAGE105
  J100   46  VSS18 SCONN288_DDR506112002KQ-SCONN288_DDR506112002KQ,SMA   I176 @T6G_MB_LIB.T6G(SCH_1):PAGE105
  J100   48  VSS19 SCONN288_DDR506112002KQ-SCONN288_DDR506112002KQ,SMA   I176 @T6G_MB_LIB.T6G(SCH_1):PAGE105
  J100   50  VSS20 SCONN288_DDR506112002KQ-SCONN288_DDR506112002KQ,SMA   I176 @T6G_MB_LIB.T6G(SCH_1):PAGE105
  J100   52  VSS21 SCONN288_DDR506112002KQ-SCONN288_DDR506112002KQ,SMA   I176 @T6G_MB_LIB.T6G(SCH_1):PAGE105
  J100   54  VSS22 SCONN288_DDR506112002KQ-SCONN288_DDR506112002KQ,SMA   I176 @T6G_MB_LIB.T6G(SCH_1):PAGE105
  J100   57  VSS23 SCONN288_DDR506112002KQ-SCONN288_DDR506112002KQ,SMA   I176 @T6G_MB_LIB.T6G(SCH_1):PAGE105
  J100   59  VSS24 SCONN288_DDR506112002KQ-SCONN288_DDR506112002KQ,SMA   I176 @T6G_MB_LIB.T6G(SCH_1):PAGE105
  J100   61  VSS25 SCONN288_DDR506112002KQ-SCONN288_DDR506112002KQ,SMA   I176 @T6G_MB_LIB.T6G(SCH_1):PAGE105
  J100   63  VSS26 SCONN288_DDR506112002KQ-SCONN288_DDR506112002KQ,SMA   I176 @T6G_MB_LIB.T6G(SCH_1):PAGE105
  J100   65  VSS27 SCONN288_DDR506112002KQ-SCONN288_DDR506112002KQ,SMA   I176 @T6G_MB_LIB.T6G(SCH_1):PAGE105
  J100   67  VSS28 SCONN288_DDR506112002KQ-SCONN288_DDR506112002KQ,SMA   I176 @T6G_MB_LIB.T6G(SCH_1):PAGE105
  J100   69  VSS29 SCONN288_DDR506112002KQ-SCONN288_DDR506112002KQ,SMA   I176 @T6G_MB_LIB.T6G(SCH_1):PAGE105
  J100   71  VSS30 SCONN288_DDR506112002KQ-SCONN288_DDR506112002KQ,SMA   I176 @T6G_MB_LIB.T6G(SCH_1):PAGE105
  J100   73  VSS31 SCONN288_DDR506112002KQ-SCONN288_DDR506112002KQ,SMA   I176 @T6G_MB_LIB.T6G(SCH_1):PAGE105
  J100   75  VSS32 SCONN288_DDR506112002KQ-SCONN288_DDR506112002KQ,SMA   I176 @T6G_MB_LIB.T6G(SCH_1):PAGE105
  J100   77  VSS33 SCONN288_DDR506112002KQ-SCONN288_DDR506112002KQ,SMA   I176 @T6G_MB_LIB.T6G(SCH_1):PAGE105
  J100   79  VSS34 SCONN288_DDR506112002KQ-SCONN288_DDR506112002KQ,SMA   I176 @T6G_MB_LIB.T6G(SCH_1):PAGE105
  J100   81  VSS35 SCONN288_DDR506112002KQ-SCONN288_DDR506112002KQ,SMA   I176 @T6G_MB_LIB.T6G(SCH_1):PAGE105
  J100   83  VSS36 SCONN288_DDR506112002KQ-SCONN288_DDR506112002KQ,SMA   I176 @T6G_MB_LIB.T6G(SCH_1):PAGE105
  J100   85  VSS37 SCONN288_DDR506112002KQ-SCONN288_DDR506112002KQ,SMA   I176 @T6G_MB_LIB.T6G(SCH_1):PAGE105
  J100   88  VSS38 SCONN288_DDR506112002KQ-SCONN288_DDR506112002KQ,SMA   I176 @T6G_MB_LIB.T6G(SCH_1):PAGE105
  J100   90  VSS39 SCONN288_DDR506112002KQ-SCONN288_DDR506112002KQ,SMA   I176 @T6G_MB_LIB.T6G(SCH_1):PAGE105
  J100   92  VSS40 SCONN288_DDR506112002KQ-SCONN288_DDR506112002KQ,SMA   I176 @T6G_MB_LIB.T6G(SCH_1):PAGE105
  J100   95  VSS41 SCONN288_DDR506112002KQ-SCONN288_DDR506112002KQ,SMA   I176 @T6G_MB_LIB.T6G(SCH_1):PAGE105
  J100   97  VSS42 SCONN288_DDR506112002KQ-SCONN288_DDR506112002KQ,SMA   I176 @T6G_MB_LIB.T6G(SCH_1):PAGE105
  J100   99  VSS43 SCONN288_DDR506112002KQ-SCONN288_DDR506112002KQ,SMA   I176 @T6G_MB_LIB.T6G(SCH_1):PAGE105
  J100  101  VSS44 SCONN288_DDR506112002KQ-SCONN288_DDR506112002KQ,SMA   I176 @T6G_MB_LIB.T6G(SCH_1):PAGE105
  J100  103  VSS45 SCONN288_DDR506112002KQ-SCONN288_DDR506112002KQ,SMA   I176 @T6G_MB_LIB.T6G(SCH_1):PAGE105
  J100  106  VSS46 SCONN288_DDR506112002KQ-SCONN288_DDR506112002KQ,SMA   I176 @T6G_MB_LIB.T6G(SCH_1):PAGE105
  J100  108  VSS47 SCONN288_DDR506112002KQ-SCONN288_DDR506112002KQ,SMA   I176 @T6G_MB_LIB.T6G(SCH_1):PAGE105
  J100  110  VSS48 SCONN288_DDR506112002KQ-SCONN288_DDR506112002KQ,SMA   I176 @T6G_MB_LIB.T6G(SCH_1):PAGE105
  J100  112  VSS49 SCONN288_DDR506112002KQ-SCONN288_DDR506112002KQ,SMA   I176 @T6G_MB_LIB.T6G(SCH_1):PAGE105
  J100  114  VSS50 SCONN288_DDR506112002KQ-SCONN288_DDR506112002KQ,SMA   I176 @T6G_MB_LIB.T6G(SCH_1):PAGE105
  J100  117  VSS51 SCONN288_DDR506112002KQ-SCONN288_DDR506112002KQ,SMA   I176 @T6G_MB_LIB.T6G(SCH_1):PAGE105
  J100  119  VSS52 SCONN288_DDR506112002KQ-SCONN288_DDR506112002KQ,SMA   I176 @T6G_MB_LIB.T6G(SCH_1):PAGE105
  J100  121  VSS53 SCONN288_DDR506112002KQ-SCONN288_DDR506112002KQ,SMA   I176 @T6G_MB_LIB.T6G(SCH_1):PAGE105
  J100  123  VSS54 SCONN288_DDR506112002KQ-SCONN288_DDR506112002KQ,SMA   I176 @T6G_MB_LIB.T6G(SCH_1):PAGE105
  J100  125  VSS55 SCONN288_DDR506112002KQ-SCONN288_DDR506112002KQ,SMA   I176 @T6G_MB_LIB.T6G(SCH_1):PAGE105
  J100  128  VSS56 SCONN288_DDR506112002KQ-SCONN288_DDR506112002KQ,SMA   I176 @T6G_MB_LIB.T6G(SCH_1):PAGE105
  J100  130  VSS57 SCONN288_DDR506112002KQ-SCONN288_DDR506112002KQ,SMA   I176 @T6G_MB_LIB.T6G(SCH_1):PAGE105
  J100  132  VSS58 SCONN288_DDR506112002KQ-SCONN288_DDR506112002KQ,SMA   I176 @T6G_MB_LIB.T6G(SCH_1):PAGE105
  J100  134  VSS59 SCONN288_DDR506112002KQ-SCONN288_DDR506112002KQ,SMA   I176 @T6G_MB_LIB.T6G(SCH_1):PAGE105
  J100  136  VSS60 SCONN288_DDR506112002KQ-SCONN288_DDR506112002KQ,SMA   I176 @T6G_MB_LIB.T6G(SCH_1):PAGE105
  J100  139  VSS61 SCONN288_DDR506112002KQ-SCONN288_DDR506112002KQ,SMA   I176 @T6G_MB_LIB.T6G(SCH_1):PAGE105
  J100  141  VSS62 SCONN288_DDR506112002KQ-SCONN288_DDR506112002KQ,SMA   I176 @T6G_MB_LIB.T6G(SCH_1):PAGE105
  J100  143  VSS63 SCONN288_DDR506112002KQ-SCONN288_DDR506112002KQ,SMA   I176 @T6G_MB_LIB.T6G(SCH_1):PAGE105
  J100  151  VSS64 SCONN288_DDR506112002KQ-SCONN288_DDR506112002KQ,SMA   I176 @T6G_MB_LIB.T6G(SCH_1):PAGE105
  J100  153  VSS65 SCONN288_DDR506112002KQ-SCONN288_DDR506112002KQ,SMA   I176 @T6G_MB_LIB.T6G(SCH_1):PAGE105
  J100  155  VSS66 SCONN288_DDR506112002KQ-SCONN288_DDR506112002KQ,SMA   I176 @T6G_MB_LIB.T6G(SCH_1):PAGE105
  J100  158  VSS67 SCONN288_DDR506112002KQ-SCONN288_DDR506112002KQ,SMA   I176 @T6G_MB_LIB.T6G(SCH_1):PAGE105
  J100  160  VSS68 SCONN288_DDR506112002KQ-SCONN288_DDR506112002KQ,SMA   I176 @T6G_MB_LIB.T6G(SCH_1):PAGE105
  J100  162  VSS69 SCONN288_DDR506112002KQ-SCONN288_DDR506112002KQ,SMA   I176 @T6G_MB_LIB.T6G(SCH_1):PAGE105
  J100  164  VSS70 SCONN288_DDR506112002KQ-SCONN288_DDR506112002KQ,SMA   I176 @T6G_MB_LIB.T6G(SCH_1):PAGE105
  J100  166  VSS71 SCONN288_DDR506112002KQ-SCONN288_DDR506112002KQ,SMA   I176 @T6G_MB_LIB.T6G(SCH_1):PAGE105
  J100  169  VSS72 SCONN288_DDR506112002KQ-SCONN288_DDR506112002KQ,SMA   I176 @T6G_MB_LIB.T6G(SCH_1):PAGE105
  J100  171  VSS73 SCONN288_DDR506112002KQ-SCONN288_DDR506112002KQ,SMA   I176 @T6G_MB_LIB.T6G(SCH_1):PAGE105
  J100  173  VSS74 SCONN288_DDR506112002KQ-SCONN288_DDR506112002KQ,SMA   I176 @T6G_MB_LIB.T6G(SCH_1):PAGE105
  J100  175  VSS75 SCONN288_DDR506112002KQ-SCONN288_DDR506112002KQ,SMA   I176 @T6G_MB_LIB.T6G(SCH_1):PAGE105
  J100  177  VSS76 SCONN288_DDR506112002KQ-SCONN288_DDR506112002KQ,SMA   I176 @T6G_MB_LIB.T6G(SCH_1):PAGE105
  J100  180  VSS77 SCONN288_DDR506112002KQ-SCONN288_DDR506112002KQ,SMA   I176 @T6G_MB_LIB.T6G(SCH_1):PAGE105
  J100  182  VSS78 SCONN288_DDR506112002KQ-SCONN288_DDR506112002KQ,SMA   I176 @T6G_MB_LIB.T6G(SCH_1):PAGE105
  J100  184  VSS79 SCONN288_DDR506112002KQ-SCONN288_DDR506112002KQ,SMA   I176 @T6G_MB_LIB.T6G(SCH_1):PAGE105
  J100  186  VSS80 SCONN288_DDR506112002KQ-SCONN288_DDR506112002KQ,SMA   I176 @T6G_MB_LIB.T6G(SCH_1):PAGE105
  J100  188  VSS81 SCONN288_DDR506112002KQ-SCONN288_DDR506112002KQ,SMA   I176 @T6G_MB_LIB.T6G(SCH_1):PAGE105
  J100  191  VSS82 SCONN288_DDR506112002KQ-SCONN288_DDR506112002KQ,SMA   I176 @T6G_MB_LIB.T6G(SCH_1):PAGE105
  J100  193  VSS83 SCONN288_DDR506112002KQ-SCONN288_DDR506112002KQ,SMA   I176 @T6G_MB_LIB.T6G(SCH_1):PAGE105
  J100  195  VSS84 SCONN288_DDR506112002KQ-SCONN288_DDR506112002KQ,SMA   I176 @T6G_MB_LIB.T6G(SCH_1):PAGE105
  J100  197  VSS85 SCONN288_DDR506112002KQ-SCONN288_DDR506112002KQ,SMA   I176 @T6G_MB_LIB.T6G(SCH_1):PAGE105
  J100  199  VSS86 SCONN288_DDR506112002KQ-SCONN288_DDR506112002KQ,SMA   I176 @T6G_MB_LIB.T6G(SCH_1):PAGE105
  J100  202  VSS87 SCONN288_DDR506112002KQ-SCONN288_DDR506112002KQ,SMA   I176 @T6G_MB_LIB.T6G(SCH_1):PAGE105
  J100  204  VSS88 SCONN288_DDR506112002KQ-SCONN288_DDR506112002KQ,SMA   I176 @T6G_MB_LIB.T6G(SCH_1):PAGE105
  J100  206  VSS89 SCONN288_DDR506112002KQ-SCONN288_DDR506112002KQ,SMA   I176 @T6G_MB_LIB.T6G(SCH_1):PAGE105
  J100  208  VSS90 SCONN288_DDR506112002KQ-SCONN288_DDR506112002KQ,SMA   I176 @T6G_MB_LIB.T6G(SCH_1):PAGE105
  J100  210  VSS91 SCONN288_DDR506112002KQ-SCONN288_DDR506112002KQ,SMA   I176 @T6G_MB_LIB.T6G(SCH_1):PAGE105
  J100  212  VSS92 SCONN288_DDR506112002KQ-SCONN288_DDR506112002KQ,SMA   I176 @T6G_MB_LIB.T6G(SCH_1):PAGE105
  J100  214  VSS93 SCONN288_DDR506112002KQ-SCONN288_DDR506112002KQ,SMA   I176 @T6G_MB_LIB.T6G(SCH_1):PAGE105
  J100  216  VSS94 SCONN288_DDR506112002KQ-SCONN288_DDR506112002KQ,SMA   I176 @T6G_MB_LIB.T6G(SCH_1):PAGE105
  J100  219  VSS95 SCONN288_DDR506112002KQ-SCONN288_DDR506112002KQ,SMA   I176 @T6G_MB_LIB.T6G(SCH_1):PAGE105
  J100  222  VSS96 SCONN288_DDR506112002KQ-SCONN288_DDR506112002KQ,SMA   I176 @T6G_MB_LIB.T6G(SCH_1):PAGE105
  J100  224  VSS97 SCONN288_DDR506112002KQ-SCONN288_DDR506112002KQ,SMA   I176 @T6G_MB_LIB.T6G(SCH_1):PAGE105
  J100  226  VSS98 SCONN288_DDR506112002KQ-SCONN288_DDR506112002KQ,SMA   I176 @T6G_MB_LIB.T6G(SCH_1):PAGE105
  J100  228  VSS99 SCONN288_DDR506112002KQ-SCONN288_DDR506112002KQ,SMA   I176 @T6G_MB_LIB.T6G(SCH_1):PAGE105
  J100  230 VSS100 SCONN288_DDR506112002KQ-SCONN288_DDR506112002KQ,SMA   I176 @T6G_MB_LIB.T6G(SCH_1):PAGE105
  J100  233 VSS101 SCONN288_DDR506112002KQ-SCONN288_DDR506112002KQ,SMA   I176 @T6G_MB_LIB.T6G(SCH_1):PAGE105
  J100  235 VSS102 SCONN288_DDR506112002KQ-SCONN288_DDR506112002KQ,SMA   I176 @T6G_MB_LIB.T6G(SCH_1):PAGE105
  J100  237 VSS103 SCONN288_DDR506112002KQ-SCONN288_DDR506112002KQ,SMA   I176 @T6G_MB_LIB.T6G(SCH_1):PAGE105
  J100  240 VSS104 SCONN288_DDR506112002KQ-SCONN288_DDR506112002KQ,SMA   I176 @T6G_MB_LIB.T6G(SCH_1):PAGE105
  J100  242 VSS105 SCONN288_DDR506112002KQ-SCONN288_DDR506112002KQ,SMA   I176 @T6G_MB_LIB.T6G(SCH_1):PAGE105
  J100  244 VSS106 SCONN288_DDR506112002KQ-SCONN288_DDR506112002KQ,SMA   I176 @T6G_MB_LIB.T6G(SCH_1):PAGE105
  J100  246 VSS107 SCONN288_DDR506112002KQ-SCONN288_DDR506112002KQ,SMA   I176 @T6G_MB_LIB.T6G(SCH_1):PAGE105
  J100  248 VSS108 SCONN288_DDR506112002KQ-SCONN288_DDR506112002KQ,SMA   I176 @T6G_MB_LIB.T6G(SCH_1):PAGE105
  J100  251 VSS109 SCONN288_DDR506112002KQ-SCONN288_DDR506112002KQ,SMA   I176 @T6G_MB_LIB.T6G(SCH_1):PAGE105
  J100  253 VSS110 SCONN288_DDR506112002KQ-SCONN288_DDR506112002KQ,SMA   I176 @T6G_MB_LIB.T6G(SCH_1):PAGE105
  J100  255 VSS111 SCONN288_DDR506112002KQ-SCONN288_DDR506112002KQ,SMA   I176 @T6G_MB_LIB.T6G(SCH_1):PAGE105
  J100  257 VSS112 SCONN288_DDR506112002KQ-SCONN288_DDR506112002KQ,SMA   I176 @T6G_MB_LIB.T6G(SCH_1):PAGE105
  J100  259 VSS113 SCONN288_DDR506112002KQ-SCONN288_DDR506112002KQ,SMA   I176 @T6G_MB_LIB.T6G(SCH_1):PAGE105
  J100  262 VSS114 SCONN288_DDR506112002KQ-SCONN288_DDR506112002KQ,SMA   I176 @T6G_MB_LIB.T6G(SCH_1):PAGE105
  J100  264 VSS115 SCONN288_DDR506112002KQ-SCONN288_DDR506112002KQ,SMA   I176 @T6G_MB_LIB.T6G(SCH_1):PAGE105
  J100  266 VSS116 SCONN288_DDR506112002KQ-SCONN288_DDR506112002KQ,SMA   I176 @T6G_MB_LIB.T6G(SCH_1):PAGE105
  J100  268 VSS117 SCONN288_DDR506112002KQ-SCONN288_DDR506112002KQ,SMA   I176 @T6G_MB_LIB.T6G(SCH_1):PAGE105
  J100  270 VSS118 SCONN288_DDR506112002KQ-SCONN288_DDR506112002KQ,SMA   I176 @T6G_MB_LIB.T6G(SCH_1):PAGE105
  J100  273 VSS119 SCONN288_DDR506112002KQ-SCONN288_DDR506112002KQ,SMA   I176 @T6G_MB_LIB.T6G(SCH_1):PAGE105
  J100  275 VSS120 SCONN288_DDR506112002KQ-SCONN288_DDR506112002KQ,SMA   I176 @T6G_MB_LIB.T6G(SCH_1):PAGE105
  J100  277 VSS121 SCONN288_DDR506112002KQ-SCONN288_DDR506112002KQ,SMA   I176 @T6G_MB_LIB.T6G(SCH_1):PAGE105
  J100  279 VSS122 SCONN288_DDR506112002KQ-SCONN288_DDR506112002KQ,SMA   I176 @T6G_MB_LIB.T6G(SCH_1):PAGE105
  J100  281 VSS123 SCONN288_DDR506112002KQ-SCONN288_DDR506112002KQ,SMA   I176 @T6G_MB_LIB.T6G(SCH_1):PAGE105
  J100  284 VSS124 SCONN288_DDR506112002KQ-SCONN288_DDR506112002KQ,SMA   I176 @T6G_MB_LIB.T6G(SCH_1):PAGE105
  J100  286 VSS125 SCONN288_DDR506112002KQ-SCONN288_DDR506112002KQ,SMA   I176 @T6G_MB_LIB.T6G(SCH_1):PAGE105
  J100  288 VSS126 SCONN288_DDR506112002KQ-SCONN288_DDR506112002KQ,SMA   I176 @T6G_MB_LIB.T6G(SCH_1):PAGE105
  C168    2      B Q_CAP_0402-0.1UF,25V,10%,X7R,CH4104K1B00   I185 @T6G_MB_LIB.T6G(SCH_1):PAGE105
  C534    2      B Q_CAP_C0805-10UF,25V,10%,X6S,CH6104KEA00   I238 @T6G_MB_LIB.T6G(SCH_1):PAGE105
  C535    2      B Q_CAP_C0805-10UF,25V,10%,X6S,CH6104KEA00   I239 @T6G_MB_LIB.T6G(SCH_1):PAGE105
  R776    2      B Q_RES_0402LF-35.7K,1%,1/16W,CHIP,CS33572FB01   I127 @T6G_MB_LIB.T6G(SCH_1):PAGE106
   J29   G1     G1 SCONN288_DDR506112002KQ-SCONN288_DDR506112002KQ,SMA   I143 @T6G_MB_LIB.T6G(SCH_1):PAGE106
   J29   G2     G2 SCONN288_DDR506112002KQ-SCONN288_DDR506112002KQ,SMA   I143 @T6G_MB_LIB.T6G(SCH_1):PAGE106
   J29   G3     G3 SCONN288_DDR506112002KQ-SCONN288_DDR506112002KQ,SMA   I143 @T6G_MB_LIB.T6G(SCH_1):PAGE106
   J29    6   VSS0 SCONN288_DDR506112002KQ-SCONN288_DDR506112002KQ,SMA   I143 @T6G_MB_LIB.T6G(SCH_1):PAGE106
   J29    8   VSS1 SCONN288_DDR506112002KQ-SCONN288_DDR506112002KQ,SMA   I143 @T6G_MB_LIB.T6G(SCH_1):PAGE106
   J29   10   VSS2 SCONN288_DDR506112002KQ-SCONN288_DDR506112002KQ,SMA   I143 @T6G_MB_LIB.T6G(SCH_1):PAGE106
   J29   13   VSS3 SCONN288_DDR506112002KQ-SCONN288_DDR506112002KQ,SMA   I143 @T6G_MB_LIB.T6G(SCH_1):PAGE106
   J29   15   VSS4 SCONN288_DDR506112002KQ-SCONN288_DDR506112002KQ,SMA   I143 @T6G_MB_LIB.T6G(SCH_1):PAGE106
   J29   17   VSS5 SCONN288_DDR506112002KQ-SCONN288_DDR506112002KQ,SMA   I143 @T6G_MB_LIB.T6G(SCH_1):PAGE106
   J29   19   VSS6 SCONN288_DDR506112002KQ-SCONN288_DDR506112002KQ,SMA   I143 @T6G_MB_LIB.T6G(SCH_1):PAGE106
   J29   21   VSS7 SCONN288_DDR506112002KQ-SCONN288_DDR506112002KQ,SMA   I143 @T6G_MB_LIB.T6G(SCH_1):PAGE106
   J29   24   VSS8 SCONN288_DDR506112002KQ-SCONN288_DDR506112002KQ,SMA   I143 @T6G_MB_LIB.T6G(SCH_1):PAGE106
   J29   26   VSS9 SCONN288_DDR506112002KQ-SCONN288_DDR506112002KQ,SMA   I143 @T6G_MB_LIB.T6G(SCH_1):PAGE106
   J29   28  VSS10 SCONN288_DDR506112002KQ-SCONN288_DDR506112002KQ,SMA   I143 @T6G_MB_LIB.T6G(SCH_1):PAGE106
   J29   30  VSS11 SCONN288_DDR506112002KQ-SCONN288_DDR506112002KQ,SMA   I143 @T6G_MB_LIB.T6G(SCH_1):PAGE106
   J29   32  VSS12 SCONN288_DDR506112002KQ-SCONN288_DDR506112002KQ,SMA   I143 @T6G_MB_LIB.T6G(SCH_1):PAGE106
   J29   35  VSS13 SCONN288_DDR506112002KQ-SCONN288_DDR506112002KQ,SMA   I143 @T6G_MB_LIB.T6G(SCH_1):PAGE106
   J29   37  VSS14 SCONN288_DDR506112002KQ-SCONN288_DDR506112002KQ,SMA   I143 @T6G_MB_LIB.T6G(SCH_1):PAGE106
   J29   39  VSS15 SCONN288_DDR506112002KQ-SCONN288_DDR506112002KQ,SMA   I143 @T6G_MB_LIB.T6G(SCH_1):PAGE106
   J29   41  VSS16 SCONN288_DDR506112002KQ-SCONN288_DDR506112002KQ,SMA   I143 @T6G_MB_LIB.T6G(SCH_1):PAGE106
   J29   43  VSS17 SCONN288_DDR506112002KQ-SCONN288_DDR506112002KQ,SMA   I143 @T6G_MB_LIB.T6G(SCH_1):PAGE106
   J29   46  VSS18 SCONN288_DDR506112002KQ-SCONN288_DDR506112002KQ,SMA   I143 @T6G_MB_LIB.T6G(SCH_1):PAGE106
   J29   48  VSS19 SCONN288_DDR506112002KQ-SCONN288_DDR506112002KQ,SMA   I143 @T6G_MB_LIB.T6G(SCH_1):PAGE106
   J29   50  VSS20 SCONN288_DDR506112002KQ-SCONN288_DDR506112002KQ,SMA   I143 @T6G_MB_LIB.T6G(SCH_1):PAGE106
   J29   52  VSS21 SCONN288_DDR506112002KQ-SCONN288_DDR506112002KQ,SMA   I143 @T6G_MB_LIB.T6G(SCH_1):PAGE106
   J29   54  VSS22 SCONN288_DDR506112002KQ-SCONN288_DDR506112002KQ,SMA   I143 @T6G_MB_LIB.T6G(SCH_1):PAGE106
   J29   57  VSS23 SCONN288_DDR506112002KQ-SCONN288_DDR506112002KQ,SMA   I143 @T6G_MB_LIB.T6G(SCH_1):PAGE106
   J29   59  VSS24 SCONN288_DDR506112002KQ-SCONN288_DDR506112002KQ,SMA   I143 @T6G_MB_LIB.T6G(SCH_1):PAGE106
   J29   61  VSS25 SCONN288_DDR506112002KQ-SCONN288_DDR506112002KQ,SMA   I143 @T6G_MB_LIB.T6G(SCH_1):PAGE106
   J29   63  VSS26 SCONN288_DDR506112002KQ-SCONN288_DDR506112002KQ,SMA   I143 @T6G_MB_LIB.T6G(SCH_1):PAGE106
   J29   65  VSS27 SCONN288_DDR506112002KQ-SCONN288_DDR506112002KQ,SMA   I143 @T6G_MB_LIB.T6G(SCH_1):PAGE106
   J29   67  VSS28 SCONN288_DDR506112002KQ-SCONN288_DDR506112002KQ,SMA   I143 @T6G_MB_LIB.T6G(SCH_1):PAGE106
   J29   69  VSS29 SCONN288_DDR506112002KQ-SCONN288_DDR506112002KQ,SMA   I143 @T6G_MB_LIB.T6G(SCH_1):PAGE106
   J29   71  VSS30 SCONN288_DDR506112002KQ-SCONN288_DDR506112002KQ,SMA   I143 @T6G_MB_LIB.T6G(SCH_1):PAGE106
   J29   73  VSS31 SCONN288_DDR506112002KQ-SCONN288_DDR506112002KQ,SMA   I143 @T6G_MB_LIB.T6G(SCH_1):PAGE106
   J29   75  VSS32 SCONN288_DDR506112002KQ-SCONN288_DDR506112002KQ,SMA   I143 @T6G_MB_LIB.T6G(SCH_1):PAGE106
   J29   77  VSS33 SCONN288_DDR506112002KQ-SCONN288_DDR506112002KQ,SMA   I143 @T6G_MB_LIB.T6G(SCH_1):PAGE106
   J29   79  VSS34 SCONN288_DDR506112002KQ-SCONN288_DDR506112002KQ,SMA   I143 @T6G_MB_LIB.T6G(SCH_1):PAGE106
   J29   81  VSS35 SCONN288_DDR506112002KQ-SCONN288_DDR506112002KQ,SMA   I143 @T6G_MB_LIB.T6G(SCH_1):PAGE106
   J29   83  VSS36 SCONN288_DDR506112002KQ-SCONN288_DDR506112002KQ,SMA   I143 @T6G_MB_LIB.T6G(SCH_1):PAGE106
   J29   85  VSS37 SCONN288_DDR506112002KQ-SCONN288_DDR506112002KQ,SMA   I143 @T6G_MB_LIB.T6G(SCH_1):PAGE106
   J29   88  VSS38 SCONN288_DDR506112002KQ-SCONN288_DDR506112002KQ,SMA   I143 @T6G_MB_LIB.T6G(SCH_1):PAGE106
   J29   90  VSS39 SCONN288_DDR506112002KQ-SCONN288_DDR506112002KQ,SMA   I143 @T6G_MB_LIB.T6G(SCH_1):PAGE106
   J29   92  VSS40 SCONN288_DDR506112002KQ-SCONN288_DDR506112002KQ,SMA   I143 @T6G_MB_LIB.T6G(SCH_1):PAGE106
   J29   95  VSS41 SCONN288_DDR506112002KQ-SCONN288_DDR506112002KQ,SMA   I143 @T6G_MB_LIB.T6G(SCH_1):PAGE106
   J29   97  VSS42 SCONN288_DDR506112002KQ-SCONN288_DDR506112002KQ,SMA   I143 @T6G_MB_LIB.T6G(SCH_1):PAGE106
   J29   99  VSS43 SCONN288_DDR506112002KQ-SCONN288_DDR506112002KQ,SMA   I143 @T6G_MB_LIB.T6G(SCH_1):PAGE106
   J29  101  VSS44 SCONN288_DDR506112002KQ-SCONN288_DDR506112002KQ,SMA   I143 @T6G_MB_LIB.T6G(SCH_1):PAGE106
   J29  103  VSS45 SCONN288_DDR506112002KQ-SCONN288_DDR506112002KQ,SMA   I143 @T6G_MB_LIB.T6G(SCH_1):PAGE106
   J29  106  VSS46 SCONN288_DDR506112002KQ-SCONN288_DDR506112002KQ,SMA   I143 @T6G_MB_LIB.T6G(SCH_1):PAGE106
   J29  108  VSS47 SCONN288_DDR506112002KQ-SCONN288_DDR506112002KQ,SMA   I143 @T6G_MB_LIB.T6G(SCH_1):PAGE106
   J29  110  VSS48 SCONN288_DDR506112002KQ-SCONN288_DDR506112002KQ,SMA   I143 @T6G_MB_LIB.T6G(SCH_1):PAGE106
   J29  112  VSS49 SCONN288_DDR506112002KQ-SCONN288_DDR506112002KQ,SMA   I143 @T6G_MB_LIB.T6G(SCH_1):PAGE106
   J29  114  VSS50 SCONN288_DDR506112002KQ-SCONN288_DDR506112002KQ,SMA   I143 @T6G_MB_LIB.T6G(SCH_1):PAGE106
   J29  117  VSS51 SCONN288_DDR506112002KQ-SCONN288_DDR506112002KQ,SMA   I143 @T6G_MB_LIB.T6G(SCH_1):PAGE106
   J29  119  VSS52 SCONN288_DDR506112002KQ-SCONN288_DDR506112002KQ,SMA   I143 @T6G_MB_LIB.T6G(SCH_1):PAGE106
   J29  121  VSS53 SCONN288_DDR506112002KQ-SCONN288_DDR506112002KQ,SMA   I143 @T6G_MB_LIB.T6G(SCH_1):PAGE106
   J29  123  VSS54 SCONN288_DDR506112002KQ-SCONN288_DDR506112002KQ,SMA   I143 @T6G_MB_LIB.T6G(SCH_1):PAGE106
   J29  125  VSS55 SCONN288_DDR506112002KQ-SCONN288_DDR506112002KQ,SMA   I143 @T6G_MB_LIB.T6G(SCH_1):PAGE106
   J29  128  VSS56 SCONN288_DDR506112002KQ-SCONN288_DDR506112002KQ,SMA   I143 @T6G_MB_LIB.T6G(SCH_1):PAGE106
   J29  130  VSS57 SCONN288_DDR506112002KQ-SCONN288_DDR506112002KQ,SMA   I143 @T6G_MB_LIB.T6G(SCH_1):PAGE106
   J29  132  VSS58 SCONN288_DDR506112002KQ-SCONN288_DDR506112002KQ,SMA   I143 @T6G_MB_LIB.T6G(SCH_1):PAGE106
   J29  134  VSS59 SCONN288_DDR506112002KQ-SCONN288_DDR506112002KQ,SMA   I143 @T6G_MB_LIB.T6G(SCH_1):PAGE106
   J29  136  VSS60 SCONN288_DDR506112002KQ-SCONN288_DDR506112002KQ,SMA   I143 @T6G_MB_LIB.T6G(SCH_1):PAGE106
   J29  139  VSS61 SCONN288_DDR506112002KQ-SCONN288_DDR506112002KQ,SMA   I143 @T6G_MB_LIB.T6G(SCH_1):PAGE106
   J29  141  VSS62 SCONN288_DDR506112002KQ-SCONN288_DDR506112002KQ,SMA   I143 @T6G_MB_LIB.T6G(SCH_1):PAGE106
   J29  143  VSS63 SCONN288_DDR506112002KQ-SCONN288_DDR506112002KQ,SMA   I143 @T6G_MB_LIB.T6G(SCH_1):PAGE106
   J29  151  VSS64 SCONN288_DDR506112002KQ-SCONN288_DDR506112002KQ,SMA   I143 @T6G_MB_LIB.T6G(SCH_1):PAGE106
   J29  153  VSS65 SCONN288_DDR506112002KQ-SCONN288_DDR506112002KQ,SMA   I143 @T6G_MB_LIB.T6G(SCH_1):PAGE106
   J29  155  VSS66 SCONN288_DDR506112002KQ-SCONN288_DDR506112002KQ,SMA   I143 @T6G_MB_LIB.T6G(SCH_1):PAGE106
   J29  158  VSS67 SCONN288_DDR506112002KQ-SCONN288_DDR506112002KQ,SMA   I143 @T6G_MB_LIB.T6G(SCH_1):PAGE106
   J29  160  VSS68 SCONN288_DDR506112002KQ-SCONN288_DDR506112002KQ,SMA   I143 @T6G_MB_LIB.T6G(SCH_1):PAGE106
   J29  162  VSS69 SCONN288_DDR506112002KQ-SCONN288_DDR506112002KQ,SMA   I143 @T6G_MB_LIB.T6G(SCH_1):PAGE106
   J29  164  VSS70 SCONN288_DDR506112002KQ-SCONN288_DDR506112002KQ,SMA   I143 @T6G_MB_LIB.T6G(SCH_1):PAGE106
   J29  166  VSS71 SCONN288_DDR506112002KQ-SCONN288_DDR506112002KQ,SMA   I143 @T6G_MB_LIB.T6G(SCH_1):PAGE106
   J29  169  VSS72 SCONN288_DDR506112002KQ-SCONN288_DDR506112002KQ,SMA   I143 @T6G_MB_LIB.T6G(SCH_1):PAGE106
   J29  171  VSS73 SCONN288_DDR506112002KQ-SCONN288_DDR506112002KQ,SMA   I143 @T6G_MB_LIB.T6G(SCH_1):PAGE106
   J29  173  VSS74 SCONN288_DDR506112002KQ-SCONN288_DDR506112002KQ,SMA   I143 @T6G_MB_LIB.T6G(SCH_1):PAGE106
   J29  175  VSS75 SCONN288_DDR506112002KQ-SCONN288_DDR506112002KQ,SMA   I143 @T6G_MB_LIB.T6G(SCH_1):PAGE106
   J29  177  VSS76 SCONN288_DDR506112002KQ-SCONN288_DDR506112002KQ,SMA   I143 @T6G_MB_LIB.T6G(SCH_1):PAGE106
   J29  180  VSS77 SCONN288_DDR506112002KQ-SCONN288_DDR506112002KQ,SMA   I143 @T6G_MB_LIB.T6G(SCH_1):PAGE106
   J29  182  VSS78 SCONN288_DDR506112002KQ-SCONN288_DDR506112002KQ,SMA   I143 @T6G_MB_LIB.T6G(SCH_1):PAGE106
   J29  184  VSS79 SCONN288_DDR506112002KQ-SCONN288_DDR506112002KQ,SMA   I143 @T6G_MB_LIB.T6G(SCH_1):PAGE106
   J29  186  VSS80 SCONN288_DDR506112002KQ-SCONN288_DDR506112002KQ,SMA   I143 @T6G_MB_LIB.T6G(SCH_1):PAGE106
   J29  188  VSS81 SCONN288_DDR506112002KQ-SCONN288_DDR506112002KQ,SMA   I143 @T6G_MB_LIB.T6G(SCH_1):PAGE106
   J29  191  VSS82 SCONN288_DDR506112002KQ-SCONN288_DDR506112002KQ,SMA   I143 @T6G_MB_LIB.T6G(SCH_1):PAGE106
   J29  193  VSS83 SCONN288_DDR506112002KQ-SCONN288_DDR506112002KQ,SMA   I143 @T6G_MB_LIB.T6G(SCH_1):PAGE106
   J29  195  VSS84 SCONN288_DDR506112002KQ-SCONN288_DDR506112002KQ,SMA   I143 @T6G_MB_LIB.T6G(SCH_1):PAGE106
   J29  197  VSS85 SCONN288_DDR506112002KQ-SCONN288_DDR506112002KQ,SMA   I143 @T6G_MB_LIB.T6G(SCH_1):PAGE106
   J29  199  VSS86 SCONN288_DDR506112002KQ-SCONN288_DDR506112002KQ,SMA   I143 @T6G_MB_LIB.T6G(SCH_1):PAGE106
   J29  202  VSS87 SCONN288_DDR506112002KQ-SCONN288_DDR506112002KQ,SMA   I143 @T6G_MB_LIB.T6G(SCH_1):PAGE106
   J29  204  VSS88 SCONN288_DDR506112002KQ-SCONN288_DDR506112002KQ,SMA   I143 @T6G_MB_LIB.T6G(SCH_1):PAGE106
   J29  206  VSS89 SCONN288_DDR506112002KQ-SCONN288_DDR506112002KQ,SMA   I143 @T6G_MB_LIB.T6G(SCH_1):PAGE106
   J29  208  VSS90 SCONN288_DDR506112002KQ-SCONN288_DDR506112002KQ,SMA   I143 @T6G_MB_LIB.T6G(SCH_1):PAGE106
   J29  210  VSS91 SCONN288_DDR506112002KQ-SCONN288_DDR506112002KQ,SMA   I143 @T6G_MB_LIB.T6G(SCH_1):PAGE106
   J29  212  VSS92 SCONN288_DDR506112002KQ-SCONN288_DDR506112002KQ,SMA   I143 @T6G_MB_LIB.T6G(SCH_1):PAGE106
   J29  214  VSS93 SCONN288_DDR506112002KQ-SCONN288_DDR506112002KQ,SMA   I143 @T6G_MB_LIB.T6G(SCH_1):PAGE106
   J29  216  VSS94 SCONN288_DDR506112002KQ-SCONN288_DDR506112002KQ,SMA   I143 @T6G_MB_LIB.T6G(SCH_1):PAGE106
   J29  219  VSS95 SCONN288_DDR506112002KQ-SCONN288_DDR506112002KQ,SMA   I143 @T6G_MB_LIB.T6G(SCH_1):PAGE106
   J29  222  VSS96 SCONN288_DDR506112002KQ-SCONN288_DDR506112002KQ,SMA   I143 @T6G_MB_LIB.T6G(SCH_1):PAGE106
   J29  224  VSS97 SCONN288_DDR506112002KQ-SCONN288_DDR506112002KQ,SMA   I143 @T6G_MB_LIB.T6G(SCH_1):PAGE106
   J29  226  VSS98 SCONN288_DDR506112002KQ-SCONN288_DDR506112002KQ,SMA   I143 @T6G_MB_LIB.T6G(SCH_1):PAGE106
   J29  228  VSS99 SCONN288_DDR506112002KQ-SCONN288_DDR506112002KQ,SMA   I143 @T6G_MB_LIB.T6G(SCH_1):PAGE106
   J29  230 VSS100 SCONN288_DDR506112002KQ-SCONN288_DDR506112002KQ,SMA   I143 @T6G_MB_LIB.T6G(SCH_1):PAGE106
   J29  233 VSS101 SCONN288_DDR506112002KQ-SCONN288_DDR506112002KQ,SMA   I143 @T6G_MB_LIB.T6G(SCH_1):PAGE106
   J29  235 VSS102 SCONN288_DDR506112002KQ-SCONN288_DDR506112002KQ,SMA   I143 @T6G_MB_LIB.T6G(SCH_1):PAGE106
   J29  237 VSS103 SCONN288_DDR506112002KQ-SCONN288_DDR506112002KQ,SMA   I143 @T6G_MB_LIB.T6G(SCH_1):PAGE106
   J29  240 VSS104 SCONN288_DDR506112002KQ-SCONN288_DDR506112002KQ,SMA   I143 @T6G_MB_LIB.T6G(SCH_1):PAGE106
   J29  242 VSS105 SCONN288_DDR506112002KQ-SCONN288_DDR506112002KQ,SMA   I143 @T6G_MB_LIB.T6G(SCH_1):PAGE106
   J29  244 VSS106 SCONN288_DDR506112002KQ-SCONN288_DDR506112002KQ,SMA   I143 @T6G_MB_LIB.T6G(SCH_1):PAGE106
   J29  246 VSS107 SCONN288_DDR506112002KQ-SCONN288_DDR506112002KQ,SMA   I143 @T6G_MB_LIB.T6G(SCH_1):PAGE106
   J29  248 VSS108 SCONN288_DDR506112002KQ-SCONN288_DDR506112002KQ,SMA   I143 @T6G_MB_LIB.T6G(SCH_1):PAGE106
   J29  251 VSS109 SCONN288_DDR506112002KQ-SCONN288_DDR506112002KQ,SMA   I143 @T6G_MB_LIB.T6G(SCH_1):PAGE106
   J29  253 VSS110 SCONN288_DDR506112002KQ-SCONN288_DDR506112002KQ,SMA   I143 @T6G_MB_LIB.T6G(SCH_1):PAGE106
   J29  255 VSS111 SCONN288_DDR506112002KQ-SCONN288_DDR506112002KQ,SMA   I143 @T6G_MB_LIB.T6G(SCH_1):PAGE106
   J29  257 VSS112 SCONN288_DDR506112002KQ-SCONN288_DDR506112002KQ,SMA   I143 @T6G_MB_LIB.T6G(SCH_1):PAGE106
   J29  259 VSS113 SCONN288_DDR506112002KQ-SCONN288_DDR506112002KQ,SMA   I143 @T6G_MB_LIB.T6G(SCH_1):PAGE106
   J29  262 VSS114 SCONN288_DDR506112002KQ-SCONN288_DDR506112002KQ,SMA   I143 @T6G_MB_LIB.T6G(SCH_1):PAGE106
   J29  264 VSS115 SCONN288_DDR506112002KQ-SCONN288_DDR506112002KQ,SMA   I143 @T6G_MB_LIB.T6G(SCH_1):PAGE106
   J29  266 VSS116 SCONN288_DDR506112002KQ-SCONN288_DDR506112002KQ,SMA   I143 @T6G_MB_LIB.T6G(SCH_1):PAGE106
   J29  268 VSS117 SCONN288_DDR506112002KQ-SCONN288_DDR506112002KQ,SMA   I143 @T6G_MB_LIB.T6G(SCH_1):PAGE106
   J29  270 VSS118 SCONN288_DDR506112002KQ-SCONN288_DDR506112002KQ,SMA   I143 @T6G_MB_LIB.T6G(SCH_1):PAGE106
   J29  273 VSS119 SCONN288_DDR506112002KQ-SCONN288_DDR506112002KQ,SMA   I143 @T6G_MB_LIB.T6G(SCH_1):PAGE106
   J29  275 VSS120 SCONN288_DDR506112002KQ-SCONN288_DDR506112002KQ,SMA   I143 @T6G_MB_LIB.T6G(SCH_1):PAGE106
   J29  277 VSS121 SCONN288_DDR506112002KQ-SCONN288_DDR506112002KQ,SMA   I143 @T6G_MB_LIB.T6G(SCH_1):PAGE106
   J29  279 VSS122 SCONN288_DDR506112002KQ-SCONN288_DDR506112002KQ,SMA   I143 @T6G_MB_LIB.T6G(SCH_1):PAGE106
   J29  281 VSS123 SCONN288_DDR506112002KQ-SCONN288_DDR506112002KQ,SMA   I143 @T6G_MB_LIB.T6G(SCH_1):PAGE106
   J29  284 VSS124 SCONN288_DDR506112002KQ-SCONN288_DDR506112002KQ,SMA   I143 @T6G_MB_LIB.T6G(SCH_1):PAGE106
   J29  286 VSS125 SCONN288_DDR506112002KQ-SCONN288_DDR506112002KQ,SMA   I143 @T6G_MB_LIB.T6G(SCH_1):PAGE106
   J29  288 VSS126 SCONN288_DDR506112002KQ-SCONN288_DDR506112002KQ,SMA   I143 @T6G_MB_LIB.T6G(SCH_1):PAGE106
  C172    2      B Q_CAP_0402-0.1UF,25V,10%,X7R,CH4104K1B00   I185 @T6G_MB_LIB.T6G(SCH_1):PAGE106
  C536    2      B Q_CAP_C0805-10UF,25V,10%,X6S,CH6104KEA00   I238 @T6G_MB_LIB.T6G(SCH_1):PAGE106
  C537    2      B Q_CAP_C0805-10UF,25V,10%,X6S,CH6104KEA00   I239 @T6G_MB_LIB.T6G(SCH_1):PAGE106
  R777    2      B Q_RES_0402LF-54.9K,1%,1/16W,CHIP,CS35492FB03   I136 @T6G_MB_LIB.T6G(SCH_1):PAGE107
   J99   G1     G1 SCONN288_DDR506112002KQ-SCONN288_DDR506112002KQ,SMA   I139 @T6G_MB_LIB.T6G(SCH_1):PAGE107
   J99   G2     G2 SCONN288_DDR506112002KQ-SCONN288_DDR506112002KQ,SMA   I139 @T6G_MB_LIB.T6G(SCH_1):PAGE107
   J99   G3     G3 SCONN288_DDR506112002KQ-SCONN288_DDR506112002KQ,SMA   I139 @T6G_MB_LIB.T6G(SCH_1):PAGE107
   J99    6   VSS0 SCONN288_DDR506112002KQ-SCONN288_DDR506112002KQ,SMA   I139 @T6G_MB_LIB.T6G(SCH_1):PAGE107
   J99    8   VSS1 SCONN288_DDR506112002KQ-SCONN288_DDR506112002KQ,SMA   I139 @T6G_MB_LIB.T6G(SCH_1):PAGE107
   J99   10   VSS2 SCONN288_DDR506112002KQ-SCONN288_DDR506112002KQ,SMA   I139 @T6G_MB_LIB.T6G(SCH_1):PAGE107
   J99   13   VSS3 SCONN288_DDR506112002KQ-SCONN288_DDR506112002KQ,SMA   I139 @T6G_MB_LIB.T6G(SCH_1):PAGE107
   J99   15   VSS4 SCONN288_DDR506112002KQ-SCONN288_DDR506112002KQ,SMA   I139 @T6G_MB_LIB.T6G(SCH_1):PAGE107
   J99   17   VSS5 SCONN288_DDR506112002KQ-SCONN288_DDR506112002KQ,SMA   I139 @T6G_MB_LIB.T6G(SCH_1):PAGE107
   J99   19   VSS6 SCONN288_DDR506112002KQ-SCONN288_DDR506112002KQ,SMA   I139 @T6G_MB_LIB.T6G(SCH_1):PAGE107
   J99   21   VSS7 SCONN288_DDR506112002KQ-SCONN288_DDR506112002KQ,SMA   I139 @T6G_MB_LIB.T6G(SCH_1):PAGE107
   J99   24   VSS8 SCONN288_DDR506112002KQ-SCONN288_DDR506112002KQ,SMA   I139 @T6G_MB_LIB.T6G(SCH_1):PAGE107
   J99   26   VSS9 SCONN288_DDR506112002KQ-SCONN288_DDR506112002KQ,SMA   I139 @T6G_MB_LIB.T6G(SCH_1):PAGE107
   J99   28  VSS10 SCONN288_DDR506112002KQ-SCONN288_DDR506112002KQ,SMA   I139 @T6G_MB_LIB.T6G(SCH_1):PAGE107
   J99   30  VSS11 SCONN288_DDR506112002KQ-SCONN288_DDR506112002KQ,SMA   I139 @T6G_MB_LIB.T6G(SCH_1):PAGE107
   J99   32  VSS12 SCONN288_DDR506112002KQ-SCONN288_DDR506112002KQ,SMA   I139 @T6G_MB_LIB.T6G(SCH_1):PAGE107
   J99   35  VSS13 SCONN288_DDR506112002KQ-SCONN288_DDR506112002KQ,SMA   I139 @T6G_MB_LIB.T6G(SCH_1):PAGE107
   J99   37  VSS14 SCONN288_DDR506112002KQ-SCONN288_DDR506112002KQ,SMA   I139 @T6G_MB_LIB.T6G(SCH_1):PAGE107
   J99   39  VSS15 SCONN288_DDR506112002KQ-SCONN288_DDR506112002KQ,SMA   I139 @T6G_MB_LIB.T6G(SCH_1):PAGE107
   J99   41  VSS16 SCONN288_DDR506112002KQ-SCONN288_DDR506112002KQ,SMA   I139 @T6G_MB_LIB.T6G(SCH_1):PAGE107
   J99   43  VSS17 SCONN288_DDR506112002KQ-SCONN288_DDR506112002KQ,SMA   I139 @T6G_MB_LIB.T6G(SCH_1):PAGE107
   J99   46  VSS18 SCONN288_DDR506112002KQ-SCONN288_DDR506112002KQ,SMA   I139 @T6G_MB_LIB.T6G(SCH_1):PAGE107
   J99   48  VSS19 SCONN288_DDR506112002KQ-SCONN288_DDR506112002KQ,SMA   I139 @T6G_MB_LIB.T6G(SCH_1):PAGE107
   J99   50  VSS20 SCONN288_DDR506112002KQ-SCONN288_DDR506112002KQ,SMA   I139 @T6G_MB_LIB.T6G(SCH_1):PAGE107
   J99   52  VSS21 SCONN288_DDR506112002KQ-SCONN288_DDR506112002KQ,SMA   I139 @T6G_MB_LIB.T6G(SCH_1):PAGE107
   J99   54  VSS22 SCONN288_DDR506112002KQ-SCONN288_DDR506112002KQ,SMA   I139 @T6G_MB_LIB.T6G(SCH_1):PAGE107
   J99   57  VSS23 SCONN288_DDR506112002KQ-SCONN288_DDR506112002KQ,SMA   I139 @T6G_MB_LIB.T6G(SCH_1):PAGE107
   J99   59  VSS24 SCONN288_DDR506112002KQ-SCONN288_DDR506112002KQ,SMA   I139 @T6G_MB_LIB.T6G(SCH_1):PAGE107
   J99   61  VSS25 SCONN288_DDR506112002KQ-SCONN288_DDR506112002KQ,SMA   I139 @T6G_MB_LIB.T6G(SCH_1):PAGE107
   J99   63  VSS26 SCONN288_DDR506112002KQ-SCONN288_DDR506112002KQ,SMA   I139 @T6G_MB_LIB.T6G(SCH_1):PAGE107
   J99   65  VSS27 SCONN288_DDR506112002KQ-SCONN288_DDR506112002KQ,SMA   I139 @T6G_MB_LIB.T6G(SCH_1):PAGE107
   J99   67  VSS28 SCONN288_DDR506112002KQ-SCONN288_DDR506112002KQ,SMA   I139 @T6G_MB_LIB.T6G(SCH_1):PAGE107
   J99   69  VSS29 SCONN288_DDR506112002KQ-SCONN288_DDR506112002KQ,SMA   I139 @T6G_MB_LIB.T6G(SCH_1):PAGE107
   J99   71  VSS30 SCONN288_DDR506112002KQ-SCONN288_DDR506112002KQ,SMA   I139 @T6G_MB_LIB.T6G(SCH_1):PAGE107
   J99   73  VSS31 SCONN288_DDR506112002KQ-SCONN288_DDR506112002KQ,SMA   I139 @T6G_MB_LIB.T6G(SCH_1):PAGE107
   J99   75  VSS32 SCONN288_DDR506112002KQ-SCONN288_DDR506112002KQ,SMA   I139 @T6G_MB_LIB.T6G(SCH_1):PAGE107
   J99   77  VSS33 SCONN288_DDR506112002KQ-SCONN288_DDR506112002KQ,SMA   I139 @T6G_MB_LIB.T6G(SCH_1):PAGE107
   J99   79  VSS34 SCONN288_DDR506112002KQ-SCONN288_DDR506112002KQ,SMA   I139 @T6G_MB_LIB.T6G(SCH_1):PAGE107
   J99   81  VSS35 SCONN288_DDR506112002KQ-SCONN288_DDR506112002KQ,SMA   I139 @T6G_MB_LIB.T6G(SCH_1):PAGE107
   J99   83  VSS36 SCONN288_DDR506112002KQ-SCONN288_DDR506112002KQ,SMA   I139 @T6G_MB_LIB.T6G(SCH_1):PAGE107
   J99   85  VSS37 SCONN288_DDR506112002KQ-SCONN288_DDR506112002KQ,SMA   I139 @T6G_MB_LIB.T6G(SCH_1):PAGE107
   J99   88  VSS38 SCONN288_DDR506112002KQ-SCONN288_DDR506112002KQ,SMA   I139 @T6G_MB_LIB.T6G(SCH_1):PAGE107
   J99   90  VSS39 SCONN288_DDR506112002KQ-SCONN288_DDR506112002KQ,SMA   I139 @T6G_MB_LIB.T6G(SCH_1):PAGE107
   J99   92  VSS40 SCONN288_DDR506112002KQ-SCONN288_DDR506112002KQ,SMA   I139 @T6G_MB_LIB.T6G(SCH_1):PAGE107
   J99   95  VSS41 SCONN288_DDR506112002KQ-SCONN288_DDR506112002KQ,SMA   I139 @T6G_MB_LIB.T6G(SCH_1):PAGE107
   J99   97  VSS42 SCONN288_DDR506112002KQ-SCONN288_DDR506112002KQ,SMA   I139 @T6G_MB_LIB.T6G(SCH_1):PAGE107
   J99   99  VSS43 SCONN288_DDR506112002KQ-SCONN288_DDR506112002KQ,SMA   I139 @T6G_MB_LIB.T6G(SCH_1):PAGE107
   J99  101  VSS44 SCONN288_DDR506112002KQ-SCONN288_DDR506112002KQ,SMA   I139 @T6G_MB_LIB.T6G(SCH_1):PAGE107
   J99  103  VSS45 SCONN288_DDR506112002KQ-SCONN288_DDR506112002KQ,SMA   I139 @T6G_MB_LIB.T6G(SCH_1):PAGE107
   J99  106  VSS46 SCONN288_DDR506112002KQ-SCONN288_DDR506112002KQ,SMA   I139 @T6G_MB_LIB.T6G(SCH_1):PAGE107
   J99  108  VSS47 SCONN288_DDR506112002KQ-SCONN288_DDR506112002KQ,SMA   I139 @T6G_MB_LIB.T6G(SCH_1):PAGE107
   J99  110  VSS48 SCONN288_DDR506112002KQ-SCONN288_DDR506112002KQ,SMA   I139 @T6G_MB_LIB.T6G(SCH_1):PAGE107
   J99  112  VSS49 SCONN288_DDR506112002KQ-SCONN288_DDR506112002KQ,SMA   I139 @T6G_MB_LIB.T6G(SCH_1):PAGE107
   J99  114  VSS50 SCONN288_DDR506112002KQ-SCONN288_DDR506112002KQ,SMA   I139 @T6G_MB_LIB.T6G(SCH_1):PAGE107
   J99  117  VSS51 SCONN288_DDR506112002KQ-SCONN288_DDR506112002KQ,SMA   I139 @T6G_MB_LIB.T6G(SCH_1):PAGE107
   J99  119  VSS52 SCONN288_DDR506112002KQ-SCONN288_DDR506112002KQ,SMA   I139 @T6G_MB_LIB.T6G(SCH_1):PAGE107
   J99  121  VSS53 SCONN288_DDR506112002KQ-SCONN288_DDR506112002KQ,SMA   I139 @T6G_MB_LIB.T6G(SCH_1):PAGE107
   J99  123  VSS54 SCONN288_DDR506112002KQ-SCONN288_DDR506112002KQ,SMA   I139 @T6G_MB_LIB.T6G(SCH_1):PAGE107
   J99  125  VSS55 SCONN288_DDR506112002KQ-SCONN288_DDR506112002KQ,SMA   I139 @T6G_MB_LIB.T6G(SCH_1):PAGE107
   J99  128  VSS56 SCONN288_DDR506112002KQ-SCONN288_DDR506112002KQ,SMA   I139 @T6G_MB_LIB.T6G(SCH_1):PAGE107
   J99  130  VSS57 SCONN288_DDR506112002KQ-SCONN288_DDR506112002KQ,SMA   I139 @T6G_MB_LIB.T6G(SCH_1):PAGE107
   J99  132  VSS58 SCONN288_DDR506112002KQ-SCONN288_DDR506112002KQ,SMA   I139 @T6G_MB_LIB.T6G(SCH_1):PAGE107
   J99  134  VSS59 SCONN288_DDR506112002KQ-SCONN288_DDR506112002KQ,SMA   I139 @T6G_MB_LIB.T6G(SCH_1):PAGE107
   J99  136  VSS60 SCONN288_DDR506112002KQ-SCONN288_DDR506112002KQ,SMA   I139 @T6G_MB_LIB.T6G(SCH_1):PAGE107
   J99  139  VSS61 SCONN288_DDR506112002KQ-SCONN288_DDR506112002KQ,SMA   I139 @T6G_MB_LIB.T6G(SCH_1):PAGE107
   J99  141  VSS62 SCONN288_DDR506112002KQ-SCONN288_DDR506112002KQ,SMA   I139 @T6G_MB_LIB.T6G(SCH_1):PAGE107
   J99  143  VSS63 SCONN288_DDR506112002KQ-SCONN288_DDR506112002KQ,SMA   I139 @T6G_MB_LIB.T6G(SCH_1):PAGE107
   J99  151  VSS64 SCONN288_DDR506112002KQ-SCONN288_DDR506112002KQ,SMA   I139 @T6G_MB_LIB.T6G(SCH_1):PAGE107
   J99  153  VSS65 SCONN288_DDR506112002KQ-SCONN288_DDR506112002KQ,SMA   I139 @T6G_MB_LIB.T6G(SCH_1):PAGE107
   J99  155  VSS66 SCONN288_DDR506112002KQ-SCONN288_DDR506112002KQ,SMA   I139 @T6G_MB_LIB.T6G(SCH_1):PAGE107
   J99  158  VSS67 SCONN288_DDR506112002KQ-SCONN288_DDR506112002KQ,SMA   I139 @T6G_MB_LIB.T6G(SCH_1):PAGE107
   J99  160  VSS68 SCONN288_DDR506112002KQ-SCONN288_DDR506112002KQ,SMA   I139 @T6G_MB_LIB.T6G(SCH_1):PAGE107
   J99  162  VSS69 SCONN288_DDR506112002KQ-SCONN288_DDR506112002KQ,SMA   I139 @T6G_MB_LIB.T6G(SCH_1):PAGE107
   J99  164  VSS70 SCONN288_DDR506112002KQ-SCONN288_DDR506112002KQ,SMA   I139 @T6G_MB_LIB.T6G(SCH_1):PAGE107
   J99  166  VSS71 SCONN288_DDR506112002KQ-SCONN288_DDR506112002KQ,SMA   I139 @T6G_MB_LIB.T6G(SCH_1):PAGE107
   J99  169  VSS72 SCONN288_DDR506112002KQ-SCONN288_DDR506112002KQ,SMA   I139 @T6G_MB_LIB.T6G(SCH_1):PAGE107
   J99  171  VSS73 SCONN288_DDR506112002KQ-SCONN288_DDR506112002KQ,SMA   I139 @T6G_MB_LIB.T6G(SCH_1):PAGE107
   J99  173  VSS74 SCONN288_DDR506112002KQ-SCONN288_DDR506112002KQ,SMA   I139 @T6G_MB_LIB.T6G(SCH_1):PAGE107
   J99  175  VSS75 SCONN288_DDR506112002KQ-SCONN288_DDR506112002KQ,SMA   I139 @T6G_MB_LIB.T6G(SCH_1):PAGE107
   J99  177  VSS76 SCONN288_DDR506112002KQ-SCONN288_DDR506112002KQ,SMA   I139 @T6G_MB_LIB.T6G(SCH_1):PAGE107
   J99  180  VSS77 SCONN288_DDR506112002KQ-SCONN288_DDR506112002KQ,SMA   I139 @T6G_MB_LIB.T6G(SCH_1):PAGE107
   J99  182  VSS78 SCONN288_DDR506112002KQ-SCONN288_DDR506112002KQ,SMA   I139 @T6G_MB_LIB.T6G(SCH_1):PAGE107
   J99  184  VSS79 SCONN288_DDR506112002KQ-SCONN288_DDR506112002KQ,SMA   I139 @T6G_MB_LIB.T6G(SCH_1):PAGE107
   J99  186  VSS80 SCONN288_DDR506112002KQ-SCONN288_DDR506112002KQ,SMA   I139 @T6G_MB_LIB.T6G(SCH_1):PAGE107
   J99  188  VSS81 SCONN288_DDR506112002KQ-SCONN288_DDR506112002KQ,SMA   I139 @T6G_MB_LIB.T6G(SCH_1):PAGE107
   J99  191  VSS82 SCONN288_DDR506112002KQ-SCONN288_DDR506112002KQ,SMA   I139 @T6G_MB_LIB.T6G(SCH_1):PAGE107
   J99  193  VSS83 SCONN288_DDR506112002KQ-SCONN288_DDR506112002KQ,SMA   I139 @T6G_MB_LIB.T6G(SCH_1):PAGE107
   J99  195  VSS84 SCONN288_DDR506112002KQ-SCONN288_DDR506112002KQ,SMA   I139 @T6G_MB_LIB.T6G(SCH_1):PAGE107
   J99  197  VSS85 SCONN288_DDR506112002KQ-SCONN288_DDR506112002KQ,SMA   I139 @T6G_MB_LIB.T6G(SCH_1):PAGE107
   J99  199  VSS86 SCONN288_DDR506112002KQ-SCONN288_DDR506112002KQ,SMA   I139 @T6G_MB_LIB.T6G(SCH_1):PAGE107
   J99  202  VSS87 SCONN288_DDR506112002KQ-SCONN288_DDR506112002KQ,SMA   I139 @T6G_MB_LIB.T6G(SCH_1):PAGE107
   J99  204  VSS88 SCONN288_DDR506112002KQ-SCONN288_DDR506112002KQ,SMA   I139 @T6G_MB_LIB.T6G(SCH_1):PAGE107
   J99  206  VSS89 SCONN288_DDR506112002KQ-SCONN288_DDR506112002KQ,SMA   I139 @T6G_MB_LIB.T6G(SCH_1):PAGE107
   J99  208  VSS90 SCONN288_DDR506112002KQ-SCONN288_DDR506112002KQ,SMA   I139 @T6G_MB_LIB.T6G(SCH_1):PAGE107
   J99  210  VSS91 SCONN288_DDR506112002KQ-SCONN288_DDR506112002KQ,SMA   I139 @T6G_MB_LIB.T6G(SCH_1):PAGE107
   J99  212  VSS92 SCONN288_DDR506112002KQ-SCONN288_DDR506112002KQ,SMA   I139 @T6G_MB_LIB.T6G(SCH_1):PAGE107
   J99  214  VSS93 SCONN288_DDR506112002KQ-SCONN288_DDR506112002KQ,SMA   I139 @T6G_MB_LIB.T6G(SCH_1):PAGE107
   J99  216  VSS94 SCONN288_DDR506112002KQ-SCONN288_DDR506112002KQ,SMA   I139 @T6G_MB_LIB.T6G(SCH_1):PAGE107
   J99  219  VSS95 SCONN288_DDR506112002KQ-SCONN288_DDR506112002KQ,SMA   I139 @T6G_MB_LIB.T6G(SCH_1):PAGE107
   J99  222  VSS96 SCONN288_DDR506112002KQ-SCONN288_DDR506112002KQ,SMA   I139 @T6G_MB_LIB.T6G(SCH_1):PAGE107
   J99  224  VSS97 SCONN288_DDR506112002KQ-SCONN288_DDR506112002KQ,SMA   I139 @T6G_MB_LIB.T6G(SCH_1):PAGE107
   J99  226  VSS98 SCONN288_DDR506112002KQ-SCONN288_DDR506112002KQ,SMA   I139 @T6G_MB_LIB.T6G(SCH_1):PAGE107
   J99  228  VSS99 SCONN288_DDR506112002KQ-SCONN288_DDR506112002KQ,SMA   I139 @T6G_MB_LIB.T6G(SCH_1):PAGE107
   J99  230 VSS100 SCONN288_DDR506112002KQ-SCONN288_DDR506112002KQ,SMA   I139 @T6G_MB_LIB.T6G(SCH_1):PAGE107
   J99  233 VSS101 SCONN288_DDR506112002KQ-SCONN288_DDR506112002KQ,SMA   I139 @T6G_MB_LIB.T6G(SCH_1):PAGE107
   J99  235 VSS102 SCONN288_DDR506112002KQ-SCONN288_DDR506112002KQ,SMA   I139 @T6G_MB_LIB.T6G(SCH_1):PAGE107
   J99  237 VSS103 SCONN288_DDR506112002KQ-SCONN288_DDR506112002KQ,SMA   I139 @T6G_MB_LIB.T6G(SCH_1):PAGE107
   J99  240 VSS104 SCONN288_DDR506112002KQ-SCONN288_DDR506112002KQ,SMA   I139 @T6G_MB_LIB.T6G(SCH_1):PAGE107
   J99  242 VSS105 SCONN288_DDR506112002KQ-SCONN288_DDR506112002KQ,SMA   I139 @T6G_MB_LIB.T6G(SCH_1):PAGE107
   J99  244 VSS106 SCONN288_DDR506112002KQ-SCONN288_DDR506112002KQ,SMA   I139 @T6G_MB_LIB.T6G(SCH_1):PAGE107
   J99  246 VSS107 SCONN288_DDR506112002KQ-SCONN288_DDR506112002KQ,SMA   I139 @T6G_MB_LIB.T6G(SCH_1):PAGE107
   J99  248 VSS108 SCONN288_DDR506112002KQ-SCONN288_DDR506112002KQ,SMA   I139 @T6G_MB_LIB.T6G(SCH_1):PAGE107
   J99  251 VSS109 SCONN288_DDR506112002KQ-SCONN288_DDR506112002KQ,SMA   I139 @T6G_MB_LIB.T6G(SCH_1):PAGE107
   J99  253 VSS110 SCONN288_DDR506112002KQ-SCONN288_DDR506112002KQ,SMA   I139 @T6G_MB_LIB.T6G(SCH_1):PAGE107
   J99  255 VSS111 SCONN288_DDR506112002KQ-SCONN288_DDR506112002KQ,SMA   I139 @T6G_MB_LIB.T6G(SCH_1):PAGE107
   J99  257 VSS112 SCONN288_DDR506112002KQ-SCONN288_DDR506112002KQ,SMA   I139 @T6G_MB_LIB.T6G(SCH_1):PAGE107
   J99  259 VSS113 SCONN288_DDR506112002KQ-SCONN288_DDR506112002KQ,SMA   I139 @T6G_MB_LIB.T6G(SCH_1):PAGE107
   J99  262 VSS114 SCONN288_DDR506112002KQ-SCONN288_DDR506112002KQ,SMA   I139 @T6G_MB_LIB.T6G(SCH_1):PAGE107
   J99  264 VSS115 SCONN288_DDR506112002KQ-SCONN288_DDR506112002KQ,SMA   I139 @T6G_MB_LIB.T6G(SCH_1):PAGE107
   J99  266 VSS116 SCONN288_DDR506112002KQ-SCONN288_DDR506112002KQ,SMA   I139 @T6G_MB_LIB.T6G(SCH_1):PAGE107
   J99  268 VSS117 SCONN288_DDR506112002KQ-SCONN288_DDR506112002KQ,SMA   I139 @T6G_MB_LIB.T6G(SCH_1):PAGE107
   J99  270 VSS118 SCONN288_DDR506112002KQ-SCONN288_DDR506112002KQ,SMA   I139 @T6G_MB_LIB.T6G(SCH_1):PAGE107
   J99  273 VSS119 SCONN288_DDR506112002KQ-SCONN288_DDR506112002KQ,SMA   I139 @T6G_MB_LIB.T6G(SCH_1):PAGE107
   J99  275 VSS120 SCONN288_DDR506112002KQ-SCONN288_DDR506112002KQ,SMA   I139 @T6G_MB_LIB.T6G(SCH_1):PAGE107
   J99  277 VSS121 SCONN288_DDR506112002KQ-SCONN288_DDR506112002KQ,SMA   I139 @T6G_MB_LIB.T6G(SCH_1):PAGE107
   J99  279 VSS122 SCONN288_DDR506112002KQ-SCONN288_DDR506112002KQ,SMA   I139 @T6G_MB_LIB.T6G(SCH_1):PAGE107
   J99  281 VSS123 SCONN288_DDR506112002KQ-SCONN288_DDR506112002KQ,SMA   I139 @T6G_MB_LIB.T6G(SCH_1):PAGE107
   J99  284 VSS124 SCONN288_DDR506112002KQ-SCONN288_DDR506112002KQ,SMA   I139 @T6G_MB_LIB.T6G(SCH_1):PAGE107
   J99  286 VSS125 SCONN288_DDR506112002KQ-SCONN288_DDR506112002KQ,SMA   I139 @T6G_MB_LIB.T6G(SCH_1):PAGE107
   J99  288 VSS126 SCONN288_DDR506112002KQ-SCONN288_DDR506112002KQ,SMA   I139 @T6G_MB_LIB.T6G(SCH_1):PAGE107
  C176    2      B Q_CAP_0402-0.1UF,25V,10%,X7R,CH4104K1B00   I185 @T6G_MB_LIB.T6G(SCH_1):PAGE107
  C546    2      B Q_CAP_C0805-10UF,25V,10%,X6S,CH6104KEA00   I237 @T6G_MB_LIB.T6G(SCH_1):PAGE107
  C547    2      B Q_CAP_C0805-10UF,25V,10%,X6S,CH6104KEA00   I238 @T6G_MB_LIB.T6G(SCH_1):PAGE107
  R778    2      B Q_RES_0402LF-84.5K,1%,1/16W,CHIP,CS38452FB05   I136 @T6G_MB_LIB.T6G(SCH_1):PAGE108
   J37   G1     G1 SCONN288_DDR506112002KQ-SCONN288_DDR506112002KQ,SMA   I138 @T6G_MB_LIB.T6G(SCH_1):PAGE108
   J37   G2     G2 SCONN288_DDR506112002KQ-SCONN288_DDR506112002KQ,SMA   I138 @T6G_MB_LIB.T6G(SCH_1):PAGE108
   J37   G3     G3 SCONN288_DDR506112002KQ-SCONN288_DDR506112002KQ,SMA   I138 @T6G_MB_LIB.T6G(SCH_1):PAGE108
   J37    6   VSS0 SCONN288_DDR506112002KQ-SCONN288_DDR506112002KQ,SMA   I138 @T6G_MB_LIB.T6G(SCH_1):PAGE108
   J37    8   VSS1 SCONN288_DDR506112002KQ-SCONN288_DDR506112002KQ,SMA   I138 @T6G_MB_LIB.T6G(SCH_1):PAGE108
   J37   10   VSS2 SCONN288_DDR506112002KQ-SCONN288_DDR506112002KQ,SMA   I138 @T6G_MB_LIB.T6G(SCH_1):PAGE108
   J37   13   VSS3 SCONN288_DDR506112002KQ-SCONN288_DDR506112002KQ,SMA   I138 @T6G_MB_LIB.T6G(SCH_1):PAGE108
   J37   15   VSS4 SCONN288_DDR506112002KQ-SCONN288_DDR506112002KQ,SMA   I138 @T6G_MB_LIB.T6G(SCH_1):PAGE108
   J37   17   VSS5 SCONN288_DDR506112002KQ-SCONN288_DDR506112002KQ,SMA   I138 @T6G_MB_LIB.T6G(SCH_1):PAGE108
   J37   19   VSS6 SCONN288_DDR506112002KQ-SCONN288_DDR506112002KQ,SMA   I138 @T6G_MB_LIB.T6G(SCH_1):PAGE108
   J37   21   VSS7 SCONN288_DDR506112002KQ-SCONN288_DDR506112002KQ,SMA   I138 @T6G_MB_LIB.T6G(SCH_1):PAGE108
   J37   24   VSS8 SCONN288_DDR506112002KQ-SCONN288_DDR506112002KQ,SMA   I138 @T6G_MB_LIB.T6G(SCH_1):PAGE108
   J37   26   VSS9 SCONN288_DDR506112002KQ-SCONN288_DDR506112002KQ,SMA   I138 @T6G_MB_LIB.T6G(SCH_1):PAGE108
   J37   28  VSS10 SCONN288_DDR506112002KQ-SCONN288_DDR506112002KQ,SMA   I138 @T6G_MB_LIB.T6G(SCH_1):PAGE108
   J37   30  VSS11 SCONN288_DDR506112002KQ-SCONN288_DDR506112002KQ,SMA   I138 @T6G_MB_LIB.T6G(SCH_1):PAGE108
   J37   32  VSS12 SCONN288_DDR506112002KQ-SCONN288_DDR506112002KQ,SMA   I138 @T6G_MB_LIB.T6G(SCH_1):PAGE108
   J37   35  VSS13 SCONN288_DDR506112002KQ-SCONN288_DDR506112002KQ,SMA   I138 @T6G_MB_LIB.T6G(SCH_1):PAGE108
   J37   37  VSS14 SCONN288_DDR506112002KQ-SCONN288_DDR506112002KQ,SMA   I138 @T6G_MB_LIB.T6G(SCH_1):PAGE108
   J37   39  VSS15 SCONN288_DDR506112002KQ-SCONN288_DDR506112002KQ,SMA   I138 @T6G_MB_LIB.T6G(SCH_1):PAGE108
   J37   41  VSS16 SCONN288_DDR506112002KQ-SCONN288_DDR506112002KQ,SMA   I138 @T6G_MB_LIB.T6G(SCH_1):PAGE108
   J37   43  VSS17 SCONN288_DDR506112002KQ-SCONN288_DDR506112002KQ,SMA   I138 @T6G_MB_LIB.T6G(SCH_1):PAGE108
   J37   46  VSS18 SCONN288_DDR506112002KQ-SCONN288_DDR506112002KQ,SMA   I138 @T6G_MB_LIB.T6G(SCH_1):PAGE108
   J37   48  VSS19 SCONN288_DDR506112002KQ-SCONN288_DDR506112002KQ,SMA   I138 @T6G_MB_LIB.T6G(SCH_1):PAGE108
   J37   50  VSS20 SCONN288_DDR506112002KQ-SCONN288_DDR506112002KQ,SMA   I138 @T6G_MB_LIB.T6G(SCH_1):PAGE108
   J37   52  VSS21 SCONN288_DDR506112002KQ-SCONN288_DDR506112002KQ,SMA   I138 @T6G_MB_LIB.T6G(SCH_1):PAGE108
   J37   54  VSS22 SCONN288_DDR506112002KQ-SCONN288_DDR506112002KQ,SMA   I138 @T6G_MB_LIB.T6G(SCH_1):PAGE108
   J37   57  VSS23 SCONN288_DDR506112002KQ-SCONN288_DDR506112002KQ,SMA   I138 @T6G_MB_LIB.T6G(SCH_1):PAGE108
   J37   59  VSS24 SCONN288_DDR506112002KQ-SCONN288_DDR506112002KQ,SMA   I138 @T6G_MB_LIB.T6G(SCH_1):PAGE108
   J37   61  VSS25 SCONN288_DDR506112002KQ-SCONN288_DDR506112002KQ,SMA   I138 @T6G_MB_LIB.T6G(SCH_1):PAGE108
   J37   63  VSS26 SCONN288_DDR506112002KQ-SCONN288_DDR506112002KQ,SMA   I138 @T6G_MB_LIB.T6G(SCH_1):PAGE108
   J37   65  VSS27 SCONN288_DDR506112002KQ-SCONN288_DDR506112002KQ,SMA   I138 @T6G_MB_LIB.T6G(SCH_1):PAGE108
   J37   67  VSS28 SCONN288_DDR506112002KQ-SCONN288_DDR506112002KQ,SMA   I138 @T6G_MB_LIB.T6G(SCH_1):PAGE108
   J37   69  VSS29 SCONN288_DDR506112002KQ-SCONN288_DDR506112002KQ,SMA   I138 @T6G_MB_LIB.T6G(SCH_1):PAGE108
   J37   71  VSS30 SCONN288_DDR506112002KQ-SCONN288_DDR506112002KQ,SMA   I138 @T6G_MB_LIB.T6G(SCH_1):PAGE108
   J37   73  VSS31 SCONN288_DDR506112002KQ-SCONN288_DDR506112002KQ,SMA   I138 @T6G_MB_LIB.T6G(SCH_1):PAGE108
   J37   75  VSS32 SCONN288_DDR506112002KQ-SCONN288_DDR506112002KQ,SMA   I138 @T6G_MB_LIB.T6G(SCH_1):PAGE108
   J37   77  VSS33 SCONN288_DDR506112002KQ-SCONN288_DDR506112002KQ,SMA   I138 @T6G_MB_LIB.T6G(SCH_1):PAGE108
   J37   79  VSS34 SCONN288_DDR506112002KQ-SCONN288_DDR506112002KQ,SMA   I138 @T6G_MB_LIB.T6G(SCH_1):PAGE108
   J37   81  VSS35 SCONN288_DDR506112002KQ-SCONN288_DDR506112002KQ,SMA   I138 @T6G_MB_LIB.T6G(SCH_1):PAGE108
   J37   83  VSS36 SCONN288_DDR506112002KQ-SCONN288_DDR506112002KQ,SMA   I138 @T6G_MB_LIB.T6G(SCH_1):PAGE108
   J37   85  VSS37 SCONN288_DDR506112002KQ-SCONN288_DDR506112002KQ,SMA   I138 @T6G_MB_LIB.T6G(SCH_1):PAGE108
   J37   88  VSS38 SCONN288_DDR506112002KQ-SCONN288_DDR506112002KQ,SMA   I138 @T6G_MB_LIB.T6G(SCH_1):PAGE108
   J37   90  VSS39 SCONN288_DDR506112002KQ-SCONN288_DDR506112002KQ,SMA   I138 @T6G_MB_LIB.T6G(SCH_1):PAGE108
   J37   92  VSS40 SCONN288_DDR506112002KQ-SCONN288_DDR506112002KQ,SMA   I138 @T6G_MB_LIB.T6G(SCH_1):PAGE108
   J37   95  VSS41 SCONN288_DDR506112002KQ-SCONN288_DDR506112002KQ,SMA   I138 @T6G_MB_LIB.T6G(SCH_1):PAGE108
   J37   97  VSS42 SCONN288_DDR506112002KQ-SCONN288_DDR506112002KQ,SMA   I138 @T6G_MB_LIB.T6G(SCH_1):PAGE108
   J37   99  VSS43 SCONN288_DDR506112002KQ-SCONN288_DDR506112002KQ,SMA   I138 @T6G_MB_LIB.T6G(SCH_1):PAGE108
   J37  101  VSS44 SCONN288_DDR506112002KQ-SCONN288_DDR506112002KQ,SMA   I138 @T6G_MB_LIB.T6G(SCH_1):PAGE108
   J37  103  VSS45 SCONN288_DDR506112002KQ-SCONN288_DDR506112002KQ,SMA   I138 @T6G_MB_LIB.T6G(SCH_1):PAGE108
   J37  106  VSS46 SCONN288_DDR506112002KQ-SCONN288_DDR506112002KQ,SMA   I138 @T6G_MB_LIB.T6G(SCH_1):PAGE108
   J37  108  VSS47 SCONN288_DDR506112002KQ-SCONN288_DDR506112002KQ,SMA   I138 @T6G_MB_LIB.T6G(SCH_1):PAGE108
   J37  110  VSS48 SCONN288_DDR506112002KQ-SCONN288_DDR506112002KQ,SMA   I138 @T6G_MB_LIB.T6G(SCH_1):PAGE108
   J37  112  VSS49 SCONN288_DDR506112002KQ-SCONN288_DDR506112002KQ,SMA   I138 @T6G_MB_LIB.T6G(SCH_1):PAGE108
   J37  114  VSS50 SCONN288_DDR506112002KQ-SCONN288_DDR506112002KQ,SMA   I138 @T6G_MB_LIB.T6G(SCH_1):PAGE108
   J37  117  VSS51 SCONN288_DDR506112002KQ-SCONN288_DDR506112002KQ,SMA   I138 @T6G_MB_LIB.T6G(SCH_1):PAGE108
   J37  119  VSS52 SCONN288_DDR506112002KQ-SCONN288_DDR506112002KQ,SMA   I138 @T6G_MB_LIB.T6G(SCH_1):PAGE108
   J37  121  VSS53 SCONN288_DDR506112002KQ-SCONN288_DDR506112002KQ,SMA   I138 @T6G_MB_LIB.T6G(SCH_1):PAGE108
   J37  123  VSS54 SCONN288_DDR506112002KQ-SCONN288_DDR506112002KQ,SMA   I138 @T6G_MB_LIB.T6G(SCH_1):PAGE108
   J37  125  VSS55 SCONN288_DDR506112002KQ-SCONN288_DDR506112002KQ,SMA   I138 @T6G_MB_LIB.T6G(SCH_1):PAGE108
   J37  128  VSS56 SCONN288_DDR506112002KQ-SCONN288_DDR506112002KQ,SMA   I138 @T6G_MB_LIB.T6G(SCH_1):PAGE108
   J37  130  VSS57 SCONN288_DDR506112002KQ-SCONN288_DDR506112002KQ,SMA   I138 @T6G_MB_LIB.T6G(SCH_1):PAGE108
   J37  132  VSS58 SCONN288_DDR506112002KQ-SCONN288_DDR506112002KQ,SMA   I138 @T6G_MB_LIB.T6G(SCH_1):PAGE108
   J37  134  VSS59 SCONN288_DDR506112002KQ-SCONN288_DDR506112002KQ,SMA   I138 @T6G_MB_LIB.T6G(SCH_1):PAGE108
   J37  136  VSS60 SCONN288_DDR506112002KQ-SCONN288_DDR506112002KQ,SMA   I138 @T6G_MB_LIB.T6G(SCH_1):PAGE108
   J37  139  VSS61 SCONN288_DDR506112002KQ-SCONN288_DDR506112002KQ,SMA   I138 @T6G_MB_LIB.T6G(SCH_1):PAGE108
   J37  141  VSS62 SCONN288_DDR506112002KQ-SCONN288_DDR506112002KQ,SMA   I138 @T6G_MB_LIB.T6G(SCH_1):PAGE108
   J37  143  VSS63 SCONN288_DDR506112002KQ-SCONN288_DDR506112002KQ,SMA   I138 @T6G_MB_LIB.T6G(SCH_1):PAGE108
   J37  151  VSS64 SCONN288_DDR506112002KQ-SCONN288_DDR506112002KQ,SMA   I138 @T6G_MB_LIB.T6G(SCH_1):PAGE108
   J37  153  VSS65 SCONN288_DDR506112002KQ-SCONN288_DDR506112002KQ,SMA   I138 @T6G_MB_LIB.T6G(SCH_1):PAGE108
   J37  155  VSS66 SCONN288_DDR506112002KQ-SCONN288_DDR506112002KQ,SMA   I138 @T6G_MB_LIB.T6G(SCH_1):PAGE108
   J37  158  VSS67 SCONN288_DDR506112002KQ-SCONN288_DDR506112002KQ,SMA   I138 @T6G_MB_LIB.T6G(SCH_1):PAGE108
   J37  160  VSS68 SCONN288_DDR506112002KQ-SCONN288_DDR506112002KQ,SMA   I138 @T6G_MB_LIB.T6G(SCH_1):PAGE108
   J37  162  VSS69 SCONN288_DDR506112002KQ-SCONN288_DDR506112002KQ,SMA   I138 @T6G_MB_LIB.T6G(SCH_1):PAGE108
   J37  164  VSS70 SCONN288_DDR506112002KQ-SCONN288_DDR506112002KQ,SMA   I138 @T6G_MB_LIB.T6G(SCH_1):PAGE108
   J37  166  VSS71 SCONN288_DDR506112002KQ-SCONN288_DDR506112002KQ,SMA   I138 @T6G_MB_LIB.T6G(SCH_1):PAGE108
   J37  169  VSS72 SCONN288_DDR506112002KQ-SCONN288_DDR506112002KQ,SMA   I138 @T6G_MB_LIB.T6G(SCH_1):PAGE108
   J37  171  VSS73 SCONN288_DDR506112002KQ-SCONN288_DDR506112002KQ,SMA   I138 @T6G_MB_LIB.T6G(SCH_1):PAGE108
   J37  173  VSS74 SCONN288_DDR506112002KQ-SCONN288_DDR506112002KQ,SMA   I138 @T6G_MB_LIB.T6G(SCH_1):PAGE108
   J37  175  VSS75 SCONN288_DDR506112002KQ-SCONN288_DDR506112002KQ,SMA   I138 @T6G_MB_LIB.T6G(SCH_1):PAGE108
   J37  177  VSS76 SCONN288_DDR506112002KQ-SCONN288_DDR506112002KQ,SMA   I138 @T6G_MB_LIB.T6G(SCH_1):PAGE108
   J37  180  VSS77 SCONN288_DDR506112002KQ-SCONN288_DDR506112002KQ,SMA   I138 @T6G_MB_LIB.T6G(SCH_1):PAGE108
   J37  182  VSS78 SCONN288_DDR506112002KQ-SCONN288_DDR506112002KQ,SMA   I138 @T6G_MB_LIB.T6G(SCH_1):PAGE108
   J37  184  VSS79 SCONN288_DDR506112002KQ-SCONN288_DDR506112002KQ,SMA   I138 @T6G_MB_LIB.T6G(SCH_1):PAGE108
   J37  186  VSS80 SCONN288_DDR506112002KQ-SCONN288_DDR506112002KQ,SMA   I138 @T6G_MB_LIB.T6G(SCH_1):PAGE108
   J37  188  VSS81 SCONN288_DDR506112002KQ-SCONN288_DDR506112002KQ,SMA   I138 @T6G_MB_LIB.T6G(SCH_1):PAGE108
   J37  191  VSS82 SCONN288_DDR506112002KQ-SCONN288_DDR506112002KQ,SMA   I138 @T6G_MB_LIB.T6G(SCH_1):PAGE108
   J37  193  VSS83 SCONN288_DDR506112002KQ-SCONN288_DDR506112002KQ,SMA   I138 @T6G_MB_LIB.T6G(SCH_1):PAGE108
   J37  195  VSS84 SCONN288_DDR506112002KQ-SCONN288_DDR506112002KQ,SMA   I138 @T6G_MB_LIB.T6G(SCH_1):PAGE108
   J37  197  VSS85 SCONN288_DDR506112002KQ-SCONN288_DDR506112002KQ,SMA   I138 @T6G_MB_LIB.T6G(SCH_1):PAGE108
   J37  199  VSS86 SCONN288_DDR506112002KQ-SCONN288_DDR506112002KQ,SMA   I138 @T6G_MB_LIB.T6G(SCH_1):PAGE108
   J37  202  VSS87 SCONN288_DDR506112002KQ-SCONN288_DDR506112002KQ,SMA   I138 @T6G_MB_LIB.T6G(SCH_1):PAGE108
   J37  204  VSS88 SCONN288_DDR506112002KQ-SCONN288_DDR506112002KQ,SMA   I138 @T6G_MB_LIB.T6G(SCH_1):PAGE108
   J37  206  VSS89 SCONN288_DDR506112002KQ-SCONN288_DDR506112002KQ,SMA   I138 @T6G_MB_LIB.T6G(SCH_1):PAGE108
   J37  208  VSS90 SCONN288_DDR506112002KQ-SCONN288_DDR506112002KQ,SMA   I138 @T6G_MB_LIB.T6G(SCH_1):PAGE108
   J37  210  VSS91 SCONN288_DDR506112002KQ-SCONN288_DDR506112002KQ,SMA   I138 @T6G_MB_LIB.T6G(SCH_1):PAGE108
   J37  212  VSS92 SCONN288_DDR506112002KQ-SCONN288_DDR506112002KQ,SMA   I138 @T6G_MB_LIB.T6G(SCH_1):PAGE108
   J37  214  VSS93 SCONN288_DDR506112002KQ-SCONN288_DDR506112002KQ,SMA   I138 @T6G_MB_LIB.T6G(SCH_1):PAGE108
   J37  216  VSS94 SCONN288_DDR506112002KQ-SCONN288_DDR506112002KQ,SMA   I138 @T6G_MB_LIB.T6G(SCH_1):PAGE108
   J37  219  VSS95 SCONN288_DDR506112002KQ-SCONN288_DDR506112002KQ,SMA   I138 @T6G_MB_LIB.T6G(SCH_1):PAGE108
   J37  222  VSS96 SCONN288_DDR506112002KQ-SCONN288_DDR506112002KQ,SMA   I138 @T6G_MB_LIB.T6G(SCH_1):PAGE108
   J37  224  VSS97 SCONN288_DDR506112002KQ-SCONN288_DDR506112002KQ,SMA   I138 @T6G_MB_LIB.T6G(SCH_1):PAGE108
   J37  226  VSS98 SCONN288_DDR506112002KQ-SCONN288_DDR506112002KQ,SMA   I138 @T6G_MB_LIB.T6G(SCH_1):PAGE108
   J37  228  VSS99 SCONN288_DDR506112002KQ-SCONN288_DDR506112002KQ,SMA   I138 @T6G_MB_LIB.T6G(SCH_1):PAGE108
   J37  230 VSS100 SCONN288_DDR506112002KQ-SCONN288_DDR506112002KQ,SMA   I138 @T6G_MB_LIB.T6G(SCH_1):PAGE108
   J37  233 VSS101 SCONN288_DDR506112002KQ-SCONN288_DDR506112002KQ,SMA   I138 @T6G_MB_LIB.T6G(SCH_1):PAGE108
   J37  235 VSS102 SCONN288_DDR506112002KQ-SCONN288_DDR506112002KQ,SMA   I138 @T6G_MB_LIB.T6G(SCH_1):PAGE108
   J37  237 VSS103 SCONN288_DDR506112002KQ-SCONN288_DDR506112002KQ,SMA   I138 @T6G_MB_LIB.T6G(SCH_1):PAGE108
   J37  240 VSS104 SCONN288_DDR506112002KQ-SCONN288_DDR506112002KQ,SMA   I138 @T6G_MB_LIB.T6G(SCH_1):PAGE108
   J37  242 VSS105 SCONN288_DDR506112002KQ-SCONN288_DDR506112002KQ,SMA   I138 @T6G_MB_LIB.T6G(SCH_1):PAGE108
   J37  244 VSS106 SCONN288_DDR506112002KQ-SCONN288_DDR506112002KQ,SMA   I138 @T6G_MB_LIB.T6G(SCH_1):PAGE108
   J37  246 VSS107 SCONN288_DDR506112002KQ-SCONN288_DDR506112002KQ,SMA   I138 @T6G_MB_LIB.T6G(SCH_1):PAGE108
   J37  248 VSS108 SCONN288_DDR506112002KQ-SCONN288_DDR506112002KQ,SMA   I138 @T6G_MB_LIB.T6G(SCH_1):PAGE108
   J37  251 VSS109 SCONN288_DDR506112002KQ-SCONN288_DDR506112002KQ,SMA   I138 @T6G_MB_LIB.T6G(SCH_1):PAGE108
   J37  253 VSS110 SCONN288_DDR506112002KQ-SCONN288_DDR506112002KQ,SMA   I138 @T6G_MB_LIB.T6G(SCH_1):PAGE108
   J37  255 VSS111 SCONN288_DDR506112002KQ-SCONN288_DDR506112002KQ,SMA   I138 @T6G_MB_LIB.T6G(SCH_1):PAGE108
   J37  257 VSS112 SCONN288_DDR506112002KQ-SCONN288_DDR506112002KQ,SMA   I138 @T6G_MB_LIB.T6G(SCH_1):PAGE108
   J37  259 VSS113 SCONN288_DDR506112002KQ-SCONN288_DDR506112002KQ,SMA   I138 @T6G_MB_LIB.T6G(SCH_1):PAGE108
   J37  262 VSS114 SCONN288_DDR506112002KQ-SCONN288_DDR506112002KQ,SMA   I138 @T6G_MB_LIB.T6G(SCH_1):PAGE108
   J37  264 VSS115 SCONN288_DDR506112002KQ-SCONN288_DDR506112002KQ,SMA   I138 @T6G_MB_LIB.T6G(SCH_1):PAGE108
   J37  266 VSS116 SCONN288_DDR506112002KQ-SCONN288_DDR506112002KQ,SMA   I138 @T6G_MB_LIB.T6G(SCH_1):PAGE108
   J37  268 VSS117 SCONN288_DDR506112002KQ-SCONN288_DDR506112002KQ,SMA   I138 @T6G_MB_LIB.T6G(SCH_1):PAGE108
   J37  270 VSS118 SCONN288_DDR506112002KQ-SCONN288_DDR506112002KQ,SMA   I138 @T6G_MB_LIB.T6G(SCH_1):PAGE108
   J37  273 VSS119 SCONN288_DDR506112002KQ-SCONN288_DDR506112002KQ,SMA   I138 @T6G_MB_LIB.T6G(SCH_1):PAGE108
   J37  275 VSS120 SCONN288_DDR506112002KQ-SCONN288_DDR506112002KQ,SMA   I138 @T6G_MB_LIB.T6G(SCH_1):PAGE108
   J37  277 VSS121 SCONN288_DDR506112002KQ-SCONN288_DDR506112002KQ,SMA   I138 @T6G_MB_LIB.T6G(SCH_1):PAGE108
   J37  279 VSS122 SCONN288_DDR506112002KQ-SCONN288_DDR506112002KQ,SMA   I138 @T6G_MB_LIB.T6G(SCH_1):PAGE108
   J37  281 VSS123 SCONN288_DDR506112002KQ-SCONN288_DDR506112002KQ,SMA   I138 @T6G_MB_LIB.T6G(SCH_1):PAGE108
   J37  284 VSS124 SCONN288_DDR506112002KQ-SCONN288_DDR506112002KQ,SMA   I138 @T6G_MB_LIB.T6G(SCH_1):PAGE108
   J37  286 VSS125 SCONN288_DDR506112002KQ-SCONN288_DDR506112002KQ,SMA   I138 @T6G_MB_LIB.T6G(SCH_1):PAGE108
   J37  288 VSS126 SCONN288_DDR506112002KQ-SCONN288_DDR506112002KQ,SMA   I138 @T6G_MB_LIB.T6G(SCH_1):PAGE108
  C180    2      B Q_CAP_0402-0.1UF,25V,10%,X7R,CH4104K1B00   I185 @T6G_MB_LIB.T6G(SCH_1):PAGE108
  C548    2      B Q_CAP_C0805-10UF,25V,10%,X6S,CH6104KEA00   I237 @T6G_MB_LIB.T6G(SCH_1):PAGE108
  C549    2      B Q_CAP_C0805-10UF,25V,10%,X6S,CH6104KEA00   I238 @T6G_MB_LIB.T6G(SCH_1):PAGE108
    Q4    1     S1 MOSFET_DUAL_6P-2N7002KDW,SMLF,IC,BAM70020047    I12 @T6G_MB_LIB.T6G(SCH_1):PAGE132
    Q4    4     S2 MOSFET_DUAL_6P-2N7002KDW,SMLF,IC,BAM70020047    I12 @T6G_MB_LIB.T6G(SCH_1):PAGE132
  U105    5    GND PI3CSW12ZUAEX-PI3CSW12ZUAEX,SMLF,IC,AL3CSW12000    I47 @T6G_MB_LIB.T6G(SCH_1):PAGE136
 C1336    2      B Q_CAP_0402-0.1UF,25V,10%,X7R,CH4104K1B00    I50 @T6G_MB_LIB.T6G(SCH_1):PAGE136
  U106    5    GND PI3CSW12ZUAEX-PI3CSW12ZUAEX,SMLF,IC,AL3CSW12000    I54 @T6G_MB_LIB.T6G(SCH_1):PAGE136
 C1337    2      B Q_CAP_0402-0.1UF,25V,10%,X7R,CH4104K1B00    I56 @T6G_MB_LIB.T6G(SCH_1):PAGE136
 C1338    2      B Q_CAP_0402-0.1UF,25V,10%,X7R,CH4104K1B00    I61 @T6G_MB_LIB.T6G(SCH_1):PAGE136
  U107    5    GND PI3CSW12ZUAEX-PI3CSW12ZUAEX,SMLF,IC,AL3CSW12000    I63 @T6G_MB_LIB.T6G(SCH_1):PAGE136
 C1339    2      B Q_CAP_0402-0.1UF,25V,10%,X7R,CH4104K1B00    I66 @T6G_MB_LIB.T6G(SCH_1):PAGE136
  U108    5    GND PI3CSW12ZUAEX-PI3CSW12ZUAEX,SMLF,IC,AL3CSW12000    I68 @T6G_MB_LIB.T6G(SCH_1):PAGE136
 R5004    2      B Q_RES_0402LF-10K,1%,1/16W,CHIP,CS31002FB08    I27 @T6G_MB_LIB.T6G(SCH_1):PAGE138
   Q61    S SOURCE MOSFET_N_GSD-NX138BK,SMLF,IC,BAM01380023    I89 @T6G_MB_LIB.T6G(SCH_1):PAGE141
  U116    2   DIR2 SN74AVC4T774PWR-SN74AVC4T774PWR,SMLF,IC,AL04T774K00   I117 @T6G_MB_LIB.T6G(SCH_1):PAGE141
  U116    8   DIR4 SN74AVC4T774PWR-SN74AVC4T774PWR,SMLF,IC,AL04T774K00   I117 @T6G_MB_LIB.T6G(SCH_1):PAGE141
  U116   10    GND SN74AVC4T774PWR-SN74AVC4T774PWR,SMLF,IC,AL04T774K00   I117 @T6G_MB_LIB.T6G(SCH_1):PAGE141
 C1354    2      B Q_CAP_0402-0.1UF,25V,10%,X7R,CH4104K1B00   I133 @T6G_MB_LIB.T6G(SCH_1):PAGE141
 C1352    2      B Q_CAP_0402-0.1UF,25V,10%,X7R,CH4104K1B00   I137 @T6G_MB_LIB.T6G(SCH_1):PAGE141
  C364    2      B Q_CAP_C0402-220PF,50V,5%,C0G,CH12206JB00   I187 @T6G_MB_LIB.T6G(SCH_1):PAGE141
  C363    2      B Q_CAP_C0402-220PF,50V,5%,C0G,CH12206JB00   I190 @T6G_MB_LIB.T6G(SCH_1):PAGE141
   J13    4      4 CONN4_HFK1040L0P1L7H-CONN4_HFK1040-L0P1L-7H,THLF,IA   I195 @T6G_MB_LIB.T6G(SCH_1):PAGE141
    Q2    1     S1 MOSFET_DUAL_6P-2N7002KDW,SMLF,IC,BAM70020047    I16 @T6G_MB_LIB.T6G(SCH_1):PAGE143
    Q2    4     S2 MOSFET_DUAL_6P-2N7002KDW,SMLF,IC,BAM70020047    I16 @T6G_MB_LIB.T6G(SCH_1):PAGE143
   Q11    1     S1 MOSFET_DUAL_6P-2N7002KDW,SMLF,IC,BAM70020047    I19 @T6G_MB_LIB.T6G(SCH_1):PAGE143
   Q11    4     S2 MOSFET_DUAL_6P-2N7002KDW,SMLF,IC,BAM70020047    I19 @T6G_MB_LIB.T6G(SCH_1):PAGE143
  C218    2      B Q_CAP_0402-0.1UF,25V,10%,X7R,CH4104K1B00    I24 @T6G_MB_LIB.T6G(SCH_1):PAGE143
   U82    3    GND SN74LVC1G07DBVR_SMLF-SN74LVC1G07DBVR,IC,AL1G0007024    I26 @T6G_MB_LIB.T6G(SCH_1):PAGE143
  C219    2      B Q_CAP_0402-0.1UF,25V,10%,X7R,CH4104K1B00    I29 @T6G_MB_LIB.T6G(SCH_1):PAGE143
   U86    3    GND SN74LVC1G07DBVR_SMLF-SN74LVC1G07DBVR,IC,AL1G0007024    I31 @T6G_MB_LIB.T6G(SCH_1):PAGE143
   D49    C      C Q_LED_SMLF-LED_BLUE,LTST-C281TBKT-5A,IC,BEBL0172Z00    I38 @T6G_MB_LIB.T6G(SCH_1):PAGE143
   Q12    S SOURCE MOSFET_N_GSD-NX138BK,SMLF,IC,BAM01380023    I44 @T6G_MB_LIB.T6G(SCH_1):PAGE143
  U124    3    GND SN74LVC1G07DBVR_SMLF-SN74LVC1G07DBVR,IC,AL1G0007024    I38 @T6G_MB_LIB.T6G(SCH_1):PAGE144
  C693    2      B Q_CAP_0402-0.1UF,25V,10%,X7R,CH4104K1B00    I39 @T6G_MB_LIB.T6G(SCH_1):PAGE144
 R1735    2      B Q_RES_0402LF-10K,1%,1/16W,EMPTY,CS31002FB08   I246 @T6G_MB_LIB.T6G(SCH_1):PAGE148
 R1748    2      B Q_RES_0402LF-10K,1%,1/16W,EMPTY,CS31002FB08   I258 @T6G_MB_LIB.T6G(SCH_1):PAGE148
  U160    8    GND 74LV4052PW-74LV4052PW,SMLF,IC,ALLV4052K19   I266 @T6G_MB_LIB.T6G(SCH_1):PAGE148
  U160    7    VEE 74LV4052PW-74LV4052PW,SMLF,IC,ALLV4052K19   I266 @T6G_MB_LIB.T6G(SCH_1):PAGE148
 C1554    2      B Q_CAP_C0402-0.1UF,16V,10%,X7R,CH4103K1B08   I293 @T6G_MB_LIB.T6G(SCH_1):PAGE148
  C194    2      B Q_CAP_C0402-0.1UF,16V,10%,X7R,CH4103K1B08   I299 @T6G_MB_LIB.T6G(SCH_1):PAGE148
  U212    8    GND 74LV4052PW-74LV4052PW,SMLF,IC,ALLV4052K19   I302 @T6G_MB_LIB.T6G(SCH_1):PAGE148
  U212    7    VEE 74LV4052PW-74LV4052PW,SMLF,IC,ALLV4052K19   I302 @T6G_MB_LIB.T6G(SCH_1):PAGE148
 R1729    2      B Q_RES_0402LF-4.7K,5%,1/16W,CHIP,CS24702JB10   I306 @T6G_MB_LIB.T6G(SCH_1):PAGE148
 R1658    2      B Q_RES_0402LF-4.7K,5%,1/16W,CHIP,CS24702JB10   I310 @T6G_MB_LIB.T6G(SCH_1):PAGE148
   U99    3    GND SN74LVC1G07DBVR_SMLF-SN74LVC1G07DBVR,EMPTY,AL1G000A   I340 @T6G_MB_LIB.T6G(SCH_1):PAGE148
  C553    2      B Q_CAP_0402-0.1UF,25V,10%,X7R,CH4104K1B00   I342 @T6G_MB_LIB.T6G(SCH_1):PAGE148
  U147    1   DIR2 SN74AVC2T245RSWR-SN74AVC2T245RSWR,SMLF,IC,AL02T245A     I1 @T6G_MB_LIB.T6G(SCH_1):PAGE149
  U147    3    GND SN74AVC2T245RSWR-SN74AVC2T245RSWR,SMLF,IC,AL02T245A     I1 @T6G_MB_LIB.T6G(SCH_1):PAGE149
 C1509    2      B Q_CAP_C0402-0.1UF,16V,10%,X7R,CH4103K1B08    I10 @T6G_MB_LIB.T6G(SCH_1):PAGE149
 C1512    2      B Q_CAP_0402-33PF,50V,5%,NPO,TMP_QCH03306JB04    I21 @T6G_MB_LIB.T6G(SCH_1):PAGE149
 C1511    2      B Q_CAP_0402-33PF,50V,5%,NPO,TMP_QCH03306JB04    I23 @T6G_MB_LIB.T6G(SCH_1):PAGE149
 C1510    2      B Q_CAP_0402-33PF,50V,5%,NPO,TMP_QCH03306JB04    I25 @T6G_MB_LIB.T6G(SCH_1):PAGE149
 C1508    2      B Q_CAP_C0402-0.1UF,16V,10%,X7R,CH4103K1B08    I29 @T6G_MB_LIB.T6G(SCH_1):PAGE149
  U149   10    GND SN74AVC4T774PWR-SN74AVC4T774PWR,SMLF,IC,AL04T774K00    I31 @T6G_MB_LIB.T6G(SCH_1):PAGE149
  U148   10    GND SN74AVC4T774PWR-SN74AVC4T774PWR,SMLF,IC,AL04T774K00    I34 @T6G_MB_LIB.T6G(SCH_1):PAGE149
 C1507    2      B Q_CAP_C0402-0.1UF,16V,10%,X7R,CH4103K1B08    I41 @T6G_MB_LIB.T6G(SCH_1):PAGE149
 C1504    2      B Q_CAP_C0402-0.1UF,16V,10%,X7R,CH4103K1B08    I56 @T6G_MB_LIB.T6G(SCH_1):PAGE149
 C1506    2      B Q_CAP_C0402-0.1UF,16V,10%,X7R,CH4103K1B08    I62 @T6G_MB_LIB.T6G(SCH_1):PAGE149
 C1505    2      B Q_CAP_C0402-0.1UF,16V,10%,X7R,CH4103K1B08    I74 @T6G_MB_LIB.T6G(SCH_1):PAGE149
  U146    1   DIR2 SN74AVC2T245RSWR-SN74AVC2T245RSWR,SMLF,IC,AL02T245A    I76 @T6G_MB_LIB.T6G(SCH_1):PAGE149
  U146    3    GND SN74AVC2T245RSWR-SN74AVC2T245RSWR,SMLF,IC,AL02T245A    I76 @T6G_MB_LIB.T6G(SCH_1):PAGE149
 C1503    2      B Q_CAP_C0402-0.1UF,16V,10%,X7R,CH4103K1B08    I80 @T6G_MB_LIB.T6G(SCH_1):PAGE149
   Q62    S SOURCE MOSFET_N_SMLF-BSS138K,BSS138K,IC,BAM138K0000   I102 @T6G_MB_LIB.T6G(SCH_1):PAGE149
 R1629    2      B Q_RES_0402LF-1K,1%,1/16W,CHIP,CS21002FB06   I112 @T6G_MB_LIB.T6G(SCH_1):PAGE149
  C551    2      B Q_CAP_C0402-0.01UF,50V,10%,X7R,CH31006KB18   I123 @T6G_MB_LIB.T6G(SCH_1):PAGE149
   C87    2      B Q_CAP_C0402-0.001UF,50V,10%,X7R,CH30106KB19   I134 @T6G_MB_LIB.T6G(SCH_1):PAGE149
  C605    2      B Q_CAP_C0402-0.001UF,50V,10%,X7R,CH30106KB19   I137 @T6G_MB_LIB.T6G(SCH_1):PAGE149
  C604    2      B Q_CAP_C0402-0.001UF,50V,10%,X7R,CH30106KB19   I140 @T6G_MB_LIB.T6G(SCH_1):PAGE149
   J54    5      5 SCONN20_HSU2101L00007H-SCONN20_HSU2101-L0000-7H,SMA   I142 @T6G_MB_LIB.T6G(SCH_1):PAGE149
   J54    7      7 SCONN20_HSU2101L00007H-SCONN20_HSU2101-L0000-7H,SMA   I142 @T6G_MB_LIB.T6G(SCH_1):PAGE149
   J54   17     17 SCONN20_HSU2101L00007H-SCONN20_HSU2101-L0000-7H,SMA   I142 @T6G_MB_LIB.T6G(SCH_1):PAGE149
   C85    2      B Q_CAP_C0402-0.001UF,50V,10%,X7R,CH30106KB19   I152 @T6G_MB_LIB.T6G(SCH_1):PAGE149
  U150   10    GND SN74AVC4T774PWR-SN74AVC4T774PWR,SMLF,IC,AL04T774K00     I8 @T6G_MB_LIB.T6G(SCH_1):PAGE150
 C1516    2      B Q_CAP_C0402-0.1UF,16V,10%,X7R,CH4103K1B08    I14 @T6G_MB_LIB.T6G(SCH_1):PAGE150
 C1514    2      B Q_CAP_C0402-0.1UF,16V,10%,X7R,CH4103K1B08    I19 @T6G_MB_LIB.T6G(SCH_1):PAGE150
  U151   10    GND SN74AVC4T774PWR-SN74AVC4T774PWR,SMLF,IC,AL04T774K00    I28 @T6G_MB_LIB.T6G(SCH_1):PAGE150
 C1517    2      B Q_CAP_C0402-0.1UF,16V,10%,X7R,CH4103K1B08    I40 @T6G_MB_LIB.T6G(SCH_1):PAGE150
 C1515    2      B Q_CAP_C0402-0.1UF,16V,10%,X7R,CH4103K1B08    I43 @T6G_MB_LIB.T6G(SCH_1):PAGE150
  U152    1   DIR2 SN74AVC2T245RSWR-SN74AVC2T245RSWR,SMLF,IC,AL02T245A    I60 @T6G_MB_LIB.T6G(SCH_1):PAGE150
  U152    3    GND SN74AVC2T245RSWR-SN74AVC2T245RSWR,SMLF,IC,AL02T245A    I60 @T6G_MB_LIB.T6G(SCH_1):PAGE150
 C1518    2      B Q_CAP_C0402-0.1UF,16V,10%,X7R,CH4103K1B08    I66 @T6G_MB_LIB.T6G(SCH_1):PAGE150
 C1513    2      B Q_CAP_C0402-0.1UF,16V,10%,X7R,CH4103K1B08    I69 @T6G_MB_LIB.T6G(SCH_1):PAGE150
 R1637    2      B Q_RES_0402LF-4.7K,5%,1/16W,CHIP,CS24702JB10    I71 @T6G_MB_LIB.T6G(SCH_1):PAGE150
  U153    4    GND SN74AUC2G66DCTR-SN74AUC2G66DCTR,SMLF,IC,AL2G0066C00     I1 @T6G_MB_LIB.T6G(SCH_1):PAGE151
 C1520    2      B Q_CAP_C0402-0.01UF,50V,10%,EMPTY,CH31006KB18     I4 @T6G_MB_LIB.T6G(SCH_1):PAGE151
 C1519    2      B Q_CAP_C0402-0.1UF,16V,10%,X7R,CH4103K1B08    I15 @T6G_MB_LIB.T6G(SCH_1):PAGE151
   U13    4    GND SN74AUC2G66DCTR-SN74AUC2G66DCTR,SMLF,IC,AL2G0066C00    I17 @T6G_MB_LIB.T6G(SCH_1):PAGE151
 C1521    2      B Q_CAP_C0402-0.1UF,16V,10%,X7R,CH4103K1B08    I22 @T6G_MB_LIB.T6G(SCH_1):PAGE151
   U14    4    GND SN74AUC2G66DCTR-SN74AUC2G66DCTR,SMLF,IC,AL2G0066C00    I23 @T6G_MB_LIB.T6G(SCH_1):PAGE151
  U154    4    GND SN74AUC2G66DCTR-SN74AUC2G66DCTR,SMLF,IC,AL2G0066C00    I31 @T6G_MB_LIB.T6G(SCH_1):PAGE151
 C1522    2      B Q_CAP_C0402-0.1UF,16V,10%,X7R,CH4103K1B08    I36 @T6G_MB_LIB.T6G(SCH_1):PAGE151
 C1523    2      B Q_CAP_C0402-0.1UF,16V,10%,X7R,CH4103K1B08    I42 @T6G_MB_LIB.T6G(SCH_1):PAGE151
   Q63    S SOURCE MOSFET_N_SMLF-BSS138K,BSS138K,IC,BAM138K0000    I45 @T6G_MB_LIB.T6G(SCH_1):PAGE151
   Q64    S SOURCE MOSFET_N_SMLF-BSS138K,BSS138K,IC,BAM138K0000    I46 @T6G_MB_LIB.T6G(SCH_1):PAGE151
 R1342    2      B Q_RES_0402LF-10K,1%,1/16W,CHIP,CS31002FB08   I369 @T6G_MB_LIB.T6G(SCH_1):PAGE148
   Q29    S SOURCE MOSFET_N_GSD-NX138BK,SMLF,IC,BAM01380023    I80 @T6G_MB_LIB.T6G(SCH_1):PAGE142
   Q30    S SOURCE MOSFET_N_GSD-NX138BK,SMLF,IC,BAM01380023    I81 @T6G_MB_LIB.T6G(SCH_1):PAGE142
PC6002    2      B Q_CAP_0402-0.1UF,25V,10%,X7R,CH4104K1B00     I3 @T6G_MB_LIB.T6G(SCH_1):PAGE201
  C675    2      B Q_CAP_0402-0.1UF,25V,10%,EMPTY,CH4104K1B00     I6 @T6G_MB_LIB.T6G(SCH_1):PAGE201
   PR8    2      B Q_RES_0402LF-8.66K,1%,1/16W,CHIP,CS28662FB02    I11 @T6G_MB_LIB.T6G(SCH_1):PAGE201
   PU3    2   AGND MPQ8633BGLEC838Z-MPQ8633BGLE-C838-Z,SMLF,IC,AL0086A    I15 @T6G_MB_LIB.T6G(SCH_1):PAGE201
   PU3 11_18   PGND MPQ8633BGLEC838Z-MPQ8633BGLE-C838-Z,SMLF,IC,AL0086A    I15 @T6G_MB_LIB.T6G(SCH_1):PAGE201
 PC153    2      B Q_CAP_0402-0.022UF,25V,10%,X7R,CH3224K1B01    I18 @T6G_MB_LIB.T6G(SCH_1):PAGE201
  PC61    2      B Q_CAP_C0805-22UF,16V,20%,X6S,CH6223MEA01    I21 @T6G_MB_LIB.T6G(SCH_1):PAGE201
 PC150    2      B Q_CAP_C0805-22UF,16V,20%,X6S,CH6223MEA01    I22 @T6G_MB_LIB.T6G(SCH_1):PAGE201
 PC152    2      B Q_CAP_C0805-22UF,16V,20%,X6S,CH6223MEA01    I23 @T6G_MB_LIB.T6G(SCH_1):PAGE201
  PC22    2      B Q_CAP_C0402-1UF,25V,10%,X6S,CH5104KEB02    I24 @T6G_MB_LIB.T6G(SCH_1):PAGE201
  PC65    2      B Q_CAP_C0805-22UF,4V,20%,X6S,CH622KMEA03    I37 @T6G_MB_LIB.T6G(SCH_1):PAGE201
  PC83    2      B Q_CAP_C0805-22UF,4V,20%,X6S,CH622KMEA03    I38 @T6G_MB_LIB.T6G(SCH_1):PAGE201
  PC88    2      B Q_CAP_C0805-22UF,4V,20%,EMPTY,CH622KMEA03    I42 @T6G_MB_LIB.T6G(SCH_1):PAGE201
  PC89    2      B Q_CAPP_SMLF-390UF,2.5V,20%,ALUM,CC7390JMZ13    I43 @T6G_MB_LIB.T6G(SCH_1):PAGE201
 PR403    2      B Q_RES_0402LF-1K,1%,1/16W,CHIP,CS21002FB06    I50 @T6G_MB_LIB.T6G(SCH_1):PAGE201
  PC20    2      B Q_CAP_C0402-1UF,25V,10%,X6S,CH5104KEB02    I53 @T6G_MB_LIB.T6G(SCH_1):PAGE201
  R754    1      A Q_RES_0402LF-10K,5%,1/16W,EMPTY,CS31002JB08    I91 @T6G_MB_LIB.T6G(SCH_1):PAGE75
  R760    1      A Q_RES_0402LF-10K,5%,1/16W,CHIP,CS31002JB08    I92 @T6G_MB_LIB.T6G(SCH_1):PAGE75
 R1502    1      A Q_RES_0402LF-10K,5%,1/16W,CHIP,CS31002JB08    I94 @T6G_MB_LIB.T6G(SCH_1):PAGE75
 PR519    2      B Q_RES_0402LF-1.5,1%,1/8W,EMPTY,CS-1504FB00    I25 @T6G_MB_LIB.T6G(SCH_1):PAGE200
PC510_2    2      B Q_CAP_0402-0.1UF,25V,10%,X7R,CH4104K1B00    I29 @T6G_MB_LIB.T6G(SCH_1):PAGE200
PC503_1    2      B Q_CAP_0402-0.1UF,25V,10%,X7R,CH4104K1B00    I34 @T6G_MB_LIB.T6G(SCH_1):PAGE200
 PR328    1      A Q_RES_0402LF-4.87K,1%,1/16W,EMPTY,CS24872FB07    I37 @T6G_MB_LIB.T6G(SCH_1):PAGE200
PC507_11P1_1    2      B Q_CAP_C0402-2.2UF,10V,10%,X6S,CH5222KEB01    I43 @T6G_MB_LIB.T6G(SCH_1):PAGE200
PC509_1    2      B Q_CAP_0402-0.1UF,25V,10%,X7R,CH4104K1B00    I48 @T6G_MB_LIB.T6G(SCH_1):PAGE200
PC518_2    2      B Q_CAP_C0805-22UF,16V,20%,X6S,CH6223MEA01    I52 @T6G_MB_LIB.T6G(SCH_1):PAGE200
 PC528    2      B Q_CAPP_SMLF-470UF,2.5V,20%,SPCAP,CH747LM8825    I63 @T6G_MB_LIB.T6G(SCH_1):PAGE200
PC527_2    2      B Q_CAP_C0805-22UF,4V,20%,X6S,CH622KMEA03    I67 @T6G_MB_LIB.T6G(SCH_1):PAGE200
 PC530    2      B Q_CAPP_SMLF-390UF,2.5V,20%,ALUM,CC7390JMZ13    I69 @T6G_MB_LIB.T6G(SCH_1):PAGE200
 PC522    2      B Q_CAPP_THLF-270UF,16V,20%,OSCON,CC72703MD38    I81 @T6G_MB_LIB.T6G(SCH_1):PAGE200
    J1   G1     G1 SCONN288_DDR506112002KQ-SCONN288_DDR506112002KQ,SMA   I538 @T6G_MB_LIB.T6G(SCH_1):PAGE85
    J1   G2     G2 SCONN288_DDR506112002KQ-SCONN288_DDR506112002KQ,SMA   I538 @T6G_MB_LIB.T6G(SCH_1):PAGE85
    J1   G3     G3 SCONN288_DDR506112002KQ-SCONN288_DDR506112002KQ,SMA   I538 @T6G_MB_LIB.T6G(SCH_1):PAGE85
    J1    6   VSS0 SCONN288_DDR506112002KQ-SCONN288_DDR506112002KQ,SMA   I538 @T6G_MB_LIB.T6G(SCH_1):PAGE85
    J1    8   VSS1 SCONN288_DDR506112002KQ-SCONN288_DDR506112002KQ,SMA   I538 @T6G_MB_LIB.T6G(SCH_1):PAGE85
    J1   10   VSS2 SCONN288_DDR506112002KQ-SCONN288_DDR506112002KQ,SMA   I538 @T6G_MB_LIB.T6G(SCH_1):PAGE85
    J1   13   VSS3 SCONN288_DDR506112002KQ-SCONN288_DDR506112002KQ,SMA   I538 @T6G_MB_LIB.T6G(SCH_1):PAGE85
    J1   15   VSS4 SCONN288_DDR506112002KQ-SCONN288_DDR506112002KQ,SMA   I538 @T6G_MB_LIB.T6G(SCH_1):PAGE85
    J1   17   VSS5 SCONN288_DDR506112002KQ-SCONN288_DDR506112002KQ,SMA   I538 @T6G_MB_LIB.T6G(SCH_1):PAGE85
    J1   19   VSS6 SCONN288_DDR506112002KQ-SCONN288_DDR506112002KQ,SMA   I538 @T6G_MB_LIB.T6G(SCH_1):PAGE85
    J1   21   VSS7 SCONN288_DDR506112002KQ-SCONN288_DDR506112002KQ,SMA   I538 @T6G_MB_LIB.T6G(SCH_1):PAGE85
    J1   24   VSS8 SCONN288_DDR506112002KQ-SCONN288_DDR506112002KQ,SMA   I538 @T6G_MB_LIB.T6G(SCH_1):PAGE85
    J1   26   VSS9 SCONN288_DDR506112002KQ-SCONN288_DDR506112002KQ,SMA   I538 @T6G_MB_LIB.T6G(SCH_1):PAGE85
    J1   28  VSS10 SCONN288_DDR506112002KQ-SCONN288_DDR506112002KQ,SMA   I538 @T6G_MB_LIB.T6G(SCH_1):PAGE85
    J1   30  VSS11 SCONN288_DDR506112002KQ-SCONN288_DDR506112002KQ,SMA   I538 @T6G_MB_LIB.T6G(SCH_1):PAGE85
    J1   32  VSS12 SCONN288_DDR506112002KQ-SCONN288_DDR506112002KQ,SMA   I538 @T6G_MB_LIB.T6G(SCH_1):PAGE85
    J1   35  VSS13 SCONN288_DDR506112002KQ-SCONN288_DDR506112002KQ,SMA   I538 @T6G_MB_LIB.T6G(SCH_1):PAGE85
    J1   37  VSS14 SCONN288_DDR506112002KQ-SCONN288_DDR506112002KQ,SMA   I538 @T6G_MB_LIB.T6G(SCH_1):PAGE85
    J1   39  VSS15 SCONN288_DDR506112002KQ-SCONN288_DDR506112002KQ,SMA   I538 @T6G_MB_LIB.T6G(SCH_1):PAGE85
    J1   41  VSS16 SCONN288_DDR506112002KQ-SCONN288_DDR506112002KQ,SMA   I538 @T6G_MB_LIB.T6G(SCH_1):PAGE85
    J1   43  VSS17 SCONN288_DDR506112002KQ-SCONN288_DDR506112002KQ,SMA   I538 @T6G_MB_LIB.T6G(SCH_1):PAGE85
    J1   46  VSS18 SCONN288_DDR506112002KQ-SCONN288_DDR506112002KQ,SMA   I538 @T6G_MB_LIB.T6G(SCH_1):PAGE85
    J1   48  VSS19 SCONN288_DDR506112002KQ-SCONN288_DDR506112002KQ,SMA   I538 @T6G_MB_LIB.T6G(SCH_1):PAGE85
    J1   50  VSS20 SCONN288_DDR506112002KQ-SCONN288_DDR506112002KQ,SMA   I538 @T6G_MB_LIB.T6G(SCH_1):PAGE85
    J1   52  VSS21 SCONN288_DDR506112002KQ-SCONN288_DDR506112002KQ,SMA   I538 @T6G_MB_LIB.T6G(SCH_1):PAGE85
    J1   54  VSS22 SCONN288_DDR506112002KQ-SCONN288_DDR506112002KQ,SMA   I538 @T6G_MB_LIB.T6G(SCH_1):PAGE85
    J1   57  VSS23 SCONN288_DDR506112002KQ-SCONN288_DDR506112002KQ,SMA   I538 @T6G_MB_LIB.T6G(SCH_1):PAGE85
    J1   59  VSS24 SCONN288_DDR506112002KQ-SCONN288_DDR506112002KQ,SMA   I538 @T6G_MB_LIB.T6G(SCH_1):PAGE85
    J1   61  VSS25 SCONN288_DDR506112002KQ-SCONN288_DDR506112002KQ,SMA   I538 @T6G_MB_LIB.T6G(SCH_1):PAGE85
    J1   63  VSS26 SCONN288_DDR506112002KQ-SCONN288_DDR506112002KQ,SMA   I538 @T6G_MB_LIB.T6G(SCH_1):PAGE85
    J1   65  VSS27 SCONN288_DDR506112002KQ-SCONN288_DDR506112002KQ,SMA   I538 @T6G_MB_LIB.T6G(SCH_1):PAGE85
    J1   67  VSS28 SCONN288_DDR506112002KQ-SCONN288_DDR506112002KQ,SMA   I538 @T6G_MB_LIB.T6G(SCH_1):PAGE85
    J1   69  VSS29 SCONN288_DDR506112002KQ-SCONN288_DDR506112002KQ,SMA   I538 @T6G_MB_LIB.T6G(SCH_1):PAGE85
    J1   71  VSS30 SCONN288_DDR506112002KQ-SCONN288_DDR506112002KQ,SMA   I538 @T6G_MB_LIB.T6G(SCH_1):PAGE85
    J1   73  VSS31 SCONN288_DDR506112002KQ-SCONN288_DDR506112002KQ,SMA   I538 @T6G_MB_LIB.T6G(SCH_1):PAGE85
    J1   75  VSS32 SCONN288_DDR506112002KQ-SCONN288_DDR506112002KQ,SMA   I538 @T6G_MB_LIB.T6G(SCH_1):PAGE85
    J1   77  VSS33 SCONN288_DDR506112002KQ-SCONN288_DDR506112002KQ,SMA   I538 @T6G_MB_LIB.T6G(SCH_1):PAGE85
    J1   79  VSS34 SCONN288_DDR506112002KQ-SCONN288_DDR506112002KQ,SMA   I538 @T6G_MB_LIB.T6G(SCH_1):PAGE85
    J1   81  VSS35 SCONN288_DDR506112002KQ-SCONN288_DDR506112002KQ,SMA   I538 @T6G_MB_LIB.T6G(SCH_1):PAGE85
    J1   83  VSS36 SCONN288_DDR506112002KQ-SCONN288_DDR506112002KQ,SMA   I538 @T6G_MB_LIB.T6G(SCH_1):PAGE85
    J1   85  VSS37 SCONN288_DDR506112002KQ-SCONN288_DDR506112002KQ,SMA   I538 @T6G_MB_LIB.T6G(SCH_1):PAGE85
    J1   88  VSS38 SCONN288_DDR506112002KQ-SCONN288_DDR506112002KQ,SMA   I538 @T6G_MB_LIB.T6G(SCH_1):PAGE85
    J1   90  VSS39 SCONN288_DDR506112002KQ-SCONN288_DDR506112002KQ,SMA   I538 @T6G_MB_LIB.T6G(SCH_1):PAGE85
    J1   92  VSS40 SCONN288_DDR506112002KQ-SCONN288_DDR506112002KQ,SMA   I538 @T6G_MB_LIB.T6G(SCH_1):PAGE85
    J1   95  VSS41 SCONN288_DDR506112002KQ-SCONN288_DDR506112002KQ,SMA   I538 @T6G_MB_LIB.T6G(SCH_1):PAGE85
    J1   97  VSS42 SCONN288_DDR506112002KQ-SCONN288_DDR506112002KQ,SMA   I538 @T6G_MB_LIB.T6G(SCH_1):PAGE85
    J1   99  VSS43 SCONN288_DDR506112002KQ-SCONN288_DDR506112002KQ,SMA   I538 @T6G_MB_LIB.T6G(SCH_1):PAGE85
    J1  101  VSS44 SCONN288_DDR506112002KQ-SCONN288_DDR506112002KQ,SMA   I538 @T6G_MB_LIB.T6G(SCH_1):PAGE85
    J1  103  VSS45 SCONN288_DDR506112002KQ-SCONN288_DDR506112002KQ,SMA   I538 @T6G_MB_LIB.T6G(SCH_1):PAGE85
    J1  106  VSS46 SCONN288_DDR506112002KQ-SCONN288_DDR506112002KQ,SMA   I538 @T6G_MB_LIB.T6G(SCH_1):PAGE85
    J1  108  VSS47 SCONN288_DDR506112002KQ-SCONN288_DDR506112002KQ,SMA   I538 @T6G_MB_LIB.T6G(SCH_1):PAGE85
    J1  110  VSS48 SCONN288_DDR506112002KQ-SCONN288_DDR506112002KQ,SMA   I538 @T6G_MB_LIB.T6G(SCH_1):PAGE85
    J1  112  VSS49 SCONN288_DDR506112002KQ-SCONN288_DDR506112002KQ,SMA   I538 @T6G_MB_LIB.T6G(SCH_1):PAGE85
    J1  114  VSS50 SCONN288_DDR506112002KQ-SCONN288_DDR506112002KQ,SMA   I538 @T6G_MB_LIB.T6G(SCH_1):PAGE85
    J1  117  VSS51 SCONN288_DDR506112002KQ-SCONN288_DDR506112002KQ,SMA   I538 @T6G_MB_LIB.T6G(SCH_1):PAGE85
    J1  119  VSS52 SCONN288_DDR506112002KQ-SCONN288_DDR506112002KQ,SMA   I538 @T6G_MB_LIB.T6G(SCH_1):PAGE85
    J1  121  VSS53 SCONN288_DDR506112002KQ-SCONN288_DDR506112002KQ,SMA   I538 @T6G_MB_LIB.T6G(SCH_1):PAGE85
    J1  123  VSS54 SCONN288_DDR506112002KQ-SCONN288_DDR506112002KQ,SMA   I538 @T6G_MB_LIB.T6G(SCH_1):PAGE85
    J1  125  VSS55 SCONN288_DDR506112002KQ-SCONN288_DDR506112002KQ,SMA   I538 @T6G_MB_LIB.T6G(SCH_1):PAGE85
    J1  128  VSS56 SCONN288_DDR506112002KQ-SCONN288_DDR506112002KQ,SMA   I538 @T6G_MB_LIB.T6G(SCH_1):PAGE85
    J1  130  VSS57 SCONN288_DDR506112002KQ-SCONN288_DDR506112002KQ,SMA   I538 @T6G_MB_LIB.T6G(SCH_1):PAGE85
    J1  132  VSS58 SCONN288_DDR506112002KQ-SCONN288_DDR506112002KQ,SMA   I538 @T6G_MB_LIB.T6G(SCH_1):PAGE85
    J1  134  VSS59 SCONN288_DDR506112002KQ-SCONN288_DDR506112002KQ,SMA   I538 @T6G_MB_LIB.T6G(SCH_1):PAGE85
    J1  136  VSS60 SCONN288_DDR506112002KQ-SCONN288_DDR506112002KQ,SMA   I538 @T6G_MB_LIB.T6G(SCH_1):PAGE85
    J1  139  VSS61 SCONN288_DDR506112002KQ-SCONN288_DDR506112002KQ,SMA   I538 @T6G_MB_LIB.T6G(SCH_1):PAGE85
    J1  141  VSS62 SCONN288_DDR506112002KQ-SCONN288_DDR506112002KQ,SMA   I538 @T6G_MB_LIB.T6G(SCH_1):PAGE85
    J1  143  VSS63 SCONN288_DDR506112002KQ-SCONN288_DDR506112002KQ,SMA   I538 @T6G_MB_LIB.T6G(SCH_1):PAGE85
    J1  151  VSS64 SCONN288_DDR506112002KQ-SCONN288_DDR506112002KQ,SMA   I538 @T6G_MB_LIB.T6G(SCH_1):PAGE85
    J1  153  VSS65 SCONN288_DDR506112002KQ-SCONN288_DDR506112002KQ,SMA   I538 @T6G_MB_LIB.T6G(SCH_1):PAGE85
    J1  155  VSS66 SCONN288_DDR506112002KQ-SCONN288_DDR506112002KQ,SMA   I538 @T6G_MB_LIB.T6G(SCH_1):PAGE85
    J1  158  VSS67 SCONN288_DDR506112002KQ-SCONN288_DDR506112002KQ,SMA   I538 @T6G_MB_LIB.T6G(SCH_1):PAGE85
    J1  160  VSS68 SCONN288_DDR506112002KQ-SCONN288_DDR506112002KQ,SMA   I538 @T6G_MB_LIB.T6G(SCH_1):PAGE85
    J1  162  VSS69 SCONN288_DDR506112002KQ-SCONN288_DDR506112002KQ,SMA   I538 @T6G_MB_LIB.T6G(SCH_1):PAGE85
    J1  164  VSS70 SCONN288_DDR506112002KQ-SCONN288_DDR506112002KQ,SMA   I538 @T6G_MB_LIB.T6G(SCH_1):PAGE85
    J1  166  VSS71 SCONN288_DDR506112002KQ-SCONN288_DDR506112002KQ,SMA   I538 @T6G_MB_LIB.T6G(SCH_1):PAGE85
    J1  169  VSS72 SCONN288_DDR506112002KQ-SCONN288_DDR506112002KQ,SMA   I538 @T6G_MB_LIB.T6G(SCH_1):PAGE85
    J1  171  VSS73 SCONN288_DDR506112002KQ-SCONN288_DDR506112002KQ,SMA   I538 @T6G_MB_LIB.T6G(SCH_1):PAGE85
    J1  173  VSS74 SCONN288_DDR506112002KQ-SCONN288_DDR506112002KQ,SMA   I538 @T6G_MB_LIB.T6G(SCH_1):PAGE85
    J1  175  VSS75 SCONN288_DDR506112002KQ-SCONN288_DDR506112002KQ,SMA   I538 @T6G_MB_LIB.T6G(SCH_1):PAGE85
    J1  177  VSS76 SCONN288_DDR506112002KQ-SCONN288_DDR506112002KQ,SMA   I538 @T6G_MB_LIB.T6G(SCH_1):PAGE85
    J1  180  VSS77 SCONN288_DDR506112002KQ-SCONN288_DDR506112002KQ,SMA   I538 @T6G_MB_LIB.T6G(SCH_1):PAGE85
    J1  182  VSS78 SCONN288_DDR506112002KQ-SCONN288_DDR506112002KQ,SMA   I538 @T6G_MB_LIB.T6G(SCH_1):PAGE85
    J1  184  VSS79 SCONN288_DDR506112002KQ-SCONN288_DDR506112002KQ,SMA   I538 @T6G_MB_LIB.T6G(SCH_1):PAGE85
    J1  186  VSS80 SCONN288_DDR506112002KQ-SCONN288_DDR506112002KQ,SMA   I538 @T6G_MB_LIB.T6G(SCH_1):PAGE85
    J1  188  VSS81 SCONN288_DDR506112002KQ-SCONN288_DDR506112002KQ,SMA   I538 @T6G_MB_LIB.T6G(SCH_1):PAGE85
    J1  191  VSS82 SCONN288_DDR506112002KQ-SCONN288_DDR506112002KQ,SMA   I538 @T6G_MB_LIB.T6G(SCH_1):PAGE85
    J1  193  VSS83 SCONN288_DDR506112002KQ-SCONN288_DDR506112002KQ,SMA   I538 @T6G_MB_LIB.T6G(SCH_1):PAGE85
    J1  195  VSS84 SCONN288_DDR506112002KQ-SCONN288_DDR506112002KQ,SMA   I538 @T6G_MB_LIB.T6G(SCH_1):PAGE85
    J1  197  VSS85 SCONN288_DDR506112002KQ-SCONN288_DDR506112002KQ,SMA   I538 @T6G_MB_LIB.T6G(SCH_1):PAGE85
    J1  199  VSS86 SCONN288_DDR506112002KQ-SCONN288_DDR506112002KQ,SMA   I538 @T6G_MB_LIB.T6G(SCH_1):PAGE85
    J1  202  VSS87 SCONN288_DDR506112002KQ-SCONN288_DDR506112002KQ,SMA   I538 @T6G_MB_LIB.T6G(SCH_1):PAGE85
    J1  204  VSS88 SCONN288_DDR506112002KQ-SCONN288_DDR506112002KQ,SMA   I538 @T6G_MB_LIB.T6G(SCH_1):PAGE85
    J1  206  VSS89 SCONN288_DDR506112002KQ-SCONN288_DDR506112002KQ,SMA   I538 @T6G_MB_LIB.T6G(SCH_1):PAGE85
    J1  208  VSS90 SCONN288_DDR506112002KQ-SCONN288_DDR506112002KQ,SMA   I538 @T6G_MB_LIB.T6G(SCH_1):PAGE85
    J1  210  VSS91 SCONN288_DDR506112002KQ-SCONN288_DDR506112002KQ,SMA   I538 @T6G_MB_LIB.T6G(SCH_1):PAGE85
    J1  212  VSS92 SCONN288_DDR506112002KQ-SCONN288_DDR506112002KQ,SMA   I538 @T6G_MB_LIB.T6G(SCH_1):PAGE85
    J1  214  VSS93 SCONN288_DDR506112002KQ-SCONN288_DDR506112002KQ,SMA   I538 @T6G_MB_LIB.T6G(SCH_1):PAGE85
    J1  216  VSS94 SCONN288_DDR506112002KQ-SCONN288_DDR506112002KQ,SMA   I538 @T6G_MB_LIB.T6G(SCH_1):PAGE85
    J1  219  VSS95 SCONN288_DDR506112002KQ-SCONN288_DDR506112002KQ,SMA   I538 @T6G_MB_LIB.T6G(SCH_1):PAGE85
    J1  222  VSS96 SCONN288_DDR506112002KQ-SCONN288_DDR506112002KQ,SMA   I538 @T6G_MB_LIB.T6G(SCH_1):PAGE85
    J1  224  VSS97 SCONN288_DDR506112002KQ-SCONN288_DDR506112002KQ,SMA   I538 @T6G_MB_LIB.T6G(SCH_1):PAGE85
    J1  226  VSS98 SCONN288_DDR506112002KQ-SCONN288_DDR506112002KQ,SMA   I538 @T6G_MB_LIB.T6G(SCH_1):PAGE85
    J1  228  VSS99 SCONN288_DDR506112002KQ-SCONN288_DDR506112002KQ,SMA   I538 @T6G_MB_LIB.T6G(SCH_1):PAGE85
    J1  230 VSS100 SCONN288_DDR506112002KQ-SCONN288_DDR506112002KQ,SMA   I538 @T6G_MB_LIB.T6G(SCH_1):PAGE85
    J1  233 VSS101 SCONN288_DDR506112002KQ-SCONN288_DDR506112002KQ,SMA   I538 @T6G_MB_LIB.T6G(SCH_1):PAGE85
    J1  235 VSS102 SCONN288_DDR506112002KQ-SCONN288_DDR506112002KQ,SMA   I538 @T6G_MB_LIB.T6G(SCH_1):PAGE85
    J1  237 VSS103 SCONN288_DDR506112002KQ-SCONN288_DDR506112002KQ,SMA   I538 @T6G_MB_LIB.T6G(SCH_1):PAGE85
    J1  240 VSS104 SCONN288_DDR506112002KQ-SCONN288_DDR506112002KQ,SMA   I538 @T6G_MB_LIB.T6G(SCH_1):PAGE85
    J1  242 VSS105 SCONN288_DDR506112002KQ-SCONN288_DDR506112002KQ,SMA   I538 @T6G_MB_LIB.T6G(SCH_1):PAGE85
    J1  244 VSS106 SCONN288_DDR506112002KQ-SCONN288_DDR506112002KQ,SMA   I538 @T6G_MB_LIB.T6G(SCH_1):PAGE85
    J1  246 VSS107 SCONN288_DDR506112002KQ-SCONN288_DDR506112002KQ,SMA   I538 @T6G_MB_LIB.T6G(SCH_1):PAGE85
    J1  248 VSS108 SCONN288_DDR506112002KQ-SCONN288_DDR506112002KQ,SMA   I538 @T6G_MB_LIB.T6G(SCH_1):PAGE85
    J1  251 VSS109 SCONN288_DDR506112002KQ-SCONN288_DDR506112002KQ,SMA   I538 @T6G_MB_LIB.T6G(SCH_1):PAGE85
    J1  253 VSS110 SCONN288_DDR506112002KQ-SCONN288_DDR506112002KQ,SMA   I538 @T6G_MB_LIB.T6G(SCH_1):PAGE85
    J1  255 VSS111 SCONN288_DDR506112002KQ-SCONN288_DDR506112002KQ,SMA   I538 @T6G_MB_LIB.T6G(SCH_1):PAGE85
    J1  257 VSS112 SCONN288_DDR506112002KQ-SCONN288_DDR506112002KQ,SMA   I538 @T6G_MB_LIB.T6G(SCH_1):PAGE85
    J1  259 VSS113 SCONN288_DDR506112002KQ-SCONN288_DDR506112002KQ,SMA   I538 @T6G_MB_LIB.T6G(SCH_1):PAGE85
    J1  262 VSS114 SCONN288_DDR506112002KQ-SCONN288_DDR506112002KQ,SMA   I538 @T6G_MB_LIB.T6G(SCH_1):PAGE85
    J1  264 VSS115 SCONN288_DDR506112002KQ-SCONN288_DDR506112002KQ,SMA   I538 @T6G_MB_LIB.T6G(SCH_1):PAGE85
    J1  266 VSS116 SCONN288_DDR506112002KQ-SCONN288_DDR506112002KQ,SMA   I538 @T6G_MB_LIB.T6G(SCH_1):PAGE85
    J1  268 VSS117 SCONN288_DDR506112002KQ-SCONN288_DDR506112002KQ,SMA   I538 @T6G_MB_LIB.T6G(SCH_1):PAGE85
    J1  270 VSS118 SCONN288_DDR506112002KQ-SCONN288_DDR506112002KQ,SMA   I538 @T6G_MB_LIB.T6G(SCH_1):PAGE85
    J1  273 VSS119 SCONN288_DDR506112002KQ-SCONN288_DDR506112002KQ,SMA   I538 @T6G_MB_LIB.T6G(SCH_1):PAGE85
    J1  275 VSS120 SCONN288_DDR506112002KQ-SCONN288_DDR506112002KQ,SMA   I538 @T6G_MB_LIB.T6G(SCH_1):PAGE85
    J1  277 VSS121 SCONN288_DDR506112002KQ-SCONN288_DDR506112002KQ,SMA   I538 @T6G_MB_LIB.T6G(SCH_1):PAGE85
    J1  279 VSS122 SCONN288_DDR506112002KQ-SCONN288_DDR506112002KQ,SMA   I538 @T6G_MB_LIB.T6G(SCH_1):PAGE85
    J1  281 VSS123 SCONN288_DDR506112002KQ-SCONN288_DDR506112002KQ,SMA   I538 @T6G_MB_LIB.T6G(SCH_1):PAGE85
    J1  284 VSS124 SCONN288_DDR506112002KQ-SCONN288_DDR506112002KQ,SMA   I538 @T6G_MB_LIB.T6G(SCH_1):PAGE85
    J1  286 VSS125 SCONN288_DDR506112002KQ-SCONN288_DDR506112002KQ,SMA   I538 @T6G_MB_LIB.T6G(SCH_1):PAGE85
    J1  288 VSS126 SCONN288_DDR506112002KQ-SCONN288_DDR506112002KQ,SMA   I538 @T6G_MB_LIB.T6G(SCH_1):PAGE85
 PR283    2      B Q_RES_0402LF-0,5%,1/16W,CHIP,CS00002JB13     I4 @T6G_MB_LIB.T6G(SCH_1):PAGE168
  C461    2      B Q_CAP_0402-1000PF,50V,5%,X7R,TMP_QCH21006JB10    I13 @T6G_MB_LIB.T6G(SCH_1):PAGE168
 PR297    2      B Q_RES_0402LF-49.9,1%,1/16W,CHIP,CS04992FB07    I36 @T6G_MB_LIB.T6G(SCH_1):PAGE168
 PR599    2      B Q_RES_0402LF-4.99K,1%,1/16W,EMPTY,CS24992FB07    I47 @T6G_MB_LIB.T6G(SCH_1):PAGE168
  C299    2      B Q_CAP_0402-10PF,50V,5%,EMPTY,CH01006JB08    I66 @T6G_MB_LIB.T6G(SCH_1):PAGE168
  C302    2      B Q_CAP_0402-10PF,50V,5%,EMPTY,CH01006JB08    I68 @T6G_MB_LIB.T6G(SCH_1):PAGE168
  C468    2      B Q_CAP_0402-1000PF,50V,5%,X7R,TMP_QCH21006JB10    I90 @T6G_MB_LIB.T6G(SCH_1):PAGE168
  PC13    2      B Q_CAP_0402-0.1UF,25V,10%,X7R,CH4104K1B00   I118 @T6G_MB_LIB.T6G(SCH_1):PAGE168
  PU43    2   AGND ISL99390FRZTR5935-ISL99390FRZ-TR5935,SMLF,IC,AL099A    I16 @T6G_MB_LIB.T6G(SCH_1):PAGE169
  PU43    5  PGND1 ISL99390FRZTR5935-ISL99390FRZ-TR5935,SMLF,IC,AL099A    I16 @T6G_MB_LIB.T6G(SCH_1):PAGE169
  PU43 7_9-20_24  PGND2 ISL99390FRZTR5935-ISL99390FRZ-TR5935,SMLF,IC,AL099A    I16 @T6G_MB_LIB.T6G(SCH_1):PAGE169
  PU43   40  PGND3 ISL99390FRZTR5935-ISL99390FRZ-TR5935,SMLF,IC,AL099A    I16 @T6G_MB_LIB.T6G(SCH_1):PAGE169
PC478_C0P0_2    2      B Q_CAP_C0402-2.2UF,10V,10%,X6S,CH5222KEB01    I19 @T6G_MB_LIB.T6G(SCH_1):PAGE169
   PU6    2   AGND ISL99390FRZTR5935-ISL99390FRZ-TR5935,SMLF,IC,AL099A    I26 @T6G_MB_LIB.T6G(SCH_1):PAGE169
   PU6    5  PGND1 ISL99390FRZTR5935-ISL99390FRZ-TR5935,SMLF,IC,AL099A    I26 @T6G_MB_LIB.T6G(SCH_1):PAGE169
   PU6 7_9-20_24  PGND2 ISL99390FRZTR5935-ISL99390FRZ-TR5935,SMLF,IC,AL099A    I26 @T6G_MB_LIB.T6G(SCH_1):PAGE169
   PU6   40  PGND3 ISL99390FRZTR5935-ISL99390FRZ-TR5935,SMLF,IC,AL099A    I26 @T6G_MB_LIB.T6G(SCH_1):PAGE169
PC482_2    2      B Q_CAP_0402-0.1UF,25V,10%,X7R,CH4104K1B00    I33 @T6G_MB_LIB.T6G(SCH_1):PAGE169
 PC108    2      B Q_CAPP_SMLF-220UF,4V,20%,SPCAP,CH122KM8801    I64 @T6G_MB_LIB.T6G(SCH_1):PAGE169
 PC494    2      B Q_CAPP_SMLF-220UF,4V,20%,SPCAP,CH122KM8801    I65 @T6G_MB_LIB.T6G(SCH_1):PAGE169
 PC495    2      B Q_CAPP_SMLF-220UF,4V,20%,SPCAP,CH122KM8801    I66 @T6G_MB_LIB.T6G(SCH_1):PAGE169
 PC496    2      B Q_CAPP_SMLF-220UF,4V,20%,SPCAP,CH122KM8801    I67 @T6G_MB_LIB.T6G(SCH_1):PAGE169
PC499_2    2      B Q_CAP_C0805-22UF,4V,20%,X6S,CH622KMEA03    I68 @T6G_MB_LIB.T6G(SCH_1):PAGE169
 PR499    2      B Q_RES_0402LF-1.5,1%,1/8W,EMPTY,CS-1504FB00    I18 @T6G_MB_LIB.T6G(SCH_1):PAGE170
PC551_4    2      B Q_CAP_0402-0.1UF,25V,10%,X7R,CH4104K1B00    I21 @T6G_MB_LIB.T6G(SCH_1):PAGE170
PC555_4    2      B Q_CAP_C0805-22UF,16V,20%,X6S,CH6223MEA01    I23 @T6G_MB_LIB.T6G(SCH_1):PAGE170
 PR346    1      A Q_RES_0402LF-8.87K,1%,1/16W,EMPTY,CS28872FB01    I33 @T6G_MB_LIB.T6G(SCH_1):PAGE170
PC578_8    2      B Q_CAP_0402-0.1UF,25V,10%,X7R,CH4104K1B00     I4 @T6G_MB_LIB.T6G(SCH_1):PAGE173
 PR503    2      B Q_RES_0402LF-1.5,1%,1/8W,EMPTY,CS-1504FB00    I19 @T6G_MB_LIB.T6G(SCH_1):PAGE173
PC584_2    2      B Q_CAP_C0402-1UF,25V,10%,X6S,CH5104KEB02    I23 @T6G_MB_LIB.T6G(SCH_1):PAGE173
PC588_2    2      B Q_CAP_C0805-22UF,16V,20%,X6S,CH6223MEA01    I24 @T6G_MB_LIB.T6G(SCH_1):PAGE173
PC590_2    2      B Q_CAP_C0805-22UF,16V,20%,X6S,CH6223MEA01    I25 @T6G_MB_LIB.T6G(SCH_1):PAGE173
PC577_7    2      B Q_CAP_0402-0.1UF,25V,10%,X7R,CH4104K1B00    I29 @T6G_MB_LIB.T6G(SCH_1):PAGE173
PC583_1    2      B Q_CAP_0402-0.1UF,25V,10%,X7R,CH4104K1B00    I43 @T6G_MB_LIB.T6G(SCH_1):PAGE173
 PC597    2      B Q_CAPP_SMLF-470UF,2.5V,20%,EMPTY,CH747LM8825    I63 @T6G_MB_LIB.T6G(SCH_1):PAGE173
 PC601    2      B Q_CAPP_SMLF-470UF,2.5V,20%,SPCAP,CH747LM8825    I66 @T6G_MB_LIB.T6G(SCH_1):PAGE173
  PL63    3      3 Q_INDUCTOR4P_14-150NH,SMLF,IND,CV+15^0TZ04    I69 @T6G_MB_LIB.T6G(SCH_1):PAGE173
 PC599    2      B Q_CAP_0402-0.1UF,25V,10%,X7R,CH4104K1B00    I79 @T6G_MB_LIB.T6G(SCH_1):PAGE173
PC604_1    2      B Q_CAP_C0805-22UF,4V,20%,X6S,CH622KMEA03    I83 @T6G_MB_LIB.T6G(SCH_1):PAGE173
 PR365    1      A Q_RES_0402LF-8.87K,1%,1/16W,EMPTY,CS28872FB01     I7 @T6G_MB_LIB.T6G(SCH_1):PAGE174
PC608_3    2      B Q_CAP_C0402-1UF,25V,10%,X6S,CH5104KEB02    I21 @T6G_MB_LIB.T6G(SCH_1):PAGE174
PC610_3    2      B Q_CAP_C0805-22UF,16V,20%,X6S,CH6223MEA01    I22 @T6G_MB_LIB.T6G(SCH_1):PAGE174
PC615_3    2      B Q_CAP_C0805-22UF,4V,20%,X6S,CH622KMEA03    I29 @T6G_MB_LIB.T6G(SCH_1):PAGE174
PC611_3    2      B Q_CAP_C0805-22UF,16V,20%,X6S,CH6223MEA01    I31 @T6G_MB_LIB.T6G(SCH_1):PAGE174
PC613_3    2      B Q_CAP_C0805-22UF,16V,20%,X6S,CH6223MEA01    I32 @T6G_MB_LIB.T6G(SCH_1):PAGE174
PC609_3    2      B Q_CAP_0402-0.1UF,25V,10%,X7R,CH4104K1B00    I37 @T6G_MB_LIB.T6G(SCH_1):PAGE174
  PU51    2   AGND ISL99390FRZTR5935-ISL99390FRZ-TR5935,SMLF,IC,AL099A    I38 @T6G_MB_LIB.T6G(SCH_1):PAGE174
  PU51    5  PGND1 ISL99390FRZTR5935-ISL99390FRZ-TR5935,SMLF,IC,AL099A    I38 @T6G_MB_LIB.T6G(SCH_1):PAGE174
  PU51 7_9-20_24  PGND2 ISL99390FRZTR5935-ISL99390FRZ-TR5935,SMLF,IC,AL099A    I38 @T6G_MB_LIB.T6G(SCH_1):PAGE174
  PU51   40  PGND3 ISL99390FRZTR5935-ISL99390FRZ-TR5935,SMLF,IC,AL099A    I38 @T6G_MB_LIB.T6G(SCH_1):PAGE174
PC83_2    2      B Q_CAP_0402-0.1UF,25V,10%,X7R,CH4104K1B00     I2 @T6G_MB_LIB.T6G(SCH_1):PAGE176
  PC79    2      B Q_CAP_C0402-2.2UF,10V,10%,X6S,CH5222KEB01    I24 @T6G_MB_LIB.T6G(SCH_1):PAGE176
PC88_2    2      B Q_CAP_C0402-1UF,25V,10%,X6S,CH5104KEB02    I47 @T6G_MB_LIB.T6G(SCH_1):PAGE176
PC95_1    2      B Q_CAP_C0805-22UF,16V,20%,X6S,CH6223MEA01    I65 @T6G_MB_LIB.T6G(SCH_1):PAGE176
 PC101    2      B Q_CAPP_THLF-270UF,16V,20%,OSCON,CC72703MD38    I66 @T6G_MB_LIB.T6G(SCH_1):PAGE176
 PC103    2      B Q_CAPP_SMLF-220UF,4V,20%,SPCAP,CH122KM8801    I75 @T6G_MB_LIB.T6G(SCH_1):PAGE176
  PC85    2      B Q_CAP_0402-0.1UF,25V,10%,X7R,CH4104K1B00    I87 @T6G_MB_LIB.T6G(SCH_1):PAGE176
PC113_4    2      B Q_CAP_0402-0.1UF,25V,10%,X7R,CH4104K1B00     I2 @T6G_MB_LIB.T6G(SCH_1):PAGE177
  PL13    3      3 Q_INDUCTOR4P_14-150NH,SMLF,IND,CV+15^0TZ04    I42 @T6G_MB_LIB.T6G(SCH_1):PAGE177
PC128_4    2      B Q_CAP_C0805-22UF,4V,20%,X6S,CH622KMEA03    I55 @T6G_MB_LIB.T6G(SCH_1):PAGE177
PC133_C1P0_5    2      B Q_CAP_C0402-2.2UF,10V,10%,X6S,CH5222KEB01    I31 @T6G_MB_LIB.T6G(SCH_1):PAGE178
PC114_6    2      B Q_CAP_0402-0.1UF,25V,10%,X7R,CH4104K1B00    I40 @T6G_MB_LIB.T6G(SCH_1):PAGE178
PC135_5    2      B Q_CAP_C0402-1UF,25V,10%,X6S,CH5104KEB02    I59 @T6G_MB_LIB.T6G(SCH_1):PAGE178
PC136_5    2      B Q_CAP_C0805-22UF,16V,20%,X6S,CH6223MEA01    I60 @T6G_MB_LIB.T6G(SCH_1):PAGE178
PC182_4    2      B Q_CAP_C0805-22UF,16V,20%,X6S,CH6223MEA01    I46 @T6G_MB_LIB.T6G(SCH_1):PAGE181
 PR379    2      B Q_RES_0402LF-1.5,1%,1/8W,EMPTY,CS-1504FB00    I55 @T6G_MB_LIB.T6G(SCH_1):PAGE181
PC191_4    2      B Q_CAP_C0805-22UF,4V,20%,X6S,CH622KMEA03    I68 @T6G_MB_LIB.T6G(SCH_1):PAGE181
PC192_3    2      B Q_CAP_C0805-22UF,4V,20%,X6S,CH622KMEA03    I71 @T6G_MB_LIB.T6G(SCH_1):PAGE181
  C196    2      B Q_CAP_0402-1000PF,50V,5%,EMPTY,TMP_QCH21006JB10    I47 @T6G_MB_LIB.T6G(SCH_1):PAGE182
   PC9    2      B Q_CAP_0402-0.1UF,25V,10%,X7R,CH4104K1B00    I77 @T6G_MB_LIB.T6G(SCH_1):PAGE182
 PC200    2      B Q_CAP_C0402-1UF,16V,10%,X6S,CH5103KEB01    I82 @T6G_MB_LIB.T6G(SCH_1):PAGE182
 PR389    2      B Q_RES_0402LF-1.5,1%,1/8W,EMPTY,CS-1504FB00    I24 @T6G_MB_LIB.T6G(SCH_1):PAGE183
PC210_2    2      B Q_CAP_C0402-1UF,25V,10%,X6S,CH5104KEB02    I27 @T6G_MB_LIB.T6G(SCH_1):PAGE183
PC208_2    2      B Q_CAP_0402-0.1UF,25V,10%,X7R,CH4104K1B00    I29 @T6G_MB_LIB.T6G(SCH_1):PAGE183
PC201_1    2      B Q_CAP_0402-0.1UF,25V,10%,X7R,CH4104K1B00    I34 @T6G_MB_LIB.T6G(SCH_1):PAGE183
 PR133    1      A Q_RES_0402LF-4.87K,1%,1/16W,EMPTY,CS24872FB01    I37 @T6G_MB_LIB.T6G(SCH_1):PAGE183
PC209_1    2      B Q_CAP_C0402-1UF,25V,10%,X6S,CH5104KEB02    I44 @T6G_MB_LIB.T6G(SCH_1):PAGE183
PC211_1    2      B Q_CAP_C0805-22UF,16V,20%,X6S,CH6223MEA01    I48 @T6G_MB_LIB.T6G(SCH_1):PAGE183
 PC229    2      B Q_CAPP_SMLF-390UF,2.5V,20%,ALUM,CC7390JMZ13    I66 @T6G_MB_LIB.T6G(SCH_1):PAGE183
 PC230    2      B Q_CAPP_SMLF-390UF,2.5V,20%,ALUM,CC7390JMZ13    I67 @T6G_MB_LIB.T6G(SCH_1):PAGE183
 PC801    2      B Q_CAPP_SMLF-390UF,2.5V,20%,ALUM,CC7390JMZ13    I70 @T6G_MB_LIB.T6G(SCH_1):PAGE183
PC6003    2      B Q_CAP_0402-0.1UF,25V,10%,X7R,CH4104K1B00    I79 @T6G_MB_LIB.T6G(SCH_1):PAGE183
PC224_1    2      B Q_CAP_C0805-22UF,4V,20%,X6S,CH622KMEA03    I81 @T6G_MB_LIB.T6G(SCH_1):PAGE183
 PR150    2      B Q_RES_0402LF-0,5%,1/16W,CHIP,CS00002JB13     I4 @T6G_MB_LIB.T6G(SCH_1):PAGE185
  C242    2      B Q_CAP_0402-1000PF,50V,5%,X7R,TMP_QCH21006JB10    I13 @T6G_MB_LIB.T6G(SCH_1):PAGE185
 PR164    2      B Q_RES_0402LF-49.9,1%,1/16W,CHIP,CS04992FB07    I36 @T6G_MB_LIB.T6G(SCH_1):PAGE185
  C295    2      B Q_CAP_0402-10PF,50V,5%,EMPTY,CH01006JB08    I62 @T6G_MB_LIB.T6G(SCH_1):PAGE185
  C249    2      B Q_CAP_0402-1000PF,50V,5%,X7R,TMP_QCH21006JB10    I86 @T6G_MB_LIB.T6G(SCH_1):PAGE185
  C248    2      B Q_CAP_0402-1000PF,50V,5%,EMPTY,TMP_QCH21006JB10    I88 @T6G_MB_LIB.T6G(SCH_1):PAGE185
  PC11    2      B Q_CAP_0402-0.1UF,25V,10%,X7R,CH4104K1B00   I114 @T6G_MB_LIB.T6G(SCH_1):PAGE185
PC259_C0P1_2    2      B Q_CAP_C0402-2.2UF,10V,10%,X6S,CH5222KEB01    I13 @T6G_MB_LIB.T6G(SCH_1):PAGE186
PC254_1    2      B Q_CAP_0402-0.1UF,25V,10%,X7R,CH4104K1B00    I16 @T6G_MB_LIB.T6G(SCH_1):PAGE186
PC263_2    2      B Q_CAP_C0402-1UF,25V,10%,X6S,CH5104KEB02    I26 @T6G_MB_LIB.T6G(SCH_1):PAGE186
PC269_2    2      B Q_CAP_C0805-22UF,16V,20%,X6S,CH6223MEA01    I31 @T6G_MB_LIB.T6G(SCH_1):PAGE186
PC260_1    2      B Q_CAP_0402-0.1UF,25V,10%,X7R,CH4104K1B00    I46 @T6G_MB_LIB.T6G(SCH_1):PAGE186
PC282_2    2      B Q_CAP_C0805-22UF,4V,20%,X6S,CH622KMEA03    I63 @T6G_MB_LIB.T6G(SCH_1):PAGE186
 PC279    2      B Q_CAPP_SMLF-220UF,4V,20%,SPCAP,CH122KM8801    I66 @T6G_MB_LIB.T6G(SCH_1):PAGE186
 PC273    2      B Q_CAPP_THLF-270UF,16V,20%,OSCON,CC72703MD38    I71 @T6G_MB_LIB.T6G(SCH_1):PAGE186
PC318_8    2      B Q_CAP_0402-0.1UF,25V,10%,X7R,CH4104K1B00     I4 @T6G_MB_LIB.T6G(SCH_1):PAGE190
PC326_2    2      B Q_CAP_0402-0.1UF,25V,10%,X7R,CH4104K1B00    I22 @T6G_MB_LIB.T6G(SCH_1):PAGE190
PC324_2    2      B Q_CAP_C0402-1UF,25V,10%,X6S,CH5104KEB02    I25 @T6G_MB_LIB.T6G(SCH_1):PAGE190
PC328_2    2      B Q_CAP_C0805-22UF,16V,20%,X6S,CH6223MEA01    I26 @T6G_MB_LIB.T6G(SCH_1):PAGE190
 PR525    2      B Q_RES_0402LF-1.5,1%,1/8W,EMPTY,CS-1504FB00    I29 @T6G_MB_LIB.T6G(SCH_1):PAGE190
PC325_1    2      B Q_CAP_0402-0.1UF,25V,10%,X7R,CH4104K1B00    I43 @T6G_MB_LIB.T6G(SCH_1):PAGE190
PC323_1    2      B Q_CAP_C0402-1UF,25V,10%,X6S,CH5104KEB02    I44 @T6G_MB_LIB.T6G(SCH_1):PAGE190
PC327_1    2      B Q_CAP_C0805-22UF,16V,20%,X6S,CH6223MEA01    I48 @T6G_MB_LIB.T6G(SCH_1):PAGE190
 PC340    2      B Q_CAPP_SMLF-470UF,2.5V,20%,EMPTY,CH747LM8825    I63 @T6G_MB_LIB.T6G(SCH_1):PAGE190
 PC343    2      B Q_CAPP_SMLF-470UF,2.5V,20%,SPCAP,CH747LM8825    I66 @T6G_MB_LIB.T6G(SCH_1):PAGE190
  PL35    3      3 Q_INDUCTOR4P_14-150NH,SMLF,IND,CV+15^0TZ04    I69 @T6G_MB_LIB.T6G(SCH_1):PAGE190
 PC338    2      B Q_CAP_0402-0.1UF,25V,10%,X7R,CH4104K1B00    I79 @T6G_MB_LIB.T6G(SCH_1):PAGE190
PC344_1    2      B Q_CAP_C0805-22UF,4V,20%,X6S,CH622KMEA03    I81 @T6G_MB_LIB.T6G(SCH_1):PAGE190
 PR339    2      B Q_RES_0402LF-1K,1%,1/16W,CHIP,CS21002FB06    I83 @T6G_MB_LIB.T6G(SCH_1):PAGE190
 PR214    1      A Q_RES_0402LF-8.87K,1%,1/16W,EMPTY,CS28872FB01     I7 @T6G_MB_LIB.T6G(SCH_1):PAGE191
PC347_SOP1_3    2      B Q_CAP_C0402-2.2UF,10V,10%,X6S,CH5222KEB01    I18 @T6G_MB_LIB.T6G(SCH_1):PAGE191
PC349_3    2      B Q_CAP_C0402-1UF,25V,10%,X6S,CH5104KEB02    I20 @T6G_MB_LIB.T6G(SCH_1):PAGE191
PC350_3    2      B Q_CAP_C0805-22UF,16V,20%,X6S,CH6223MEA01    I22 @T6G_MB_LIB.T6G(SCH_1):PAGE191
  PL34    1      1 Q_INDUCTOR_SMLF-0.22UH/33A,IND,CV+22Y0EZ00    I25 @T6G_MB_LIB.T6G(SCH_1):PAGE191
PC351_3    2      B Q_CAP_C0805-22UF,16V,20%,X6S,CH6223MEA01    I31 @T6G_MB_LIB.T6G(SCH_1):PAGE191
PC352_3    2      B Q_CAP_C0805-22UF,16V,20%,X6S,CH6223MEA01    I32 @T6G_MB_LIB.T6G(SCH_1):PAGE191
PC353_3    2      B Q_CAP_C0805-22UF,16V,20%,X6S,CH6223MEA01    I34 @T6G_MB_LIB.T6G(SCH_1):PAGE191
  PU32    2   AGND ISL99390FRZTR5935-ISL99390FRZ-TR5935,SMLF,IC,AL099A    I38 @T6G_MB_LIB.T6G(SCH_1):PAGE191
  PU32    5  PGND1 ISL99390FRZTR5935-ISL99390FRZ-TR5935,SMLF,IC,AL099A    I38 @T6G_MB_LIB.T6G(SCH_1):PAGE191
  PU32 7_9-20_24  PGND2 ISL99390FRZTR5935-ISL99390FRZ-TR5935,SMLF,IC,AL099A    I38 @T6G_MB_LIB.T6G(SCH_1):PAGE191
  PU32   40  PGND3 ISL99390FRZTR5935-ISL99390FRZ-TR5935,SMLF,IC,AL099A    I38 @T6G_MB_LIB.T6G(SCH_1):PAGE191
PC373_2    2      B Q_CAP_0402-0.1UF,25V,10%,X7R,CH4104K1B00     I2 @T6G_MB_LIB.T6G(SCH_1):PAGE193
 PC369    2      B Q_CAP_C0402-2.2UF,10V,10%,X6S,CH5222KEB01    I23 @T6G_MB_LIB.T6G(SCH_1):PAGE193
PC382_2    2      B Q_CAP_C0805-22UF,16V,20%,X6S,CH6223MEA01    I46 @T6G_MB_LIB.T6G(SCH_1):PAGE193
 PC106    2      B Q_CAPP_SMLF-220UF,4V,20%,SPCAP,CH122KM8801    I65 @T6G_MB_LIB.T6G(SCH_1):PAGE193
 PC387    2      B Q_CAPP_SMLF-220UF,4V,20%,SPCAP,CH122KM8801    I66 @T6G_MB_LIB.T6G(SCH_1):PAGE193
 PC388    2      B Q_CAPP_SMLF-220UF,4V,20%,SPCAP,CH122KM8801    I67 @T6G_MB_LIB.T6G(SCH_1):PAGE193
 PC391    2      B Q_CAPP_SMLF-220UF,4V,20%,SPCAP,CH122KM8801    I74 @T6G_MB_LIB.T6G(SCH_1):PAGE193
 PR342    2      B Q_RES_0402LF-1K,1%,1/16W,CHIP,CS21002FB06    I87 @T6G_MB_LIB.T6G(SCH_1):PAGE193
PC403_4    2      B Q_CAP_0402-0.1UF,25V,10%,X7R,CH4104K1B00     I2 @T6G_MB_LIB.T6G(SCH_1):PAGE194
PC409_4    2      B Q_CAP_C0805-22UF,16V,20%,X6S,CH6223MEA01    I42 @T6G_MB_LIB.T6G(SCH_1):PAGE194
  PL43    3      3 Q_INDUCTOR4P_14-150NH,SMLF,IND,CV+15^0TZ04    I50 @T6G_MB_LIB.T6G(SCH_1):PAGE194
PC410_3    2      B Q_CAP_C0805-22UF,16V,20%,X6S,CH6223MEA01    I55 @T6G_MB_LIB.T6G(SCH_1):PAGE194
PC423_C1P1_5    2      B Q_CAP_C0402-2.2UF,10V,10%,X6S,CH5222KEB01    I31 @T6G_MB_LIB.T6G(SCH_1):PAGE195
PC140_6    2      B Q_CAP_C0402-1UF,25V,10%,X6S,CH5104KEB02    I40 @T6G_MB_LIB.T6G(SCH_1):PAGE195
PC427_5    2      B Q_CAP_C0805-22UF,16V,20%,X6S,CH6223MEA01    I60 @T6G_MB_LIB.T6G(SCH_1):PAGE195
PC621_10    2      B Q_CAP_0402-0.1UF,25V,10%,X7R,CH4104K1B00     I2 @T6G_MB_LIB.T6G(SCH_1):PAGE198
  PU53    2   AGND ISL99390FRZTR5935-ISL99390FRZ-TR5935,SMLF,IC,AL099A    I15 @T6G_MB_LIB.T6G(SCH_1):PAGE198
  PU53    5  PGND1 ISL99390FRZTR5935-ISL99390FRZ-TR5935,SMLF,IC,AL099A    I15 @T6G_MB_LIB.T6G(SCH_1):PAGE198
  PU53 7_9-20_24  PGND2 ISL99390FRZTR5935-ISL99390FRZ-TR5935,SMLF,IC,AL099A    I15 @T6G_MB_LIB.T6G(SCH_1):PAGE198
  PU53   40  PGND3 ISL99390FRZTR5935-ISL99390FRZ-TR5935,SMLF,IC,AL099A    I15 @T6G_MB_LIB.T6G(SCH_1):PAGE198
 PC617    2      B Q_CAP_C0402-2.2UF,10V,10%,X6S,CH5222KEB01    I28 @T6G_MB_LIB.T6G(SCH_1):PAGE198
PC629_4    2      B Q_CAP_C0805-22UF,16V,20%,X6S,CH6223MEA01    I46 @T6G_MB_LIB.T6G(SCH_1):PAGE198
PC634_4    2      B Q_CAP_C0805-22UF,4V,20%,X6S,CH622KMEA03    I51 @T6G_MB_LIB.T6G(SCH_1):PAGE198
 PR492    2      B Q_RES_0402LF-1.5,1%,1/8W,EMPTY,CS-1504FB00    I57 @T6G_MB_LIB.T6G(SCH_1):PAGE198
PC632_3    2      B Q_CAP_C0805-22UF,16V,20%,X6S,CH6223MEA01    I65 @T6G_MB_LIB.T6G(SCH_1):PAGE198
PC635_3    2      B Q_CAP_C0805-22UF,4V,20%,X6S,CH622KMEA03    I68 @T6G_MB_LIB.T6G(SCH_1):PAGE198
 R3118    2      B Q_RES_0402LF-86.6K,1%,1/16W,EMPTY,CS38662FB05     I2 @T6G_MB_LIB.T6G(SCH_1):PAGE245
PC1870    2      B Q_CAP_0402-0.1UF,25V,10%,EMPTY,CH4104K1B00     I8 @T6G_MB_LIB.T6G(SCH_1):PAGE245
 PR833    2      B Q_RES_0402LF-1.5K,1%,1/16W,EMPTY,CS21502FB07    I15 @T6G_MB_LIB.T6G(SCH_1):PAGE245
 PR834    2      B Q_RES_0402LF-21.5K,1%,1/16W,CHIP,CS32152FB04    I17 @T6G_MB_LIB.T6G(SCH_1):PAGE245
   PU9   32   AGND NCP3284AMNTXG-NCP3284AMNTXG,SMLF,IC,AL003284002    I21 @T6G_MB_LIB.T6G(SCH_1):PAGE245
   PU9 7_10-19   PGND NCP3284AMNTXG-NCP3284AMNTXG,SMLF,IC,AL003284002    I21 @T6G_MB_LIB.T6G(SCH_1):PAGE245
   PU9   31  VSNS- NCP3284AMNTXG-NCP3284AMNTXG,SMLF,IC,AL003284002    I21 @T6G_MB_LIB.T6G(SCH_1):PAGE245
PC1649    2      B Q_CAP_C0402-0.1UF,25V,10%,X6S,CH4104KEB00    I23 @T6G_MB_LIB.T6G(SCH_1):PAGE245
PC2260    2      B Q_CAP_C0805-22UF,16V,20%,X6S,CH6223MEA01    I26 @T6G_MB_LIB.T6G(SCH_1):PAGE245
   PC3    2      B Q_CAPP_THLF-270UF,16V,20%,OSCON,CC72703MD38    I29 @T6G_MB_LIB.T6G(SCH_1):PAGE245
 PC566    2      B Q_CAPP_THLF-270UF,16V,20%,OSCON,CC72703MD38    I30 @T6G_MB_LIB.T6G(SCH_1):PAGE245
PC2262    2      B Q_CAP_C0805-22UF,16V,20%,X6S,CH6223MEA01    I31 @T6G_MB_LIB.T6G(SCH_1):PAGE245
PC8567    2      B Q_CAP_C0805-22UF,16V,20%,X6S,CH6223MEA01    I32 @T6G_MB_LIB.T6G(SCH_1):PAGE245
PC2263    2      B Q_CAP_C0805-22UF,16V,20%,X6S,CH6223MEA01    I33 @T6G_MB_LIB.T6G(SCH_1):PAGE245
PC2342    2      B Q_CAP_C0805-22UF,16V,20%,X6S,CH6223MEA01    I34 @T6G_MB_LIB.T6G(SCH_1):PAGE245
 PC570    2      B Q_CAP_C0805-22UF,16V,20%,X6S,CH6223MEA01    I35 @T6G_MB_LIB.T6G(SCH_1):PAGE245
 PC571    2      B Q_CAP_C0805-22UF,16V,20%,X6S,CH6223MEA01    I36 @T6G_MB_LIB.T6G(SCH_1):PAGE245
PC2343    2      B Q_CAP_C0805-22UF,16V,20%,X6S,CH6223MEA01    I37 @T6G_MB_LIB.T6G(SCH_1):PAGE245
PC2344    2      B Q_CAP_C0805-22UF,16V,20%,X6S,CH6223MEA01    I38 @T6G_MB_LIB.T6G(SCH_1):PAGE245
 PC576    2      B Q_CAP_C0805-22UF,16V,20%,X6S,CH6223MEA01    I39 @T6G_MB_LIB.T6G(SCH_1):PAGE245
PC8071    2      B Q_CAP_C0805-22UF,16V,20%,X6S,CH6223MEA01    I40 @T6G_MB_LIB.T6G(SCH_1):PAGE245
 PC577    2      B Q_CAP_0402-0.1UF,25V,10%,X7R,CH4104K1B00    I41 @T6G_MB_LIB.T6G(SCH_1):PAGE245
 PR830    2      B Q_RES_0402LF-15K,0.1%,1/16W,CHIP,CS31502BB03    I51 @T6G_MB_LIB.T6G(SCH_1):PAGE245
PC1866    2      B Q_CAPP_THLF-560UF,6.3V,20%,OSCON,CC75601MD16    I57 @T6G_MB_LIB.T6G(SCH_1):PAGE245
PC1867    2      B Q_CAPP_THLF-560UF,6.3V,20%,OSCON,CC75601MD16    I58 @T6G_MB_LIB.T6G(SCH_1):PAGE245
PC1868    2      B Q_CAP_C0805-22UF,10V,20%,X6S,CH6222MEA01    I59 @T6G_MB_LIB.T6G(SCH_1):PAGE245
PC1600    2      B Q_CAP_C0805-22UF,10V,20%,X6S,CH6222MEA01    I62 @T6G_MB_LIB.T6G(SCH_1):PAGE245
PC1869    2      B Q_CAP_0402-0.1UF,25V,10%,X7R,CH4104K1B00    I63 @T6G_MB_LIB.T6G(SCH_1):PAGE245
 R3430    2      B Q_RES_0402LF-100K,1%,1/16W,EMPTY,CS41002FB09     I3 @T6G_MB_LIB.T6G(SCH_1):PAGE299
 R3428    2      B Q_RES_0402LF-100K,1%,1/16W,EMPTY,CS41002FB09    I17 @T6G_MB_LIB.T6G(SCH_1):PAGE299
  Q104    1     S1 MOSFET_NCH_DUAL-PJT138K,SMLF,IC,BAM138K0003    I21 @T6G_MB_LIB.T6G(SCH_1):PAGE299
  Q104    4     S2 MOSFET_NCH_DUAL-PJT138K,SMLF,IC,BAM138K0003    I26 @T6G_MB_LIB.T6G(SCH_1):PAGE299
 C1976    2      B Q_CAP_0402-0.1UF,25V,10%,X7R,CH4104K1B00    I30 @T6G_MB_LIB.T6G(SCH_1):PAGE299
  Q103    1     S1 MOSFET_NCH_DUAL-PJT138K,SMLF,IC,BAM138K0003    I37 @T6G_MB_LIB.T6G(SCH_1):PAGE299
  Q102    1     S1 MOSFET_NCH_DUAL-PJT138K,SMLF,IC,BAM138K0003    I40 @T6G_MB_LIB.T6G(SCH_1):PAGE299
  Q103    4     S2 MOSFET_NCH_DUAL-PJT138K,SMLF,IC,BAM138K0003    I43 @T6G_MB_LIB.T6G(SCH_1):PAGE299
  Q102    4     S2 MOSFET_NCH_DUAL-PJT138K,SMLF,IC,BAM138K0003    I48 @T6G_MB_LIB.T6G(SCH_1):PAGE299
  Q101    1     S1 MOSFET_NCH_DUAL-PJT138K,SMLF,IC,BAM138K0003    I52 @T6G_MB_LIB.T6G(SCH_1):PAGE299
  Q101    4     S2 MOSFET_NCH_DUAL-PJT138K,SMLF,IC,BAM138K0003    I57 @T6G_MB_LIB.T6G(SCH_1):PAGE299
 C1973    2      B Q_CAP_0402-0.1UF,25V,10%,X7R,CH4104K1B00    I71 @T6G_MB_LIB.T6G(SCH_1):PAGE299
 C1974    2      B Q_CAP_0402-0.1UF,25V,10%,X7R,CH4104K1B00    I74 @T6G_MB_LIB.T6G(SCH_1):PAGE299
 C1975    2      B Q_CAP_0402-0.1UF,25V,10%,X7R,CH4104K1B00   I129 @T6G_MB_LIB.T6G(SCH_1):PAGE299
 R3463    2      B Q_RES_0402LF-54.9K,1%,1/16W,CHIP,CS35492FB03   I131 @T6G_MB_LIB.T6G(SCH_1):PAGE299
 R3431    2      B Q_RES_0402LF-100K,1%,1/16W,EMPTY,CS41002FB09   I133 @T6G_MB_LIB.T6G(SCH_1):PAGE299
 C1978    2      B Q_CAP_0402-0.1UF,25V,10%,X7R,CH4104K1B00   I152 @T6G_MB_LIB.T6G(SCH_1):PAGE299
  Q107    4     S2 MOSFET_NCH_DUAL-PJT138K,SMLF,IC,BAM138K0003   I157 @T6G_MB_LIB.T6G(SCH_1):PAGE299
  Q107    1     S1 MOSFET_NCH_DUAL-PJT138K,SMLF,IC,BAM138K0003   I160 @T6G_MB_LIB.T6G(SCH_1):PAGE299
 R3473    2      B Q_RES_0402LF-100K,1%,1/16W,EMPTY,CS41002FB09   I163 @T6G_MB_LIB.T6G(SCH_1):PAGE299
  Q108    4     S2 MOSFET_NCH_DUAL-PJT138K,SMLF,IC,BAM138K0003   I168 @T6G_MB_LIB.T6G(SCH_1):PAGE299
  Q108    1     S1 MOSFET_NCH_DUAL-PJT138K,SMLF,IC,BAM138K0003   I169 @T6G_MB_LIB.T6G(SCH_1):PAGE299
 C1988    2      B Q_CAP_0402-0.1UF,25V,10%,X7R,CH4104K1B00   I171 @T6G_MB_LIB.T6G(SCH_1):PAGE299
 R3502    2      B Q_RES_0402LF-100K,1%,1/16W,EMPTY,CS41002FB09   I181 @T6G_MB_LIB.T6G(SCH_1):PAGE299
 R4161    2      B Q_RES_0402LF-100K,1%,1/16W,EMPTY,CS41002FB09     I2 @T6G_MB_LIB.T6G(SCH_1):PAGE331
 R4163    2      B Q_RES_0402LF-100K,1%,1/16W,EMPTY,CS41002FB09     I8 @T6G_MB_LIB.T6G(SCH_1):PAGE331
 R4159    2      B Q_RES_0402LF-100K,1%,1/16W,EMPTY,CS41002FB09    I13 @T6G_MB_LIB.T6G(SCH_1):PAGE331
  Q136    1     S1 MOSFET_NCH_DUAL-PJT138K,SMLF,IC,BAM138K0003    I17 @T6G_MB_LIB.T6G(SCH_1):PAGE331
  Q137    1     S1 MOSFET_NCH_DUAL-PJT138K,SMLF,IC,BAM138K0003    I21 @T6G_MB_LIB.T6G(SCH_1):PAGE331
  Q136    4     S2 MOSFET_NCH_DUAL-PJT138K,SMLF,IC,BAM138K0003    I22 @T6G_MB_LIB.T6G(SCH_1):PAGE331
  Q135    1     S1 MOSFET_NCH_DUAL-PJT138K,SMLF,IC,BAM138K0003    I25 @T6G_MB_LIB.T6G(SCH_1):PAGE331
  Q137    4     S2 MOSFET_NCH_DUAL-PJT138K,SMLF,IC,BAM138K0003    I28 @T6G_MB_LIB.T6G(SCH_1):PAGE331
  Q135    4     S2 MOSFET_NCH_DUAL-PJT138K,SMLF,IC,BAM138K0003    I29 @T6G_MB_LIB.T6G(SCH_1):PAGE331
    C5    2      B Q_CAP_0402-0.1UF,25V,10%,X7R,CH4104K1B00    I33 @T6G_MB_LIB.T6G(SCH_1):PAGE331
    C7    2      B Q_CAP_0402-0.1UF,25V,10%,X7R,CH4104K1B00    I42 @T6G_MB_LIB.T6G(SCH_1):PAGE331
    C4    2      B Q_CAP_0402-0.1UF,25V,10%,X7R,CH4104K1B00    I44 @T6G_MB_LIB.T6G(SCH_1):PAGE331
  Q148    4     S2 MOSFET_NCH_DUAL-PJT138K,SMLF,IC,BAM138K0003    I55 @T6G_MB_LIB.T6G(SCH_1):PAGE331
  Q148    1     S1 MOSFET_NCH_DUAL-PJT138K,SMLF,IC,BAM138K0003    I61 @T6G_MB_LIB.T6G(SCH_1):PAGE331
 R4544    2      B Q_RES_0402LF-100K,1%,1/16W,EMPTY,CS41002FB09    I62 @T6G_MB_LIB.T6G(SCH_1):PAGE331
  U316    3     A1 74LVC2G17GW-74LVC2G17GW,SMLF,IC,AL2G0017005    I86 @T6G_MB_LIB.T6G(SCH_1):PAGE331
  U316    2    GND 74LVC2G17GW-74LVC2G17GW,SMLF,IC,AL2G0017005    I86 @T6G_MB_LIB.T6G(SCH_1):PAGE331
 R4548    2      B Q_RES_0402LF-100K,1%,1/16W,CHIP,CS41002FB09    I87 @T6G_MB_LIB.T6G(SCH_1):PAGE331
    C8    2      B Q_CAP_0402-0.1UF,25V,10%,X7R,CH4104K1B00    I93 @T6G_MB_LIB.T6G(SCH_1):PAGE331
 R4555    2      B Q_RES_0402LF-4.7K,5%,1/16W,EMPTY,CS24702JB10    I99 @T6G_MB_LIB.T6G(SCH_1):PAGE331
   Q67    1     S1 MOSFET_NCH_DUAL-PJT138K,SMLF,IC,BAM138K0003    I33 @T6G_MB_LIB.T6G(SCH_1):PAGE333
   Q70    1     S1 MOSFET_NCH_DUAL-PJT138K,SMLF,IC,BAM138K0003    I35 @T6G_MB_LIB.T6G(SCH_1):PAGE333
   Q72    1     S1 MOSFET_NCH_DUAL-PJT138K,SMLF,IC,BAM138K0003    I37 @T6G_MB_LIB.T6G(SCH_1):PAGE333
 R2831    2      B Q_RES_0402LF-100K,1%,1/16W,EMPTY,CS41002FB09    I56 @T6G_MB_LIB.T6G(SCH_1):PAGE333
 R2829    2      B Q_RES_0402LF-100K,1%,1/16W,EMPTY,CS41002FB09    I58 @T6G_MB_LIB.T6G(SCH_1):PAGE333
 R2833    2      B Q_RES_0402LF-100K,1%,1/16W,EMPTY,CS41002FB09    I60 @T6G_MB_LIB.T6G(SCH_1):PAGE333
 R2838    2      B Q_RES_0402LF-100K,1%,1/16W,CHIP,CS41002FB09    I62 @T6G_MB_LIB.T6G(SCH_1):PAGE333
   Q67    4     S2 MOSFET_NCH_DUAL-PJT138K,SMLF,IC,BAM138K0003    I82 @T6G_MB_LIB.T6G(SCH_1):PAGE333
   Q69    4     S2 MOSFET_NCH_DUAL-PJT138K,SMLF,IC,BAM138K0003    I88 @T6G_MB_LIB.T6G(SCH_1):PAGE333
 C1754    2      B Q_CAP_0402-0.1UF,25V,10%,X7R,CH4104K1B00    I92 @T6G_MB_LIB.T6G(SCH_1):PAGE333
   Q71    4     S2 MOSFET_NCH_DUAL-PJT138K,SMLF,IC,BAM138K0003   I100 @T6G_MB_LIB.T6G(SCH_1):PAGE333
 C1756    2      B Q_CAP_0402-0.1UF,25V,10%,X7R,CH4104K1B00   I105 @T6G_MB_LIB.T6G(SCH_1):PAGE333
 C1774    2      B Q_CAP_0402-0.1UF,25V,10%,X7R,CH4104K1B00   I111 @T6G_MB_LIB.T6G(SCH_1):PAGE333
 C1773    2      B Q_CAP_0402-0.1UF,25V,10%,X7R,CH4104K1B00   I114 @T6G_MB_LIB.T6G(SCH_1):PAGE333
 C1772    2      B Q_CAP_0402-0.1UF,25V,10%,X7R,CH4104K1B00   I116 @T6G_MB_LIB.T6G(SCH_1):PAGE333
   Q69    1     S1 MOSFET_NCH_DUAL-PJT138K,SMLF,IC,BAM138K0003   I117 @T6G_MB_LIB.T6G(SCH_1):PAGE333
   Q71    1     S1 MOSFET_NCH_DUAL-PJT138K,SMLF,IC,BAM138K0003   I118 @T6G_MB_LIB.T6G(SCH_1):PAGE333
   Q72    4     S2 MOSFET_NCH_DUAL-PJT138K,SMLF,IC,BAM138K0003   I119 @T6G_MB_LIB.T6G(SCH_1):PAGE333
   Q70    4     S2 MOSFET_NCH_DUAL-PJT138K,SMLF,IC,BAM138K0003   I120 @T6G_MB_LIB.T6G(SCH_1):PAGE333
   Q74    1     S1 MOSFET_NCH_DUAL-PJT138K,SMLF,IC,BAM138K0003   I121 @T6G_MB_LIB.T6G(SCH_1):PAGE333
   Q74    4     S2 MOSFET_NCH_DUAL-PJT138K,SMLF,IC,BAM138K0003   I122 @T6G_MB_LIB.T6G(SCH_1):PAGE333
 C1804    2      B Q_CAP_0402-0.1UF,25V,10%,X7R,CH4104K1B00   I125 @T6G_MB_LIB.T6G(SCH_1):PAGE333
 R3032    2      B Q_RES_0402LF-100K,1%,1/16W,EMPTY,CS41002FB09   I134 @T6G_MB_LIB.T6G(SCH_1):PAGE333
 R3028    2      B Q_RES_0402LF-100K,1%,1/16W,EMPTY,CS41002FB09   I139 @T6G_MB_LIB.T6G(SCH_1):PAGE333
 C1802    2      B Q_CAP_0402-0.1UF,25V,10%,X7R,CH4104K1B00   I148 @T6G_MB_LIB.T6G(SCH_1):PAGE333
   Q75    4     S2 MOSFET_NCH_DUAL-PJT138K,SMLF,IC,BAM138K0003   I151 @T6G_MB_LIB.T6G(SCH_1):PAGE333
   Q75    1     S1 MOSFET_NCH_DUAL-PJT138K,SMLF,IC,BAM138K0003   I152 @T6G_MB_LIB.T6G(SCH_1):PAGE333
   Q96    1     S1 MOSFET_NCH_DUAL-PJT138K,SMLF,IC,BAM138K0003   I154 @T6G_MB_LIB.T6G(SCH_1):PAGE333
 C1881    2      B Q_CAP_0402-0.1UF,25V,10%,X7R,CH4104K1B00   I156 @T6G_MB_LIB.T6G(SCH_1):PAGE333
   Q96    4     S2 MOSFET_NCH_DUAL-PJT138K,SMLF,IC,BAM138K0003   I159 @T6G_MB_LIB.T6G(SCH_1):PAGE333
 R3511    2      B Q_RES_0402LF-54.9K,1%,1/16W,CHIP,CS35492FB03   I172 @T6G_MB_LIB.T6G(SCH_1):PAGE333
 R3513    2      B Q_RES_0402LF-54.9K,1%,1/16W,CHIP,CS35492FB03   I173 @T6G_MB_LIB.T6G(SCH_1):PAGE333
  U253    2    GND 74LVC2G17GW-74LVC2G17GW,SMLF,IC,AL2G0017005    I26 @T6G_MB_LIB.T6G(SCH_1):PAGE334
 C1958    2      B Q_CAP_0402-0.1UF,25V,10%,X7R,CH4104K1B00    I29 @T6G_MB_LIB.T6G(SCH_1):PAGE334
 R3452    2      B Q_RES_0402LF-100K,1%,1/16W,CHIP,CS41002FB09    I95 @T6G_MB_LIB.T6G(SCH_1):PAGE334
 R3457    2      B Q_RES_0402LF-10K,1%,1/16W,CHIP,CS31002FB08   I123 @T6G_MB_LIB.T6G(SCH_1):PAGE334
 R3455    2      B Q_RES_0402LF-10K,1%,1/16W,CHIP,CS31002FB08   I139 @T6G_MB_LIB.T6G(SCH_1):PAGE334
 C1957    2      B Q_CAP_0402-0.1UF,25V,10%,X7R,CH4104K1B00   I148 @T6G_MB_LIB.T6G(SCH_1):PAGE334
  U252    2    GND 74LVC2G17GW-74LVC2G17GW,SMLF,IC,AL2G0017005   I153 @T6G_MB_LIB.T6G(SCH_1):PAGE334
 R3454    2      B Q_RES_0402LF-1K,1%,1/16W,CHIP,CS21002FB06   I165 @T6G_MB_LIB.T6G(SCH_1):PAGE334
 R3449    2      B Q_RES_0402LF-100K,1%,1/16W,CHIP,CS41002FB09   I170 @T6G_MB_LIB.T6G(SCH_1):PAGE334
  U256    2    GND 74LVC2G17GW-74LVC2G17GW,SMLF,IC,AL2G0017005   I173 @T6G_MB_LIB.T6G(SCH_1):PAGE334
 C1977    2      B Q_CAP_0402-0.1UF,25V,10%,X7R,CH4104K1B00   I175 @T6G_MB_LIB.T6G(SCH_1):PAGE334
 R3467    2      B Q_RES_0402LF-10K,1%,1/16W,CHIP,CS31002FB08   I181 @T6G_MB_LIB.T6G(SCH_1):PAGE334
 R3466    2      B Q_RES_0402LF-10K,1%,1/16W,CHIP,CS31002FB08   I184 @T6G_MB_LIB.T6G(SCH_1):PAGE334
 R2918    2      B Q_RES_0402LF-4.7K,5%,1/16W,CHIP,CS24702JB10   I188 @T6G_MB_LIB.T6G(SCH_1):PAGE334
 R2932    2      B Q_RES_0402LF-4.7K,5%,1/16W,CHIP,CS24702JB10   I195 @T6G_MB_LIB.T6G(SCH_1):PAGE334
 C1963    2      B Q_CAP_0402-0.1UF,25V,10%,X7R,CH4104K1B00    I13 @T6G_MB_LIB.T6G(SCH_1):PAGE255
  U255    2    GND 74LVC2G07DW7-74LVC2G07DW-7,SMLF,IC,AL002G07003    I16 @T6G_MB_LIB.T6G(SCH_1):PAGE255
 R3460    2      B Q_RES_0402LF-100K,1%,1/16W,EMPTY,CS41002FB09    I31 @T6G_MB_LIB.T6G(SCH_1):PAGE255
 R3462    2      B Q_RES_0402LF-100K,1%,1/16W,EMPTY,CS41002FB09    I33 @T6G_MB_LIB.T6G(SCH_1):PAGE255
 R3489    2      B Q_RES_0402LF-100K,1%,1/16W,EMPTY,CS41002FB09    I42 @T6G_MB_LIB.T6G(SCH_1):PAGE255
 R3493    2      B Q_RES_0402LF-100K,1%,1/16W,EMPTY,CS41002FB09    I48 @T6G_MB_LIB.T6G(SCH_1):PAGE255
  U257    3     2A 74LVC2G07DW7-74LVC2G07DW-7,SMLF,IC,AL002G07003    I50 @T6G_MB_LIB.T6G(SCH_1):PAGE255
  U257    2    GND 74LVC2G07DW7-74LVC2G07DW-7,SMLF,IC,AL002G07003    I50 @T6G_MB_LIB.T6G(SCH_1):PAGE255
 R3495    2      B Q_RES_0402LF-100K,1%,1/16W,EMPTY,CS41002FB09    I62 @T6G_MB_LIB.T6G(SCH_1):PAGE255
 C1979    2      B Q_CAP_0402-0.1UF,25V,10%,X7R,CH4104K1B00    I67 @T6G_MB_LIB.T6G(SCH_1):PAGE255
 R3491    2      B Q_RES_0402LF-100K,1%,1/16W,EMPTY,CS41002FB09    I70 @T6G_MB_LIB.T6G(SCH_1):PAGE255
  U195    2    GND 74LVC2G17GW-74LVC2G17GW,SMLF,IC,AL2G0017005    I65 @T6G_MB_LIB.T6G(SCH_1):PAGE256
 C1769    2      B Q_CAP_0402-0.1UF,25V,10%,X7R,CH4104K1B00    I89 @T6G_MB_LIB.T6G(SCH_1):PAGE256
 R2915    2      B Q_RES_0402LF-4.7K,5%,1/16W,CHIP,CS24702JB10    I92 @T6G_MB_LIB.T6G(SCH_1):PAGE256
 R2916    2      B Q_RES_0402LF-4.7K,5%,1/16W,EMPTY,CS24702JB10    I93 @T6G_MB_LIB.T6G(SCH_1):PAGE256
 R2926    2      B Q_RES_0402LF-4.7K,5%,1/16W,CHIP,CS24702JB10   I121 @T6G_MB_LIB.T6G(SCH_1):PAGE256
  U196    2    GND 74LVC2G17GW-74LVC2G17GW,SMLF,IC,AL2G0017005   I127 @T6G_MB_LIB.T6G(SCH_1):PAGE256
 C1770    2      B Q_CAP_0402-0.1UF,25V,10%,X7R,CH4104K1B00   I140 @T6G_MB_LIB.T6G(SCH_1):PAGE256
 R2937    2      B Q_RES_0402LF-4.7K,5%,1/16W,CHIP,CS24702JB10   I160 @T6G_MB_LIB.T6G(SCH_1):PAGE256
 C1803    2      B Q_CAP_0402-0.1UF,25V,10%,X7R,CH4104K1B00   I166 @T6G_MB_LIB.T6G(SCH_1):PAGE256
 R3509    2      B Q_RES_0402LF-10K,1%,1/16W,CHIP,CS31002FB08   I191 @T6G_MB_LIB.T6G(SCH_1):PAGE256
 R3507    2      B Q_RES_0402LF-10K,1%,1/16W,CHIP,CS31002FB08   I192 @T6G_MB_LIB.T6G(SCH_1):PAGE256
 R3508    2      B Q_RES_0402LF-54.9K,1%,1/16W,CHIP,CS35492FB03   I194 @T6G_MB_LIB.T6G(SCH_1):PAGE256
  U204    3    GND 74LVC1G126SE7-74LVC1G126SE-7,SMLF,IC,AL1G0126009   I195 @T6G_MB_LIB.T6G(SCH_1):PAGE256
 R2927    2      B Q_RES_0402LF-100K,1%,1/16W,CHIP,CS41002FB09   I203 @T6G_MB_LIB.T6G(SCH_1):PAGE256
 R3207    2      B Q_RES_0402LF-100K,1%,1/16W,CHIP,CS41002FB09    I15 @T6G_MB_LIB.T6G(SCH_1):PAGE307
 C1825    2      B Q_CAP_0402-0.1UF,25V,10%,X7R,CH4104K1B00    I17 @T6G_MB_LIB.T6G(SCH_1):PAGE307
  U222    7    GND 74CBTLV3126PW-74CBTLV3126PW,SMLF,IC,AL003126K08    I32 @T6G_MB_LIB.T6G(SCH_1):PAGE307
 C1826    2      B Q_CAP_0402-0.1UF,25V,10%,X7R,CH4104K1B00    I33 @T6G_MB_LIB.T6G(SCH_1):PAGE307
 R3208    2      B Q_RES_0402LF-100,1%,1/16W,CHIP,CS11002FB07    I37 @T6G_MB_LIB.T6G(SCH_1):PAGE307
 R3216    2      B Q_RES_0402LF-100,1%,1/16W,CHIP,CS11002FB07    I38 @T6G_MB_LIB.T6G(SCH_1):PAGE307
 R3217    2      B Q_RES_0402LF-100,1%,1/16W,CHIP,CS11002FB07    I40 @T6G_MB_LIB.T6G(SCH_1):PAGE307
 C1827    2      B Q_CAP_0402-0.1UF,25V,10%,X7R,CH4104K1B00    I77 @T6G_MB_LIB.T6G(SCH_1):PAGE307
  U223    7    GND 74CBTLV3126PW-74CBTLV3126PW,SMLF,IC,AL003126K08    I78 @T6G_MB_LIB.T6G(SCH_1):PAGE307
  U286    3    GND 74LVC1G126SE7-74LVC1G126SE-7,SMLF,IC,AL1G0126009    I80 @T6G_MB_LIB.T6G(SCH_1):PAGE307
   R32    2      B Q_RES_0402LF-4.7K,1%,1/16W,CHIP,CS24702FB06     I2 @T6G_MB_LIB.T6G(SCH_1):PAGE335
 R3132    1      A Q_RES_0402LF-100K,1%,1/16W,CHIP,CS41002FB09     I6 @T6G_MB_LIB.T6G(SCH_1):PAGE335
   C21    2      B Q_CAP_0402-0.1UF,25V,10%,X7R,CH4104K1B00    I89 @T6G_MB_LIB.T6G(SCH_1):PAGE335
 C1235    2      B Q_CAP_0402-0.1UF,25V,10%,X7R,CH4104K1B00    I90 @T6G_MB_LIB.T6G(SCH_1):PAGE335
 C1237    2      B Q_CAP_0402-0.1UF,25V,10%,X7R,CH4104K1B00   I110 @T6G_MB_LIB.T6G(SCH_1):PAGE335
 C1238    2      B Q_CAP_0402-0.1UF,25V,10%,X7R,CH4104K1B00   I111 @T6G_MB_LIB.T6G(SCH_1):PAGE335
 C1240    2      B Q_CAP_0402-0.1UF,25V,10%,X7R,CH4104K1B00   I114 @T6G_MB_LIB.T6G(SCH_1):PAGE335
   J38   G1     G1 SCONN168_ME1016810202011-SCONN168_ME1016810202011,A   I168 @T6G_MB_LIB.T6G(SCH_1):PAGE335
   J38   G2     G2 SCONN168_ME1016810202011-SCONN168_ME1016810202011,A   I168 @T6G_MB_LIB.T6G(SCH_1):PAGE335
   J38   G3     G3 SCONN168_ME1016810202011-SCONN168_ME1016810202011,A   I168 @T6G_MB_LIB.T6G(SCH_1):PAGE335
   J38   G4     G4 SCONN168_ME1016810202011-SCONN168_ME1016810202011,A   I168 @T6G_MB_LIB.T6G(SCH_1):PAGE335
   J38   G5     G5 SCONN168_ME1016810202011-SCONN168_ME1016810202011,A   I168 @T6G_MB_LIB.T6G(SCH_1):PAGE335
   J38   A1 GND_A1 SCONN168_ME1016810202011-SCONN168_ME1016810202011,A   I168 @T6G_MB_LIB.T6G(SCH_1):PAGE335
   J38   A2 GND_A2 SCONN168_ME1016810202011-SCONN168_ME1016810202011,A   I168 @T6G_MB_LIB.T6G(SCH_1):PAGE335
   J38   A3 GND_A3 SCONN168_ME1016810202011-SCONN168_ME1016810202011,A   I168 @T6G_MB_LIB.T6G(SCH_1):PAGE335
   J38   A4 GND_A4 SCONN168_ME1016810202011-SCONN168_ME1016810202011,A   I168 @T6G_MB_LIB.T6G(SCH_1):PAGE335
   J38   A5 GND_A5 SCONN168_ME1016810202011-SCONN168_ME1016810202011,A   I168 @T6G_MB_LIB.T6G(SCH_1):PAGE335
   J38   A6 GND_A6 SCONN168_ME1016810202011-SCONN168_ME1016810202011,A   I168 @T6G_MB_LIB.T6G(SCH_1):PAGE335
   J38  A13 GND_A13 SCONN168_ME1016810202011-SCONN168_ME1016810202011,A   I168 @T6G_MB_LIB.T6G(SCH_1):PAGE335
   J38  A16 GND_A16 SCONN168_ME1016810202011-SCONN168_ME1016810202011,A   I168 @T6G_MB_LIB.T6G(SCH_1):PAGE335
   J38  A19 GND_A19 SCONN168_ME1016810202011-SCONN168_ME1016810202011,A   I168 @T6G_MB_LIB.T6G(SCH_1):PAGE335
   J38  A22 GND_A22 SCONN168_ME1016810202011-SCONN168_ME1016810202011,A   I168 @T6G_MB_LIB.T6G(SCH_1):PAGE335
   J38  A25 GND_A25 SCONN168_ME1016810202011-SCONN168_ME1016810202011,A   I168 @T6G_MB_LIB.T6G(SCH_1):PAGE335
   J38  A28 GND_A28 SCONN168_ME1016810202011-SCONN168_ME1016810202011,A   I168 @T6G_MB_LIB.T6G(SCH_1):PAGE335
   J38  A29 GND_A29 SCONN168_ME1016810202011-SCONN168_ME1016810202011,A   I168 @T6G_MB_LIB.T6G(SCH_1):PAGE335
   J38  A32 GND_A32 SCONN168_ME1016810202011-SCONN168_ME1016810202011,A   I168 @T6G_MB_LIB.T6G(SCH_1):PAGE335
   J38  A35 GND_A35 SCONN168_ME1016810202011-SCONN168_ME1016810202011,A   I168 @T6G_MB_LIB.T6G(SCH_1):PAGE335
   J38  A38 GND_A38 SCONN168_ME1016810202011-SCONN168_ME1016810202011,A   I168 @T6G_MB_LIB.T6G(SCH_1):PAGE335
   J38  A41 GND_A41 SCONN168_ME1016810202011-SCONN168_ME1016810202011,A   I168 @T6G_MB_LIB.T6G(SCH_1):PAGE335
   J38  A43 GND_A43 SCONN168_ME1016810202011-SCONN168_ME1016810202011,A   I168 @T6G_MB_LIB.T6G(SCH_1):PAGE335
   J38  A46 GND_A46 SCONN168_ME1016810202011-SCONN168_ME1016810202011,A   I168 @T6G_MB_LIB.T6G(SCH_1):PAGE335
   J38  A49 GND_A49 SCONN168_ME1016810202011-SCONN168_ME1016810202011,A   I168 @T6G_MB_LIB.T6G(SCH_1):PAGE335
   J38  A52 GND_A52 SCONN168_ME1016810202011-SCONN168_ME1016810202011,A   I168 @T6G_MB_LIB.T6G(SCH_1):PAGE335
   J38  A55 GND_A55 SCONN168_ME1016810202011-SCONN168_ME1016810202011,A   I168 @T6G_MB_LIB.T6G(SCH_1):PAGE335
   J38  A58 GND_A58 SCONN168_ME1016810202011-SCONN168_ME1016810202011,A   I168 @T6G_MB_LIB.T6G(SCH_1):PAGE335
   J38  A61 GND_A61 SCONN168_ME1016810202011-SCONN168_ME1016810202011,A   I168 @T6G_MB_LIB.T6G(SCH_1):PAGE335
   J38  A64 GND_A64 SCONN168_ME1016810202011-SCONN168_ME1016810202011,A   I168 @T6G_MB_LIB.T6G(SCH_1):PAGE335
   J38  A67 GND_A67 SCONN168_ME1016810202011-SCONN168_ME1016810202011,A   I168 @T6G_MB_LIB.T6G(SCH_1):PAGE335
   J38  B13 GND_B13 SCONN168_ME1016810202011-SCONN168_ME1016810202011,A   I168 @T6G_MB_LIB.T6G(SCH_1):PAGE335
   J38  B16 GND_B16 SCONN168_ME1016810202011-SCONN168_ME1016810202011,A   I168 @T6G_MB_LIB.T6G(SCH_1):PAGE335
   J38  B19 GND_B19 SCONN168_ME1016810202011-SCONN168_ME1016810202011,A   I168 @T6G_MB_LIB.T6G(SCH_1):PAGE335
   J38  B22 GND_B22 SCONN168_ME1016810202011-SCONN168_ME1016810202011,A   I168 @T6G_MB_LIB.T6G(SCH_1):PAGE335
   J38  B25 GND_B25 SCONN168_ME1016810202011-SCONN168_ME1016810202011,A   I168 @T6G_MB_LIB.T6G(SCH_1):PAGE335
   J38  B28 GND_B28 SCONN168_ME1016810202011-SCONN168_ME1016810202011,A   I168 @T6G_MB_LIB.T6G(SCH_1):PAGE335
   J38  B29 GND_B29 SCONN168_ME1016810202011-SCONN168_ME1016810202011,A   I168 @T6G_MB_LIB.T6G(SCH_1):PAGE335
   J38  B32 GND_B32 SCONN168_ME1016810202011-SCONN168_ME1016810202011,A   I168 @T6G_MB_LIB.T6G(SCH_1):PAGE335
   J38  B35 GND_B35 SCONN168_ME1016810202011-SCONN168_ME1016810202011,A   I168 @T6G_MB_LIB.T6G(SCH_1):PAGE335
   J38  B38 GND_B38 SCONN168_ME1016810202011-SCONN168_ME1016810202011,A   I168 @T6G_MB_LIB.T6G(SCH_1):PAGE335
   J38  B41 GND_B41 SCONN168_ME1016810202011-SCONN168_ME1016810202011,A   I168 @T6G_MB_LIB.T6G(SCH_1):PAGE335
   J38  B43 GND_B43 SCONN168_ME1016810202011-SCONN168_ME1016810202011,A   I168 @T6G_MB_LIB.T6G(SCH_1):PAGE335
   J38  B46 GND_B46 SCONN168_ME1016810202011-SCONN168_ME1016810202011,A   I168 @T6G_MB_LIB.T6G(SCH_1):PAGE335
   J38  B49 GND_B49 SCONN168_ME1016810202011-SCONN168_ME1016810202011,A   I168 @T6G_MB_LIB.T6G(SCH_1):PAGE335
   J38  B52 GND_B52 SCONN168_ME1016810202011-SCONN168_ME1016810202011,A   I168 @T6G_MB_LIB.T6G(SCH_1):PAGE335
   J38  B55 GND_B55 SCONN168_ME1016810202011-SCONN168_ME1016810202011,A   I168 @T6G_MB_LIB.T6G(SCH_1):PAGE335
   J38  B58 GND_B58 SCONN168_ME1016810202011-SCONN168_ME1016810202011,A   I168 @T6G_MB_LIB.T6G(SCH_1):PAGE335
   J38  B61 GND_B61 SCONN168_ME1016810202011-SCONN168_ME1016810202011,A   I168 @T6G_MB_LIB.T6G(SCH_1):PAGE335
   J38  B64 GND_B64 SCONN168_ME1016810202011-SCONN168_ME1016810202011,A   I168 @T6G_MB_LIB.T6G(SCH_1):PAGE335
   J38  B67 GND_B67 SCONN168_ME1016810202011-SCONN168_ME1016810202011,A   I168 @T6G_MB_LIB.T6G(SCH_1):PAGE335
   J38 OA10 GND_OA10 SCONN168_ME1016810202011-SCONN168_ME1016810202011,A   I168 @T6G_MB_LIB.T6G(SCH_1):PAGE335
   J38 OA13 GND_OA13 SCONN168_ME1016810202011-SCONN168_ME1016810202011,A   I168 @T6G_MB_LIB.T6G(SCH_1):PAGE335
   J38 OB10 GND_OB10 SCONN168_ME1016810202011-SCONN168_ME1016810202011,A   I168 @T6G_MB_LIB.T6G(SCH_1):PAGE335
   J38 OB13 GND_OB13 SCONN168_ME1016810202011-SCONN168_ME1016810202011,A   I168 @T6G_MB_LIB.T6G(SCH_1):PAGE335
   U67    7    GND 74CBTLV3126PW-74CBTLV3126PW,SMLF,IC,AL003126K08     I1 @T6G_MB_LIB.T6G(SCH_1):PAGE336
    U7    7    GND 74CBTLV3126PW-74CBTLV3126PW,SMLF,IC,AL003126K08     I2 @T6G_MB_LIB.T6G(SCH_1):PAGE336
  C641    2      B Q_CAP_0402-0.1UF,25V,10%,X7R,CH4104K1B00    I16 @T6G_MB_LIB.T6G(SCH_1):PAGE336
  C640    2      B Q_CAP_0402-0.1UF,25V,10%,X7R,CH4104K1B00    I47 @T6G_MB_LIB.T6G(SCH_1):PAGE336
 R1289    2      B Q_RES_0402LF-100K,1%,1/16W,CHIP,CS41002FB09    I56 @T6G_MB_LIB.T6G(SCH_1):PAGE336
  C639    2      B Q_CAP_0402-0.1UF,25V,10%,X7R,CH4104K1B00    I59 @T6G_MB_LIB.T6G(SCH_1):PAGE336
 R1898    2      B Q_RES_0402LF-100,1%,1/16W,CHIP,CS11002FB07   I122 @T6G_MB_LIB.T6G(SCH_1):PAGE336
 R1896    2      B Q_RES_0402LF-100,1%,1/16W,CHIP,CS11002FB07   I123 @T6G_MB_LIB.T6G(SCH_1):PAGE336
 R1897    2      B Q_RES_0402LF-100,1%,1/16W,CHIP,CS11002FB07   I124 @T6G_MB_LIB.T6G(SCH_1):PAGE336
   R84    2      B Q_RES_0402LF-100K,1%,1/16W,CHIP,CS41002FB09   I129 @T6G_MB_LIB.T6G(SCH_1):PAGE336
   R77    2      B Q_RES_0402LF-100K,1%,1/16W,CHIP,CS41002FB09   I131 @T6G_MB_LIB.T6G(SCH_1):PAGE336
   R79    2      B Q_RES_0402LF-100K,1%,1/16W,CHIP,CS41002FB09   I132 @T6G_MB_LIB.T6G(SCH_1):PAGE336
   R80    2      B Q_RES_0402LF-100K,1%,1/16W,CHIP,CS41002FB09   I133 @T6G_MB_LIB.T6G(SCH_1):PAGE336
   R82    2      B Q_RES_0402LF-100K,1%,1/16W,CHIP,CS41002FB09   I134 @T6G_MB_LIB.T6G(SCH_1):PAGE336
   R83    2      B Q_RES_0402LF-100K,1%,1/16W,CHIP,CS41002FB09   I135 @T6G_MB_LIB.T6G(SCH_1):PAGE336
   R87    2      B Q_RES_0402LF-1K,1%,1/16W,CHIP,CS21002FB06   I136 @T6G_MB_LIB.T6G(SCH_1):PAGE336
 C1840    2      B Q_CAP_0402-0.1UF,25V,10%,X7R,CH4104K1B00   I147 @T6G_MB_LIB.T6G(SCH_1):PAGE336
 R3232    2      B Q_RES_0402LF-100K,1%,1/16W,CHIP,CS41002FB09   I152 @T6G_MB_LIB.T6G(SCH_1):PAGE336
   U66    3    GND 74LVC1G126SE7-74LVC1G126SE-7,SMLF,IC,AL1G0126009   I157 @T6G_MB_LIB.T6G(SCH_1):PAGE336
  U224    3    GND 74LVC1G126SE7-74LVC1G126SE-7,SMLF,IC,AL1G0126009   I159 @T6G_MB_LIB.T6G(SCH_1):PAGE336
   C72    2      B Q_CAP_0402-0.1UF,25V,10%,X7R,CH4104K1B00    I40 @T6G_MB_LIB.T6G(SCH_1):PAGE337
 C2344    2      B Q_CAP_0402-0.1UF,25V,10%,X7R,CH4104K1B00    I53 @T6G_MB_LIB.T6G(SCH_1):PAGE337
 C1834    2      B Q_CAP_0402-0.1UF,25V,10%,X7R,CH4104K1B00    I20 @T6G_MB_LIB.T6G(SCH_1):PAGE341
 C1837    2      B Q_CAP_0402-0.1UF,25V,10%,X7R,CH4104K1B00    I23 @T6G_MB_LIB.T6G(SCH_1):PAGE341
 R3165    1      A Q_RES_0402LF-10K,1%,1/16W,CHIP,CS31002FB08    I32 @T6G_MB_LIB.T6G(SCH_1):PAGE341
 R8413    1      A Q_RES_0402LF-100K,1%,1/16W,CHIP,CS41002FB09    I33 @T6G_MB_LIB.T6G(SCH_1):PAGE341
   J35   G1     G1 SCONN168_ME1016810202011-SCONN168_ME1016810202011,A   I168 @T6G_MB_LIB.T6G(SCH_1):PAGE341
   J35   G2     G2 SCONN168_ME1016810202011-SCONN168_ME1016810202011,A   I168 @T6G_MB_LIB.T6G(SCH_1):PAGE341
   J35   G3     G3 SCONN168_ME1016810202011-SCONN168_ME1016810202011,A   I168 @T6G_MB_LIB.T6G(SCH_1):PAGE341
   J35   G4     G4 SCONN168_ME1016810202011-SCONN168_ME1016810202011,A   I168 @T6G_MB_LIB.T6G(SCH_1):PAGE341
   J35   G5     G5 SCONN168_ME1016810202011-SCONN168_ME1016810202011,A   I168 @T6G_MB_LIB.T6G(SCH_1):PAGE341
   J35   A1 GND_A1 SCONN168_ME1016810202011-SCONN168_ME1016810202011,A   I168 @T6G_MB_LIB.T6G(SCH_1):PAGE341
   J35   A2 GND_A2 SCONN168_ME1016810202011-SCONN168_ME1016810202011,A   I168 @T6G_MB_LIB.T6G(SCH_1):PAGE341
   J35   A3 GND_A3 SCONN168_ME1016810202011-SCONN168_ME1016810202011,A   I168 @T6G_MB_LIB.T6G(SCH_1):PAGE341
   J35   A4 GND_A4 SCONN168_ME1016810202011-SCONN168_ME1016810202011,A   I168 @T6G_MB_LIB.T6G(SCH_1):PAGE341
   J35   A5 GND_A5 SCONN168_ME1016810202011-SCONN168_ME1016810202011,A   I168 @T6G_MB_LIB.T6G(SCH_1):PAGE341
   J35   A6 GND_A6 SCONN168_ME1016810202011-SCONN168_ME1016810202011,A   I168 @T6G_MB_LIB.T6G(SCH_1):PAGE341
   J35  A13 GND_A13 SCONN168_ME1016810202011-SCONN168_ME1016810202011,A   I168 @T6G_MB_LIB.T6G(SCH_1):PAGE341
   J35  A16 GND_A16 SCONN168_ME1016810202011-SCONN168_ME1016810202011,A   I168 @T6G_MB_LIB.T6G(SCH_1):PAGE341
   J35  A19 GND_A19 SCONN168_ME1016810202011-SCONN168_ME1016810202011,A   I168 @T6G_MB_LIB.T6G(SCH_1):PAGE341
   J35  A22 GND_A22 SCONN168_ME1016810202011-SCONN168_ME1016810202011,A   I168 @T6G_MB_LIB.T6G(SCH_1):PAGE341
   J35  A25 GND_A25 SCONN168_ME1016810202011-SCONN168_ME1016810202011,A   I168 @T6G_MB_LIB.T6G(SCH_1):PAGE341
   J35  A28 GND_A28 SCONN168_ME1016810202011-SCONN168_ME1016810202011,A   I168 @T6G_MB_LIB.T6G(SCH_1):PAGE341
   J35  A29 GND_A29 SCONN168_ME1016810202011-SCONN168_ME1016810202011,A   I168 @T6G_MB_LIB.T6G(SCH_1):PAGE341
   J35  A32 GND_A32 SCONN168_ME1016810202011-SCONN168_ME1016810202011,A   I168 @T6G_MB_LIB.T6G(SCH_1):PAGE341
   J35  A35 GND_A35 SCONN168_ME1016810202011-SCONN168_ME1016810202011,A   I168 @T6G_MB_LIB.T6G(SCH_1):PAGE341
   J35  A38 GND_A38 SCONN168_ME1016810202011-SCONN168_ME1016810202011,A   I168 @T6G_MB_LIB.T6G(SCH_1):PAGE341
   J35  A41 GND_A41 SCONN168_ME1016810202011-SCONN168_ME1016810202011,A   I168 @T6G_MB_LIB.T6G(SCH_1):PAGE341
   J35  A43 GND_A43 SCONN168_ME1016810202011-SCONN168_ME1016810202011,A   I168 @T6G_MB_LIB.T6G(SCH_1):PAGE341
   J35  A46 GND_A46 SCONN168_ME1016810202011-SCONN168_ME1016810202011,A   I168 @T6G_MB_LIB.T6G(SCH_1):PAGE341
   J35  A49 GND_A49 SCONN168_ME1016810202011-SCONN168_ME1016810202011,A   I168 @T6G_MB_LIB.T6G(SCH_1):PAGE341
   J35  A52 GND_A52 SCONN168_ME1016810202011-SCONN168_ME1016810202011,A   I168 @T6G_MB_LIB.T6G(SCH_1):PAGE341
   J35  A55 GND_A55 SCONN168_ME1016810202011-SCONN168_ME1016810202011,A   I168 @T6G_MB_LIB.T6G(SCH_1):PAGE341
   J35  A58 GND_A58 SCONN168_ME1016810202011-SCONN168_ME1016810202011,A   I168 @T6G_MB_LIB.T6G(SCH_1):PAGE341
   J35  A61 GND_A61 SCONN168_ME1016810202011-SCONN168_ME1016810202011,A   I168 @T6G_MB_LIB.T6G(SCH_1):PAGE341
   J35  A64 GND_A64 SCONN168_ME1016810202011-SCONN168_ME1016810202011,A   I168 @T6G_MB_LIB.T6G(SCH_1):PAGE341
   J35  A67 GND_A67 SCONN168_ME1016810202011-SCONN168_ME1016810202011,A   I168 @T6G_MB_LIB.T6G(SCH_1):PAGE341
   J35  B13 GND_B13 SCONN168_ME1016810202011-SCONN168_ME1016810202011,A   I168 @T6G_MB_LIB.T6G(SCH_1):PAGE341
   J35  B16 GND_B16 SCONN168_ME1016810202011-SCONN168_ME1016810202011,A   I168 @T6G_MB_LIB.T6G(SCH_1):PAGE341
   J35  B19 GND_B19 SCONN168_ME1016810202011-SCONN168_ME1016810202011,A   I168 @T6G_MB_LIB.T6G(SCH_1):PAGE341
   J35  B22 GND_B22 SCONN168_ME1016810202011-SCONN168_ME1016810202011,A   I168 @T6G_MB_LIB.T6G(SCH_1):PAGE341
   J35  B25 GND_B25 SCONN168_ME1016810202011-SCONN168_ME1016810202011,A   I168 @T6G_MB_LIB.T6G(SCH_1):PAGE341
   J35  B28 GND_B28 SCONN168_ME1016810202011-SCONN168_ME1016810202011,A   I168 @T6G_MB_LIB.T6G(SCH_1):PAGE341
   J35  B29 GND_B29 SCONN168_ME1016810202011-SCONN168_ME1016810202011,A   I168 @T6G_MB_LIB.T6G(SCH_1):PAGE341
   J35  B32 GND_B32 SCONN168_ME1016810202011-SCONN168_ME1016810202011,A   I168 @T6G_MB_LIB.T6G(SCH_1):PAGE341
   J35  B35 GND_B35 SCONN168_ME1016810202011-SCONN168_ME1016810202011,A   I168 @T6G_MB_LIB.T6G(SCH_1):PAGE341
   J35  B38 GND_B38 SCONN168_ME1016810202011-SCONN168_ME1016810202011,A   I168 @T6G_MB_LIB.T6G(SCH_1):PAGE341
   J35  B41 GND_B41 SCONN168_ME1016810202011-SCONN168_ME1016810202011,A   I168 @T6G_MB_LIB.T6G(SCH_1):PAGE341
   J35  B43 GND_B43 SCONN168_ME1016810202011-SCONN168_ME1016810202011,A   I168 @T6G_MB_LIB.T6G(SCH_1):PAGE341
   J35  B46 GND_B46 SCONN168_ME1016810202011-SCONN168_ME1016810202011,A   I168 @T6G_MB_LIB.T6G(SCH_1):PAGE341
   J35  B49 GND_B49 SCONN168_ME1016810202011-SCONN168_ME1016810202011,A   I168 @T6G_MB_LIB.T6G(SCH_1):PAGE341
   J35  B52 GND_B52 SCONN168_ME1016810202011-SCONN168_ME1016810202011,A   I168 @T6G_MB_LIB.T6G(SCH_1):PAGE341
   J35  B55 GND_B55 SCONN168_ME1016810202011-SCONN168_ME1016810202011,A   I168 @T6G_MB_LIB.T6G(SCH_1):PAGE341
   J35  B58 GND_B58 SCONN168_ME1016810202011-SCONN168_ME1016810202011,A   I168 @T6G_MB_LIB.T6G(SCH_1):PAGE341
   J35  B61 GND_B61 SCONN168_ME1016810202011-SCONN168_ME1016810202011,A   I168 @T6G_MB_LIB.T6G(SCH_1):PAGE341
   J35  B64 GND_B64 SCONN168_ME1016810202011-SCONN168_ME1016810202011,A   I168 @T6G_MB_LIB.T6G(SCH_1):PAGE341
   J35  B67 GND_B67 SCONN168_ME1016810202011-SCONN168_ME1016810202011,A   I168 @T6G_MB_LIB.T6G(SCH_1):PAGE341
   J35 OA10 GND_OA10 SCONN168_ME1016810202011-SCONN168_ME1016810202011,A   I168 @T6G_MB_LIB.T6G(SCH_1):PAGE341
   J35 OA13 GND_OA13 SCONN168_ME1016810202011-SCONN168_ME1016810202011,A   I168 @T6G_MB_LIB.T6G(SCH_1):PAGE341
   J35 OB10 GND_OB10 SCONN168_ME1016810202011-SCONN168_ME1016810202011,A   I168 @T6G_MB_LIB.T6G(SCH_1):PAGE341
   J35 OB13 GND_OB13 SCONN168_ME1016810202011-SCONN168_ME1016810202011,A   I168 @T6G_MB_LIB.T6G(SCH_1):PAGE341
 C1841    2      B Q_CAP_0402-0.1UF,25V,10%,X7R,CH4104K1B00    I12 @T6G_MB_LIB.T6G(SCH_1):PAGE342
 R3235    2      B Q_RES_0402LF-100K,1%,1/16W,CHIP,CS41002FB09    I24 @T6G_MB_LIB.T6G(SCH_1):PAGE342
 C1823    2      B Q_CAP_0402-0.1UF,25V,10%,X7R,CH4104K1B00    I31 @T6G_MB_LIB.T6G(SCH_1):PAGE342
 C1824    2      B Q_CAP_0402-0.1UF,25V,10%,X7R,CH4104K1B00    I41 @T6G_MB_LIB.T6G(SCH_1):PAGE342
   C38    2      B Q_CAP_0402-0.1UF,25V,10%,X7R,CH4104K1B00    I47 @T6G_MB_LIB.T6G(SCH_1):PAGE342
  Q118    1     S1 MOSFET_NCH_DUAL-PJT138K,SMLF,IC,BAM138K0003    I10 @T6G_MB_LIB.T6G(SCH_1):PAGE343
  Q118    4     S2 MOSFET_NCH_DUAL-PJT138K,SMLF,IC,BAM138K0003    I19 @T6G_MB_LIB.T6G(SCH_1):PAGE343
   U58    2    GND 74LVC2G07DW7-74LVC2G07DW-7,SMLF,IC,AL002G07003    I28 @T6G_MB_LIB.T6G(SCH_1):PAGE343
  Q119    1     S1 MOSFET_NCH_DUAL-PJT138K,SMLF,IC,BAM138K0003    I42 @T6G_MB_LIB.T6G(SCH_1):PAGE343
  Q119    4     S2 MOSFET_NCH_DUAL-PJT138K,SMLF,IC,BAM138K0003    I45 @T6G_MB_LIB.T6G(SCH_1):PAGE343
 PD107    A      A DIODE_TVS-SMF14A,SMLF,IC,BCSMF14AZ01    I47 @T6G_MB_LIB.T6G(SCH_1):PAGE343
PC2139    2      B Q_CAP_C0402-1UF,25V,10%,X6S,CH5104KEB02    I49 @T6G_MB_LIB.T6G(SCH_1):PAGE343
PR3812    2      B Q_RES_0402LF-15K,1%,1/16W,CHIP,CS31502FB05    I51 @T6G_MB_LIB.T6G(SCH_1):PAGE343
PR3821    2      B Q_RES_0402LF-30.1K,1%,1/16W,CHIP,CS33012FB03    I63 @T6G_MB_LIB.T6G(SCH_1):PAGE343
PC2098    2      B Q_CAP_C0402-1UF,25V,10%,X6S,CH5104KEB02    I65 @T6G_MB_LIB.T6G(SCH_1):PAGE343
PC2146    1      A Q_CAP_C0402-1UF,25V,10%,X6S,CH5104KEB02    I66 @T6G_MB_LIB.T6G(SCH_1):PAGE343
 PU201   A7   CDLY MAX15090BEWIT-MAX15090BEWI+T,SMLF,IC,AL015080B00    I67 @T6G_MB_LIB.T6G(SCH_1):PAGE343
 PU201   B7    EN# MAX15090BEWIT-MAX15090BEWI+T,SMLF,IC,AL015080B00    I67 @T6G_MB_LIB.T6G(SCH_1):PAGE343
 PU201   B2 GND_B2 MAX15090BEWIT-MAX15090BEWI+T,SMLF,IC,AL015080B00    I67 @T6G_MB_LIB.T6G(SCH_1):PAGE343
 PU201   C1 GND_C1 MAX15090BEWIT-MAX15090BEWI+T,SMLF,IC,AL015080B00    I67 @T6G_MB_LIB.T6G(SCH_1):PAGE343
 PU201   C2 GND_C2 MAX15090BEWIT-MAX15090BEWI+T,SMLF,IC,AL015080B00    I67 @T6G_MB_LIB.T6G(SCH_1):PAGE343
PR3823    2      B Q_RES_0402LF-845,1%,1/16W,CHIP,CS18452FB01    I71 @T6G_MB_LIB.T6G(SCH_1):PAGE343
PC2147    1      A Q_CAP_C0402-1UF,25V,10%,X6S,CH5104KEB02    I86 @T6G_MB_LIB.T6G(SCH_1):PAGE343
PR3822    2      B Q_RES_0402LF-5.36K,1%,1/16W,CHIP,CS25362FB02    I88 @T6G_MB_LIB.T6G(SCH_1):PAGE343
 PU200   A7   CDLY MAX15090BEWIT-MAX15090BEWI+T,SMLF,IC,AL015080B00    I89 @T6G_MB_LIB.T6G(SCH_1):PAGE343
 PU200   B7    EN# MAX15090BEWIT-MAX15090BEWI+T,SMLF,IC,AL015080B00    I89 @T6G_MB_LIB.T6G(SCH_1):PAGE343
 PU200   B2 GND_B2 MAX15090BEWIT-MAX15090BEWI+T,SMLF,IC,AL015080B00    I89 @T6G_MB_LIB.T6G(SCH_1):PAGE343
 PU200   C1 GND_C1 MAX15090BEWIT-MAX15090BEWI+T,SMLF,IC,AL015080B00    I89 @T6G_MB_LIB.T6G(SCH_1):PAGE343
 PU200   C2 GND_C2 MAX15090BEWIT-MAX15090BEWI+T,SMLF,IC,AL015080B00    I89 @T6G_MB_LIB.T6G(SCH_1):PAGE343
   C39    2      B Q_CAP_C0402-1UF,25V,10%,X6S,CH5104KEB02    I90 @T6G_MB_LIB.T6G(SCH_1):PAGE343
 PD108    A      A SCHOTTKY_AC-B340A-13-F,SMLF,IC,BC000340Z30    I92 @T6G_MB_LIB.T6G(SCH_1):PAGE343
PR3824    2      B Q_RES_0402LF-4.53K,1%,1/16W,CHIP,CS24532FB03    I94 @T6G_MB_LIB.T6G(SCH_1):PAGE343
PC2152    2      B Q_CAP_0402-0.1UF,25V,10%,X7R,CH4104K1B00    I97 @T6G_MB_LIB.T6G(SCH_1):PAGE343
PC2141    2      B Q_CAP_C0805-22UF,16V,20%,X6S,CH6223MEA01    I99 @T6G_MB_LIB.T6G(SCH_1):PAGE343
PC2143    2      B Q_CAP_C0805-10UF,16V,10%,X6S,CH6103KEA01   I101 @T6G_MB_LIB.T6G(SCH_1):PAGE343
PC2164    2      B Q_CAP_0402-0.22UF,16V,10%,X7R,CH4223K1B00     I2 @T6G_MB_LIB.T6G(SCH_1):PAGE344
PR3847    2      B Q_RES_0402LF-14.3K,1%,1/16W,CHIP,CS31432FB02     I4 @T6G_MB_LIB.T6G(SCH_1):PAGE344
PC2166    2      B Q_CAP_C0402-0.047UF,25V,10%,X7R,CH3474K1B04     I6 @T6G_MB_LIB.T6G(SCH_1):PAGE344
PC2165    2      B Q_CAP_C0402-1UF,25V,10%,X6S,CH5104KEB02    I13 @T6G_MB_LIB.T6G(SCH_1):PAGE344
PR3849    2      B Q_RES_0402LF-17.4K,1%,1/16W,CHIP,CS31742FB04    I15 @T6G_MB_LIB.T6G(SCH_1):PAGE344
PR3854    2      B Q_RES_0402LF-10K,1%,1/16W,CHIP,CS31002FB08    I20 @T6G_MB_LIB.T6G(SCH_1):PAGE344
PC1320    2      B Q_CAP_C0603-2.2UF,16V,20%,X7R,CH5223M1900    I24 @T6G_MB_LIB.T6G(SCH_1):PAGE344
PC2168    2      B Q_CAP_0402-39PF,50V,5%,NPO,CH03906JB06    I35 @T6G_MB_LIB.T6G(SCH_1):PAGE344
PC2174    2      B Q_CAP_0402-0.1UF,25V,10%,X7R,CH4104K1B00    I40 @T6G_MB_LIB.T6G(SCH_1):PAGE344
PR3855    2      B Q_RES_0402LF-71.5K,1%,1/16W,CHIP,CS37152FB05    I43 @T6G_MB_LIB.T6G(SCH_1):PAGE344
PR3856    1      A Q_RES_0402LF-1.33K,1%,1/16W,CHIP,CS21332FB05    I46 @T6G_MB_LIB.T6G(SCH_1):PAGE344
PC2169    2      B Q_CAP_C0402-1UF,25V,10%,X6S,CH5104KEB02    I48 @T6G_MB_LIB.T6G(SCH_1):PAGE344
PC1321    2      B Q_CAP_0402-0.068UF,16V,10%,X7R,CH3683K1B09    I50 @T6G_MB_LIB.T6G(SCH_1):PAGE344
 PU207    3    GND MP5016GQHLZ-MP5016GQH-L-Z,SMLF,IC,AL005016007    I51 @T6G_MB_LIB.T6G(SCH_1):PAGE344
PC1322    2      B Q_CAP_0402-100PF,50V,5%,X7R,CH11006JB18    I54 @T6G_MB_LIB.T6G(SCH_1):PAGE344
PC2173    2      B Q_CAP_C0805-10UF,16V,10%,X6S,CH6103KEA01    I56 @T6G_MB_LIB.T6G(SCH_1):PAGE344
  U241    4    GND 74LVC2G08DP-74LVC2G08DP,SMLF,EMPTY,ALVC2G08K01     I1 @T6G_MB_LIB.T6G(SCH_1):PAGE258
  U240    4    GND 74LVC2G08DP-74LVC2G08DP,SMLF,EMPTY,ALVC2G08K01    I11 @T6G_MB_LIB.T6G(SCH_1):PAGE258
  U242    4    GND 74LVC2G08DP-74LVC2G08DP,SMLF,EMPTY,ALVC2G08K01    I13 @T6G_MB_LIB.T6G(SCH_1):PAGE258
  U243    2    GND NC7SB3157_SMLF-NC7SB3157P6X,NC7SB3157P6X,EMPTY,ALSA    I15 @T6G_MB_LIB.T6G(SCH_1):PAGE258
  U244    2    GND NC7SB3157_SMLF-NC7SB3157P6X,NC7SB3157P6X,EMPTY,ALSA    I16 @T6G_MB_LIB.T6G(SCH_1):PAGE258
  U246    2    GND NC7SB3157_SMLF-NC7SB3157P6X,NC7SB3157P6X,EMPTY,ALSA    I17 @T6G_MB_LIB.T6G(SCH_1):PAGE258
  U245    2    GND NC7SB3157_SMLF-NC7SB3157P6X,NC7SB3157P6X,EMPTY,ALSA    I18 @T6G_MB_LIB.T6G(SCH_1):PAGE258
 C1875    2      B Q_CAP_0402-0.1UF,25V,10%,X7R,CH4104K1B00    I21 @T6G_MB_LIB.T6G(SCH_1):PAGE258
 C1874    2      B Q_CAP_0402-0.1UF,25V,10%,X7R,CH4104K1B00    I22 @T6G_MB_LIB.T6G(SCH_1):PAGE258
 C1880    2      B Q_CAP_0402-0.1UF,25V,10%,X7R,CH4104K1B00    I27 @T6G_MB_LIB.T6G(SCH_1):PAGE258
 C1879    2      B Q_CAP_0402-0.1UF,25V,10%,X7R,CH4104K1B00    I31 @T6G_MB_LIB.T6G(SCH_1):PAGE258
 C1877    2      B Q_CAP_0402-0.1UF,25V,10%,X7R,CH4104K1B00    I34 @T6G_MB_LIB.T6G(SCH_1):PAGE258
 C1878    2      B Q_CAP_0402-0.1UF,25V,10%,X7R,CH4104K1B00    I37 @T6G_MB_LIB.T6G(SCH_1):PAGE258
 C1876    2      B Q_CAP_0402-0.1UF,25V,10%,X7R,CH4104K1B00    I41 @T6G_MB_LIB.T6G(SCH_1):PAGE258
PC2197    2      B Q_CAP_0402-39PF,50V,5%,NPO,CH03906JB06     I3 @T6G_MB_LIB.T6G(SCH_1):PAGE323
PR3945    2      B Q_RES_0402LF-71.5K,1%,1/16W,CHIP,CS37152FB05     I4 @T6G_MB_LIB.T6G(SCH_1):PAGE323
PR3947    1      A Q_RES_0402LF-2.8K,1%,1/16W,CHIP,CS22802FB04     I6 @T6G_MB_LIB.T6G(SCH_1):PAGE323
PC2200    2      B Q_CAP_C0402-1UF,25V,10%,X6S,CH5104KEB02     I9 @T6G_MB_LIB.T6G(SCH_1):PAGE323
PC2196    2      B Q_CAP_0402-0.22UF,16V,10%,X7R,CH4223K1B00    I13 @T6G_MB_LIB.T6G(SCH_1):PAGE323
PR3944    2      B Q_RES_0402LF-46.4K,1%,1/16W,CHIP,CS34642FB02    I15 @T6G_MB_LIB.T6G(SCH_1):PAGE323
PC2341    2      B Q_CAP_C0402-560PF,50V,10%,X7R,CH1566K1B09    I17 @T6G_MB_LIB.T6G(SCH_1):PAGE323
PC2281    2      B Q_CAP_C0402-0.047UF,25V,10%,X7R,CH3474K1B04    I22 @T6G_MB_LIB.T6G(SCH_1):PAGE323
PC2198    2      B Q_CAP_C0402-1UF,25V,10%,X6S,CH5104KEB02    I25 @T6G_MB_LIB.T6G(SCH_1):PAGE323
PC2201    2      B Q_CAP_0402-0.068UF,16V,10%,X7R,CH3683K1B09    I30 @T6G_MB_LIB.T6G(SCH_1):PAGE323
 PU293    3    GND MP5016GQHLZ-MP5016GQH-L-Z,SMLF,IC,AL005016007    I31 @T6G_MB_LIB.T6G(SCH_1):PAGE323
PC2203    2      B Q_CAP_0402-100PF,50V,5%,X7R,CH11006JB18    I32 @T6G_MB_LIB.T6G(SCH_1):PAGE323
PC2204    2      B Q_CAP_C0805-10UF,16V,10%,X6S,CH6103KEA01    I34 @T6G_MB_LIB.T6G(SCH_1):PAGE323
PR3949    2      B Q_RES_0402LF-56K,1%,1/16W,CHIP,CS35602FB00    I36 @T6G_MB_LIB.T6G(SCH_1):PAGE323
PC2202    2      B Q_CAP_C0402-100NF,50V,10%,X7R,CH4106K1B01    I39 @T6G_MB_LIB.T6G(SCH_1):PAGE323
PR3954    2      B Q_RES_0402LF-10K,1%,1/16W,CHIP,CS31002FB08    I49 @T6G_MB_LIB.T6G(SCH_1):PAGE323
PC2205    2      B Q_CAP_C0603-2.2UF,16V,20%,X7R,CH5223M1900    I51 @T6G_MB_LIB.T6G(SCH_1):PAGE323
PC2206    2      B Q_CAP_0402-0.1UF,25V,10%,X7R,CH4104K1B00    I56 @T6G_MB_LIB.T6G(SCH_1):PAGE323
 R6049    2      B Q_RES_0402LF-4.7K,5%,1/16W,CHIP,CS24702JB10     I4 @T6G_MB_LIB.T6G(SCH_1):PAGE324
  Q126    1     S1 MOSFET_NCH_DUAL-PJT138K,SMLF,IC,BAM138K0003     I6 @T6G_MB_LIB.T6G(SCH_1):PAGE324
 R4073    2      B Q_RES_0402LF-4.7K,5%,1/16W,CHIP,CS24702JB10    I11 @T6G_MB_LIB.T6G(SCH_1):PAGE324
PR3965    2      B Q_RES_0402LF-15K,1%,1/16W,CHIP,CS31502FB05    I16 @T6G_MB_LIB.T6G(SCH_1):PAGE324
PC2208    2      B Q_CAP_C0402-1UF,25V,10%,X6S,CH5104KEB02    I20 @T6G_MB_LIB.T6G(SCH_1):PAGE324
  Q127    4     S2 MOSFET_NCH_DUAL-PJT138K,SMLF,IC,BAM138K0003    I27 @T6G_MB_LIB.T6G(SCH_1):PAGE324
PR3962    2      B Q_RES_0402LF-15K,1%,1/16W,CHIP,CS31502FB05    I31 @T6G_MB_LIB.T6G(SCH_1):PAGE324
 PD114    A      A DIODE_TVS-SMF14A,SMLF,IC,BCSMF14AZ01    I33 @T6G_MB_LIB.T6G(SCH_1):PAGE324
PC2207    2      B Q_CAP_C0402-1UF,25V,10%,X6S,CH5104KEB02    I36 @T6G_MB_LIB.T6G(SCH_1):PAGE324
PR3969    2      B Q_RES_0402LF-2.49K,1%,1/16W,CHIP,CS22492FB05    I39 @T6G_MB_LIB.T6G(SCH_1):PAGE324
PC2210    2      B Q_CAP_C0402-1UF,25V,10%,X6S,CH5104KEB02    I41 @T6G_MB_LIB.T6G(SCH_1):PAGE324
PR3971    2      B Q_RES_0402LF-9.76K,1%,1/16W,CHIP,CS29762FB05    I45 @T6G_MB_LIB.T6G(SCH_1):PAGE324
 PD113    A      A SCHOTTKY_AC-B340A-13-F,SMLF,IC,BC000340Z30    I50 @T6G_MB_LIB.T6G(SCH_1):PAGE324
PC2220    2      B Q_CAP_C0805-10UF,16V,10%,X6S,CH6103KEA01    I58 @T6G_MB_LIB.T6G(SCH_1):PAGE324
PC2211    1      A Q_CAP_C0402-1UF,25V,10%,X6S,CH5104KEB02    I61 @T6G_MB_LIB.T6G(SCH_1):PAGE324
PR3968    2      B Q_RES_0402LF-9.31K,1%,1/16W,CHIP,CS29312FB02    I63 @T6G_MB_LIB.T6G(SCH_1):PAGE324
 PU294   A7   CDLY MAX15090BEWIT-MAX15090BEWI+T,SMLF,IC,AL015080B00    I66 @T6G_MB_LIB.T6G(SCH_1):PAGE324
 PU294   B7    EN# MAX15090BEWIT-MAX15090BEWI+T,SMLF,IC,AL015080B00    I66 @T6G_MB_LIB.T6G(SCH_1):PAGE324
 PU294   B2 GND_B2 MAX15090BEWIT-MAX15090BEWI+T,SMLF,IC,AL015080B00    I66 @T6G_MB_LIB.T6G(SCH_1):PAGE324
 PU294   C1 GND_C1 MAX15090BEWIT-MAX15090BEWI+T,SMLF,IC,AL015080B00    I66 @T6G_MB_LIB.T6G(SCH_1):PAGE324
 PU294   C2 GND_C2 MAX15090BEWIT-MAX15090BEWI+T,SMLF,IC,AL015080B00    I66 @T6G_MB_LIB.T6G(SCH_1):PAGE324
PR3970    2      B Q_RES_0402LF-2.67K,1%,1/16W,CHIP,CS22672FB03    I68 @T6G_MB_LIB.T6G(SCH_1):PAGE324
PC2215    2      B Q_CAP_C0402-3900PF,50V,10%,X7R,CH23906KB14    I69 @T6G_MB_LIB.T6G(SCH_1):PAGE324
 PD112    A      A SCHOTTKY_AC-B340A-13-F,SMLF,IC,BC000340Z30    I74 @T6G_MB_LIB.T6G(SCH_1):PAGE324
PC2217    2      B Q_CAP_0402-0.1UF,25V,10%,X7R,CH4104K1B00    I78 @T6G_MB_LIB.T6G(SCH_1):PAGE324
PC2280    2      B Q_CAP_C0805-10UF,16V,10%,X6S,CH6103KEA01    I80 @T6G_MB_LIB.T6G(SCH_1):PAGE324
   J59   G1     G1 SCONN75K_APCI0155P004A-SCONN75K_APCI0155-P004A,SMLA    I88 @T6G_MB_LIB.T6G(SCH_1):PAGE345
   J59   G2     G2 SCONN75K_APCI0155P004A-SCONN75K_APCI0155-P004A,SMLA    I88 @T6G_MB_LIB.T6G(SCH_1):PAGE345
   J59    3   GND2 SCONN75K_APCI0155P004A-SCONN75K_APCI0155-P004A,SMLA    I88 @T6G_MB_LIB.T6G(SCH_1):PAGE345
   J59    9   GND3 SCONN75K_APCI0155P004A-SCONN75K_APCI0155-P004A,SMLA    I88 @T6G_MB_LIB.T6G(SCH_1):PAGE345
   J59   15   GND4 SCONN75K_APCI0155P004A-SCONN75K_APCI0155-P004A,SMLA    I88 @T6G_MB_LIB.T6G(SCH_1):PAGE345
   J59   21   GND5 SCONN75K_APCI0155P004A-SCONN75K_APCI0155-P004A,SMLA    I88 @T6G_MB_LIB.T6G(SCH_1):PAGE345
   J59   27   GND6 SCONN75K_APCI0155P004A-SCONN75K_APCI0155-P004A,SMLA    I88 @T6G_MB_LIB.T6G(SCH_1):PAGE345
   J59   33   GND7 SCONN75K_APCI0155P004A-SCONN75K_APCI0155-P004A,SMLA    I88 @T6G_MB_LIB.T6G(SCH_1):PAGE345
   J59   39   GND8 SCONN75K_APCI0155P004A-SCONN75K_APCI0155-P004A,SMLA    I88 @T6G_MB_LIB.T6G(SCH_1):PAGE345
   J59   45   GND9 SCONN75K_APCI0155P004A-SCONN75K_APCI0155-P004A,SMLA    I88 @T6G_MB_LIB.T6G(SCH_1):PAGE345
   J59   51  GND10 SCONN75K_APCI0155P004A-SCONN75K_APCI0155-P004A,SMLA    I88 @T6G_MB_LIB.T6G(SCH_1):PAGE345
   J59   57  GND11 SCONN75K_APCI0155P004A-SCONN75K_APCI0155-P004A,SMLA    I88 @T6G_MB_LIB.T6G(SCH_1):PAGE345
   J59   71  GND12 SCONN75K_APCI0155P004A-SCONN75K_APCI0155-P004A,SMLA    I88 @T6G_MB_LIB.T6G(SCH_1):PAGE345
   J59   73  GND13 SCONN75K_APCI0155P004A-SCONN75K_APCI0155-P004A,SMLA    I88 @T6G_MB_LIB.T6G(SCH_1):PAGE345
   J59   75  GND14 SCONN75K_APCI0155P004A-SCONN75K_APCI0155-P004A,SMLA    I88 @T6G_MB_LIB.T6G(SCH_1):PAGE345
   U98    1    GND PCA9306DP1-PCA9306DP1,SMLF,IC,AL009306K04    I27 @T6G_MB_LIB.T6G(SCH_1):PAGE346
 C1323    2      B Q_CAP_0402-0.1UF,25V,10%,X7R,CH4104K1B00    I28 @T6G_MB_LIB.T6G(SCH_1):PAGE346
 C1305    2      B Q_CAP_0402-0.1UF,25V,10%,X7R,CH4104K1B00    I52 @T6G_MB_LIB.T6G(SCH_1):PAGE346
 C1998    2      B Q_CAP_0402-0.1UF,25V,10%,X7R,CH4104K1B00    I82 @T6G_MB_LIB.T6G(SCH_1):PAGE346
 C1997    2      B Q_CAP_0402-0.1UF,25V,10%,X7R,CH4104K1B00    I89 @T6G_MB_LIB.T6G(SCH_1):PAGE346
  U279    4    GND PCA9617ADP-PCA9617ADP,SMLF,IC,AL009617K02    I93 @T6G_MB_LIB.T6G(SCH_1):PAGE346
PC2229    2      B Q_CAP_0402-0.22UF,16V,10%,X7R,CH4223K1B00     I8 @T6G_MB_LIB.T6G(SCH_1):PAGE350
PR3999    2      B Q_RES_0402LF-24.3K,1%,1/16W,CHIP,CS32432FB03    I11 @T6G_MB_LIB.T6G(SCH_1):PAGE350
PC2230    2      B Q_CAP_C0402-1UF,25V,10%,X6S,CH5104KEB02    I31 @T6G_MB_LIB.T6G(SCH_1):PAGE350
PC2232    2      B Q_CAP_C0402-0.047UF,25V,10%,X7R,CH3474K1B04    I33 @T6G_MB_LIB.T6G(SCH_1):PAGE350
PC2231    2      B Q_CAP_C0402-1UF,25V,10%,X6S,CH5104KEB02    I37 @T6G_MB_LIB.T6G(SCH_1):PAGE350
PC2235    2      B Q_CAP_C0402-100NF,50V,10%,X7R,CH4106K1B01    I45 @T6G_MB_LIB.T6G(SCH_1):PAGE350
PC2239    2      B Q_CAP_C0603-2.2UF,16V,20%,X7R,CH5223M1900    I52 @T6G_MB_LIB.T6G(SCH_1):PAGE350
PR4004    2      B Q_RES_0402LF-17.8K,1%,1/16W,CHIP,CS31782FB04    I62 @T6G_MB_LIB.T6G(SCH_1):PAGE350
PC2233    2      B Q_CAP_C0402-1UF,25V,10%,X6S,CH5104KEB02    I66 @T6G_MB_LIB.T6G(SCH_1):PAGE350
PC2234    1      A Q_CAP_C0402-1UF,25V,10%,X6S,CH5104KEB02    I67 @T6G_MB_LIB.T6G(SCH_1):PAGE350
PR4008    2      B Q_RES_0402LF-1.33K,1%,1/16W,CHIP,CS21332FB05    I70 @T6G_MB_LIB.T6G(SCH_1):PAGE350
PC2237    2      B Q_CAP_C0402-3900PF,50V,10%,X7R,CH23906KB14    I72 @T6G_MB_LIB.T6G(SCH_1):PAGE350
 PD116    A      A SCHOTTKY_AC-B340A-13-F,SMLF,IC,BC000340Z30    I79 @T6G_MB_LIB.T6G(SCH_1):PAGE350
PC2238    2      B Q_CAP_0402-0.1UF,25V,10%,X7R,CH4104K1B00    I80 @T6G_MB_LIB.T6G(SCH_1):PAGE350
   Q37    1     S1 MOSFET_NCH_DUAL-PJT138K,SMLF,IC,BAM138K0003     I9 @T6G_MB_LIB.T6G(SCH_1):PAGE273
   Q37    4     S2 MOSFET_NCH_DUAL-PJT138K,SMLF,IC,BAM138K0003    I14 @T6G_MB_LIB.T6G(SCH_1):PAGE273
 C1227    2      B Q_CAP_C0402-100NF,50V,10%,X7R,CH4106K1B01    I41 @T6G_MB_LIB.T6G(SCH_1):PAGE273
 C1332    2      B Q_CAP_C0402-100NF,50V,10%,X7R,CH4106K1B01    I48 @T6G_MB_LIB.T6G(SCH_1):PAGE273
 C1333    2      B Q_CAP_C0805-10UF,16V,10%,X6S,CH6103KEA00    I49 @T6G_MB_LIB.T6G(SCH_1):PAGE273
   C60    2      B Q_CAP_C0805-10UF,16V,10%,EMPTY,CH6103KEA00    I51 @T6G_MB_LIB.T6G(SCH_1):PAGE273
 C1340    2      B Q_CAP_C0805-10UF,16V,10%,X6S,CH6103KEA00    I61 @T6G_MB_LIB.T6G(SCH_1):PAGE273
  U266   10    GND ISL28022FRZT-ISL28022FRZ-T,SMLF,IC,AL028022003    I30 @T6G_MB_LIB.T6G(SCH_1):PAGE295
  U266   TH TH_GND ISL28022FRZT-ISL28022FRZ-T,SMLF,IC,AL028022003    I30 @T6G_MB_LIB.T6G(SCH_1):PAGE295
 R3616    1      A Q_RES_0402LF-4.7K,1%,1/16W,CHIP,CS24702FB06    I31 @T6G_MB_LIB.T6G(SCH_1):PAGE295
 C2015    2      B Q_CAP_0402-0.1UF,25V,10%,X7R,CH4104K1B00    I34 @T6G_MB_LIB.T6G(SCH_1):PAGE295
 R3617    1      A Q_RES_0402LF-4.7K,1%,1/16W,EMPTY,CS24702FB06    I40 @T6G_MB_LIB.T6G(SCH_1):PAGE295
 C2024    2      B Q_CAP_0402-0.1UF,25V,10%,X7R,CH4104K1B00    I50 @T6G_MB_LIB.T6G(SCH_1):PAGE295
 C2067    2      B Q_CAP_0402-0.1UF,25V,10%,X7R,CH4104K1B00   I125 @T6G_MB_LIB.T6G(SCH_1):PAGE295
  U276   10    GND ISL28022FRZT-ISL28022FRZ-T,SMLF,IC,AL028022003   I129 @T6G_MB_LIB.T6G(SCH_1):PAGE295
  U276   TH TH_GND ISL28022FRZT-ISL28022FRZ-T,SMLF,IC,AL028022003   I129 @T6G_MB_LIB.T6G(SCH_1):PAGE295
 R3764    1      A Q_RES_0402LF-4.7K,1%,1/16W,EMPTY,CS24702FB06   I135 @T6G_MB_LIB.T6G(SCH_1):PAGE295
 R3763    1      A Q_RES_0402LF-4.7K,1%,1/16W,CHIP,CS24702FB06   I136 @T6G_MB_LIB.T6G(SCH_1):PAGE295
 C2069    2      B Q_CAP_0402-0.1UF,25V,10%,X7R,CH4104K1B00   I142 @T6G_MB_LIB.T6G(SCH_1):PAGE295
 C5232    2      B Q_CAP_C0402-0.1UF,25V,10%,EMPTY,CH4104KEB00    I81 @T6G_MB_LIB.T6G(SCH_1):PAGE358
 R5238    2      B Q_RES_0402LF-3.9K,5%,1/16W,EMPTY,CS23902JB04    I83 @T6G_MB_LIB.T6G(SCH_1):PAGE358
 U5201   10    GND TUSB211IRWBR-TUSB211IRWBR,SMLF,EMPTY,AL000211007    I84 @T6G_MB_LIB.T6G(SCH_1):PAGE358
 C5236    2      B Q_CAP_C0402-0.1UF,25V,10%,EMPTY,CH4104KEB00    I87 @T6G_MB_LIB.T6G(SCH_1):PAGE358
 C5229    2      B Q_CAP_C0402-1UF,25V,10%,EMPTY,CH5104KEB02    I88 @T6G_MB_LIB.T6G(SCH_1):PAGE358
 C5234    2      B Q_CAP_C0402-0.1UF,25V,10%,EMPTY,CH4104KEB00    I92 @T6G_MB_LIB.T6G(SCH_1):PAGE358
  U268   TH     TH GL852GOHY60-GL852G-OHY60,SMLF,IC,AL000852001   I100 @T6G_MB_LIB.T6G(SCH_1):PAGE358
 R3653    2      B Q_RES_0402LF-680,1%,1/16W,CHIP,CS16802FB03   I139 @T6G_MB_LIB.T6G(SCH_1):PAGE358
 C2034    2      B Q_CAP_0402-0.1UF,25V,10%,X7R,CH4104K1B00   I142 @T6G_MB_LIB.T6G(SCH_1):PAGE358
 C2033    2      B Q_CAP_0402-0.1UF,25V,10%,X7R,CH4104K1B00   I143 @T6G_MB_LIB.T6G(SCH_1):PAGE358
 C2032    2      B Q_CAP_0402-0.1UF,25V,10%,X7R,CH4104K1B00   I145 @T6G_MB_LIB.T6G(SCH_1):PAGE358
 C2035    2      B Q_CAP_C0402-1UF,25V,10%,X6S,CH5104KEB02   I147 @T6G_MB_LIB.T6G(SCH_1):PAGE358
 C2031    2      B Q_CAP_C0402-1UF,25V,10%,X6S,CH5104KEB02   I148 @T6G_MB_LIB.T6G(SCH_1):PAGE358
 C2041    2      B Q_CAP_C0402-1UF,25V,10%,X6S,CH5104KEB02   I158 @T6G_MB_LIB.T6G(SCH_1):PAGE358
 C2040    2      B Q_CAP_0402-0.1UF,25V,10%,X7R,CH4104K1B00   I162 @T6G_MB_LIB.T6G(SCH_1):PAGE358
 C2039    2      B Q_CAP_0402-0.1UF,25V,10%,X7R,CH4104K1B00   I163 @T6G_MB_LIB.T6G(SCH_1):PAGE358
 C2038    2      B Q_CAP_C0402-10UF,6.3V,20%,X6S,CH6101MEB01   I164 @T6G_MB_LIB.T6G(SCH_1):PAGE358
 R3665    2      B Q_RES_0402LF-100K,1%,1/16W,CHIP,CS41002FB09   I182 @T6G_MB_LIB.T6G(SCH_1):PAGE358
 R3664    2      B Q_RES_0402LF-10K,1%,1/16W,EMPTY,CS31002FB08   I187 @T6G_MB_LIB.T6G(SCH_1):PAGE358
 R3666    2      B Q_RES_0402LF-0,5%,1/16W,CHIP,CS00002JB13   I199 @T6G_MB_LIB.T6G(SCH_1):PAGE358
 R3661    1      A Q_RES_0402LF-47K,0.1%,1/16W,EMPTY,CS34702BB05   I201 @T6G_MB_LIB.T6G(SCH_1):PAGE358
 R4420    2      B Q_RES_0402LF-49.9,1%,1/16W,EMPTY,CS04992FB07   I202 @T6G_MB_LIB.T6G(SCH_1):PAGE358
 R4419    2      B Q_RES_0402LF-49.9,1%,1/16W,EMPTY,CS04992FB07   I203 @T6G_MB_LIB.T6G(SCH_1):PAGE358
 R4483    2      B Q_RES_0402LF-49.9,1%,1/16W,EMPTY,CS04992FB07   I206 @T6G_MB_LIB.T6G(SCH_1):PAGE358
 R4482    2      B Q_RES_0402LF-49.9,1%,1/16W,EMPTY,CS04992FB07   I208 @T6G_MB_LIB.T6G(SCH_1):PAGE358
 C2010    2      B Q_CAP_0402-0.1UF,25V,10%,X7R,CH4104K1B00    I16 @T6G_MB_LIB.T6G(SCH_1):PAGE359
 R4199    2      B Q_RES_0402LF-1K,1%,1/16W,CHIP,CS21002FB06    I81 @T6G_MB_LIB.T6G(SCH_1):PAGE359
 R4207    2      B Q_RES_0402LF-1K,1%,1/16W,CHIP,CS21002FB06    I85 @T6G_MB_LIB.T6G(SCH_1):PAGE359
 R4191    2      B Q_RES_0402LF-1K,1%,1/16W,CHIP,CS21002FB06    I89 @T6G_MB_LIB.T6G(SCH_1):PAGE359
 R4205    2      B Q_RES_0402LF-1K,1%,1/16W,CHIP,CS21002FB06    I96 @T6G_MB_LIB.T6G(SCH_1):PAGE359
 R4197    2      B Q_RES_0402LF-1K,1%,1/16W,CHIP,CS21002FB06    I98 @T6G_MB_LIB.T6G(SCH_1):PAGE359
 R4189    2      B Q_RES_0402LF-1K,1%,1/16W,CHIP,CS21002FB06   I102 @T6G_MB_LIB.T6G(SCH_1):PAGE359
   C73    2      B Q_CAP_0402-0.1UF,25V,10%,X7R,CH4104K1B00   I104 @T6G_MB_LIB.T6G(SCH_1):PAGE359
   C32    2      B Q_CAP_0402-0.1UF,25V,10%,X7R,CH4104K1B00   I119 @T6G_MB_LIB.T6G(SCH_1):PAGE359
 R4187    2      B Q_RES_0402LF-1K,1%,1/16W,CHIP,CS21002FB06   I121 @T6G_MB_LIB.T6G(SCH_1):PAGE359
 R4195    2      B Q_RES_0402LF-1K,1%,1/16W,CHIP,CS21002FB06   I125 @T6G_MB_LIB.T6G(SCH_1):PAGE359
 R4203    2      B Q_RES_0402LF-1K,1%,1/16W,CHIP,CS21002FB06   I127 @T6G_MB_LIB.T6G(SCH_1):PAGE359
   C31    2      B Q_CAP_0402-0.1UF,25V,10%,X7R,CH4104K1B00   I139 @T6G_MB_LIB.T6G(SCH_1):PAGE359
 R4185    2      B Q_RES_0402LF-1K,1%,1/16W,CHIP,CS21002FB06   I141 @T6G_MB_LIB.T6G(SCH_1):PAGE359
 R4193    2      B Q_RES_0402LF-1K,1%,1/16W,CHIP,CS21002FB06   I145 @T6G_MB_LIB.T6G(SCH_1):PAGE359
 R4201    2      B Q_RES_0402LF-1K,1%,1/16W,CHIP,CS21002FB06   I147 @T6G_MB_LIB.T6G(SCH_1):PAGE359
  U270    4    GND LM75BD-LM75BD,SMLF,IC,AL0075BD000   I164 @T6G_MB_LIB.T6G(SCH_1):PAGE359
  U271    4    GND LM75BD-LM75BD,SMLF,IC,AL0075BD000   I165 @T6G_MB_LIB.T6G(SCH_1):PAGE359
  U272    4    GND LM75BD-LM75BD,SMLF,IC,AL0075BD000   I166 @T6G_MB_LIB.T6G(SCH_1):PAGE359
  U273    4    GND LM75BD-LM75BD,SMLF,IC,AL0075BD000   I167 @T6G_MB_LIB.T6G(SCH_1):PAGE359
 C2018    2      B Q_CAP_0402-0.1UF,25V,10%,X7R,CH4104K1B00    I26 @T6G_MB_LIB.T6G(SCH_1):PAGE360
 R3611    1      A Q_RES_0402LF-4.7K,1%,1/16W,CHIP,CS24702FB06    I36 @T6G_MB_LIB.T6G(SCH_1):PAGE360
 C2013    2      B Q_CAP_0402-0.1UF,25V,10%,X7R,CH4104K1B00    I42 @T6G_MB_LIB.T6G(SCH_1):PAGE360
 R3610    1      A Q_RES_0402LF-4.7K,1%,1/16W,EMPTY,CS24702FB06    I45 @T6G_MB_LIB.T6G(SCH_1):PAGE360
  U264   10    GND ISL28022FRZT-ISL28022FRZ-T,SMLF,IC,AL028022003    I46 @T6G_MB_LIB.T6G(SCH_1):PAGE360
  U264   TH TH_GND ISL28022FRZT-ISL28022FRZ-T,SMLF,IC,AL028022003    I46 @T6G_MB_LIB.T6G(SCH_1):PAGE360
 C2019    2      B Q_CAP_0402-0.1UF,25V,10%,X7R,CH4104K1B00    I49 @T6G_MB_LIB.T6G(SCH_1):PAGE360
 R3613    1      A Q_RES_0402LF-4.7K,1%,1/16W,EMPTY,CS24702FB06    I59 @T6G_MB_LIB.T6G(SCH_1):PAGE360
 C2014    2      B Q_CAP_0402-0.1UF,25V,10%,X7R,CH4104K1B00    I65 @T6G_MB_LIB.T6G(SCH_1):PAGE360
 R3612    1      A Q_RES_0402LF-4.7K,1%,1/16W,EMPTY,CS24702FB06    I68 @T6G_MB_LIB.T6G(SCH_1):PAGE360
  U265   10    GND ISL28022FRZT-ISL28022FRZ-T,SMLF,IC,AL028022003    I69 @T6G_MB_LIB.T6G(SCH_1):PAGE360
  U265   TH TH_GND ISL28022FRZT-ISL28022FRZ-T,SMLF,IC,AL028022003    I69 @T6G_MB_LIB.T6G(SCH_1):PAGE360
  U263   10    GND ISL28022FRZT-ISL28022FRZ-T,SMLF,IC,AL028022003    I94 @T6G_MB_LIB.T6G(SCH_1):PAGE360
  U263   TH TH_GND ISL28022FRZT-ISL28022FRZ-T,SMLF,IC,AL028022003    I94 @T6G_MB_LIB.T6G(SCH_1):PAGE360
 C2012    2      B Q_CAP_0402-0.1UF,25V,10%,X7R,CH4104K1B00    I98 @T6G_MB_LIB.T6G(SCH_1):PAGE360
 R3608    1      A Q_RES_0402LF-4.7K,1%,1/16W,CHIP,CS24702FB06   I103 @T6G_MB_LIB.T6G(SCH_1):PAGE360
 R3609    1      A Q_RES_0402LF-4.7K,1%,1/16W,EMPTY,CS24702FB06   I104 @T6G_MB_LIB.T6G(SCH_1):PAGE360
 C2017    2      B Q_CAP_0402-0.1UF,25V,10%,X7R,CH4104K1B00   I114 @T6G_MB_LIB.T6G(SCH_1):PAGE360
   U64    4    VSS M24128BWMN6TP-M24128-BWMN6TP,SMLF,IC,AKE30Z00613    I35 @T6G_MB_LIB.T6G(SCH_1):PAGE361
  R718    2      B Q_RES_0402LF-1K,1%,1/16W,CHIP,CS21002FB06    I50 @T6G_MB_LIB.T6G(SCH_1):PAGE361
  R714    2      B Q_RES_0402LF-1K,1%,1/16W,CHIP,CS21002FB06    I52 @T6G_MB_LIB.T6G(SCH_1):PAGE361
  C629    2      B Q_CAP_0402-0.1UF,25V,10%,X7R,CH4104K1B00    I55 @T6G_MB_LIB.T6G(SCH_1):PAGE361
  R710    2      B Q_RES_0402LF-1K,1%,1/16W,CHIP,CS21002FB06    I57 @T6G_MB_LIB.T6G(SCH_1):PAGE361
  R722    2      B Q_RES_0402LF-1K,1%,1/16W,EMPTY,CS21002FB06    I61 @T6G_MB_LIB.T6G(SCH_1):PAGE361
  U190    S      S MOSFET_NCH_GDS_ESD_PROTECTED-2N7002K,SMLF,IC,BAM70A   I392 @T6G_MB_LIB.T6G(SCH_1):PAGE363
  U192    4    GND LTC4307CMS8-LTC4307CMS8,SMLF,IC,AL004307000   I398 @T6G_MB_LIB.T6G(SCH_1):PAGE363
 C1751    2      B Q_CAP_0402-0.1UF,25V,10%,X7R,CH4104K1B00   I412 @T6G_MB_LIB.T6G(SCH_1):PAGE363
   C74    2      B Q_CAP_0402-0.1UF,25V,10%,EMPTY,CH4104K1B00   I452 @T6G_MB_LIB.T6G(SCH_1):PAGE363
   C64    2      B Q_CAP_0402-0.1UF,25V,10%,EMPTY,CH4104K1B00   I453 @T6G_MB_LIB.T6G(SCH_1):PAGE363
   C65    2      B Q_CAP_0402-0.1UF,25V,10%,EMPTY,CH4104K1B00   I454 @T6G_MB_LIB.T6G(SCH_1):PAGE363
   C66    2      B Q_CAP_0402-0.1UF,25V,10%,EMPTY,CH4104K1B00   I455 @T6G_MB_LIB.T6G(SCH_1):PAGE363
   C67    2      B Q_CAP_0402-0.1UF,25V,10%,EMPTY,CH4104K1B00   I456 @T6G_MB_LIB.T6G(SCH_1):PAGE363
 C1775    2      B Q_CAP_0402-0.1UF,25V,10%,X7R,CH4104K1B00    I14 @T6G_MB_LIB.T6G(SCH_1):PAGE364
 R2941    2      B Q_RES_0402LF-100K,1%,1/16W,CHIP,CS41002FB09    I29 @T6G_MB_LIB.T6G(SCH_1):PAGE364
 R2948    2      B Q_RES_0402LF-4.7K,5%,1/16W,EMPTY,CS24702JB10    I30 @T6G_MB_LIB.T6G(SCH_1):PAGE364
  U278    3    GND 74LVC1G08W57-74LVC1G08W5-7,SMLF,IC,AL1G0008020    I31 @T6G_MB_LIB.T6G(SCH_1):PAGE364
  U308    2    GND 74LVC2G07DW7-74LVC2G07DW-7,SMLF,IC,AL002G07003    I37 @T6G_MB_LIB.T6G(SCH_1):PAGE364
   C69    2      B Q_CAP_0402-0.1UF,25V,10%,X7R,CH4104K1B00    I40 @T6G_MB_LIB.T6G(SCH_1):PAGE364
 R4265    2      B Q_RES_0402LF-4.7K,5%,1/16W,EMPTY,CS24702JB10    I43 @T6G_MB_LIB.T6G(SCH_1):PAGE364
 R4552    2      B Q_RES_0402LF-100K,1%,1/16W,CHIP,CS41002FB09    I50 @T6G_MB_LIB.T6G(SCH_1):PAGE364
  Q145    1     S1 MOSFET_NCH_DUAL-PJT138K,SMLF,IC,BAM138K0003    I53 @T6G_MB_LIB.T6G(SCH_1):PAGE364
  Q145    4     S2 MOSFET_NCH_DUAL-PJT138K,SMLF,IC,BAM138K0003    I58 @T6G_MB_LIB.T6G(SCH_1):PAGE364
   C70    2      B Q_CAP_0402-0.1UF,25V,10%,X7R,CH4104K1B00    I62 @T6G_MB_LIB.T6G(SCH_1):PAGE364
  U158    S      S MOSFET_NCH_GDS_ESD_PROTECTED-2N7002K,SMLF,IC,BAM70A     I6 @T6G_MB_LIB.T6G(SCH_1):PAGE365
   Q54    S      S MOSFET_NCH_GDS_ESD_PROTECTED-2N7002K,SMLF,IC,BAM70A    I14 @T6G_MB_LIB.T6G(SCH_1):PAGE365
 R6035    2      B Q_RES_0402LF-4.7K,5%,1/16W,EMPTY,CS24702JB10    I17 @T6G_MB_LIB.T6G(SCH_1):PAGE348
 R1801    2      B Q_RES_0402LF-0,5%,1/16W,CHIP,CS00002JB13   I171 @T6G_MB_LIB.T6G(SCH_1):PAGE348
   J41  OB4 DATA_IN SCONN168_ME1016810202011-SCONN168_ME1016810202011,A   I176 @T6G_MB_LIB.T6G(SCH_1):PAGE348
   J41   G1     G1 SCONN168_ME1016810202011-SCONN168_ME1016810202011,A   I176 @T6G_MB_LIB.T6G(SCH_1):PAGE348
   J41   G2     G2 SCONN168_ME1016810202011-SCONN168_ME1016810202011,A   I176 @T6G_MB_LIB.T6G(SCH_1):PAGE348
   J41   G3     G3 SCONN168_ME1016810202011-SCONN168_ME1016810202011,A   I176 @T6G_MB_LIB.T6G(SCH_1):PAGE348
   J41   G4     G4 SCONN168_ME1016810202011-SCONN168_ME1016810202011,A   I176 @T6G_MB_LIB.T6G(SCH_1):PAGE348
   J41   G5     G5 SCONN168_ME1016810202011-SCONN168_ME1016810202011,A   I176 @T6G_MB_LIB.T6G(SCH_1):PAGE348
   J41  A13 GND_A13 SCONN168_ME1016810202011-SCONN168_ME1016810202011,A   I176 @T6G_MB_LIB.T6G(SCH_1):PAGE348
   J41  A16 GND_A16 SCONN168_ME1016810202011-SCONN168_ME1016810202011,A   I176 @T6G_MB_LIB.T6G(SCH_1):PAGE348
   J41  A19 GND_A19 SCONN168_ME1016810202011-SCONN168_ME1016810202011,A   I176 @T6G_MB_LIB.T6G(SCH_1):PAGE348
   J41  A22 GND_A22 SCONN168_ME1016810202011-SCONN168_ME1016810202011,A   I176 @T6G_MB_LIB.T6G(SCH_1):PAGE348
   J41  A58 GND_A58 SCONN168_ME1016810202011-SCONN168_ME1016810202011,A   I176 @T6G_MB_LIB.T6G(SCH_1):PAGE348
   J41  A61 GND_A61 SCONN168_ME1016810202011-SCONN168_ME1016810202011,A   I176 @T6G_MB_LIB.T6G(SCH_1):PAGE348
   J41  A64 GND_A64 SCONN168_ME1016810202011-SCONN168_ME1016810202011,A   I176 @T6G_MB_LIB.T6G(SCH_1):PAGE348
   J41  A67 GND_A67 SCONN168_ME1016810202011-SCONN168_ME1016810202011,A   I176 @T6G_MB_LIB.T6G(SCH_1):PAGE348
   J41  B38 GND_B38 SCONN168_ME1016810202011-SCONN168_ME1016810202011,A   I176 @T6G_MB_LIB.T6G(SCH_1):PAGE348
   J41  B49 GND_B49 SCONN168_ME1016810202011-SCONN168_ME1016810202011,A   I176 @T6G_MB_LIB.T6G(SCH_1):PAGE348
   J41  B52 GND_B52 SCONN168_ME1016810202011-SCONN168_ME1016810202011,A   I176 @T6G_MB_LIB.T6G(SCH_1):PAGE348
   J41  B55 GND_B55 SCONN168_ME1016810202011-SCONN168_ME1016810202011,A   I176 @T6G_MB_LIB.T6G(SCH_1):PAGE348
   J41  B58 GND_B58 SCONN168_ME1016810202011-SCONN168_ME1016810202011,A   I176 @T6G_MB_LIB.T6G(SCH_1):PAGE348
   J41  B61 GND_B61 SCONN168_ME1016810202011-SCONN168_ME1016810202011,A   I176 @T6G_MB_LIB.T6G(SCH_1):PAGE348
   J41  B64 GND_B64 SCONN168_ME1016810202011-SCONN168_ME1016810202011,A   I176 @T6G_MB_LIB.T6G(SCH_1):PAGE348
   J41  B67 GND_B67 SCONN168_ME1016810202011-SCONN168_ME1016810202011,A   I176 @T6G_MB_LIB.T6G(SCH_1):PAGE348
   J41 OA13 GND_OA13 SCONN168_ME1016810202011-SCONN168_ME1016810202011,A   I176 @T6G_MB_LIB.T6G(SCH_1):PAGE348
   J41 OB10 GND_OB10 SCONN168_ME1016810202011-SCONN168_ME1016810202011,A   I176 @T6G_MB_LIB.T6G(SCH_1):PAGE348
   J41  A33  PERN5 SCONN168_ME1016810202011-SCONN168_ME1016810202011,A   I176 @T6G_MB_LIB.T6G(SCH_1):PAGE348
   J41  B10 PERST0# SCONN168_ME1016810202011-SCONN168_ME1016810202011,A   I176 @T6G_MB_LIB.T6G(SCH_1):PAGE348
   J41  B17  PETN0 SCONN168_ME1016810202011-SCONN168_ME1016810202011,A   I176 @T6G_MB_LIB.T6G(SCH_1):PAGE348
   J41  B26  PETN3 SCONN168_ME1016810202011-SCONN168_ME1016810202011,A   I176 @T6G_MB_LIB.T6G(SCH_1):PAGE348
   J41  B33  PETN5 SCONN168_ME1016810202011-SCONN168_ME1016810202011,A   I176 @T6G_MB_LIB.T6G(SCH_1):PAGE348
   J41  A42 PRSNTB1# SCONN168_ME1016810202011-SCONN168_ME1016810202011,A   I176 @T6G_MB_LIB.T6G(SCH_1):PAGE348
   J41  B70 PRSNTB3# SCONN168_ME1016810202011-SCONN168_ME1016810202011,A   I176 @T6G_MB_LIB.T6G(SCH_1):PAGE348
   J41  A70 PWRBRK0# SCONN168_ME1016810202011-SCONN168_ME1016810202011,A   I176 @T6G_MB_LIB.T6G(SCH_1):PAGE348
   J41  OA4 RBT_ARB_IN SCONN168_ME1016810202011-SCONN168_ME1016810202011,A   I176 @T6G_MB_LIB.T6G(SCH_1):PAGE348
   J41  OB7 SLOT_ID0 SCONN168_ME1016810202011-SCONN168_ME1016810202011,A   I176 @T6G_MB_LIB.T6G(SCH_1):PAGE348
   J41  OA3  WAKE# SCONN168_ME1016810202011-SCONN168_ME1016810202011,A   I176 @T6G_MB_LIB.T6G(SCH_1):PAGE348
 R6027    2      B Q_RES_0402LF-4.7K,5%,1/16W,EMPTY,CS24702JB10    I32 @T6G_MB_LIB.T6G(SCH_1):PAGE349
   C63    2      B Q_CAP_C0402-220PF,50V,5%,C0G,CH12206JB00   I112 @T6G_MB_LIB.T6G(SCH_1):PAGE349
    J8    4      4 CONN4_HFK1040L0P1L7H-CONN4_HFK1040-L0P1L-7H,THLF,IA   I148 @T6G_MB_LIB.T6G(SCH_1):PAGE349
 R2694    2      B Q_RES_0402LF-1K,1%,1/16W,CHIP,CS21002FB06     I2 @T6G_MB_LIB.T6G(SCH_1):PAGE246
 R2696    2      B Q_RES_0402LF-1K,1%,1/16W,CHIP,CS21002FB06     I6 @T6G_MB_LIB.T6G(SCH_1):PAGE246
 R4514    2      B Q_RES_0402LF-4.7K,1%,1/16W,EMPTY,CS24702FB06     I8 @T6G_MB_LIB.T6G(SCH_1):PAGE232
 Y8003    2     G1 Q_XTAL_4P_13BI_24GND-25MHZ,SMLF,MISC,BG6250000L4    I14 @T6G_MB_LIB.T6G(SCH_1):PAGE232
 Y8003    4     G2 Q_XTAL_4P_13BI_24GND-25MHZ,SMLF,MISC,BG6250000L4    I14 @T6G_MB_LIB.T6G(SCH_1):PAGE232
  U248    3    GND 74LVC1G32GW_SMLF-74LVC1G32GW,IC,ALVC1G32007    I26 @T6G_MB_LIB.T6G(SCH_1):PAGE232
 C1882    2      B Q_CAP_0402-0.1UF,25V,10%,X7R,CH4104K1B00    I28 @T6G_MB_LIB.T6G(SCH_1):PAGE232
 C1883    2      B Q_CAP_C0805-10UF,25V,10%,X6S,CH6104KEA00    I36 @T6G_MB_LIB.T6G(SCH_1):PAGE232
 C2257    2      B Q_CAP_0402-0.1UF,25V,10%,X7R,CH4104K1B00    I37 @T6G_MB_LIB.T6G(SCH_1):PAGE232
 C1886    2      B Q_CAP_0402-0.1UF,25V,10%,X7R,CH4104K1B00    I40 @T6G_MB_LIB.T6G(SCH_1):PAGE232
 C1889    2      B Q_CAP_0402-0.1UF,25V,10%,X7R,CH4104K1B00    I41 @T6G_MB_LIB.T6G(SCH_1):PAGE232
   C95    2      B Q_CAP_0402-0.1UF,25V,10%,X7R,CH4104K1B00    I42 @T6G_MB_LIB.T6G(SCH_1):PAGE232
 R4079    2      B Q_RES_0402LF-10K,1%,1/16W,CHIP,CS31002FB08    I46 @T6G_MB_LIB.T6G(SCH_1):PAGE232
 R4082    2      B Q_RES_0402LF-10K,1%,1/16W,EMPTY,CS31002FB08    I55 @T6G_MB_LIB.T6G(SCH_1):PAGE232
 C1884    2      B Q_CAP_C0402-1UF,25V,10%,X6S,CH5104KEB02    I68 @T6G_MB_LIB.T6G(SCH_1):PAGE232
   C97    2      B Q_CAP_0402-0.1UF,25V,10%,X7R,CH4104K1B00    I69 @T6G_MB_LIB.T6G(SCH_1):PAGE232
 C1859    2      B Q_CAP_0402-0.1UF,25V,10%,X7R,CH4104K1B00     I4 @T6G_MB_LIB.T6G(SCH_1):PAGE248
  U235    4    GND PCA9617ADP-PCA9617ADP,SMLF,IC,AL009617K02     I6 @T6G_MB_LIB.T6G(SCH_1):PAGE248
 C1861    2      B Q_CAP_0402-0.1UF,25V,10%,X7R,CH4104K1B00     I9 @T6G_MB_LIB.T6G(SCH_1):PAGE248
  U236    4    GND PCA9617ADP-PCA9617ADP,SMLF,IC,AL009617K02    I14 @T6G_MB_LIB.T6G(SCH_1):PAGE248
 C1860    2      B Q_CAP_0402-0.1UF,25V,10%,X7R,CH4104K1B00    I15 @T6G_MB_LIB.T6G(SCH_1):PAGE248
 C1862    2      B Q_CAP_0402-0.1UF,25V,10%,X7R,CH4104K1B00    I19 @T6G_MB_LIB.T6G(SCH_1):PAGE248
 R2666    2      B Q_RES_0402LF-10K,1%,1/16W,CHIP,CS31002FB08     I8 @T6G_MB_LIB.T6G(SCH_1):PAGE249
  U200    4    GND LTC4307CMS8-LTC4307CMS8,SMLF,IC,AL004307000    I15 @T6G_MB_LIB.T6G(SCH_1):PAGE249
 R4603    2      B Q_RES_0402LF-10K,1%,1/16W,CHIP,CS31002FB08    I23 @T6G_MB_LIB.T6G(SCH_1):PAGE249
  U176    4    GND LTC4307CMS8-LTC4307CMS8,SMLF,EMPTY,AL004307000    I30 @T6G_MB_LIB.T6G(SCH_1):PAGE249
 C1796    2      B Q_CAP_0402-0.1UF,25V,10%,X7R,CH4104K1B00    I32 @T6G_MB_LIB.T6G(SCH_1):PAGE249
  U194    4    GND LTC4307CMS8-LTC4307CMS8,SMLF,IC,AL004307000    I42 @T6G_MB_LIB.T6G(SCH_1):PAGE249
  U175    4    GND LTC4307CMS8-LTC4307CMS8,SMLF,IC,AL004307000    I49 @T6G_MB_LIB.T6G(SCH_1):PAGE249
 C1707    2      B Q_CAP_0402-0.1UF,25V,10%,X7R,CH4104K1B00    I52 @T6G_MB_LIB.T6G(SCH_1):PAGE249
 C1708    2      B Q_CAP_0402-0.1UF,25V,10%,X7R,CH4104K1B00    I61 @T6G_MB_LIB.T6G(SCH_1):PAGE249
 C1766    2      B Q_CAP_0402-0.1UF,25V,10%,X7R,CH4104K1B00    I78 @T6G_MB_LIB.T6G(SCH_1):PAGE249
  C611    2      B Q_CAP_0402-0.1UF,25V,10%,X7R,CH4104K1B00     I6 @T6G_MB_LIB.T6G(SCH_1):PAGE137
  C612    2      B Q_CAP_0402-0.1UF,25V,10%,X7R,CH4104K1B00     I8 @T6G_MB_LIB.T6G(SCH_1):PAGE137
   C23    2      B Q_CAP_0402-0.1UF,25V,10%,X7R,CH4104K1B00    I26 @T6G_MB_LIB.T6G(SCH_1):PAGE137
   C26    2      B Q_CAP_0402-0.1UF,25V,10%,X7R,CH4104K1B00    I29 @T6G_MB_LIB.T6G(SCH_1):PAGE137
    U5    4    GND PCA9617ADP-PCA9617ADP,SMLF,EMPTY,AL009617K02    I48 @T6G_MB_LIB.T6G(SCH_1):PAGE137
 R3704    2      B Q_RES_0402LF-1K,1%,1/16W,CHIP,CS21002FB06     I1 @T6G_MB_LIB.T6G(SCH_1):PAGE251
 R3707    2      B Q_RES_0402LF-1K,1%,1/16W,CHIP,CS21002FB06     I4 @T6G_MB_LIB.T6G(SCH_1):PAGE251
 R3709    2      B Q_RES_0402LF-1K,1%,1/16W,CHIP,CS21002FB06     I6 @T6G_MB_LIB.T6G(SCH_1):PAGE251
 C2056    2      B Q_CAP_0402-0.1UF,25V,10%,X7R,CH4104K1B00    I38 @T6G_MB_LIB.T6G(SCH_1):PAGE251
   U39   12    GND TCA9548APWR-TCA9548APWR,SMLF,IC,AL009548K02    I74 @T6G_MB_LIB.T6G(SCH_1):PAGE251
  R317    2      B Q_RES_0402LF-1K,1%,1/16W,CHIP,CS21002FB06     I2 @T6G_MB_LIB.T6G(SCH_1):PAGE252
  R319    2      B Q_RES_0402LF-1K,1%,1/16W,CHIP,CS21002FB06     I4 @T6G_MB_LIB.T6G(SCH_1):PAGE252
  R587    2      B Q_RES_0402LF-1K,1%,1/16W,CHIP,CS21002FB06     I6 @T6G_MB_LIB.T6G(SCH_1):PAGE252
   U36   12    GND TCA9548APWR-TCA9548APWR,SMLF,IC,AL009548K02    I33 @T6G_MB_LIB.T6G(SCH_1):PAGE252
  C106    2      B Q_CAP_0402-0.1UF,25V,10%,X7R,CH4104K1B00    I34 @T6G_MB_LIB.T6G(SCH_1):PAGE252
  U134    2    GND 74LVC2G07DW7-74LVC2G07DW-7,SMLF,IC,AL002G07003     I4 @T6G_MB_LIB.T6G(SCH_1):PAGE297
R10296    2      B Q_RES_0402LF-1K,1%,1/16W,CHIP,CS21002FB06     I6 @T6G_MB_LIB.T6G(SCH_1):PAGE297
 C1592    2      B Q_CAP_0402-0.1UF,25V,10%,X7R,CH4104K1B00    I36 @T6G_MB_LIB.T6G(SCH_1):PAGE297
 C1276    2      B Q_CAP_C0805-22UF,16V,20%,X6S,CH6223MEA01    I66 @T6G_MB_LIB.T6G(SCH_1):PAGE297
 C1277    2      B Q_CAP_C0805-22UF,16V,20%,X6S,CH6223MEA01    I67 @T6G_MB_LIB.T6G(SCH_1):PAGE297
 C1278    2      B Q_CAP_0402-0.1UF,25V,10%,X7R,CH4104K1B00    I68 @T6G_MB_LIB.T6G(SCH_1):PAGE297
 C1279    2      B Q_CAP_0402-0.1UF,25V,10%,X7R,CH4104K1B00    I74 @T6G_MB_LIB.T6G(SCH_1):PAGE297
 R2426    2      B Q_RES_0402LF-100,1%,1/16W,EMPTY,CS11002FB07    I75 @T6G_MB_LIB.T6G(SCH_1):PAGE297
 C1282    2      B Q_CAP_0402-0.1UF,25V,10%,X7R,CH4104K1B00    I87 @T6G_MB_LIB.T6G(SCH_1):PAGE297
 C1283    2      B Q_CAP_0402-0.1UF,25V,10%,X7R,CH4104K1B00    I88 @T6G_MB_LIB.T6G(SCH_1):PAGE297
   J90   G1     G1 SCONN56_123276793-SCONN56_1-2327679-3,SMLF,IO,DFHSA    I90 @T6G_MB_LIB.T6G(SCH_1):PAGE297
   J90   G2     G2 SCONN56_123276793-SCONN56_1-2327679-3,SMLF,IO,DFHSA    I90 @T6G_MB_LIB.T6G(SCH_1):PAGE297
   J90   A1 GND_A1 SCONN56_123276793-SCONN56_1-2327679-3,SMLF,IO,DFHSA    I90 @T6G_MB_LIB.T6G(SCH_1):PAGE297
   J90   A2 GND_A2 SCONN56_123276793-SCONN56_1-2327679-3,SMLF,IO,DFHSA    I90 @T6G_MB_LIB.T6G(SCH_1):PAGE297
   J90   A3 GND_A3 SCONN56_123276793-SCONN56_1-2327679-3,SMLF,IO,DFHSA    I90 @T6G_MB_LIB.T6G(SCH_1):PAGE297
   J90   A4 GND_A4 SCONN56_123276793-SCONN56_1-2327679-3,SMLF,IO,DFHSA    I90 @T6G_MB_LIB.T6G(SCH_1):PAGE297
   J90   A5 GND_A5 SCONN56_123276793-SCONN56_1-2327679-3,SMLF,IO,DFHSA    I90 @T6G_MB_LIB.T6G(SCH_1):PAGE297
   J90   A6 GND_A6 SCONN56_123276793-SCONN56_1-2327679-3,SMLF,IO,DFHSA    I90 @T6G_MB_LIB.T6G(SCH_1):PAGE297
   J90  A13 GND_A13 SCONN56_123276793-SCONN56_1-2327679-3,SMLF,IO,DFHSA    I90 @T6G_MB_LIB.T6G(SCH_1):PAGE297
   J90  A16 GND_A16 SCONN56_123276793-SCONN56_1-2327679-3,SMLF,IO,DFHSA    I90 @T6G_MB_LIB.T6G(SCH_1):PAGE297
   J90  A19 GND_A19 SCONN56_123276793-SCONN56_1-2327679-3,SMLF,IO,DFHSA    I90 @T6G_MB_LIB.T6G(SCH_1):PAGE297
   J90  A22 GND_A22 SCONN56_123276793-SCONN56_1-2327679-3,SMLF,IO,DFHSA    I90 @T6G_MB_LIB.T6G(SCH_1):PAGE297
   J90  A25 GND_A25 SCONN56_123276793-SCONN56_1-2327679-3,SMLF,IO,DFHSA    I90 @T6G_MB_LIB.T6G(SCH_1):PAGE297
   J90  A28 GND_A28 SCONN56_123276793-SCONN56_1-2327679-3,SMLF,IO,DFHSA    I90 @T6G_MB_LIB.T6G(SCH_1):PAGE297
   J90  B13 GND_B13 SCONN56_123276793-SCONN56_1-2327679-3,SMLF,IO,DFHSA    I90 @T6G_MB_LIB.T6G(SCH_1):PAGE297
   J90  B16 GND_B16 SCONN56_123276793-SCONN56_1-2327679-3,SMLF,IO,DFHSA    I90 @T6G_MB_LIB.T6G(SCH_1):PAGE297
   J90  B19 GND_B19 SCONN56_123276793-SCONN56_1-2327679-3,SMLF,IO,DFHSA    I90 @T6G_MB_LIB.T6G(SCH_1):PAGE297
   J90  B22 GND_B22 SCONN56_123276793-SCONN56_1-2327679-3,SMLF,IO,DFHSA    I90 @T6G_MB_LIB.T6G(SCH_1):PAGE297
   J90  B25 GND_B25 SCONN56_123276793-SCONN56_1-2327679-3,SMLF,IO,DFHSA    I90 @T6G_MB_LIB.T6G(SCH_1):PAGE297
   J90  B28 GND_B28 SCONN56_123276793-SCONN56_1-2327679-3,SMLF,IO,DFHSA    I90 @T6G_MB_LIB.T6G(SCH_1):PAGE297
  U259    2    GND SN74LVC2G07DCKR_SMLF-SN74LVC2G07DCKR,IC,AL002G07006     I5 @T6G_MB_LIB.T6G(SCH_1):PAGE345
 C2007    2      B Q_CAP_C0402-1UF,25V,10%,X6S,CH5104KEB02     I6 @T6G_MB_LIB.T6G(SCH_1):PAGE345
   Q95    1     S1 MOSFET_NCH_DUAL-PJT138K,SMLF,IC,BAM138K0003     I8 @T6G_MB_LIB.T6G(SCH_1):PAGE345
  R138    2      B Q_RES_0402LF-4.7K,1%,1/16W,EMPTY,CS24702FB06    I15 @T6G_MB_LIB.T6G(SCH_1):PAGE345
  U239    3    GND 74LVC1G126SE7-74LVC1G126SE-7,SMLF,IC,AL1G0126009    I53 @T6G_MB_LIB.T6G(SCH_1):PAGE345
 C1873    2      B Q_CAP_0402-0.1UF,25V,10%,X7R,CH4104K1B00    I56 @T6G_MB_LIB.T6G(SCH_1):PAGE345
 R3297    2      B Q_RES_0402LF-10K,1%,1/16W,CHIP,CS31002FB08    I60 @T6G_MB_LIB.T6G(SCH_1):PAGE345
 C1920    2      B Q_CAP_C0603-22UF,6.3V,20%,X6S,CH6221ME900    I77 @T6G_MB_LIB.T6G(SCH_1):PAGE345
 C1921    2      B Q_CAP_C0603-22UF,6.3V,20%,X6S,CH6221ME900    I78 @T6G_MB_LIB.T6G(SCH_1):PAGE345
 C9922    2      B Q_CAP_C0603-22UF,6.3V,20%,X6S,CH6221ME900    I79 @T6G_MB_LIB.T6G(SCH_1):PAGE345
 R1605    2      B Q_RES_0402LF-1K,1%,1/16W,CHIP,CS21002FB06    I83 @T6G_MB_LIB.T6G(SCH_1):PAGE345
 C1923    2      B Q_CAP_0402-0.1UF,25V,10%,X7R,CH4104K1B00    I84 @T6G_MB_LIB.T6G(SCH_1):PAGE345
 C1924    2      B Q_CAP_0402-0.1UF,25V,10%,X7R,CH4104K1B00    I85 @T6G_MB_LIB.T6G(SCH_1):PAGE345
 C1925    2      B Q_CAP_0402-0.1UF,25V,10%,X7R,CH4104K1B00    I86 @T6G_MB_LIB.T6G(SCH_1):PAGE345
 R3163    2      B Q_RES_0402LF-4.7K,1%,1/16W,EMPTY,CS24702FB06     I2 @T6G_MB_LIB.T6G(SCH_1):PAGE341
 R3167    2      B Q_RES_0402LF-4.7K,1%,1/16W,CHIP,CS24702FB06     I3 @T6G_MB_LIB.T6G(SCH_1):PAGE341
 R3175    2      B Q_RES_0402LF-10K,1%,1/16W,CHIP,CS31002FB08    I11 @T6G_MB_LIB.T6G(SCH_1):PAGE341
 C1829    2      B Q_CAP_C0805-22UF,16V,20%,X6S,CH6223MEA00    I13 @T6G_MB_LIB.T6G(SCH_1):PAGE341
 C1830    2      B Q_CAP_C0805-22UF,16V,20%,X6S,CH6223MEA00    I14 @T6G_MB_LIB.T6G(SCH_1):PAGE341
 C1831    2      B Q_CAP_0402-0.1UF,25V,10%,X7R,CH4104K1B00    I15 @T6G_MB_LIB.T6G(SCH_1):PAGE341
 C1832    2      B Q_CAP_0402-0.1UF,25V,10%,X7R,CH4104K1B00    I16 @T6G_MB_LIB.T6G(SCH_1):PAGE341
 C1833    2      B Q_CAP_0402-0.1UF,25V,10%,X7R,CH4104K1B00    I17 @T6G_MB_LIB.T6G(SCH_1):PAGE341
 C1839    2      B Q_CAP_0402-0.1UF,25V,10%,X7R,CH4104K1B00    I18 @T6G_MB_LIB.T6G(SCH_1):PAGE341
 C1835    2      B Q_CAP_0402-0.1UF,25V,10%,X7R,CH4104K1B00    I21 @T6G_MB_LIB.T6G(SCH_1):PAGE341
 C1836    2      B Q_CAP_0402-0.1UF,25V,10%,X7R,CH4104K1B00    I22 @T6G_MB_LIB.T6G(SCH_1):PAGE341
 C1838    2      B Q_CAP_0402-0.1UF,25V,10%,X7R,CH4104K1B00    I24 @T6G_MB_LIB.T6G(SCH_1):PAGE341
 R3164    1      A Q_RES_0402LF-10K,1%,1/16W,CHIP,CS31002FB08    I34 @T6G_MB_LIB.T6G(SCH_1):PAGE341
 R3180    2      B Q_RES_0402LF-0,5%,1/16W,CHIP,CS00002JB13   I150 @T6G_MB_LIB.T6G(SCH_1):PAGE341
 R3268    2      B Q_RES_0402LF-68K,1%,1/16W,EMPTY,CS36802FB04     I2 @T6G_MB_LIB.T6G(SCH_1):PAGE110
 R3272    2      B Q_RES_0402LF-1K,1%,1/16W,EMPTY,CS21002FB06     I4 @T6G_MB_LIB.T6G(SCH_1):PAGE110
 R3267    2      B Q_RES_0402LF-68K,1%,1/16W,EMPTY,CS36802FB04     I8 @T6G_MB_LIB.T6G(SCH_1):PAGE110
 R3270    2      B Q_RES_0402LF-1K,1%,1/16W,EMPTY,CS21002FB06     I9 @T6G_MB_LIB.T6G(SCH_1):PAGE110
 R3273    2      B Q_RES_0402LF-68K,1%,1/16W,EMPTY,CS36802FB04    I12 @T6G_MB_LIB.T6G(SCH_1):PAGE110
 R3274    2      B Q_RES_0402LF-68K,1%,1/16W,EMPTY,CS36802FB04    I16 @T6G_MB_LIB.T6G(SCH_1):PAGE110
 R3278    2      B Q_RES_0402LF-1K,1%,1/16W,CHIP,CS21002FB06    I18 @T6G_MB_LIB.T6G(SCH_1):PAGE110
 R3279    2      B Q_RES_0402LF-68K,1%,1/16W,EMPTY,CS36802FB04    I22 @T6G_MB_LIB.T6G(SCH_1):PAGE110
 R3281    2      B Q_RES_0402LF-1K,1%,1/16W,EMPTY,CS21002FB06    I25 @T6G_MB_LIB.T6G(SCH_1):PAGE110
 R3276    2      B Q_RES_0402LF-1K,1%,1/16W,EMPTY,CS21002FB06    I29 @T6G_MB_LIB.T6G(SCH_1):PAGE110
 R3282    2      B Q_RES_0402LF-68K,1%,1/16W,EMPTY,CS36802FB04    I34 @T6G_MB_LIB.T6G(SCH_1):PAGE110
 R3284    2      B Q_RES_0402LF-1K,1%,1/16W,CHIP,CS21002FB06    I36 @T6G_MB_LIB.T6G(SCH_1):PAGE110
 R3285    2      B Q_RES_0402LF-68K,1%,1/16W,EMPTY,CS36802FB04    I42 @T6G_MB_LIB.T6G(SCH_1):PAGE110
 R3287    2      B Q_RES_0402LF-1K,1%,1/16W,EMPTY,CS21002FB06    I44 @T6G_MB_LIB.T6G(SCH_1):PAGE110
 C1867    2      B Q_CAP_C0805-10UF,25V,10%,X6S,CH6104KEA00    I60 @T6G_MB_LIB.T6G(SCH_1):PAGE110
 C1863    2      B Q_CAP_0402-0.1UF,25V,10%,X7R,CH4104K1B00    I61 @T6G_MB_LIB.T6G(SCH_1):PAGE110
 C1864    2      B Q_CAP_0402-0.1UF,25V,10%,X7R,CH4104K1B00    I62 @T6G_MB_LIB.T6G(SCH_1):PAGE110
  U237    4   GND1 PI3EQX12902AZLEX-PI3EQX12902AZLEX,SMLF,IC,AL012902A    I63 @T6G_MB_LIB.T6G(SCH_1):PAGE110
  U237    6   GND2 PI3EQX12902AZLEX-PI3EQX12902AZLEX,SMLF,IC,AL012902A    I63 @T6G_MB_LIB.T6G(SCH_1):PAGE110
  U237    7   GND3 PI3EQX12902AZLEX-PI3EQX12902AZLEX,SMLF,IC,AL012902A    I63 @T6G_MB_LIB.T6G(SCH_1):PAGE110
  U237   13   GND4 PI3EQX12902AZLEX-PI3EQX12902AZLEX,SMLF,IC,AL012902A    I63 @T6G_MB_LIB.T6G(SCH_1):PAGE110
  U237   19   GND5 PI3EQX12902AZLEX-PI3EQX12902AZLEX,SMLF,IC,AL012902A    I63 @T6G_MB_LIB.T6G(SCH_1):PAGE110
  U237   22   GND6 PI3EQX12902AZLEX-PI3EQX12902AZLEX,SMLF,IC,AL012902A    I63 @T6G_MB_LIB.T6G(SCH_1):PAGE110
  U237   28   GND7 PI3EQX12902AZLEX-PI3EQX12902AZLEX,SMLF,IC,AL012902A    I63 @T6G_MB_LIB.T6G(SCH_1):PAGE110
  U237   TH GND_TH PI3EQX12902AZLEX-PI3EQX12902AZLEX,SMLF,IC,AL012902A    I63 @T6G_MB_LIB.T6G(SCH_1):PAGE110
 C1865    2      B Q_CAP_0402-0.1UF,25V,10%,X7R,CH4104K1B00    I64 @T6G_MB_LIB.T6G(SCH_1):PAGE110
 C1866    2      B Q_CAP_0402-0.1UF,25V,10%,X7R,CH4104K1B00    I65 @T6G_MB_LIB.T6G(SCH_1):PAGE110
 R3288    2      B Q_RES_0402LF-68K,1%,1/16W,EMPTY,CS36802FB04    I74 @T6G_MB_LIB.T6G(SCH_1):PAGE110
 R3290    2      B Q_RES_0402LF-1K,1%,1/16W,EMPTY,CS21002FB06    I76 @T6G_MB_LIB.T6G(SCH_1):PAGE110
 R3265    2      B Q_RES_0402LF-4.7K,1%,1/16W,EMPTY,CS24702FB06    I81 @T6G_MB_LIB.T6G(SCH_1):PAGE110
 R3291    2      B Q_RES_0402LF-4.7K,1%,1/16W,EMPTY,CS24702FB06    I88 @T6G_MB_LIB.T6G(SCH_1):PAGE110
 R3293    2      B Q_RES_0402LF-4.7K,1%,1/16W,EMPTY,CS24702FB06    I92 @T6G_MB_LIB.T6G(SCH_1):PAGE110
 R1930    1      A Q_RES_0402LF-10K,1%,1/16W,CHIP,CS31002FB08     I7 @T6G_MB_LIB.T6G(SCH_1):PAGE335
 R1929    1      A Q_RES_0402LF-10K,1%,1/16W,CHIP,CS31002FB08     I8 @T6G_MB_LIB.T6G(SCH_1):PAGE335
   R34    2      B Q_RES_0402LF-4.7K,1%,1/16W,CHIP,CS24702FB06    I12 @T6G_MB_LIB.T6G(SCH_1):PAGE335
 R8422    2      B Q_RES_0402LF-10K,1%,1/16W,CHIP,CS31002FB08    I19 @T6G_MB_LIB.T6G(SCH_1):PAGE335
 C1213    2      B Q_CAP_C0805-22UF,16V,20%,X6S,CH6223MEA00    I87 @T6G_MB_LIB.T6G(SCH_1):PAGE335
   C34    2      B Q_CAP_C0805-22UF,16V,20%,X6S,CH6223MEA00    I88 @T6G_MB_LIB.T6G(SCH_1):PAGE335
 C1239    2      B Q_CAP_0402-0.1UF,25V,10%,X7R,CH4104K1B00   I112 @T6G_MB_LIB.T6G(SCH_1):PAGE335
   C27    2      B Q_CAP_0402-0.1UF,25V,10%,X7R,CH4104K1B00   I163 @T6G_MB_LIB.T6G(SCH_1):PAGE335
 C1236    2      B Q_CAP_0402-0.1UF,25V,10%,X7R,CH4104K1B00   I164 @T6G_MB_LIB.T6G(SCH_1):PAGE335
  Q144    1     S1 MOSFET_NCH_DUAL-PJT138K,SMLF,IC,BAM138K0003     I3 @T6G_MB_LIB.T6G(SCH_1):PAGE368
  Q144    4     S2 MOSFET_NCH_DUAL-PJT138K,SMLF,IC,BAM138K0003    I10 @T6G_MB_LIB.T6G(SCH_1):PAGE368
   D99    C      C Q_LED_SMLF-LED_BLUE,LTST-C281TBKT-5A,IC,BEBL0172Z00     I3 @T6G_MB_LIB.T6G(SCH_1):PAGE254
   D98    C      C Q_LED_SMLF-LED_BLUE,LTST-C281TBKT-5A,IC,BEBL0172Z00    I17 @T6G_MB_LIB.T6G(SCH_1):PAGE254
   Q78    4     S2 MOSFET_NCH_DUAL-PJT138K,SMLF,IC,BAM138K0003    I18 @T6G_MB_LIB.T6G(SCH_1):PAGE254
 C1134    2      B Q_CAP_C0402-0.1UF,16V,10%,X7R,CH4103K1B08    I79 @T6G_MB_LIB.T6G(SCH_1):PAGE82
 C1132    2      B Q_CAP_C0402-0.1UF,16V,10%,X7R,CH4103K1B08    I80 @T6G_MB_LIB.T6G(SCH_1):PAGE82
 C1131    2      B Q_CAP_C0402-0.1UF,16V,10%,X7R,CH4103K1B08    I82 @T6G_MB_LIB.T6G(SCH_1):PAGE82
  C352    2      B Q_CAP_C0402-0.1UF,16V,10%,X7R,CH4103K1B08    I83 @T6G_MB_LIB.T6G(SCH_1):PAGE82
 C1128    2      B Q_CAP_C0402-0.1UF,16V,10%,X7R,CH4103K1B08    I84 @T6G_MB_LIB.T6G(SCH_1):PAGE82
 C1129    2      B Q_CAP_C0402-0.1UF,16V,10%,X7R,CH4103K1B08    I85 @T6G_MB_LIB.T6G(SCH_1):PAGE82
 C1126    2      B Q_CAP_C0402-0.1UF,16V,10%,X7R,CH4103K1B08    I86 @T6G_MB_LIB.T6G(SCH_1):PAGE82
 C1127    2      B Q_CAP_C0402-0.1UF,16V,10%,X7R,CH4103K1B08    I87 @T6G_MB_LIB.T6G(SCH_1):PAGE82
   R25    2      B Q_RES_0402LF-10K,1%,1/16W,CHIP,CS31002FB08    I97 @T6G_MB_LIB.T6G(SCH_1):PAGE82
  C358    2      B Q_CAP_C0402-0.1UF,16V,10%,X7R,CH4103K1B08   I105 @T6G_MB_LIB.T6G(SCH_1):PAGE82
  C357    2      B Q_CAP_C0402-0.1UF,16V,10%,X7R,CH4103K1B08   I106 @T6G_MB_LIB.T6G(SCH_1):PAGE82
  C356    2      B Q_CAP_C0402-0.1UF,16V,10%,X7R,CH4103K1B08   I107 @T6G_MB_LIB.T6G(SCH_1):PAGE82
  C355    2      B Q_CAP_C0402-0.1UF,16V,10%,X7R,CH4103K1B08   I108 @T6G_MB_LIB.T6G(SCH_1):PAGE82
 C1176    2      B Q_CAP_C0402-0.1UF,16V,10%,X7R,CH4103K1B08   I109 @T6G_MB_LIB.T6G(SCH_1):PAGE82
 C1175    2      B Q_CAP_C0402-0.1UF,16V,10%,X7R,CH4103K1B08   I110 @T6G_MB_LIB.T6G(SCH_1):PAGE82
 C1174    2      B Q_CAP_C0402-0.1UF,16V,10%,X7R,CH4103K1B08   I111 @T6G_MB_LIB.T6G(SCH_1):PAGE82
 C1172    2      B Q_CAP_C0402-0.1UF,16V,10%,X7R,CH4103K1B08   I112 @T6G_MB_LIB.T6G(SCH_1):PAGE82
 C1173    2      B Q_CAP_C0402-0.1UF,16V,10%,X7R,CH4103K1B08   I113 @T6G_MB_LIB.T6G(SCH_1):PAGE82
 C1171    2      B Q_CAP_C0402-0.1UF,16V,10%,X7R,CH4103K1B08   I114 @T6G_MB_LIB.T6G(SCH_1):PAGE82
  R804    2      B Q_RES_0402LF-10K,1%,1/16W,CHIP,CS31002FB08   I120 @T6G_MB_LIB.T6G(SCH_1):PAGE82
   R18    2      B Q_RES_0402LF-10K,1%,1/16W,CHIP,CS31002FB08   I126 @T6G_MB_LIB.T6G(SCH_1):PAGE82
   R19    2      B Q_RES_0402LF-10K,1%,1/16W,CHIP,CS31002FB08   I128 @T6G_MB_LIB.T6G(SCH_1):PAGE82
  Q123    1     S1 MOSFET_NCH_DUAL-PJT138K,SMLF,IC,BAM138K0003    I11 @T6G_MB_LIB.T6G(SCH_1):PAGE338
  Q123    4     S2 MOSFET_NCH_DUAL-PJT138K,SMLF,IC,BAM138K0003    I19 @T6G_MB_LIB.T6G(SCH_1):PAGE338
  Q124    1     S1 MOSFET_NCH_DUAL-PJT138K,SMLF,IC,BAM138K0003    I23 @T6G_MB_LIB.T6G(SCH_1):PAGE338
    U8    2    GND 74LVC2G07DW7-74LVC2G07DW-7,SMLF,IC,AL002G07003    I26 @T6G_MB_LIB.T6G(SCH_1):PAGE338
  U211    2    GND 74LVC2G07DW7-74LVC2G07DW-7,SMLF,IC,AL002G07003    I29 @T6G_MB_LIB.T6G(SCH_1):PAGE338
  C593    2      B Q_CAP_0402-0.1UF,25V,10%,X7R,CH4104K1B00    I30 @T6G_MB_LIB.T6G(SCH_1):PAGE338
  C592    2      B Q_CAP_0402-0.1UF,25V,10%,X7R,CH4104K1B00    I33 @T6G_MB_LIB.T6G(SCH_1):PAGE338
PR3788    2      B Q_RES_0402LF-15K,1%,1/16W,CHIP,CS31502FB05    I36 @T6G_MB_LIB.T6G(SCH_1):PAGE338
PC2079    2      B Q_CAP_C0402-1UF,25V,10%,X6S,CH5104KEB02    I45 @T6G_MB_LIB.T6G(SCH_1):PAGE338
PR5484    2      B Q_RES_0402LF-30.1K,1%,1/16W,CHIP,CS33012FB03    I48 @T6G_MB_LIB.T6G(SCH_1):PAGE338
 PU203   A7   CDLY MAX15090BEWIT-MAX15090BEWI+T,SMLF,IC,AL015080B00    I50 @T6G_MB_LIB.T6G(SCH_1):PAGE338
 PU203   B7    EN# MAX15090BEWIT-MAX15090BEWI+T,SMLF,IC,AL015080B00    I50 @T6G_MB_LIB.T6G(SCH_1):PAGE338
 PU203   B2 GND_B2 MAX15090BEWIT-MAX15090BEWI+T,SMLF,IC,AL015080B00    I50 @T6G_MB_LIB.T6G(SCH_1):PAGE338
 PU203   C1 GND_C1 MAX15090BEWIT-MAX15090BEWI+T,SMLF,IC,AL015080B00    I50 @T6G_MB_LIB.T6G(SCH_1):PAGE338
 PU203   C2 GND_C2 MAX15090BEWIT-MAX15090BEWI+T,SMLF,IC,AL015080B00    I50 @T6G_MB_LIB.T6G(SCH_1):PAGE338
PC2087    1      A Q_CAP_C0402-1UF,25V,10%,X6S,CH5104KEB02    I54 @T6G_MB_LIB.T6G(SCH_1):PAGE338
PC2085    2      B Q_CAP_C0402-1UF,25V,10%,X6S,CH5104KEB02    I55 @T6G_MB_LIB.T6G(SCH_1):PAGE338
PC5328    2      B Q_CAP_C0402-1UF,25V,10%,X6S,CH5104KEB02    I62 @T6G_MB_LIB.T6G(SCH_1):PAGE338
PC2093    1      A Q_CAP_C0402-1UF,25V,10%,X6S,CH5104KEB02    I67 @T6G_MB_LIB.T6G(SCH_1):PAGE338
PR3781    2      B Q_RES_0402LF-845,1%,1/16W,CHIP,CS18452FB01    I73 @T6G_MB_LIB.T6G(SCH_1):PAGE338
PC4056    2      B Q_CAP_C0402-3900PF,50V,10%,X7R,CH23906KB14    I77 @T6G_MB_LIB.T6G(SCH_1):PAGE338
 PD102    A      A SCHOTTKY_AC-B340A-13-F,SMLF,IC,BC000340Z30    I79 @T6G_MB_LIB.T6G(SCH_1):PAGE338
PC2092    2      B Q_CAP_0402-0.1UF,25V,10%,X7R,CH4104K1B00    I86 @T6G_MB_LIB.T6G(SCH_1):PAGE338
PC2080    2      B Q_CAP_C0805-22UF,16V,20%,X6S,CH6223MEA01    I87 @T6G_MB_LIB.T6G(SCH_1):PAGE338
PC2082    2      B Q_CAP_C0805-10UF,16V,10%,X6S,CH6103KEA01    I89 @T6G_MB_LIB.T6G(SCH_1):PAGE338
PR5481    2      B Q_RES_0402LF-4.53K,1%,1/16W,CHIP,CS24532FB03    I95 @T6G_MB_LIB.T6G(SCH_1):PAGE338
 PD103    A      A SCHOTTKY_AC-B340A-13-F,SMLF,IC,BC000340Z30    I97 @T6G_MB_LIB.T6G(SCH_1):PAGE338
PC2089    2      B Q_CAP_C0402-6800PF,50V,10%,X7R,CH2686K1B01   I100 @T6G_MB_LIB.T6G(SCH_1):PAGE338
PC2091    2      B Q_CAP_0402-0.1UF,25V,10%,X7R,CH4104K1B00   I104 @T6G_MB_LIB.T6G(SCH_1):PAGE338
PC2081    2      B Q_CAP_C0805-10UF,16V,10%,X6S,CH6103KEA01   I106 @T6G_MB_LIB.T6G(SCH_1):PAGE338
PC2086    2      B Q_CAP_C0402-1UF,25V,10%,X6S,CH5104KEB02   I110 @T6G_MB_LIB.T6G(SCH_1):PAGE338
PR3780    2      B Q_RES_0402LF-5.36K,1%,1/16W,CHIP,CS25362FB02   I111 @T6G_MB_LIB.T6G(SCH_1):PAGE338
  Q124    4     S2 MOSFET_NCH_DUAL-PJT138K,SMLF,IC,BAM138K0003   I112 @T6G_MB_LIB.T6G(SCH_1):PAGE338
 PU202   A7   CDLY MAX15090BEWIT-MAX15090BEWI+T,SMLF,IC,AL015080B00   I113 @T6G_MB_LIB.T6G(SCH_1):PAGE338
 PU202   B7    EN# MAX15090BEWIT-MAX15090BEWI+T,SMLF,IC,AL015080B00   I113 @T6G_MB_LIB.T6G(SCH_1):PAGE338
 PU202   B2 GND_B2 MAX15090BEWIT-MAX15090BEWI+T,SMLF,IC,AL015080B00   I113 @T6G_MB_LIB.T6G(SCH_1):PAGE338
 PU202   C1 GND_C1 MAX15090BEWIT-MAX15090BEWI+T,SMLF,IC,AL015080B00   I113 @T6G_MB_LIB.T6G(SCH_1):PAGE338
 PU202   C2 GND_C2 MAX15090BEWIT-MAX15090BEWI+T,SMLF,IC,AL015080B00   I113 @T6G_MB_LIB.T6G(SCH_1):PAGE338
PR3791    2      B Q_RES_0402LF-15K,1%,1/16W,CHIP,CS31502FB05   I114 @T6G_MB_LIB.T6G(SCH_1):PAGE338
 PD101    A      A DIODE_TVS-SMF14A,SMLF,IC,BCSMF14AZ01   I115 @T6G_MB_LIB.T6G(SCH_1):PAGE338
  R999    2      B Q_RES_0402LF-4.7K,5%,1/16W,CHIP,CS24702JB10    I95 @T6G_MB_LIB.T6G(SCH_1):PAGE297
   U44    3    GND 74LVC1G17GW-74LVC1G17GW,SMLF,IC,AL1G0017K01    I97 @T6G_MB_LIB.T6G(SCH_1):PAGE297
  C508    2      B Q_CAP_0402-0.1UF,25V,10%,X7R,CH4104K1B00    I99 @T6G_MB_LIB.T6G(SCH_1):PAGE297
 R1000    2      B Q_RES_0402LF-4.7K,5%,1/16W,CHIP,CS24702JB10   I102 @T6G_MB_LIB.T6G(SCH_1):PAGE297
  C552    2      B Q_CAP_0402-0.1UF,25V,10%,X7R,CH4104K1B00    I24 @T6G_MB_LIB.T6G(SCH_1):PAGE83
   U92    3    GND SN74LVC1G07DBVR_SMLF-SN74LVC1G07DBVR,IC,AL1G0007024    I26 @T6G_MB_LIB.T6G(SCH_1):PAGE83
 R6145    2      B Q_RES_0402LF-1K,1%,1/16W,CHIP,CS21002FB06    I54 @T6G_MB_LIB.T6G(SCH_1):PAGE83
 R1508    1      A Q_RES_0402LF-100,1%,1/16W,CHIP,CS11002FB07     I6 @T6G_MB_LIB.T6G(SCH_1):PAGE144
 R6044    2      B Q_RES_0402LF-10K,5%,1/16W,CHIP,CS31002JB08    I33 @T6G_MB_LIB.T6G(SCH_1):PAGE144
    R8    1      A Q_RES_0402LF-100K,1%,1/16W,CHIP,CS41002FB09    I47 @T6G_MB_LIB.T6G(SCH_1):PAGE144
 R1265    2      B Q_RES_0402LF-10K,5%,1/16W,CHIP,CS31002JB08    I52 @T6G_MB_LIB.T6G(SCH_1):PAGE144
 R6043    1      A Q_RES_0402LF-100K,1%,1/16W,CHIP,CS41002FB09    I61 @T6G_MB_LIB.T6G(SCH_1):PAGE144
 R6041    1      A Q_RES_0402LF-100K,1%,1/16W,CHIP,CS41002FB09    I69 @T6G_MB_LIB.T6G(SCH_1):PAGE144
  Q126    4     S2 MOSFET_NCH_DUAL-PJT138K,SMLF,IC,BAM138K0003     I7 @T6G_MB_LIB.T6G(SCH_1):PAGE324
  Q127    1     S1 MOSFET_NCH_DUAL-PJT138K,SMLF,IC,BAM138K0003    I12 @T6G_MB_LIB.T6G(SCH_1):PAGE324
PC2212    1      A Q_CAP_C0402-1UF,25V,10%,X6S,CH5104KEB02    I42 @T6G_MB_LIB.T6G(SCH_1):PAGE324
PC2216    2      B Q_CAP_C0402-6800PF,50V,10%,X7R,CH2686K1B01    I49 @T6G_MB_LIB.T6G(SCH_1):PAGE324
PC2218    2      B Q_CAP_0402-0.1UF,25V,10%,X7R,CH4104K1B00    I57 @T6G_MB_LIB.T6G(SCH_1):PAGE324
PC2209    2      B Q_CAP_C0402-1UF,25V,10%,X6S,CH5104KEB02    I64 @T6G_MB_LIB.T6G(SCH_1):PAGE324
PC2219    2      B Q_CAP_C0805-10UF,16V,10%,X6S,CH6103KEA01    I79 @T6G_MB_LIB.T6G(SCH_1):PAGE324
 PU295   A7   CDLY MAX15090BEWIT-MAX15090BEWI+T,SMLF,IC,AL015080B00    I88 @T6G_MB_LIB.T6G(SCH_1):PAGE324
 PU295   B7    EN# MAX15090BEWIT-MAX15090BEWI+T,SMLF,IC,AL015080B00    I88 @T6G_MB_LIB.T6G(SCH_1):PAGE324
 PU295   B2 GND_B2 MAX15090BEWIT-MAX15090BEWI+T,SMLF,IC,AL015080B00    I88 @T6G_MB_LIB.T6G(SCH_1):PAGE324
 PU295   C1 GND_C1 MAX15090BEWIT-MAX15090BEWI+T,SMLF,IC,AL015080B00    I88 @T6G_MB_LIB.T6G(SCH_1):PAGE324
 PU295   C2 GND_C2 MAX15090BEWIT-MAX15090BEWI+T,SMLF,IC,AL015080B00    I88 @T6G_MB_LIB.T6G(SCH_1):PAGE324
PC2153    2      B Q_CAP_0402-0.22UF,16V,10%,X7R,CH4223K1B00    I60 @T6G_MB_LIB.T6G(SCH_1):PAGE339
PR3835    2      B Q_RES_0402LF-14.3K,1%,1/16W,CHIP,CS31432FB02    I63 @T6G_MB_LIB.T6G(SCH_1):PAGE339
PC2155    2      B Q_CAP_C0402-0.047UF,25V,10%,X7R,CH3474K1B04    I64 @T6G_MB_LIB.T6G(SCH_1):PAGE339
PC2154    2      B Q_CAP_C0402-1UF,25V,10%,X6S,CH5104KEB02    I68 @T6G_MB_LIB.T6G(SCH_1):PAGE339
PR3837    2      B Q_RES_0402LF-17.4K,1%,1/16W,CHIP,CS31742FB04    I71 @T6G_MB_LIB.T6G(SCH_1):PAGE339
PC2156    2      B Q_CAP_C0402-100NF,50V,10%,X7R,CH4106K1B01    I73 @T6G_MB_LIB.T6G(SCH_1):PAGE339
PR3842    2      B Q_RES_0402LF-10K,1%,1/16W,CHIP,CS31002FB08    I80 @T6G_MB_LIB.T6G(SCH_1):PAGE339
PC2158    2      B Q_CAP_C0603-2.2UF,16V,20%,X7R,CH5223M1900    I86 @T6G_MB_LIB.T6G(SCH_1):PAGE339
PC2160    2      B Q_CAP_0402-0.1UF,25V,10%,X7R,CH4104K1B00    I91 @T6G_MB_LIB.T6G(SCH_1):PAGE339
PC2157    2      B Q_CAP_0402-39PF,50V,5%,NPO,CH03906JB06    I98 @T6G_MB_LIB.T6G(SCH_1):PAGE339
PR3844    2      B Q_RES_0402LF-71.5K,1%,1/16W,CHIP,CS37152FB05   I100 @T6G_MB_LIB.T6G(SCH_1):PAGE339
PR3846    1      A Q_RES_0402LF-1.33K,1%,1/16W,CHIP,CS21332FB05   I102 @T6G_MB_LIB.T6G(SCH_1):PAGE339
PC2161    2      B Q_CAP_0402-0.068UF,16V,10%,X7R,CH3683K1B09   I104 @T6G_MB_LIB.T6G(SCH_1):PAGE339
PC2162    2      B Q_CAP_0402-100PF,50V,5%,X7R,CH11006JB18   I106 @T6G_MB_LIB.T6G(SCH_1):PAGE339
PC2163    2      B Q_CAP_C0805-10UF,16V,10%,X6S,CH6103KEA01   I108 @T6G_MB_LIB.T6G(SCH_1):PAGE339
PC2159    2      B Q_CAP_C0402-1UF,25V,10%,X6S,CH5104KEB02   I111 @T6G_MB_LIB.T6G(SCH_1):PAGE339
 PU205    3    GND MP5016GQHLZ-MP5016GQH-L-Z,SMLF,IC,AL005016007   I113 @T6G_MB_LIB.T6G(SCH_1):PAGE339
  R334    2      B Q_RES_0402LF-100K,1%,1/16W,CHIP,CS41002FB09     I7 @T6G_MB_LIB.T6G(SCH_1):PAGE273
 C1042    2      B Q_CAP_C0402-100NF,50V,10%,X7R,CH4106K1B01    I18 @T6G_MB_LIB.T6G(SCH_1):PAGE273
 C1170    2      B Q_CAP_C0805-10UF,16V,10%,X6S,CH6103KEA00    I19 @T6G_MB_LIB.T6G(SCH_1):PAGE273
   C57    2      B Q_CAP_C0805-10UF,16V,10%,EMPTY,CH6103KEA00    I20 @T6G_MB_LIB.T6G(SCH_1):PAGE273
 C9226    2      B Q_CAP_C0402-0.22UF,25V,10%,X7R,CH4224K1B01    I38 @T6G_MB_LIB.T6G(SCH_1):PAGE273
 C1331    2      B Q_CAP_C0805-10UF,16V,10%,X6S,CH6103KEA00    I43 @T6G_MB_LIB.T6G(SCH_1):PAGE273
   C61    2      B Q_CAP_C0402-100NF,50V,10%,X7R,CH4106K1B01    I59 @T6G_MB_LIB.T6G(SCH_1):PAGE273
  U324    S      S MOSFET_NCH_GDS_ESD_PROTECTED-2N7002K,SMLF,IC,BAM70A    I62 @T6G_MB_LIB.T6G(SCH_1):PAGE273
   J57    7      7 CONN8_HBB1081L200D8H-CONN8_HBB1081-L200D-8H,THLF,IA    I41 @T6G_MB_LIB.T6G(SCH_1):PAGE84
   C20    2      B Q_CAP_C0402-0.1UF,16V,10%,X7R,CH4103K1B08    I42 @T6G_MB_LIB.T6G(SCH_1):PAGE84
 R5032    1      A Q_RES_0402LF-4.7K,5%,1/16W,EMPTY,CS24702JB10   I330 @T6G_MB_LIB.T6G(SCH_1):PAGE55
 R5031    1      A Q_RES_0402LF-4.7K,5%,1/16W,EMPTY,CS24702JB10   I331 @T6G_MB_LIB.T6G(SCH_1):PAGE55
 R5030    1      A Q_RES_0402LF-4.7K,5%,1/16W,EMPTY,CS24702JB10   I334 @T6G_MB_LIB.T6G(SCH_1):PAGE55
  R491    1      A Q_RES_0402LF-4.7K,5%,1/16W,EMPTY,CS24702JB10   I335 @T6G_MB_LIB.T6G(SCH_1):PAGE55
  R584    1      A Q_RES_0402LF-4.7K,5%,1/16W,EMPTY,CS24702JB10   I341 @T6G_MB_LIB.T6G(SCH_1):PAGE55
PC1648    2      B Q_CAP_C0402-0.1UF,25V,10%,X6S,CH4104KEB00     I2 @T6G_MB_LIB.T6G(SCH_1):PAGE244
PC1849    2      B Q_CAP_C0805-22UF,16V,20%,X6S,CH6223MEA01     I7 @T6G_MB_LIB.T6G(SCH_1):PAGE244
PC1848    2      B Q_CAP_C0402-1UF,25V,10%,X6S,CH5104KEB02     I8 @T6G_MB_LIB.T6G(SCH_1):PAGE244
PC1850    2      B Q_CAP_C0805-22UF,16V,20%,X6S,CH6223MEA01    I10 @T6G_MB_LIB.T6G(SCH_1):PAGE244
PC1898    2      B Q_CAP_C0805-22UF,16V,20%,X6S,CH6223MEA01    I11 @T6G_MB_LIB.T6G(SCH_1):PAGE244
PC1846    2      B Q_CAP_C0402-1UF,16V,10%,X6S,CH5103KEB01    I13 @T6G_MB_LIB.T6G(SCH_1):PAGE244
PR8089    2      B Q_RES_0402LF-16.9K,1%,1/16W,CHIP,CS31692FB03    I15 @T6G_MB_LIB.T6G(SCH_1):PAGE244
PC1853    2      B Q_CAP_0402-0.1UF,25V,10%,X7R,CH4104K1B00    I19 @T6G_MB_LIB.T6G(SCH_1):PAGE244
PR8091    2      B Q_RES_0402LF-11.8K,0.1%,1/16W,CHIP,CS31182BB06    I23 @T6G_MB_LIB.T6G(SCH_1):PAGE244
PC1845    2      B Q_CAPP_SMLF-220UF,6.3V,20%,ALUM,CC72201MZ28    I30 @T6G_MB_LIB.T6G(SCH_1):PAGE244
PC1855    2      B Q_CAP_C0805-22UF,10V,20%,X6S,CH6222MEA01    I31 @T6G_MB_LIB.T6G(SCH_1):PAGE244
PC1856    2      B Q_CAP_C0805-22UF,10V,20%,X6S,CH6222MEA01    I32 @T6G_MB_LIB.T6G(SCH_1):PAGE244
PC1852    2      B Q_CAP_0402-0.1UF,25V,10%,X7R,CH4104K1B00    I34 @T6G_MB_LIB.T6G(SCH_1):PAGE244
PR3337    2      B Q_RES_0402LF-0,5%,1/16W,CHIP,CS00002JB13    I37 @T6G_MB_LIB.T6G(SCH_1):PAGE244
  U326    2   AGND MPQ8633AGLEC807Z-MPQ8633AGLE-C807-Z,SMLF,IC,AL0086A    I38 @T6G_MB_LIB.T6G(SCH_1):PAGE244
  U326 11_18   PGND MPQ8633AGLEC807Z-MPQ8633AGLE-C807-Z,SMLF,IC,AL0086A    I38 @T6G_MB_LIB.T6G(SCH_1):PAGE244
  U326    6   RGND MPQ8633AGLEC807Z-MPQ8633AGLE-C807-Z,SMLF,IC,AL0086A    I38 @T6G_MB_LIB.T6G(SCH_1):PAGE244
 PR832    2      B Q_RES_0402LF-0,5%,1/16W,CHIP,CS00002JB13    I10 @T6G_MB_LIB.T6G(SCH_1):PAGE245
 PC581    2      B Q_CAP_C0603-4.7UF,16V,10%,X6S,CH5473KE902    I12 @T6G_MB_LIB.T6G(SCH_1):PAGE245
 PC591    2      B Q_CAP_C0603-2.2UF,16V,10%,X6S,CH5223KE901    I19 @T6G_MB_LIB.T6G(SCH_1):PAGE245
PC2261    2      B Q_CAP_C0805-22UF,16V,20%,X6S,CH6223MEA01    I27 @T6G_MB_LIB.T6G(SCH_1):PAGE245
PC8008    2      B Q_CAP_0603-1UF,16V,10%,X7R,TMP_QCH5103K1900    I44 @T6G_MB_LIB.T6G(SCH_1):PAGE245
PC1599    2      B Q_CAP_C0805-22UF,10V,20%,X6S,CH6222MEA01    I60 @T6G_MB_LIB.T6G(SCH_1):PAGE245
 PC118    2      B Q_CAP_C0402-1UF,25V,10%,X6S,CH5104KEB02     I2 @T6G_MB_LIB.T6G(SCH_1):PAGE167
  C348    2      B Q_CAP_0402-0.1UF,25V,10%,EMPTY,CH4104K1B00     I5 @T6G_MB_LIB.T6G(SCH_1):PAGE167
PC6000    2      B Q_CAP_C0402-0.1UF,25V,10%,X6S,CH4104KEB00     I8 @T6G_MB_LIB.T6G(SCH_1):PAGE167
 PC119    2      B Q_CAP_C0805-22UF,16V,20%,X6S,CH6223MEA01    I12 @T6G_MB_LIB.T6G(SCH_1):PAGE167
 PC120    2      B Q_CAP_C0805-22UF,16V,20%,X6S,CH6223MEA01    I13 @T6G_MB_LIB.T6G(SCH_1):PAGE167
 PR452    2      B Q_RES_0402LF-6.98K,1%,1/16W,CHIP,CS26982FB08    I15 @T6G_MB_LIB.T6G(SCH_1):PAGE167
PR6000    1      A Q_RES_0402LF-0,5%,1/16W,CHIP,CS00002JB13    I17 @T6G_MB_LIB.T6G(SCH_1):PAGE167
 PC127    2      B Q_CAP_0402-0.1UF,25V,10%,X7R,CH4104K1B00    I19 @T6G_MB_LIB.T6G(SCH_1):PAGE167
 PR454    2      B Q_RES_0402LF-12.4K,1%,1/16W,CHIP,CS31242FB02    I23 @T6G_MB_LIB.T6G(SCH_1):PAGE167
 PC129    2      B Q_CAP_C0805-22UF,16V,20%,X6S,CH6223MEA01    I27 @T6G_MB_LIB.T6G(SCH_1):PAGE167
 PC130    2      B Q_CAP_C0805-22UF,16V,20%,X6S,CH6223MEA01    I28 @T6G_MB_LIB.T6G(SCH_1):PAGE167
 PC123    2      B Q_CAP_C0805-22UF,16V,20%,X6S,CH6223MEA01    I29 @T6G_MB_LIB.T6G(SCH_1):PAGE167
 PC126    2      B Q_CAP_C0402-1UF,25V,10%,X6S,CH5104KEB02    I30 @T6G_MB_LIB.T6G(SCH_1):PAGE167
 PC134    2      B Q_CAP_C0805-22UF,16V,20%,X6S,CH6223MEA01    I35 @T6G_MB_LIB.T6G(SCH_1):PAGE167
 PC135    2      B Q_CAP_C0805-22UF,16V,20%,X6S,CH6223MEA01    I36 @T6G_MB_LIB.T6G(SCH_1):PAGE167
 PC136    2      B Q_CAP_0402-0.1UF,25V,10%,X7R,CH4104K1B00    I37 @T6G_MB_LIB.T6G(SCH_1):PAGE167
  PU55    2   AGND MPQ8633AGLEC807Z-MPQ8633AGLE-C807-Z,SMLF,IC,AL0086A    I41 @T6G_MB_LIB.T6G(SCH_1):PAGE167
  PU55 11_18   PGND MPQ8633AGLEC807Z-MPQ8633AGLE-C807-Z,SMLF,IC,AL0086A    I41 @T6G_MB_LIB.T6G(SCH_1):PAGE167
  PU55    6   RGND MPQ8633AGLEC807Z-MPQ8633AGLE-C807-Z,SMLF,IC,AL0086A    I41 @T6G_MB_LIB.T6G(SCH_1):PAGE167
 R8286    2      B Q_RES_0402LF-1K,1%,1/16W,EMPTY,CS21002FB06     I6 @T6G_MB_LIB.T6G(SCH_1):PAGE168
  PQ17    S SOURCE MOSFET_N_SMLF-BSS138K,BSS138K,IC,BAM138K0000    I17 @T6G_MB_LIB.T6G(SCH_1):PAGE168
   PR5    2      B Q_RES_0402LF-10K,1%,1/16W,CHIP,CS31002FB08    I21 @T6G_MB_LIB.T6G(SCH_1):PAGE168
 PC462    2      B Q_CAP_0402-0.1UF,25V,10%,X7R,CH4104K1B00    I23 @T6G_MB_LIB.T6G(SCH_1):PAGE168
 PR292    2      B Q_RES_0402LF-681,1%,1/16W,CHIP,CS16812FB02    I27 @T6G_MB_LIB.T6G(SCH_1):PAGE168
 PR295    2      B Q_RES_0402LF-49.9,1%,1/16W,CHIP,CS04992FB07    I44 @T6G_MB_LIB.T6G(SCH_1):PAGE168
   PC7    2      B Q_CAP_0402-0.1UF,25V,10%,X7R,CH4104K1B00    I50 @T6G_MB_LIB.T6G(SCH_1):PAGE168
  C465    2      B Q_CAP_0402-1000PF,50V,5%,EMPTY,TMP_QCH21006JB10    I51 @T6G_MB_LIB.T6G(SCH_1):PAGE168
 PC466    2      B Q_CAP_0402-1UF,6.3V,10%,X7R,CH5101K1B01    I52 @T6G_MB_LIB.T6G(SCH_1):PAGE168
  C298    2      B Q_CAP_0402-10PF,50V,5%,EMPTY,CH01006JB08    I64 @T6G_MB_LIB.T6G(SCH_1):PAGE168
  C467    2      B Q_CAP_0402-1000PF,50V,5%,EMPTY,TMP_QCH21006JB10    I92 @T6G_MB_LIB.T6G(SCH_1):PAGE168
 PC469    2      B Q_CAP_0402-470PF,50V,10%,X7R,TMP_QCH14706KB18    I95 @T6G_MB_LIB.T6G(SCH_1):PAGE168
 PC472    2      B Q_CAP_0402-470PF,50V,10%,X7R,TMP_QCH14706KB18    I98 @T6G_MB_LIB.T6G(SCH_1):PAGE168
 PR441    2      B Q_RES_0402LF-0,5%,1/16W,CHIP,CS00002JB13   I107 @T6G_MB_LIB.T6G(SCH_1):PAGE168
 PR440    2      B Q_RES_0402LF-0,5%,1/16W,CHIP,CS00002JB13   I108 @T6G_MB_LIB.T6G(SCH_1):PAGE168
 PR531    2      B Q_RES_0402LF-0,5%,1/16W,CHIP,CS00002JB13   I111 @T6G_MB_LIB.T6G(SCH_1):PAGE168
  PC12    2      B Q_CAP_0402-0.1UF,25V,10%,X7R,CH4104K1B00   I120 @T6G_MB_LIB.T6G(SCH_1):PAGE168
 PC470    2      B Q_CAP_C0402-10UF,6.3V,20%,X6S,CH6101MEB03   I129 @T6G_MB_LIB.T6G(SCH_1):PAGE168
 PC471    2      B Q_CAP_C0402-1UF,16V,10%,X6S,CH5103KEB01   I131 @T6G_MB_LIB.T6G(SCH_1):PAGE168
  PU42   TH TH_GND RAA229620GNPHA0-RAA229620GNP#HA0,SMLF,IC,ARF0TGP40A   I135 @T6G_MB_LIB.T6G(SCH_1):PAGE168
PC474_2    2      B Q_CAP_0402-0.1UF,25V,10%,X7R,CH4104K1B00     I8 @T6G_MB_LIB.T6G(SCH_1):PAGE169
 PR321    1      A Q_RES_0402LF-8.87K,1%,1/16W,EMPTY,CS28872FB01    I10 @T6G_MB_LIB.T6G(SCH_1):PAGE169
 PC476    2      B Q_CAP_C0402-2.2UF,10V,10%,X6S,CH5222KEB01    I14 @T6G_MB_LIB.T6G(SCH_1):PAGE169
PC473_1    2      B Q_CAP_0402-0.1UF,25V,10%,X7R,CH4104K1B00    I22 @T6G_MB_LIB.T6G(SCH_1):PAGE169
 PR496    2      B Q_RES_0402LF-1.5,1%,1/8W,EMPTY,CS-1504FB00    I28 @T6G_MB_LIB.T6G(SCH_1):PAGE169
PC480_2    2      B Q_CAP_C0402-1UF,25V,10%,X6S,CH5104KEB02    I34 @T6G_MB_LIB.T6G(SCH_1):PAGE169
PC484_2    2      B Q_CAP_C0805-22UF,16V,20%,X6S,CH6223MEA01    I36 @T6G_MB_LIB.T6G(SCH_1):PAGE169
PC486_2    2      B Q_CAP_C0805-22UF,16V,20%,X6S,CH6223MEA01    I37 @T6G_MB_LIB.T6G(SCH_1):PAGE169
PC488_2    2      B Q_CAP_C0805-22UF,16V,20%,X6S,CH6223MEA01    I39 @T6G_MB_LIB.T6G(SCH_1):PAGE169
 PR495    2      B Q_RES_0402LF-1.5,1%,1/8W,EMPTY,CS-1504FB00    I42 @T6G_MB_LIB.T6G(SCH_1):PAGE169
 PC475    2      B Q_CAP_C0402-2.2UF,10V,10%,X6S,CH5222KEB01    I45 @T6G_MB_LIB.T6G(SCH_1):PAGE169
 PR320    1      A Q_RES_0402LF-8.87K,1%,1/16W,EMPTY,CS28872FB01    I46 @T6G_MB_LIB.T6G(SCH_1):PAGE169
PC477_C0P0_1    2      B Q_CAP_C0402-2.2UF,10V,10%,X6S,CH5222KEB01    I51 @T6G_MB_LIB.T6G(SCH_1):PAGE169
PC479_1    2      B Q_CAP_0402-0.1UF,25V,10%,X7R,CH4104K1B00    I52 @T6G_MB_LIB.T6G(SCH_1):PAGE169
PC481_1    2      B Q_CAP_C0402-1UF,25V,10%,X6S,CH5104KEB02    I53 @T6G_MB_LIB.T6G(SCH_1):PAGE169
PC483_1    2      B Q_CAP_C0805-22UF,16V,20%,X6S,CH6223MEA01    I57 @T6G_MB_LIB.T6G(SCH_1):PAGE169
PC485_1    2      B Q_CAP_C0805-22UF,16V,20%,X6S,CH6223MEA01    I58 @T6G_MB_LIB.T6G(SCH_1):PAGE169
PC487_1    2      B Q_CAP_C0805-22UF,16V,20%,X6S,CH6223MEA01    I59 @T6G_MB_LIB.T6G(SCH_1):PAGE169
PC501_2    2      B Q_CAP_C0805-22UF,4V,20%,X6S,CH622KMEA03    I70 @T6G_MB_LIB.T6G(SCH_1):PAGE169
 PC498    2      B Q_CAPP_SMLF-220UF,4V,20%,SPCAP,CH122KM8801    I73 @T6G_MB_LIB.T6G(SCH_1):PAGE169
 PC491    2      B Q_CAPP_THLF-270UF,16V,20%,OSCON,CC72703MD38    I79 @T6G_MB_LIB.T6G(SCH_1):PAGE169
 PC492    2      B Q_CAPP_THLF-270UF,16V,20%,OSCON,CC72703MD38    I81 @T6G_MB_LIB.T6G(SCH_1):PAGE169
 PC479    2      B Q_CAP_0402-0.1UF,25V,10%,X7R,CH4104K1B00    I85 @T6G_MB_LIB.T6G(SCH_1):PAGE169
 PC497    2      B Q_CAP_0402-0.1UF,25V,10%,X7R,CH4104K1B00    I87 @T6G_MB_LIB.T6G(SCH_1):PAGE169
PC500_1    2      B Q_CAP_C0805-22UF,4V,20%,X6S,CH622KMEA03    I88 @T6G_MB_LIB.T6G(SCH_1):PAGE169
PC502_1    2      B Q_CAP_C0805-22UF,4V,20%,X6S,CH622KMEA03    I89 @T6G_MB_LIB.T6G(SCH_1):PAGE169
 PR447    2      B Q_RES_0402LF-1K,1%,1/16W,CHIP,CS21002FB06    I90 @T6G_MB_LIB.T6G(SCH_1):PAGE169
PC545_4    2      B Q_CAP_0402-0.1UF,25V,10%,X7R,CH4104K1B00     I2 @T6G_MB_LIB.T6G(SCH_1):PAGE170
 PC547    2      B Q_CAP_C0402-2.2UF,10V,10%,X6S,CH5222KEB01     I6 @T6G_MB_LIB.T6G(SCH_1):PAGE170
  PU47    2   AGND ISL99390FRZTR5935-ISL99390FRZ-TR5935,SMLF,IC,AL099A     I9 @T6G_MB_LIB.T6G(SCH_1):PAGE170
  PU47    5  PGND1 ISL99390FRZTR5935-ISL99390FRZ-TR5935,SMLF,IC,AL099A     I9 @T6G_MB_LIB.T6G(SCH_1):PAGE170
  PU47 7_9-20_24  PGND2 ISL99390FRZTR5935-ISL99390FRZ-TR5935,SMLF,IC,AL099A     I9 @T6G_MB_LIB.T6G(SCH_1):PAGE170
  PU47   40  PGND3 ISL99390FRZTR5935-ISL99390FRZ-TR5935,SMLF,IC,AL099A     I9 @T6G_MB_LIB.T6G(SCH_1):PAGE170
 PR347    1      A Q_RES_0402LF-8.87K,1%,1/16W,EMPTY,CS28872FB01    I11 @T6G_MB_LIB.T6G(SCH_1):PAGE170
PC549_C0P0_4    2      B Q_CAP_C0402-2.2UF,10V,10%,X6S,CH5222KEB01    I15 @T6G_MB_LIB.T6G(SCH_1):PAGE170
PC553_4    2      B Q_CAP_C0402-1UF,25V,10%,X6S,CH5104KEB02    I22 @T6G_MB_LIB.T6G(SCH_1):PAGE170
PC557_4    2      B Q_CAP_C0805-22UF,16V,20%,X6S,CH6223MEA01    I24 @T6G_MB_LIB.T6G(SCH_1):PAGE170
PC544_3    2      B Q_CAP_0402-0.1UF,25V,10%,X7R,CH4104K1B00    I27 @T6G_MB_LIB.T6G(SCH_1):PAGE170
 PC546    2      B Q_CAP_C0402-2.2UF,10V,10%,X6S,CH5222KEB01    I36 @T6G_MB_LIB.T6G(SCH_1):PAGE170
  PU46    2   AGND ISL99390FRZTR5935-ISL99390FRZ-TR5935,SMLF,IC,AL099A    I38 @T6G_MB_LIB.T6G(SCH_1):PAGE170
  PU46    5  PGND1 ISL99390FRZTR5935-ISL99390FRZ-TR5935,SMLF,IC,AL099A    I38 @T6G_MB_LIB.T6G(SCH_1):PAGE170
  PU46 7_9-20_24  PGND2 ISL99390FRZTR5935-ISL99390FRZ-TR5935,SMLF,IC,AL099A    I38 @T6G_MB_LIB.T6G(SCH_1):PAGE170
  PU46   40  PGND3 ISL99390FRZTR5935-ISL99390FRZ-TR5935,SMLF,IC,AL099A    I38 @T6G_MB_LIB.T6G(SCH_1):PAGE170
PC548_C0P0_3    2      B Q_CAP_C0402-2.2UF,10V,10%,X6S,CH5222KEB01    I40 @T6G_MB_LIB.T6G(SCH_1):PAGE170
PC552_3    2      B Q_CAP_0402-0.1UF,25V,10%,X7R,CH4104K1B00    I43 @T6G_MB_LIB.T6G(SCH_1):PAGE170
 PR498    2      B Q_RES_0402LF-1.5,1%,1/8W,EMPTY,CS-1504FB00    I44 @T6G_MB_LIB.T6G(SCH_1):PAGE170
PC550_3    2      B Q_CAP_C0402-1UF,25V,10%,X6S,CH5104KEB02    I47 @T6G_MB_LIB.T6G(SCH_1):PAGE170
PC554_3    2      B Q_CAP_C0805-22UF,16V,20%,X6S,CH6223MEA01    I48 @T6G_MB_LIB.T6G(SCH_1):PAGE170
PC556_3    2      B Q_CAP_C0805-22UF,16V,20%,X6S,CH6223MEA01    I49 @T6G_MB_LIB.T6G(SCH_1):PAGE170
  PL60    3      3 Q_INDUCTOR4P_14-150NH,SMLF,IND,CV+15^0TZ04    I52 @T6G_MB_LIB.T6G(SCH_1):PAGE170
PC559_4    2      B Q_CAP_C0805-22UF,16V,20%,X6S,CH6223MEA01    I55 @T6G_MB_LIB.T6G(SCH_1):PAGE170
PC563_4    2      B Q_CAP_C0805-22UF,4V,20%,X6S,CH622KMEA03    I58 @T6G_MB_LIB.T6G(SCH_1):PAGE170
PC565_4    2      B Q_CAP_C0805-22UF,4V,20%,X6S,CH622KMEA03    I60 @T6G_MB_LIB.T6G(SCH_1):PAGE170
PC558_3    2      B Q_CAP_C0805-22UF,16V,20%,X6S,CH6223MEA01    I66 @T6G_MB_LIB.T6G(SCH_1):PAGE170
PC562_3    2      B Q_CAP_C0805-22UF,4V,20%,X6S,CH622KMEA03    I70 @T6G_MB_LIB.T6G(SCH_1):PAGE170
PC564_3    2      B Q_CAP_C0805-22UF,4V,20%,X6S,CH622KMEA03    I71 @T6G_MB_LIB.T6G(SCH_1):PAGE170
PC150_6    2      B Q_CAP_0402-0.1UF,25V,10%,X7R,CH4104K1B00     I4 @T6G_MB_LIB.T6G(SCH_1):PAGE171
 PR431    1      A Q_RES_0402LF-8.87K,1%,1/16W,EMPTY,CS28872FB01     I8 @T6G_MB_LIB.T6G(SCH_1):PAGE171
 PC151    2      B Q_CAP_C0402-2.2UF,10V,10%,X6S,CH5222KEB01    I11 @T6G_MB_LIB.T6G(SCH_1):PAGE171
PC152_C0P0_6    2      B Q_CAP_C0402-2.2UF,10V,10%,X6S,CH5222KEB01    I14 @T6G_MB_LIB.T6G(SCH_1):PAGE171
  PU48    2   AGND ISL99390FRZTR5935-ISL99390FRZ-TR5935,SMLF,IC,AL099A    I18 @T6G_MB_LIB.T6G(SCH_1):PAGE171
  PU48    5  PGND1 ISL99390FRZTR5935-ISL99390FRZ-TR5935,SMLF,IC,AL099A    I18 @T6G_MB_LIB.T6G(SCH_1):PAGE171
  PU48 7_9-20_24  PGND2 ISL99390FRZTR5935-ISL99390FRZ-TR5935,SMLF,IC,AL099A    I18 @T6G_MB_LIB.T6G(SCH_1):PAGE171
  PU48   40  PGND3 ISL99390FRZTR5935-ISL99390FRZ-TR5935,SMLF,IC,AL099A    I18 @T6G_MB_LIB.T6G(SCH_1):PAGE171
 PR500    2      B Q_RES_0402LF-1.5,1%,1/8W,EMPTY,CS-1504FB00    I22 @T6G_MB_LIB.T6G(SCH_1):PAGE171
PC153_6    2      B Q_CAP_0402-0.1UF,25V,10%,X7R,CH4104K1B00    I24 @T6G_MB_LIB.T6G(SCH_1):PAGE171
PC154_6    2      B Q_CAP_C0402-1UF,25V,10%,X6S,CH5104KEB02    I27 @T6G_MB_LIB.T6G(SCH_1):PAGE171
PC157_6    2      B Q_CAP_C0805-22UF,16V,20%,X6S,CH6223MEA01    I28 @T6G_MB_LIB.T6G(SCH_1):PAGE171
PC158_6    2      B Q_CAP_C0805-22UF,16V,20%,X6S,CH6223MEA01    I29 @T6G_MB_LIB.T6G(SCH_1):PAGE171
 PR501    2      B Q_RES_0402LF-1.5,1%,1/8W,EMPTY,CS-1504FB00    I31 @T6G_MB_LIB.T6G(SCH_1):PAGE171
PC566_5    2      B Q_CAP_0402-0.1UF,25V,10%,X7R,CH4104K1B00    I33 @T6G_MB_LIB.T6G(SCH_1):PAGE171
 PR353    1      A Q_RES_0402LF-8.87K,1%,1/16W,EMPTY,CS28872FB01    I36 @T6G_MB_LIB.T6G(SCH_1):PAGE171
 PC567    2      B Q_CAP_C0402-2.2UF,10V,10%,X6S,CH5222KEB01    I38 @T6G_MB_LIB.T6G(SCH_1):PAGE171
PC568_C0P0_5    2      B Q_CAP_C0402-2.2UF,10V,10%,X6S,CH5222KEB01    I42 @T6G_MB_LIB.T6G(SCH_1):PAGE171
PC570_5    2      B Q_CAP_0402-0.1UF,25V,10%,X7R,CH4104K1B00    I44 @T6G_MB_LIB.T6G(SCH_1):PAGE171
PC569_5    2      B Q_CAP_C0402-1UF,25V,10%,X6S,CH5104KEB02    I47 @T6G_MB_LIB.T6G(SCH_1):PAGE171
PC571_5    2      B Q_CAP_C0805-22UF,16V,20%,X6S,CH6223MEA01    I48 @T6G_MB_LIB.T6G(SCH_1):PAGE171
PC572_5    2      B Q_CAP_C0805-22UF,16V,20%,X6S,CH6223MEA01    I49 @T6G_MB_LIB.T6G(SCH_1):PAGE171
  PL50    1      1 Q_INDUCTOR_SMLF-120NH/69A,IND,CV+12^0EZ03    I51 @T6G_MB_LIB.T6G(SCH_1):PAGE171
PC159_6    2      B Q_CAP_C0805-22UF,16V,20%,X6S,CH6223MEA01    I55 @T6G_MB_LIB.T6G(SCH_1):PAGE171
PC163_6    2      B Q_CAP_C0805-22UF,4V,20%,X6S,CH622KMEA03    I59 @T6G_MB_LIB.T6G(SCH_1):PAGE171
PC166_6    2      B Q_CAP_C0805-22UF,4V,20%,X6S,CH622KMEA03    I60 @T6G_MB_LIB.T6G(SCH_1):PAGE171
PC573_5    2      B Q_CAP_C0805-22UF,16V,20%,X6S,CH6223MEA01    I66 @T6G_MB_LIB.T6G(SCH_1):PAGE171
PC575_5    2      B Q_CAP_C0805-22UF,4V,20%,X6S,CH622KMEA03    I69 @T6G_MB_LIB.T6G(SCH_1):PAGE171
PC576_5    2      B Q_CAP_C0805-22UF,4V,20%,X6S,CH622KMEA03    I71 @T6G_MB_LIB.T6G(SCH_1):PAGE171
  PU10    2   AGND ISL99390FRZTR5935-ISL99390FRZ-TR5935,SMLF,IC,AL099A    I73 @T6G_MB_LIB.T6G(SCH_1):PAGE171
  PU10    5  PGND1 ISL99390FRZTR5935-ISL99390FRZ-TR5935,SMLF,IC,AL099A    I73 @T6G_MB_LIB.T6G(SCH_1):PAGE171
  PU10 7_9-20_24  PGND2 ISL99390FRZTR5935-ISL99390FRZ-TR5935,SMLF,IC,AL099A    I73 @T6G_MB_LIB.T6G(SCH_1):PAGE171
  PU10   40  PGND3 ISL99390FRZTR5935-ISL99390FRZ-TR5935,SMLF,IC,AL099A    I73 @T6G_MB_LIB.T6G(SCH_1):PAGE171
 PR359    1      A Q_RES_0402LF-8.87K,1%,1/16W,EMPTY,CS28872FB01     I8 @T6G_MB_LIB.T6G(SCH_1):PAGE173
 PC580    2      B Q_CAP_C0402-2.2UF,10V,10%,X6S,CH5222KEB01    I11 @T6G_MB_LIB.T6G(SCH_1):PAGE173
PC582_SOP0_2    2      B Q_CAP_C0402-2.2UF,10V,10%,X6S,CH5222KEB01    I14 @T6G_MB_LIB.T6G(SCH_1):PAGE173
PC586_2    2      B Q_CAP_0402-0.1UF,25V,10%,X7R,CH4104K1B00    I21 @T6G_MB_LIB.T6G(SCH_1):PAGE173
 PR358    1      A Q_RES_0402LF-8.87K,1%,1/16W,EMPTY,CS28872FB01    I32 @T6G_MB_LIB.T6G(SCH_1):PAGE173
 PC579    2      B Q_CAP_C0402-2.2UF,10V,10%,X6S,CH5222KEB01    I36 @T6G_MB_LIB.T6G(SCH_1):PAGE173
PC581_SOP0_1    2      B Q_CAP_C0402-2.2UF,10V,10%,X6S,CH5222KEB01    I40 @T6G_MB_LIB.T6G(SCH_1):PAGE173
  PU49    2   AGND ISL99390FRZTR5935-ISL99390FRZ-TR5935,SMLF,IC,AL099A    I41 @T6G_MB_LIB.T6G(SCH_1):PAGE173
  PU49    5  PGND1 ISL99390FRZTR5935-ISL99390FRZ-TR5935,SMLF,IC,AL099A    I41 @T6G_MB_LIB.T6G(SCH_1):PAGE173
  PU49 7_9-20_24  PGND2 ISL99390FRZTR5935-ISL99390FRZ-TR5935,SMLF,IC,AL099A    I41 @T6G_MB_LIB.T6G(SCH_1):PAGE173
  PU49   40  PGND3 ISL99390FRZTR5935-ISL99390FRZ-TR5935,SMLF,IC,AL099A    I41 @T6G_MB_LIB.T6G(SCH_1):PAGE173
PC585_1    2      B Q_CAP_C0402-1UF,25V,10%,X6S,CH5104KEB02    I44 @T6G_MB_LIB.T6G(SCH_1):PAGE173
 PR502    2      B Q_RES_0402LF-1.5,1%,1/8W,EMPTY,CS-1504FB00    I45 @T6G_MB_LIB.T6G(SCH_1):PAGE173
PC587_1    2      B Q_CAP_C0805-22UF,16V,20%,X6S,CH6223MEA01    I49 @T6G_MB_LIB.T6G(SCH_1):PAGE173
PC589_1    2      B Q_CAP_C0805-22UF,16V,20%,X6S,CH6223MEA01    I50 @T6G_MB_LIB.T6G(SCH_1):PAGE173
PC591_1    2      B Q_CAP_C0805-22UF,16V,20%,X6S,CH6223MEA01    I51 @T6G_MB_LIB.T6G(SCH_1):PAGE173
PC592_2    2      B Q_CAP_C0805-22UF,16V,20%,X6S,CH6223MEA01    I56 @T6G_MB_LIB.T6G(SCH_1):PAGE173
PC595_2    2      B Q_CAP_C0805-22UF,16V,20%,X6S,CH6223MEA01    I57 @T6G_MB_LIB.T6G(SCH_1):PAGE173
PC600_2    2      B Q_CAP_C0805-22UF,4V,20%,X6S,CH622KMEA03    I59 @T6G_MB_LIB.T6G(SCH_1):PAGE173
PC603_2    2      B Q_CAP_C0805-22UF,4V,20%,X6S,CH622KMEA03    I61 @T6G_MB_LIB.T6G(SCH_1):PAGE173
 PC598    2      B Q_CAPP_SMLF-470UF,2.5V,20%,SPCAP,CH747LM8825    I64 @T6G_MB_LIB.T6G(SCH_1):PAGE173
PC593_1    2      B Q_CAP_C0805-22UF,16V,20%,X6S,CH6223MEA01    I72 @T6G_MB_LIB.T6G(SCH_1):PAGE173
 PC596    2      B Q_CAPP_THLF-270UF,16V,20%,OSCON,CC72703MD38    I73 @T6G_MB_LIB.T6G(SCH_1):PAGE173
 PC583    2      B Q_CAP_0402-0.1UF,25V,10%,X7R,CH4104K1B00    I77 @T6G_MB_LIB.T6G(SCH_1):PAGE173
PC602_1    2      B Q_CAP_C0805-22UF,4V,20%,X6S,CH622KMEA03    I80 @T6G_MB_LIB.T6G(SCH_1):PAGE173
 PR334    2      B Q_RES_0402LF-1K,1%,1/16W,CHIP,CS21002FB06    I82 @T6G_MB_LIB.T6G(SCH_1):PAGE173
  PU50    2   AGND ISL99390FRZTR5935-ISL99390FRZ-TR5935,SMLF,IC,AL099A    I86 @T6G_MB_LIB.T6G(SCH_1):PAGE173
  PU50    5  PGND1 ISL99390FRZTR5935-ISL99390FRZ-TR5935,SMLF,IC,AL099A    I86 @T6G_MB_LIB.T6G(SCH_1):PAGE173
  PU50 7_9-20_24  PGND2 ISL99390FRZTR5935-ISL99390FRZ-TR5935,SMLF,IC,AL099A    I86 @T6G_MB_LIB.T6G(SCH_1):PAGE173
  PU50   40  PGND3 ISL99390FRZTR5935-ISL99390FRZ-TR5935,SMLF,IC,AL099A    I86 @T6G_MB_LIB.T6G(SCH_1):PAGE173
PC605_9    2      B Q_CAP_0402-0.1UF,25V,10%,X7R,CH4104K1B00     I2 @T6G_MB_LIB.T6G(SCH_1):PAGE174
 PR505    2      B Q_RES_0402LF-1.5,1%,1/8W,EMPTY,CS-1504FB00    I10 @T6G_MB_LIB.T6G(SCH_1):PAGE174
 PC606    2      B Q_CAP_C0402-2.2UF,10V,10%,X6S,CH5222KEB01    I14 @T6G_MB_LIB.T6G(SCH_1):PAGE174
PC607_SOP0_3    2      B Q_CAP_C0402-2.2UF,10V,10%,X6S,CH5222KEB01    I19 @T6G_MB_LIB.T6G(SCH_1):PAGE174
  PL62    1      1 Q_INDUCTOR_SMLF-0.22UH/33A,IND,CV+22Y0EZ00    I24 @T6G_MB_LIB.T6G(SCH_1):PAGE174
PC614_3    2      B Q_CAP_C0805-22UF,4V,20%,X6S,CH622KMEA03    I27 @T6G_MB_LIB.T6G(SCH_1):PAGE174
PC612_3    2      B Q_CAP_C0805-22UF,16V,20%,X6S,CH6223MEA01    I34 @T6G_MB_LIB.T6G(SCH_1):PAGE174
 C8066    2      B Q_CAP_0402-1000PF,50V,5%,X7R,TMP_QCH21006JB10     I3 @T6G_MB_LIB.T6G(SCH_1):PAGE175
  PQ14    S SOURCE MOSFET_N_SMLF-BSS138K,BSS138K,IC,BAM138K0000     I6 @T6G_MB_LIB.T6G(SCH_1):PAGE175
  PR54    2      B Q_RES_0402LF-10K,1%,1/16W,CHIP,CS31002FB08     I8 @T6G_MB_LIB.T6G(SCH_1):PAGE175
  PR67    2      B Q_RES_0402LF-1.96K,1%,1/16W,CHIP,CS21962FB05    I12 @T6G_MB_LIB.T6G(SCH_1):PAGE175
  PR50    2      B Q_RES_0402LF-49.9,1%,1/16W,CHIP,CS04992FB07    I19 @T6G_MB_LIB.T6G(SCH_1):PAGE175
  PR49    2      B Q_RES_0402LF-49.9,1%,1/16W,CHIP,CS04992FB07    I23 @T6G_MB_LIB.T6G(SCH_1):PAGE175
  PR40    2      B Q_RES_0402LF-0,5%,1/16W,CHIP,CS00002JB13    I28 @T6G_MB_LIB.T6G(SCH_1):PAGE175
 R8042    2      B Q_RES_0402LF-1K,1%,1/16W,EMPTY,CS21002FB06    I32 @T6G_MB_LIB.T6G(SCH_1):PAGE175
  C303    2      B Q_CAP_0402-10PF,50V,5%,EMPTY,CH01006JB08    I33 @T6G_MB_LIB.T6G(SCH_1):PAGE175
  C304    2      B Q_CAP_0402-10PF,50V,5%,EMPTY,CH01006JB08    I34 @T6G_MB_LIB.T6G(SCH_1):PAGE175
  C305    2      B Q_CAP_0402-10PF,50V,5%,EMPTY,CH01006JB08    I35 @T6G_MB_LIB.T6G(SCH_1):PAGE175
  PC67    2      B Q_CAP_0402-0.1UF,25V,10%,X7R,CH4104K1B00    I50 @T6G_MB_LIB.T6G(SCH_1):PAGE175
 C8072    2      B Q_CAP_0402-1000PF,50V,5%,EMPTY,TMP_QCH21006JB10    I55 @T6G_MB_LIB.T6G(SCH_1):PAGE175
 PR600    2      B Q_RES_0402LF-4.99K,1%,1/16W,EMPTY,CS24992FB07    I59 @T6G_MB_LIB.T6G(SCH_1):PAGE175
  PC74    2      B Q_CAP_0402-0.1UF,25V,10%,X7R,CH4104K1B00    I60 @T6G_MB_LIB.T6G(SCH_1):PAGE175
  PC73    2      B Q_CAP_0402-1UF,6.3V,10%,X7R,CH5101K1B01    I63 @T6G_MB_LIB.T6G(SCH_1):PAGE175
  PC78    2      B Q_CAP_0402-470PF,50V,10%,X7R,TMP_QCH14706KB18    I73 @T6G_MB_LIB.T6G(SCH_1):PAGE175
  PC77    2      B Q_CAP_0402-470PF,50V,10%,X7R,TMP_QCH14706KB18    I75 @T6G_MB_LIB.T6G(SCH_1):PAGE175
 PR532    2      B Q_RES_0402LF-0,5%,1/16W,CHIP,CS00002JB13    I76 @T6G_MB_LIB.T6G(SCH_1):PAGE175
  PR32    2      B Q_RES_0402LF-0,5%,1/16W,CHIP,CS00002JB13    I77 @T6G_MB_LIB.T6G(SCH_1):PAGE175
 C8069    2      B Q_CAP_0402-1000PF,50V,5%,X7R,TMP_QCH21006JB10    I86 @T6G_MB_LIB.T6G(SCH_1):PAGE175
 C8070    2      B Q_CAP_0402-1000PF,50V,5%,EMPTY,TMP_QCH21006JB10    I91 @T6G_MB_LIB.T6G(SCH_1):PAGE175
  PC15    2      B Q_CAP_0402-0.1UF,25V,10%,X7R,CH4104K1B00    I94 @T6G_MB_LIB.T6G(SCH_1):PAGE175
  PC14    2      B Q_CAP_0402-0.1UF,25V,10%,X7R,CH4104K1B00    I96 @T6G_MB_LIB.T6G(SCH_1):PAGE175
  PC76    2      B Q_CAP_C0402-10UF,6.3V,20%,X6S,CH6101MEB03    I98 @T6G_MB_LIB.T6G(SCH_1):PAGE175
  PC75    2      B Q_CAP_C0402-1UF,16V,10%,X6S,CH5103KEB01   I100 @T6G_MB_LIB.T6G(SCH_1):PAGE175
  PU12   TH TH_GND RAA229620GNPHA0-RAA229620GNP#HA0,SMLF,IC,ARF0TGP40A   I128 @T6G_MB_LIB.T6G(SCH_1):PAGE175
  PR77    2      B Q_RES_0402LF-8.87K,1%,1/16W,EMPTY,CS28872FB01     I4 @T6G_MB_LIB.T6G(SCH_1):PAGE176
  PC80    2      B Q_CAP_C0402-2.2UF,10V,10%,X6S,CH5222KEB01    I10 @T6G_MB_LIB.T6G(SCH_1):PAGE176
PC84_1    2      B Q_CAP_0402-0.1UF,25V,10%,X7R,CH4104K1B00    I12 @T6G_MB_LIB.T6G(SCH_1):PAGE176
PC82_C1P0_2    2      B Q_CAP_C0402-2.2UF,10V,10%,X6S,CH5222KEB01    I15 @T6G_MB_LIB.T6G(SCH_1):PAGE176
  PR78    2      B Q_RES_0402LF-8.87K,1%,1/16W,EMPTY,CS28872FB01    I18 @T6G_MB_LIB.T6G(SCH_1):PAGE176
PC81_C1P0_1    2      B Q_CAP_C0402-2.2UF,10V,10%,X6S,CH5222KEB01    I30 @T6G_MB_LIB.T6G(SCH_1):PAGE176
   PU2    2   AGND ISL99390FRZTR5935-ISL99390FRZ-TR5935,SMLF,IC,AL099A    I33 @T6G_MB_LIB.T6G(SCH_1):PAGE176
   PU2    5  PGND1 ISL99390FRZTR5935-ISL99390FRZ-TR5935,SMLF,IC,AL099A    I33 @T6G_MB_LIB.T6G(SCH_1):PAGE176
   PU2 7_9-20_24  PGND2 ISL99390FRZTR5935-ISL99390FRZ-TR5935,SMLF,IC,AL099A    I33 @T6G_MB_LIB.T6G(SCH_1):PAGE176
   PU2   40  PGND3 ISL99390FRZTR5935-ISL99390FRZ-TR5935,SMLF,IC,AL099A    I33 @T6G_MB_LIB.T6G(SCH_1):PAGE176
  PU13    2   AGND ISL99390FRZTR5935-ISL99390FRZ-TR5935,SMLF,IC,AL099A    I35 @T6G_MB_LIB.T6G(SCH_1):PAGE176
  PU13    5  PGND1 ISL99390FRZTR5935-ISL99390FRZ-TR5935,SMLF,IC,AL099A    I35 @T6G_MB_LIB.T6G(SCH_1):PAGE176
  PU13 7_9-20_24  PGND2 ISL99390FRZTR5935-ISL99390FRZ-TR5935,SMLF,IC,AL099A    I35 @T6G_MB_LIB.T6G(SCH_1):PAGE176
  PU13   40  PGND3 ISL99390FRZTR5935-ISL99390FRZ-TR5935,SMLF,IC,AL099A    I35 @T6G_MB_LIB.T6G(SCH_1):PAGE176
PC86_2    2      B Q_CAP_0402-0.1UF,25V,10%,X7R,CH4104K1B00    I37 @T6G_MB_LIB.T6G(SCH_1):PAGE176
 PR507    2      B Q_RES_0402LF-1.5,1%,1/8W,EMPTY,CS-1504FB00    I39 @T6G_MB_LIB.T6G(SCH_1):PAGE176
PC90_2    2      B Q_CAP_C0805-22UF,16V,20%,X6S,CH6223MEA01    I48 @T6G_MB_LIB.T6G(SCH_1):PAGE176
 PR506    2      B Q_RES_0402LF-1.5,1%,1/8W,EMPTY,CS-1504FB00    I50 @T6G_MB_LIB.T6G(SCH_1):PAGE176
PC93_2    2      B Q_CAP_C0805-22UF,16V,20%,X6S,CH6223MEA01    I51 @T6G_MB_LIB.T6G(SCH_1):PAGE176
PC96_2    2      B Q_CAP_C0805-22UF,16V,20%,X6S,CH6223MEA01    I52 @T6G_MB_LIB.T6G(SCH_1):PAGE176
PC85_1    2      B Q_CAP_0402-0.1UF,25V,10%,X7R,CH4104K1B00    I55 @T6G_MB_LIB.T6G(SCH_1):PAGE176
PC87_1    2      B Q_CAP_C0402-1UF,25V,10%,X6S,CH5104KEB02    I59 @T6G_MB_LIB.T6G(SCH_1):PAGE176
PC89_1    2      B Q_CAP_C0805-22UF,16V,20%,X6S,CH6223MEA01    I60 @T6G_MB_LIB.T6G(SCH_1):PAGE176
PC91_1    2      B Q_CAP_C0805-22UF,16V,20%,X6S,CH6223MEA01    I64 @T6G_MB_LIB.T6G(SCH_1):PAGE176
PC106_2    2      B Q_CAP_C0805-22UF,4V,20%,X6S,CH622KMEA03    I69 @T6G_MB_LIB.T6G(SCH_1):PAGE176
 PC102    2      B Q_CAPP_SMLF-220UF,4V,20%,SPCAP,CH122KM8801    I70 @T6G_MB_LIB.T6G(SCH_1):PAGE176
  PC97    2      B Q_CAPP_SMLF-220UF,4V,20%,SPCAP,CH122KM8801    I71 @T6G_MB_LIB.T6G(SCH_1):PAGE176
  PC98    2      B Q_CAPP_SMLF-220UF,4V,20%,SPCAP,CH122KM8801    I72 @T6G_MB_LIB.T6G(SCH_1):PAGE176
 PC100    2      B Q_CAPP_SMLF-220UF,4V,20%,SPCAP,CH122KM8801    I73 @T6G_MB_LIB.T6G(SCH_1):PAGE176
PC108_2    2      B Q_CAP_C0805-22UF,4V,20%,X6S,CH622KMEA03    I77 @T6G_MB_LIB.T6G(SCH_1):PAGE176
 PC104    2      B Q_CAPP_THLF-270UF,16V,20%,OSCON,CC72703MD38    I82 @T6G_MB_LIB.T6G(SCH_1):PAGE176
  PC99    2      B Q_CAP_0402-0.1UF,25V,10%,X7R,CH4104K1B00    I84 @T6G_MB_LIB.T6G(SCH_1):PAGE176
PC102_1    2      B Q_CAP_C0805-22UF,4V,20%,X6S,CH622KMEA03    I86 @T6G_MB_LIB.T6G(SCH_1):PAGE176
PC105_1    2      B Q_CAP_C0805-22UF,4V,20%,X6S,CH622KMEA03    I89 @T6G_MB_LIB.T6G(SCH_1):PAGE176
 PR444    2      B Q_RES_0402LF-1K,1%,1/16W,CHIP,CS21002FB06    I90 @T6G_MB_LIB.T6G(SCH_1):PAGE176
  PR85    2      B Q_RES_0402LF-8.87K,1%,1/16W,EMPTY,CS28872FB01     I4 @T6G_MB_LIB.T6G(SCH_1):PAGE177
 PC109    2      B Q_CAP_C0402-2.2UF,10V,10%,X6S,CH5222KEB01     I7 @T6G_MB_LIB.T6G(SCH_1):PAGE177
PC114_3    2      B Q_CAP_0402-0.1UF,25V,10%,X7R,CH4104K1B00    I12 @T6G_MB_LIB.T6G(SCH_1):PAGE177
PC111_C1P0_4    2      B Q_CAP_C0402-2.2UF,10V,10%,X6S,CH5222KEB01    I16 @T6G_MB_LIB.T6G(SCH_1):PAGE177
  PR86    2      B Q_RES_0402LF-8.87K,1%,1/16W,EMPTY,CS28872FB01    I18 @T6G_MB_LIB.T6G(SCH_1):PAGE177
  PU14    2   AGND ISL99390FRZTR5935-ISL99390FRZ-TR5935,SMLF,IC,AL099A    I21 @T6G_MB_LIB.T6G(SCH_1):PAGE177
  PU14    5  PGND1 ISL99390FRZTR5935-ISL99390FRZ-TR5935,SMLF,IC,AL099A    I21 @T6G_MB_LIB.T6G(SCH_1):PAGE177
  PU14 7_9-20_24  PGND2 ISL99390FRZTR5935-ISL99390FRZ-TR5935,SMLF,IC,AL099A    I21 @T6G_MB_LIB.T6G(SCH_1):PAGE177
  PU14   40  PGND3 ISL99390FRZTR5935-ISL99390FRZ-TR5935,SMLF,IC,AL099A    I21 @T6G_MB_LIB.T6G(SCH_1):PAGE177
  PU15    2   AGND ISL99390FRZTR5935-ISL99390FRZ-TR5935,SMLF,IC,AL099A    I23 @T6G_MB_LIB.T6G(SCH_1):PAGE177
  PU15    5  PGND1 ISL99390FRZTR5935-ISL99390FRZ-TR5935,SMLF,IC,AL099A    I23 @T6G_MB_LIB.T6G(SCH_1):PAGE177
  PU15 7_9-20_24  PGND2 ISL99390FRZTR5935-ISL99390FRZ-TR5935,SMLF,IC,AL099A    I23 @T6G_MB_LIB.T6G(SCH_1):PAGE177
  PU15   40  PGND3 ISL99390FRZTR5935-ISL99390FRZ-TR5935,SMLF,IC,AL099A    I23 @T6G_MB_LIB.T6G(SCH_1):PAGE177
PC115_4    2      B Q_CAP_0402-0.1UF,25V,10%,X7R,CH4104K1B00    I24 @T6G_MB_LIB.T6G(SCH_1):PAGE177
 PC110    2      B Q_CAP_C0402-2.2UF,10V,10%,X6S,CH5222KEB01    I28 @T6G_MB_LIB.T6G(SCH_1):PAGE177
PC112_C1P0_3    2      B Q_CAP_C0402-2.2UF,10V,10%,X6S,CH5222KEB01    I32 @T6G_MB_LIB.T6G(SCH_1):PAGE177
PC116_3    2      B Q_CAP_0402-0.1UF,25V,10%,X7R,CH4104K1B00    I34 @T6G_MB_LIB.T6G(SCH_1):PAGE177
 PR509    2      B Q_RES_0402LF-1.5,1%,1/8W,EMPTY,CS-1504FB00    I36 @T6G_MB_LIB.T6G(SCH_1):PAGE177
PC117_4    2      B Q_CAP_C0402-1UF,25V,10%,X6S,CH5104KEB02    I43 @T6G_MB_LIB.T6G(SCH_1):PAGE177
PC119_4    2      B Q_CAP_C0805-22UF,16V,20%,X6S,CH6223MEA01    I44 @T6G_MB_LIB.T6G(SCH_1):PAGE177
 PR510    2      B Q_RES_0402LF-1.5,1%,1/8W,EMPTY,CS-1504FB00    I46 @T6G_MB_LIB.T6G(SCH_1):PAGE177
PC123_4    2      B Q_CAP_C0805-22UF,16V,20%,X6S,CH6223MEA01    I47 @T6G_MB_LIB.T6G(SCH_1):PAGE177
PC125_4    2      B Q_CAP_C0805-22UF,16V,20%,X6S,CH6223MEA01    I49 @T6G_MB_LIB.T6G(SCH_1):PAGE177
PC127_4    2      B Q_CAP_C0805-22UF,4V,20%,X6S,CH622KMEA03    I54 @T6G_MB_LIB.T6G(SCH_1):PAGE177
PC118_3    2      B Q_CAP_C0402-1UF,25V,10%,X6S,CH5104KEB02    I60 @T6G_MB_LIB.T6G(SCH_1):PAGE177
PC120_3    2      B Q_CAP_C0805-22UF,16V,20%,X6S,CH6223MEA01    I61 @T6G_MB_LIB.T6G(SCH_1):PAGE177
PC124_3    2      B Q_CAP_C0805-22UF,16V,20%,X6S,CH6223MEA01    I65 @T6G_MB_LIB.T6G(SCH_1):PAGE177
PC126_3    2      B Q_CAP_C0805-22UF,16V,20%,X6S,CH6223MEA01    I66 @T6G_MB_LIB.T6G(SCH_1):PAGE177
PC129_3    2      B Q_CAP_C0805-22UF,4V,20%,X6S,CH622KMEA03    I69 @T6G_MB_LIB.T6G(SCH_1):PAGE177
PC130_3    2      B Q_CAP_C0805-22UF,4V,20%,X6S,CH622KMEA03    I71 @T6G_MB_LIB.T6G(SCH_1):PAGE177
PC111_6    2      B Q_CAP_0402-0.1UF,25V,10%,X7R,CH4104K1B00     I2 @T6G_MB_LIB.T6G(SCH_1):PAGE178
   PR7    2      B Q_RES_0402LF-8.87K,1%,1/16W,EMPTY,CS28872FB01     I4 @T6G_MB_LIB.T6G(SCH_1):PAGE178
PC132_5    2      B Q_CAP_0402-0.1UF,25V,10%,X7R,CH4104K1B00    I10 @T6G_MB_LIB.T6G(SCH_1):PAGE178
 PC112    2      B Q_CAP_C0402-2.2UF,10V,10%,X6S,CH5222KEB01    I11 @T6G_MB_LIB.T6G(SCH_1):PAGE178
  PR93    2      B Q_RES_0402LF-8.87K,1%,1/16W,EMPTY,CS28872FB01    I15 @T6G_MB_LIB.T6G(SCH_1):PAGE178
PC113_C1P0_6    2      B Q_CAP_C0402-2.2UF,10V,10%,X6S,CH5222KEB01    I20 @T6G_MB_LIB.T6G(SCH_1):PAGE178
  PU16    2   AGND ISL99390FRZTR5935-ISL99390FRZ-TR5935,SMLF,IC,AL099A    I22 @T6G_MB_LIB.T6G(SCH_1):PAGE178
  PU16    5  PGND1 ISL99390FRZTR5935-ISL99390FRZ-TR5935,SMLF,IC,AL099A    I22 @T6G_MB_LIB.T6G(SCH_1):PAGE178
  PU16 7_9-20_24  PGND2 ISL99390FRZTR5935-ISL99390FRZ-TR5935,SMLF,IC,AL099A    I22 @T6G_MB_LIB.T6G(SCH_1):PAGE178
  PU16   40  PGND3 ISL99390FRZTR5935-ISL99390FRZ-TR5935,SMLF,IC,AL099A    I22 @T6G_MB_LIB.T6G(SCH_1):PAGE178
 PC131    2      B Q_CAP_C0402-2.2UF,10V,10%,X6S,CH5222KEB01    I27 @T6G_MB_LIB.T6G(SCH_1):PAGE178
 PR155    2      B Q_RES_0402LF-1.5,1%,1/8W,EMPTY,CS-1504FB00    I33 @T6G_MB_LIB.T6G(SCH_1):PAGE178
   PL9    2      2 Q_INDUCTOR_SMLF-120NH/69A,IND,CV+12^0EZ03    I36 @T6G_MB_LIB.T6G(SCH_1):PAGE178
PC115_6    2      B Q_CAP_C0402-1UF,25V,10%,X6S,CH5104KEB02    I41 @T6G_MB_LIB.T6G(SCH_1):PAGE178
PC116_6    2      B Q_CAP_C0805-22UF,16V,20%,X6S,CH6223MEA01    I42 @T6G_MB_LIB.T6G(SCH_1):PAGE178
 PR158    2      B Q_RES_0402LF-1.5,1%,1/8W,EMPTY,CS-1504FB00    I44 @T6G_MB_LIB.T6G(SCH_1):PAGE178
PC118_6    2      B Q_CAP_C0805-22UF,16V,20%,X6S,CH6223MEA01    I45 @T6G_MB_LIB.T6G(SCH_1):PAGE178
PC119_6    2      B Q_CAP_C0805-22UF,16V,20%,X6S,CH6223MEA01    I47 @T6G_MB_LIB.T6G(SCH_1):PAGE178
PC120_6    2      B Q_CAP_C0805-22UF,4V,20%,X6S,CH622KMEA03    I51 @T6G_MB_LIB.T6G(SCH_1):PAGE178
PC123_6    2      B Q_CAP_C0805-22UF,4V,20%,X6S,CH622KMEA03    I53 @T6G_MB_LIB.T6G(SCH_1):PAGE178
PC134_5    2      B Q_CAP_0402-0.1UF,25V,10%,X7R,CH4104K1B00    I58 @T6G_MB_LIB.T6G(SCH_1):PAGE178
PC138_5    2      B Q_CAP_C0805-22UF,16V,20%,X6S,CH6223MEA01    I65 @T6G_MB_LIB.T6G(SCH_1):PAGE178
PC139_5    2      B Q_CAP_C0805-22UF,16V,20%,X6S,CH6223MEA01    I66 @T6G_MB_LIB.T6G(SCH_1):PAGE178
PC140_5    2      B Q_CAP_C0805-22UF,4V,20%,X6S,CH622KMEA03    I69 @T6G_MB_LIB.T6G(SCH_1):PAGE178
PC141_5    2      B Q_CAP_C0805-22UF,4V,20%,X6S,CH622KMEA03    I70 @T6G_MB_LIB.T6G(SCH_1):PAGE178
  PU11    2   AGND ISL99390FRZTR5935-ISL99390FRZ-TR5935,SMLF,IC,AL099A    I73 @T6G_MB_LIB.T6G(SCH_1):PAGE178
  PU11    5  PGND1 ISL99390FRZTR5935-ISL99390FRZ-TR5935,SMLF,IC,AL099A    I73 @T6G_MB_LIB.T6G(SCH_1):PAGE178
  PU11 7_9-20_24  PGND2 ISL99390FRZTR5935-ISL99390FRZ-TR5935,SMLF,IC,AL099A    I73 @T6G_MB_LIB.T6G(SCH_1):PAGE178
  PU11   40  PGND3 ISL99390FRZTR5935-ISL99390FRZ-TR5935,SMLF,IC,AL099A    I73 @T6G_MB_LIB.T6G(SCH_1):PAGE178
PC146_8    2      B Q_CAP_0402-0.1UF,25V,10%,X7R,CH4104K1B00     I2 @T6G_MB_LIB.T6G(SCH_1):PAGE180
  PR97    2      B Q_RES_0402LF-8.87K,1%,1/16W,EMPTY,CS28872FB01     I4 @T6G_MB_LIB.T6G(SCH_1):PAGE180
 PC142    2      B Q_CAP_C0402-2.2UF,10V,10%,X6S,CH5222KEB01    I10 @T6G_MB_LIB.T6G(SCH_1):PAGE180
PC144_IOP0_2    2      B Q_CAP_C0402-2.2UF,10V,10%,X6S,CH5222KEB01    I13 @T6G_MB_LIB.T6G(SCH_1):PAGE180
  PU18    2   AGND ISL99390FRZTR5935-ISL99390FRZ-TR5935,SMLF,IC,AL099A    I15 @T6G_MB_LIB.T6G(SCH_1):PAGE180
  PU18    5  PGND1 ISL99390FRZTR5935-ISL99390FRZ-TR5935,SMLF,IC,AL099A    I15 @T6G_MB_LIB.T6G(SCH_1):PAGE180
  PU18 7_9-20_24  PGND2 ISL99390FRZTR5935-ISL99390FRZ-TR5935,SMLF,IC,AL099A    I15 @T6G_MB_LIB.T6G(SCH_1):PAGE180
  PU18   40  PGND3 ISL99390FRZTR5935-ISL99390FRZ-TR5935,SMLF,IC,AL099A    I15 @T6G_MB_LIB.T6G(SCH_1):PAGE180
PC149_2    2      B Q_CAP_0402-0.1UF,25V,10%,X7R,CH4104K1B00    I18 @T6G_MB_LIB.T6G(SCH_1):PAGE180
PC145_7    2      B Q_CAP_0402-0.1UF,25V,10%,X7R,CH4104K1B00    I20 @T6G_MB_LIB.T6G(SCH_1):PAGE180
  PR98    2      B Q_RES_0402LF-8.87K,1%,1/16W,EMPTY,CS28872FB01    I22 @T6G_MB_LIB.T6G(SCH_1):PAGE180
 PC143    2      B Q_CAP_C0402-2.2UF,10V,10%,X6S,CH5222KEB01    I28 @T6G_MB_LIB.T6G(SCH_1):PAGE180
PC147_IOP0_1    2      B Q_CAP_C0402-2.2UF,10V,10%,X6S,CH5222KEB01    I31 @T6G_MB_LIB.T6G(SCH_1):PAGE180
 PR223    2      B Q_RES_0402LF-1.5,1%,1/8W,EMPTY,CS-1504FB00    I36 @T6G_MB_LIB.T6G(SCH_1):PAGE180
PC151_2    2      B Q_CAP_C0402-1UF,25V,10%,X6S,CH5104KEB02    I42 @T6G_MB_LIB.T6G(SCH_1):PAGE180
PC153_2    2      B Q_CAP_C0805-22UF,16V,20%,X6S,CH6223MEA01    I43 @T6G_MB_LIB.T6G(SCH_1):PAGE180
PC157_2    2      B Q_CAP_C0805-22UF,16V,20%,X6S,CH6223MEA01    I45 @T6G_MB_LIB.T6G(SCH_1):PAGE180
PC159_2    2      B Q_CAP_C0805-22UF,16V,20%,X6S,CH6223MEA01    I47 @T6G_MB_LIB.T6G(SCH_1):PAGE180
PC168_2    2      B Q_CAP_C0805-22UF,4V,20%,X6S,CH622KMEA03    I51 @T6G_MB_LIB.T6G(SCH_1):PAGE180
PC170_2    2      B Q_CAP_C0805-22UF,4V,20%,X6S,CH622KMEA03    I53 @T6G_MB_LIB.T6G(SCH_1):PAGE180
 PC160    2      B Q_CAPP_SMLF-470UF,2.5V,20%,EMPTY,CH747LM8825    I54 @T6G_MB_LIB.T6G(SCH_1):PAGE180
 PC162    2      B Q_CAPP_SMLF-470UF,2.5V,20%,SPCAP,CH747LM8825    I57 @T6G_MB_LIB.T6G(SCH_1):PAGE180
 PC165    2      B Q_CAPP_SMLF-470UF,2.5V,20%,SPCAP,CH747LM8825    I58 @T6G_MB_LIB.T6G(SCH_1):PAGE180
 PR221    2      B Q_RES_0402LF-1.5,1%,1/8W,EMPTY,CS-1504FB00    I60 @T6G_MB_LIB.T6G(SCH_1):PAGE180
  PL17    3      3 Q_INDUCTOR4P_14-150NH,SMLF,IND,CV+15^0TZ04    I64 @T6G_MB_LIB.T6G(SCH_1):PAGE180
PC158_1    2      B Q_CAP_C0805-22UF,16V,20%,X6S,CH6223MEA01    I66 @T6G_MB_LIB.T6G(SCH_1):PAGE180
 PC164    2      B Q_CAPP_THLF-270UF,16V,20%,OSCON,CC72703MD38    I67 @T6G_MB_LIB.T6G(SCH_1):PAGE180
 PC148    2      B Q_CAP_0402-0.1UF,25V,10%,X7R,CH4104K1B00    I72 @T6G_MB_LIB.T6G(SCH_1):PAGE180
 PC107    2      B Q_CAP_0402-0.1UF,25V,10%,X7R,CH4104K1B00    I73 @T6G_MB_LIB.T6G(SCH_1):PAGE180
PC166_1    2      B Q_CAP_C0805-22UF,4V,20%,X6S,CH622KMEA03    I74 @T6G_MB_LIB.T6G(SCH_1):PAGE180
PC169_1    2      B Q_CAP_C0805-22UF,4V,20%,X6S,CH622KMEA03    I75 @T6G_MB_LIB.T6G(SCH_1):PAGE180
 PR410    2      B Q_RES_0402LF-1K,1%,1/16W,CHIP,CS21002FB06    I78 @T6G_MB_LIB.T6G(SCH_1):PAGE180
PC154_1    2      B Q_CAP_C0805-22UF,16V,20%,X6S,CH6223MEA01    I80 @T6G_MB_LIB.T6G(SCH_1):PAGE180
PC152_1    2      B Q_CAP_C0805-22UF,16V,20%,X6S,CH6223MEA01    I81 @T6G_MB_LIB.T6G(SCH_1):PAGE180
PC150_1    2      B Q_CAP_C0402-1UF,25V,10%,X6S,CH5104KEB02    I82 @T6G_MB_LIB.T6G(SCH_1):PAGE180
PC148_1    2      B Q_CAP_0402-0.1UF,25V,10%,X7R,CH4104K1B00    I83 @T6G_MB_LIB.T6G(SCH_1):PAGE180
  PU17    2   AGND ISL99390FRZTR5935-ISL99390FRZ-TR5935,SMLF,IC,AL099A    I84 @T6G_MB_LIB.T6G(SCH_1):PAGE180
  PU17    5  PGND1 ISL99390FRZTR5935-ISL99390FRZ-TR5935,SMLF,IC,AL099A    I84 @T6G_MB_LIB.T6G(SCH_1):PAGE180
  PU17 7_9-20_24  PGND2 ISL99390FRZTR5935-ISL99390FRZ-TR5935,SMLF,IC,AL099A    I84 @T6G_MB_LIB.T6G(SCH_1):PAGE180
  PU17   40  PGND3 ISL99390FRZTR5935-ISL99390FRZ-TR5935,SMLF,IC,AL099A    I84 @T6G_MB_LIB.T6G(SCH_1):PAGE180
PC176_10    2      B Q_CAP_0402-0.1UF,25V,10%,X7R,CH4104K1B00     I1 @T6G_MB_LIB.T6G(SCH_1):PAGE181
 PR105    2      B Q_RES_0402LF-8.87K,1%,1/16W,EMPTY,CS28872FB01     I4 @T6G_MB_LIB.T6G(SCH_1):PAGE181
 PC171    2      B Q_CAP_C0402-2.2UF,10V,10%,X6S,CH5222KEB01    I10 @T6G_MB_LIB.T6G(SCH_1):PAGE181
PC173_IOP0_4    2      B Q_CAP_C0402-2.2UF,10V,10%,X6S,CH5222KEB01    I13 @T6G_MB_LIB.T6G(SCH_1):PAGE181
PC178_4    2      B Q_CAP_0402-0.1UF,25V,10%,X7R,CH4104K1B00    I17 @T6G_MB_LIB.T6G(SCH_1):PAGE181
PC175_9    2      B Q_CAP_0402-0.1UF,25V,10%,X7R,CH4104K1B00    I19 @T6G_MB_LIB.T6G(SCH_1):PAGE181
 PR106    2      B Q_RES_0402LF-8.87K,1%,1/16W,EMPTY,CS28872FB01    I21 @T6G_MB_LIB.T6G(SCH_1):PAGE181
 PC172    2      B Q_CAP_C0402-2.2UF,10V,10%,X6S,CH5222KEB01    I27 @T6G_MB_LIB.T6G(SCH_1):PAGE181
PC174_IOP0_3    2      B Q_CAP_C0402-2.2UF,10V,10%,X6S,CH5222KEB01    I30 @T6G_MB_LIB.T6G(SCH_1):PAGE181
  PU19    2   AGND ISL99390FRZTR5935-ISL99390FRZ-TR5935,SMLF,IC,AL099A    I32 @T6G_MB_LIB.T6G(SCH_1):PAGE181
  PU19    5  PGND1 ISL99390FRZTR5935-ISL99390FRZ-TR5935,SMLF,IC,AL099A    I32 @T6G_MB_LIB.T6G(SCH_1):PAGE181
  PU19 7_9-20_24  PGND2 ISL99390FRZTR5935-ISL99390FRZ-TR5935,SMLF,IC,AL099A    I32 @T6G_MB_LIB.T6G(SCH_1):PAGE181
  PU19   40  PGND3 ISL99390FRZTR5935-ISL99390FRZ-TR5935,SMLF,IC,AL099A    I32 @T6G_MB_LIB.T6G(SCH_1):PAGE181
PC177_3    2      B Q_CAP_0402-0.1UF,25V,10%,X7R,CH4104K1B00    I35 @T6G_MB_LIB.T6G(SCH_1):PAGE181
PC179_3    2      B Q_CAP_C0402-1UF,25V,10%,X6S,CH5104KEB02    I36 @T6G_MB_LIB.T6G(SCH_1):PAGE181
 PR291    2      B Q_RES_0402LF-1.5,1%,1/8W,EMPTY,CS-1504FB00    I38 @T6G_MB_LIB.T6G(SCH_1):PAGE181
  PL16    2      2 Q_INDUCTOR_SMLF-0.22UH/33A,IND,CV+22Y0EZ00    I43 @T6G_MB_LIB.T6G(SCH_1):PAGE181
PC180_4    2      B Q_CAP_C0402-1UF,25V,10%,X6S,CH5104KEB02    I45 @T6G_MB_LIB.T6G(SCH_1):PAGE181
PC185_4    2      B Q_CAP_C0805-22UF,16V,20%,X6S,CH6223MEA01    I47 @T6G_MB_LIB.T6G(SCH_1):PAGE181
PC188_4    2      B Q_CAP_C0805-22UF,16V,20%,X6S,CH6223MEA01    I49 @T6G_MB_LIB.T6G(SCH_1):PAGE181
PC189_4    2      B Q_CAP_C0805-22UF,4V,20%,X6S,CH622KMEA03    I53 @T6G_MB_LIB.T6G(SCH_1):PAGE181
PC181_3    2      B Q_CAP_C0805-22UF,16V,20%,X6S,CH6223MEA01    I58 @T6G_MB_LIB.T6G(SCH_1):PAGE181
PC184_3    2      B Q_CAP_C0805-22UF,16V,20%,X6S,CH6223MEA01    I60 @T6G_MB_LIB.T6G(SCH_1):PAGE181
PC187_3    2      B Q_CAP_C0805-22UF,16V,20%,X6S,CH6223MEA01    I63 @T6G_MB_LIB.T6G(SCH_1):PAGE181
PC190_3    2      B Q_CAP_C0805-22UF,4V,20%,X6S,CH622KMEA03    I66 @T6G_MB_LIB.T6G(SCH_1):PAGE181
  PU20    2   AGND ISL99390FRZTR5935-ISL99390FRZ-TR5935,SMLF,IC,AL099A    I73 @T6G_MB_LIB.T6G(SCH_1):PAGE181
  PU20    5  PGND1 ISL99390FRZTR5935-ISL99390FRZ-TR5935,SMLF,IC,AL099A    I73 @T6G_MB_LIB.T6G(SCH_1):PAGE181
  PU20 7_9-20_24  PGND2 ISL99390FRZTR5935-ISL99390FRZ-TR5935,SMLF,IC,AL099A    I73 @T6G_MB_LIB.T6G(SCH_1):PAGE181
  PU20   40  PGND3 ISL99390FRZTR5935-ISL99390FRZ-TR5935,SMLF,IC,AL099A    I73 @T6G_MB_LIB.T6G(SCH_1):PAGE181
 PC193    2      B Q_CAP_0402-0.1UF,25V,10%,X7R,CH4104K1B00     I4 @T6G_MB_LIB.T6G(SCH_1):PAGE182
   PR3    2      B Q_RES_0402LF-10K,1%,1/16W,CHIP,CS31002FB08     I6 @T6G_MB_LIB.T6G(SCH_1):PAGE182
 PR115    2      B Q_RES_0402LF-49.9,1%,1/16W,CHIP,CS04992FB07    I15 @T6G_MB_LIB.T6G(SCH_1):PAGE182
 PR601    2      B Q_RES_0402LF-4.99K,1%,1/16W,EMPTY,CS24992FB07    I18 @T6G_MB_LIB.T6G(SCH_1):PAGE182
   PC5    2      B Q_CAP_0402-0.1UF,25V,10%,X7R,CH4104K1B00    I20 @T6G_MB_LIB.T6G(SCH_1):PAGE182
 PR126    2      B Q_RES_0402LF-3.09K,1%,1/16W,CHIP,CS23092FB04    I22 @T6G_MB_LIB.T6G(SCH_1):PAGE182
  PU21   31  RGND1 RAA229621GNPHA0-RAA229621GNP#HA0,SMLF,IC,ARF0TGP40A    I24 @T6G_MB_LIB.T6G(SCH_1):PAGE182
  PU21   18    SVC RAA229621GNPHA0-RAA229621GNP#HA0,SMLF,IC,ARF0TGP40A    I24 @T6G_MB_LIB.T6G(SCH_1):PAGE182
  PU21   17    SVD RAA229621GNPHA0-RAA229621GNP#HA0,SMLF,IC,ARF0TGP40A    I24 @T6G_MB_LIB.T6G(SCH_1):PAGE182
  PU21   20   SVTI RAA229621GNPHA0-RAA229621GNP#HA0,SMLF,IC,ARF0TGP40A    I24 @T6G_MB_LIB.T6G(SCH_1):PAGE182
  PU21   TH TH_GND RAA229621GNPHA0-RAA229621GNP#HA0,SMLF,IC,ARF0TGP40A    I24 @T6G_MB_LIB.T6G(SCH_1):PAGE182
  PU21   32  VSEN1 RAA229621GNPHA0-RAA229621GNP#HA0,SMLF,IC,ARF0TGP40A    I24 @T6G_MB_LIB.T6G(SCH_1):PAGE182
  C197    2      B Q_CAP_0402-1000PF,50V,5%,X7R,TMP_QCH21006JB10    I45 @T6G_MB_LIB.T6G(SCH_1):PAGE182
 PC198    2      B Q_CAP_0402-470PF,50V,10%,X7R,TMP_QCH14706KB18    I50 @T6G_MB_LIB.T6G(SCH_1):PAGE182
 PR412    2      B Q_RES_0402LF-0,5%,1/16W,CHIP,CS00002JB13    I52 @T6G_MB_LIB.T6G(SCH_1):PAGE182
  PR36    2      B Q_RES_0402LF-0,5%,1/16W,CHIP,CS00002JB13    I53 @T6G_MB_LIB.T6G(SCH_1):PAGE182
 PR127    2      B Q_RES_0402LF-0,5%,1/16W,EMPTY,CS00002JB13    I57 @T6G_MB_LIB.T6G(SCH_1):PAGE182
 PR419    2      B Q_RES_0402LF-0,5%,1/16W,CHIP,CS00002JB13    I58 @T6G_MB_LIB.T6G(SCH_1):PAGE182
  PR35    2      B Q_RES_0402LF-0,5%,1/16W,CHIP,CS00002JB13    I59 @T6G_MB_LIB.T6G(SCH_1):PAGE182
  PR34    2      B Q_RES_0402LF-0,5%,1/16W,CHIP,CS00002JB13    I60 @T6G_MB_LIB.T6G(SCH_1):PAGE182
  PR33    2      B Q_RES_0402LF-0,5%,1/16W,CHIP,CS00002JB13    I61 @T6G_MB_LIB.T6G(SCH_1):PAGE182
  PR37    2      B Q_RES_0402LF-0,5%,1/16W,CHIP,CS00002JB13    I71 @T6G_MB_LIB.T6G(SCH_1):PAGE182
   PC4    2      B Q_CAP_0402-0.1UF,25V,10%,X7R,CH4104K1B00    I79 @T6G_MB_LIB.T6G(SCH_1):PAGE182
 PC199    2      B Q_CAP_C0402-10UF,6.3V,20%,X6S,CH6101MEB03    I80 @T6G_MB_LIB.T6G(SCH_1):PAGE182
PC202_2    2      B Q_CAP_0402-0.1UF,25V,10%,X7R,CH4104K1B00     I7 @T6G_MB_LIB.T6G(SCH_1):PAGE183
 PC204    2      B Q_CAP_C0402-2.2UF,10V,10%,X6S,CH5222KEB01     I9 @T6G_MB_LIB.T6G(SCH_1):PAGE183
 PR134    1      A Q_RES_0402LF-4.87K,1%,1/16W,EMPTY,CS24872FB01    I11 @T6G_MB_LIB.T6G(SCH_1):PAGE183
  PU23    2   AGND ISL99390FRZTR5935-ISL99390FRZ-TR5935,SMLF,IC,AL099A    I13 @T6G_MB_LIB.T6G(SCH_1):PAGE183
  PU23    5  PGND1 ISL99390FRZTR5935-ISL99390FRZ-TR5935,SMLF,IC,AL099A    I13 @T6G_MB_LIB.T6G(SCH_1):PAGE183
  PU23 7_9-20_24  PGND2 ISL99390FRZTR5935-ISL99390FRZ-TR5935,SMLF,IC,AL099A    I13 @T6G_MB_LIB.T6G(SCH_1):PAGE183
  PU23   40  PGND3 ISL99390FRZTR5935-ISL99390FRZ-TR5935,SMLF,IC,AL099A    I13 @T6G_MB_LIB.T6G(SCH_1):PAGE183
PC206_11P0_2    2      B Q_CAP_C0402-2.2UF,10V,10%,X6S,CH5222KEB01    I17 @T6G_MB_LIB.T6G(SCH_1):PAGE183
PC212_2    2      B Q_CAP_C0805-22UF,16V,20%,X6S,CH6223MEA01    I30 @T6G_MB_LIB.T6G(SCH_1):PAGE183
PC214_2    2      B Q_CAP_C0805-22UF,16V,20%,X6S,CH6223MEA01    I31 @T6G_MB_LIB.T6G(SCH_1):PAGE183
 PR482    2      B Q_RES_0402LF-1.5,1%,1/8W,EMPTY,CS-1504FB00    I33 @T6G_MB_LIB.T6G(SCH_1):PAGE183
 PC203    2      B Q_CAP_C0402-2.2UF,10V,10%,X6S,CH5222KEB01    I36 @T6G_MB_LIB.T6G(SCH_1):PAGE183
PC205_11P0_1    2      B Q_CAP_C0402-2.2UF,10V,10%,X6S,CH5222KEB01    I42 @T6G_MB_LIB.T6G(SCH_1):PAGE183
PC207_1    2      B Q_CAP_0402-0.1UF,25V,10%,X7R,CH4104K1B00    I47 @T6G_MB_LIB.T6G(SCH_1):PAGE183
PC213_1    2      B Q_CAP_C0805-22UF,16V,20%,X6S,CH6223MEA01    I49 @T6G_MB_LIB.T6G(SCH_1):PAGE183
PC216_2    2      B Q_CAP_C0805-22UF,16V,20%,X6S,CH6223MEA01    I50 @T6G_MB_LIB.T6G(SCH_1):PAGE183
PC218_2    2      B Q_CAP_C0805-22UF,16V,20%,X6S,CH6223MEA01    I54 @T6G_MB_LIB.T6G(SCH_1):PAGE183
 PC223    2      B Q_CAPP_SMLF-470UF,2.5V,20%,SPCAP,CH747LM8825    I58 @T6G_MB_LIB.T6G(SCH_1):PAGE183
 PC226    2      B Q_CAPP_SMLF-470UF,2.5V,20%,SPCAP,CH747LM8825    I59 @T6G_MB_LIB.T6G(SCH_1):PAGE183
PC225_2    2      B Q_CAP_C0805-22UF,4V,20%,X6S,CH622KMEA03    I62 @T6G_MB_LIB.T6G(SCH_1):PAGE183
 PC228    2      B Q_CAPP_SMLF-390UF,2.5V,20%,ALUM,CC7390JMZ13    I65 @T6G_MB_LIB.T6G(SCH_1):PAGE183
 PC220    2      B Q_CAPP_THLF-270UF,16V,20%,OSCON,CC72703MD38    I75 @T6G_MB_LIB.T6G(SCH_1):PAGE183
 PC222    2      B Q_CAP_0402-0.1UF,25V,10%,X7R,CH4104K1B00    I76 @T6G_MB_LIB.T6G(SCH_1):PAGE183
PC227_1    2      B Q_CAP_C0805-22UF,4V,20%,X6S,CH622KMEA03    I82 @T6G_MB_LIB.T6G(SCH_1):PAGE183
 PR414    2      B Q_RES_0402LF-1K,1%,1/16W,CHIP,CS21002FB06    I83 @T6G_MB_LIB.T6G(SCH_1):PAGE183
PC215_1    2      B Q_CAP_C0805-22UF,16V,20%,X6S,CH6223MEA01    I87 @T6G_MB_LIB.T6G(SCH_1):PAGE183
PC219_1    2      B Q_CAP_C0805-22UF,16V,20%,X6S,CH6223MEA01    I88 @T6G_MB_LIB.T6G(SCH_1):PAGE183
 PC800    2      B Q_CAPP_SMLF-470UF,2.5V,20%,SPCAP,CH747LM8825    I89 @T6G_MB_LIB.T6G(SCH_1):PAGE183
PC221_2    2      B Q_CAP_C0805-22UF,4V,20%,X6S,CH622KMEA03    I90 @T6G_MB_LIB.T6G(SCH_1):PAGE183
  PU22    2   AGND ISL99390FRZTR5935-ISL99390FRZ-TR5935,SMLF,IC,AL099A    I92 @T6G_MB_LIB.T6G(SCH_1):PAGE183
  PU22    5  PGND1 ISL99390FRZTR5935-ISL99390FRZ-TR5935,SMLF,IC,AL099A    I92 @T6G_MB_LIB.T6G(SCH_1):PAGE183
  PU22 7_9-20_24  PGND2 ISL99390FRZTR5935-ISL99390FRZ-TR5935,SMLF,IC,AL099A    I92 @T6G_MB_LIB.T6G(SCH_1):PAGE183
  PU22   40  PGND3 ISL99390FRZTR5935-ISL99390FRZ-TR5935,SMLF,IC,AL099A    I92 @T6G_MB_LIB.T6G(SCH_1):PAGE183
  C674    2      B Q_CAP_0402-0.1UF,25V,10%,EMPTY,CH4104K1B00     I4 @T6G_MB_LIB.T6G(SCH_1):PAGE184
PC6001    2      B Q_CAP_C0402-0.1UF,25V,10%,X6S,CH4104KEB00     I5 @T6G_MB_LIB.T6G(SCH_1):PAGE184
 PC111    2      B Q_CAP_C0805-22UF,16V,20%,X6S,CH6223MEA01     I8 @T6G_MB_LIB.T6G(SCH_1):PAGE184
 PC212    2      B Q_CAP_C0402-1UF,25V,10%,X6S,CH5104KEB02    I11 @T6G_MB_LIB.T6G(SCH_1):PAGE184
 PR417    1      A Q_RES_0402LF-0,5%,1/16W,CHIP,CS00002JB13    I15 @T6G_MB_LIB.T6G(SCH_1):PAGE184
 PR448    2      B Q_RES_0402LF-8.66K,1%,1/16W,CHIP,CS28662FB02    I17 @T6G_MB_LIB.T6G(SCH_1):PAGE184
  PU57    2   AGND MPQ8633BGLEC838Z-MPQ8633BGLE-C838-Z,SMLF,IC,AL0086A    I18 @T6G_MB_LIB.T6G(SCH_1):PAGE184
  PU57 11_18   PGND MPQ8633BGLEC838Z-MPQ8633BGLE-C838-Z,SMLF,IC,AL0086A    I18 @T6G_MB_LIB.T6G(SCH_1):PAGE184
 PC258    2      B Q_CAP_0402-0.022UF,25V,10%,X7R,CH3224K1B01    I21 @T6G_MB_LIB.T6G(SCH_1):PAGE184
 PC227    2      B Q_CAP_C0805-22UF,16V,20%,X6S,CH6223MEA01    I25 @T6G_MB_LIB.T6G(SCH_1):PAGE184
 PC254    2      B Q_CAP_C0805-22UF,16V,20%,X6S,CH6223MEA01    I26 @T6G_MB_LIB.T6G(SCH_1):PAGE184
  PC81    2      B Q_CAP_C0805-22UF,16V,20%,X6S,CH6223MEA01    I27 @T6G_MB_LIB.T6G(SCH_1):PAGE184
 PC237    2      B Q_CAP_C0402-1UF,25V,10%,X6S,CH5104KEB02    I28 @T6G_MB_LIB.T6G(SCH_1):PAGE184
 PR418    1      A Q_RES_0402LF-49.9,1%,1/16W,CHIP,CS04992FB07    I31 @T6G_MB_LIB.T6G(SCH_1):PAGE184
 PC114    2      B Q_CAP_C0805-22UF,4V,20%,X6S,CH622KMEA03    I39 @T6G_MB_LIB.T6G(SCH_1):PAGE184
 PC288    2      B Q_CAP_C0805-22UF,4V,20%,X6S,CH622KMEA03    I40 @T6G_MB_LIB.T6G(SCH_1):PAGE184
 PC260    2      B Q_CAP_C0805-22UF,4V,20%,EMPTY,CH622KMEA03    I41 @T6G_MB_LIB.T6G(SCH_1):PAGE184
 PC261    2      B Q_CAP_C0805-22UF,4V,20%,EMPTY,CH622KMEA03    I46 @T6G_MB_LIB.T6G(SCH_1):PAGE184
 PC115    2      B Q_CAPP_SMLF-390UF,2.5V,20%,ALUM,CC7390JMZ13    I47 @T6G_MB_LIB.T6G(SCH_1):PAGE184
 PC215    2      B Q_CAP_0402-0.1UF,25V,10%,X7R,CH4104K1B00    I48 @T6G_MB_LIB.T6G(SCH_1):PAGE184
 PR439    2      B Q_RES_0402LF-1K,1%,1/16W,CHIP,CS21002FB06    I51 @T6G_MB_LIB.T6G(SCH_1):PAGE184
 PC285    2      B Q_CAP_C0805-22UF,4V,20%,X6S,CH622KMEA03    I54 @T6G_MB_LIB.T6G(SCH_1):PAGE184
 R8153    2      B Q_RES_0402LF-1K,1%,1/16W,EMPTY,CS21002FB06     I6 @T6G_MB_LIB.T6G(SCH_1):PAGE185
  PQ15    S SOURCE MOSFET_N_SMLF-BSS138K,BSS138K,IC,BAM138K0000    I16 @T6G_MB_LIB.T6G(SCH_1):PAGE185
   PR4    2      B Q_RES_0402LF-10K,1%,1/16W,CHIP,CS31002FB08    I20 @T6G_MB_LIB.T6G(SCH_1):PAGE185
 PC243    2      B Q_CAP_0402-0.1UF,25V,10%,X7R,CH4104K1B00    I22 @T6G_MB_LIB.T6G(SCH_1):PAGE185
 PR162    2      B Q_RES_0402LF-49.9,1%,1/16W,CHIP,CS04992FB07    I45 @T6G_MB_LIB.T6G(SCH_1):PAGE185
 PR602    2      B Q_RES_0402LF-4.99K,1%,1/16W,EMPTY,CS24992FB07    I48 @T6G_MB_LIB.T6G(SCH_1):PAGE185
   PC6    2      B Q_CAP_0402-0.1UF,25V,10%,X7R,CH4104K1B00    I51 @T6G_MB_LIB.T6G(SCH_1):PAGE185
 C8246    2      B Q_CAP_0402-1000PF,50V,5%,EMPTY,TMP_QCH21006JB10    I52 @T6G_MB_LIB.T6G(SCH_1):PAGE185
  C296    2      B Q_CAP_0402-10PF,50V,5%,EMPTY,CH01006JB08    I64 @T6G_MB_LIB.T6G(SCH_1):PAGE185
  C297    2      B Q_CAP_0402-10PF,50V,5%,EMPTY,CH01006JB08    I66 @T6G_MB_LIB.T6G(SCH_1):PAGE185
 PC250    2      B Q_CAP_0402-470PF,50V,10%,X7R,TMP_QCH14706KB18    I91 @T6G_MB_LIB.T6G(SCH_1):PAGE185
 PC253    2      B Q_CAP_0402-470PF,50V,10%,X7R,TMP_QCH14706KB18    I94 @T6G_MB_LIB.T6G(SCH_1):PAGE185
 PR437    2      B Q_RES_0402LF-0,5%,1/16W,CHIP,CS00002JB13   I102 @T6G_MB_LIB.T6G(SCH_1):PAGE185
 PR436    2      B Q_RES_0402LF-0,5%,1/16W,CHIP,CS00002JB13   I103 @T6G_MB_LIB.T6G(SCH_1):PAGE185
 PR530    2      B Q_RES_0402LF-0,5%,1/16W,CHIP,CS00002JB13   I107 @T6G_MB_LIB.T6G(SCH_1):PAGE185
  PC10    2      B Q_CAP_0402-0.1UF,25V,10%,X7R,CH4104K1B00   I116 @T6G_MB_LIB.T6G(SCH_1):PAGE185
 PC251    2      B Q_CAP_C0402-10UF,6.3V,20%,X6S,CH6101MEB03   I125 @T6G_MB_LIB.T6G(SCH_1):PAGE185
 PC252    2      B Q_CAP_C0402-1UF,16V,10%,X6S,CH5103KEB01   I127 @T6G_MB_LIB.T6G(SCH_1):PAGE185
 PC247    2      B Q_CAP_0402-1UF,6.3V,10%,X7R,CH5101K1B01   I132 @T6G_MB_LIB.T6G(SCH_1):PAGE185
  PU25   TH TH_GND RAA229620GNPHA0-RAA229620GNP#HA0,SMLF,IC,ARF0TGP40A   I133 @T6G_MB_LIB.T6G(SCH_1):PAGE185
PC255_2    2      B Q_CAP_0402-0.1UF,25V,10%,X7R,CH4104K1B00     I5 @T6G_MB_LIB.T6G(SCH_1):PAGE186
 PC257    2      B Q_CAP_C0402-2.2UF,10V,10%,X6S,CH5222KEB01     I9 @T6G_MB_LIB.T6G(SCH_1):PAGE186
 PR486    2      B Q_RES_0402LF-1.5,1%,1/8W,EMPTY,CS-1504FB00    I22 @T6G_MB_LIB.T6G(SCH_1):PAGE186
PC261_2    2      B Q_CAP_0402-0.1UF,25V,10%,X7R,CH4104K1B00    I25 @T6G_MB_LIB.T6G(SCH_1):PAGE186
PC265_2    2      B Q_CAP_C0805-22UF,16V,20%,X6S,CH6223MEA01    I28 @T6G_MB_LIB.T6G(SCH_1):PAGE186
PC267_2    2      B Q_CAP_C0805-22UF,16V,20%,X6S,CH6223MEA01    I29 @T6G_MB_LIB.T6G(SCH_1):PAGE186
 PR485    2      B Q_RES_0402LF-1.5,1%,1/8W,EMPTY,CS-1504FB00    I34 @T6G_MB_LIB.T6G(SCH_1):PAGE186
 PC256    2      B Q_CAP_C0402-2.2UF,10V,10%,X6S,CH5222KEB01    I36 @T6G_MB_LIB.T6G(SCH_1):PAGE186
 PR187    1      A Q_RES_0402LF-8.87K,1%,1/16W,EMPTY,CS28872FB01    I37 @T6G_MB_LIB.T6G(SCH_1):PAGE186
PC258_C0P1_1    2      B Q_CAP_C0402-2.2UF,10V,10%,X6S,CH5222KEB01    I44 @T6G_MB_LIB.T6G(SCH_1):PAGE186
PC262_1    2      B Q_CAP_C0402-1UF,25V,10%,X6S,CH5104KEB02    I47 @T6G_MB_LIB.T6G(SCH_1):PAGE186
PC264_1    2      B Q_CAP_C0805-22UF,16V,20%,X6S,CH6223MEA01    I51 @T6G_MB_LIB.T6G(SCH_1):PAGE186
PC266_1    2      B Q_CAP_C0805-22UF,16V,20%,X6S,CH6223MEA01    I52 @T6G_MB_LIB.T6G(SCH_1):PAGE186
PC268_1    2      B Q_CAP_C0805-22UF,16V,20%,X6S,CH6223MEA01    I53 @T6G_MB_LIB.T6G(SCH_1):PAGE186
 PC275    2      B Q_CAPP_SMLF-220UF,4V,20%,SPCAP,CH122KM8801    I58 @T6G_MB_LIB.T6G(SCH_1):PAGE186
 PC276    2      B Q_CAPP_SMLF-220UF,4V,20%,SPCAP,CH122KM8801    I59 @T6G_MB_LIB.T6G(SCH_1):PAGE186
 PC277    2      B Q_CAPP_SMLF-220UF,4V,20%,SPCAP,CH122KM8801    I60 @T6G_MB_LIB.T6G(SCH_1):PAGE186
PC280_2    2      B Q_CAP_C0805-22UF,4V,20%,X6S,CH622KMEA03    I61 @T6G_MB_LIB.T6G(SCH_1):PAGE186
 PC272    2      B Q_CAPP_THLF-270UF,16V,20%,OSCON,CC72703MD38    I70 @T6G_MB_LIB.T6G(SCH_1):PAGE186
PC6004    2      B Q_CAP_0402-0.1UF,25V,10%,X7R,CH4104K1B00    I74 @T6G_MB_LIB.T6G(SCH_1):PAGE186
PC281_1    2      B Q_CAP_C0805-22UF,4V,20%,X6S,CH622KMEA03    I76 @T6G_MB_LIB.T6G(SCH_1):PAGE186
PC283_1    2      B Q_CAP_C0805-22UF,4V,20%,X6S,CH622KMEA03    I77 @T6G_MB_LIB.T6G(SCH_1):PAGE186
 PR337    2      B Q_RES_0402LF-1K,1%,1/16W,CHIP,CS21002FB06    I78 @T6G_MB_LIB.T6G(SCH_1):PAGE186
 PR188    1      A Q_RES_0402LF-8.87K,1%,1/16W,EMPTY,CS28872FB01    I80 @T6G_MB_LIB.T6G(SCH_1):PAGE186
 PC105    2      B Q_CAPP_SMLF-220UF,4V,20%,SPCAP,CH122KM8801    I84 @T6G_MB_LIB.T6G(SCH_1):PAGE186
 PC278    2      B Q_CAP_0402-0.1UF,25V,10%,X7R,CH4104K1B00    I85 @T6G_MB_LIB.T6G(SCH_1):PAGE186
   PU4    2   AGND ISL99390FRZTR5935-ISL99390FRZ-TR5935,SMLF,IC,AL099A    I88 @T6G_MB_LIB.T6G(SCH_1):PAGE186
   PU4    5  PGND1 ISL99390FRZTR5935-ISL99390FRZ-TR5935,SMLF,IC,AL099A    I88 @T6G_MB_LIB.T6G(SCH_1):PAGE186
   PU4 7_9-20_24  PGND2 ISL99390FRZTR5935-ISL99390FRZ-TR5935,SMLF,IC,AL099A    I88 @T6G_MB_LIB.T6G(SCH_1):PAGE186
   PU4   40  PGND3 ISL99390FRZTR5935-ISL99390FRZ-TR5935,SMLF,IC,AL099A    I88 @T6G_MB_LIB.T6G(SCH_1):PAGE186
  PU26    2   AGND ISL99390FRZTR5935-ISL99390FRZ-TR5935,SMLF,IC,AL099A    I91 @T6G_MB_LIB.T6G(SCH_1):PAGE186
  PU26    5  PGND1 ISL99390FRZTR5935-ISL99390FRZ-TR5935,SMLF,IC,AL099A    I91 @T6G_MB_LIB.T6G(SCH_1):PAGE186
  PU26 7_9-20_24  PGND2 ISL99390FRZTR5935-ISL99390FRZ-TR5935,SMLF,IC,AL099A    I91 @T6G_MB_LIB.T6G(SCH_1):PAGE186
  PU26   40  PGND3 ISL99390FRZTR5935-ISL99390FRZ-TR5935,SMLF,IC,AL099A    I91 @T6G_MB_LIB.T6G(SCH_1):PAGE186
PC285_4    2      B Q_CAP_0402-0.1UF,25V,10%,X7R,CH4104K1B00     I2 @T6G_MB_LIB.T6G(SCH_1):PAGE187
 PC287    2      B Q_CAP_C0402-2.2UF,10V,10%,X6S,CH5222KEB01     I6 @T6G_MB_LIB.T6G(SCH_1):PAGE187
  PU28    2   AGND ISL99390FRZTR5935-ISL99390FRZ-TR5935,SMLF,IC,AL099A     I9 @T6G_MB_LIB.T6G(SCH_1):PAGE187
  PU28    5  PGND1 ISL99390FRZTR5935-ISL99390FRZ-TR5935,SMLF,IC,AL099A     I9 @T6G_MB_LIB.T6G(SCH_1):PAGE187
  PU28 7_9-20_24  PGND2 ISL99390FRZTR5935-ISL99390FRZ-TR5935,SMLF,IC,AL099A     I9 @T6G_MB_LIB.T6G(SCH_1):PAGE187
  PU28   40  PGND3 ISL99390FRZTR5935-ISL99390FRZ-TR5935,SMLF,IC,AL099A     I9 @T6G_MB_LIB.T6G(SCH_1):PAGE187
 PR196    1      A Q_RES_0402LF-8.87K,1%,1/16W,EMPTY,CS28872FB01    I11 @T6G_MB_LIB.T6G(SCH_1):PAGE187
PC289_C0P1_4    2      B Q_CAP_C0402-2.2UF,10V,10%,X6S,CH5222KEB01    I15 @T6G_MB_LIB.T6G(SCH_1):PAGE187
 PR523    2      B Q_RES_0402LF-1.5,1%,1/8W,EMPTY,CS-1504FB00    I19 @T6G_MB_LIB.T6G(SCH_1):PAGE187
PC293_4    2      B Q_CAP_0402-0.1UF,25V,10%,X7R,CH4104K1B00    I22 @T6G_MB_LIB.T6G(SCH_1):PAGE187
PC291_4    2      B Q_CAP_C0402-1UF,25V,10%,X6S,CH5104KEB02    I23 @T6G_MB_LIB.T6G(SCH_1):PAGE187
PC295_4    2      B Q_CAP_C0805-22UF,16V,20%,X6S,CH6223MEA01    I24 @T6G_MB_LIB.T6G(SCH_1):PAGE187
PC297_4    2      B Q_CAP_C0805-22UF,16V,20%,X6S,CH6223MEA01    I25 @T6G_MB_LIB.T6G(SCH_1):PAGE187
PC284_3    2      B Q_CAP_0402-0.1UF,25V,10%,X7R,CH4104K1B00    I28 @T6G_MB_LIB.T6G(SCH_1):PAGE187
 PR195    1      A Q_RES_0402LF-8.87K,1%,1/16W,EMPTY,CS28872FB01    I34 @T6G_MB_LIB.T6G(SCH_1):PAGE187
 PC286    2      B Q_CAP_C0402-2.2UF,10V,10%,X6S,CH5222KEB01    I37 @T6G_MB_LIB.T6G(SCH_1):PAGE187
  PU27    2   AGND ISL99390FRZTR5935-ISL99390FRZ-TR5935,SMLF,IC,AL099A    I39 @T6G_MB_LIB.T6G(SCH_1):PAGE187
  PU27    5  PGND1 ISL99390FRZTR5935-ISL99390FRZ-TR5935,SMLF,IC,AL099A    I39 @T6G_MB_LIB.T6G(SCH_1):PAGE187
  PU27 7_9-20_24  PGND2 ISL99390FRZTR5935-ISL99390FRZ-TR5935,SMLF,IC,AL099A    I39 @T6G_MB_LIB.T6G(SCH_1):PAGE187
  PU27   40  PGND3 ISL99390FRZTR5935-ISL99390FRZ-TR5935,SMLF,IC,AL099A    I39 @T6G_MB_LIB.T6G(SCH_1):PAGE187
PC288_C0P1_3    2      B Q_CAP_C0402-2.2UF,10V,10%,X6S,CH5222KEB01    I41 @T6G_MB_LIB.T6G(SCH_1):PAGE187
PC290_3    2      B Q_CAP_0402-0.1UF,25V,10%,X7R,CH4104K1B00    I44 @T6G_MB_LIB.T6G(SCH_1):PAGE187
 PR522    2      B Q_RES_0402LF-1.5,1%,1/8W,EMPTY,CS-1504FB00    I45 @T6G_MB_LIB.T6G(SCH_1):PAGE187
PC292_3    2      B Q_CAP_C0402-1UF,25V,10%,X6S,CH5104KEB02    I48 @T6G_MB_LIB.T6G(SCH_1):PAGE187
PC294_3    2      B Q_CAP_C0805-22UF,16V,20%,X6S,CH6223MEA01    I49 @T6G_MB_LIB.T6G(SCH_1):PAGE187
PC296_3    2      B Q_CAP_C0805-22UF,16V,20%,X6S,CH6223MEA01    I50 @T6G_MB_LIB.T6G(SCH_1):PAGE187
  PL32    3      3 Q_INDUCTOR4P_14-150NH,SMLF,IND,CV+15^0TZ04    I53 @T6G_MB_LIB.T6G(SCH_1):PAGE187
PC299_4    2      B Q_CAP_C0805-22UF,16V,20%,X6S,CH6223MEA01    I55 @T6G_MB_LIB.T6G(SCH_1):PAGE187
PC303_4    2      B Q_CAP_C0805-22UF,4V,20%,X6S,CH622KMEA03    I58 @T6G_MB_LIB.T6G(SCH_1):PAGE187
PC305_4    2      B Q_CAP_C0805-22UF,4V,20%,X6S,CH622KMEA03    I60 @T6G_MB_LIB.T6G(SCH_1):PAGE187
PC298_3    2      B Q_CAP_C0805-22UF,16V,20%,X6S,CH6223MEA01    I65 @T6G_MB_LIB.T6G(SCH_1):PAGE187
PC302_3    2      B Q_CAP_C0805-22UF,4V,20%,X6S,CH622KMEA03    I69 @T6G_MB_LIB.T6G(SCH_1):PAGE187
PC304_3    2      B Q_CAP_C0805-22UF,4V,20%,X6S,CH622KMEA03    I71 @T6G_MB_LIB.T6G(SCH_1):PAGE187
PC124_6    2      B Q_CAP_0402-0.1UF,25V,10%,X7R,CH4104K1B00     I4 @T6G_MB_LIB.T6G(SCH_1):PAGE188
 PR423    1      A Q_RES_0402LF-8.87K,1%,1/16W,EMPTY,CS28872FB01     I8 @T6G_MB_LIB.T6G(SCH_1):PAGE188
 PC125    2      B Q_CAP_C0402-2.2UF,10V,10%,X6S,CH5222KEB01    I10 @T6G_MB_LIB.T6G(SCH_1):PAGE188
PC126_C0P1_6    2      B Q_CAP_C0402-2.2UF,10V,10%,X6S,CH5222KEB01    I15 @T6G_MB_LIB.T6G(SCH_1):PAGE188
  PU29    2   AGND ISL99390FRZTR5935-ISL99390FRZ-TR5935,SMLF,IC,AL099A    I18 @T6G_MB_LIB.T6G(SCH_1):PAGE188
  PU29    5  PGND1 ISL99390FRZTR5935-ISL99390FRZ-TR5935,SMLF,IC,AL099A    I18 @T6G_MB_LIB.T6G(SCH_1):PAGE188
  PU29 7_9-20_24  PGND2 ISL99390FRZTR5935-ISL99390FRZ-TR5935,SMLF,IC,AL099A    I18 @T6G_MB_LIB.T6G(SCH_1):PAGE188
  PU29   40  PGND3 ISL99390FRZTR5935-ISL99390FRZ-TR5935,SMLF,IC,AL099A    I18 @T6G_MB_LIB.T6G(SCH_1):PAGE188
 PR524    2      B Q_RES_0402LF-1.5,1%,1/8W,EMPTY,CS-1504FB00    I21 @T6G_MB_LIB.T6G(SCH_1):PAGE188
PC127_6    2      B Q_CAP_0402-0.1UF,25V,10%,X7R,CH4104K1B00    I25 @T6G_MB_LIB.T6G(SCH_1):PAGE188
PC128_6    2      B Q_CAP_C0402-1UF,25V,10%,X6S,CH5104KEB02    I27 @T6G_MB_LIB.T6G(SCH_1):PAGE188
PC129_6    2      B Q_CAP_C0805-22UF,16V,20%,X6S,CH6223MEA01    I29 @T6G_MB_LIB.T6G(SCH_1):PAGE188
PC130_6    2      B Q_CAP_C0805-22UF,16V,20%,X6S,CH6223MEA01    I30 @T6G_MB_LIB.T6G(SCH_1):PAGE188
  PR46    2      B Q_RES_0402LF-1.5,1%,1/8W,EMPTY,CS-1504FB00    I32 @T6G_MB_LIB.T6G(SCH_1):PAGE188
PC306_5    2      B Q_CAP_0402-0.1UF,25V,10%,X7R,CH4104K1B00    I34 @T6G_MB_LIB.T6G(SCH_1):PAGE188
 PR202    1      A Q_RES_0402LF-8.87K,1%,1/16W,EMPTY,CS28872FB01    I37 @T6G_MB_LIB.T6G(SCH_1):PAGE188
 PC307    2      B Q_CAP_C0402-2.2UF,10V,10%,X6S,CH5222KEB01    I39 @T6G_MB_LIB.T6G(SCH_1):PAGE188
PC308_C0P1_5    2      B Q_CAP_C0402-2.2UF,10V,10%,X6S,CH5222KEB01    I43 @T6G_MB_LIB.T6G(SCH_1):PAGE188
PC309_5    2      B Q_CAP_0402-0.1UF,25V,10%,X7R,CH4104K1B00    I45 @T6G_MB_LIB.T6G(SCH_1):PAGE188
PC310_5    2      B Q_CAP_C0402-1UF,25V,10%,X6S,CH5104KEB02    I48 @T6G_MB_LIB.T6G(SCH_1):PAGE188
PC311_5    2      B Q_CAP_C0805-22UF,16V,20%,X6S,CH6223MEA01    I49 @T6G_MB_LIB.T6G(SCH_1):PAGE188
PC312_5    2      B Q_CAP_C0805-22UF,16V,20%,X6S,CH6223MEA01    I50 @T6G_MB_LIB.T6G(SCH_1):PAGE188
  PL27    1      1 Q_INDUCTOR_SMLF-120NH/69A,IND,CV+12^0EZ03    I51 @T6G_MB_LIB.T6G(SCH_1):PAGE188
PC132_6    2      B Q_CAP_C0805-22UF,16V,20%,X6S,CH6223MEA01    I55 @T6G_MB_LIB.T6G(SCH_1):PAGE188
PC134_6    2      B Q_CAP_C0805-22UF,4V,20%,X6S,CH622KMEA03    I58 @T6G_MB_LIB.T6G(SCH_1):PAGE188
PC135_6    2      B Q_CAP_C0805-22UF,4V,20%,X6S,CH622KMEA03    I60 @T6G_MB_LIB.T6G(SCH_1):PAGE188
PC313_5    2      B Q_CAP_C0805-22UF,16V,20%,X6S,CH6223MEA01    I66 @T6G_MB_LIB.T6G(SCH_1):PAGE188
PC315_5    2      B Q_CAP_C0805-22UF,4V,20%,X6S,CH622KMEA03    I69 @T6G_MB_LIB.T6G(SCH_1):PAGE188
PC316_5    2      B Q_CAP_C0805-22UF,4V,20%,X6S,CH622KMEA03    I71 @T6G_MB_LIB.T6G(SCH_1):PAGE188
  PU24    2   AGND ISL99390FRZTR5935-ISL99390FRZ-TR5935,SMLF,IC,AL099A    I73 @T6G_MB_LIB.T6G(SCH_1):PAGE188
  PU24    5  PGND1 ISL99390FRZTR5935-ISL99390FRZ-TR5935,SMLF,IC,AL099A    I73 @T6G_MB_LIB.T6G(SCH_1):PAGE188
  PU24 7_9-20_24  PGND2 ISL99390FRZTR5935-ISL99390FRZ-TR5935,SMLF,IC,AL099A    I73 @T6G_MB_LIB.T6G(SCH_1):PAGE188
  PU24   40  PGND3 ISL99390FRZTR5935-ISL99390FRZ-TR5935,SMLF,IC,AL099A    I73 @T6G_MB_LIB.T6G(SCH_1):PAGE188
PC345_9    2      B Q_CAP_0402-0.1UF,25V,10%,X7R,CH4104K1B00     I2 @T6G_MB_LIB.T6G(SCH_1):PAGE191
 PR511    2      B Q_RES_0402LF-1.5,1%,1/8W,EMPTY,CS-1504FB00    I10 @T6G_MB_LIB.T6G(SCH_1):PAGE191
 PC346    2      B Q_CAP_C0402-2.2UF,10V,10%,X6S,CH5222KEB01    I13 @T6G_MB_LIB.T6G(SCH_1):PAGE191
PC348_3    2      B Q_CAP_0402-0.1UF,25V,10%,X7R,CH4104K1B00    I19 @T6G_MB_LIB.T6G(SCH_1):PAGE191
PC354_3    2      B Q_CAP_C0805-22UF,4V,20%,X6S,CH622KMEA03    I28 @T6G_MB_LIB.T6G(SCH_1):PAGE191
PC355_3    2      B Q_CAP_C0805-22UF,4V,20%,X6S,CH622KMEA03    I30 @T6G_MB_LIB.T6G(SCH_1):PAGE191
 PR208    1      A Q_RES_0402LF-8.87K,1%,1/16W,EMPTY,CS28872FB01     I8 @T6G_MB_LIB.T6G(SCH_1):PAGE190
 PC320    2      B Q_CAP_C0402-2.2UF,10V,10%,X6S,CH5222KEB01    I11 @T6G_MB_LIB.T6G(SCH_1):PAGE190
PC322_SOP1_2    2      B Q_CAP_C0402-2.2UF,10V,10%,X6S,CH5222KEB01    I14 @T6G_MB_LIB.T6G(SCH_1):PAGE190
  PU30    2   AGND ISL99390FRZTR5935-ISL99390FRZ-TR5935,SMLF,IC,AL099A    I17 @T6G_MB_LIB.T6G(SCH_1):PAGE190
  PU30    5  PGND1 ISL99390FRZTR5935-ISL99390FRZ-TR5935,SMLF,IC,AL099A    I17 @T6G_MB_LIB.T6G(SCH_1):PAGE190
  PU30 7_9-20_24  PGND2 ISL99390FRZTR5935-ISL99390FRZ-TR5935,SMLF,IC,AL099A    I17 @T6G_MB_LIB.T6G(SCH_1):PAGE190
  PU30   40  PGND3 ISL99390FRZTR5935-ISL99390FRZ-TR5935,SMLF,IC,AL099A    I17 @T6G_MB_LIB.T6G(SCH_1):PAGE190
 PR526    2      B Q_RES_0402LF-1.5,1%,1/8W,EMPTY,CS-1504FB00    I21 @T6G_MB_LIB.T6G(SCH_1):PAGE190
PC330_2    2      B Q_CAP_C0805-22UF,16V,20%,X6S,CH6223MEA01    I27 @T6G_MB_LIB.T6G(SCH_1):PAGE190
PC317_7    2      B Q_CAP_0402-0.1UF,25V,10%,X7R,CH4104K1B00    I32 @T6G_MB_LIB.T6G(SCH_1):PAGE190
 PR207    1      A Q_RES_0402LF-8.87K,1%,1/16W,EMPTY,CS28872FB01    I35 @T6G_MB_LIB.T6G(SCH_1):PAGE190
 PC319    2      B Q_CAP_C0402-2.2UF,10V,10%,X6S,CH5222KEB01    I36 @T6G_MB_LIB.T6G(SCH_1):PAGE190
PC321_SOP1_1    2      B Q_CAP_C0402-2.2UF,10V,10%,X6S,CH5222KEB01    I41 @T6G_MB_LIB.T6G(SCH_1):PAGE190
PC329_1    2      B Q_CAP_C0805-22UF,16V,20%,X6S,CH6223MEA01    I49 @T6G_MB_LIB.T6G(SCH_1):PAGE190
PC331_1    2      B Q_CAP_C0805-22UF,16V,20%,X6S,CH6223MEA01    I50 @T6G_MB_LIB.T6G(SCH_1):PAGE190
PC332_2    2      B Q_CAP_C0805-22UF,16V,20%,X6S,CH6223MEA01    I56 @T6G_MB_LIB.T6G(SCH_1):PAGE190
PC335_2    2      B Q_CAP_C0805-22UF,16V,20%,X6S,CH6223MEA01    I57 @T6G_MB_LIB.T6G(SCH_1):PAGE190
 PC337    2      B Q_CAPP_SMLF-470UF,2.5V,20%,SPCAP,CH747LM8825    I59 @T6G_MB_LIB.T6G(SCH_1):PAGE190
PC339_2    2      B Q_CAP_C0805-22UF,4V,20%,X6S,CH622KMEA03    I60 @T6G_MB_LIB.T6G(SCH_1):PAGE190
PC342_2    2      B Q_CAP_C0805-22UF,4V,20%,X6S,CH622KMEA03    I62 @T6G_MB_LIB.T6G(SCH_1):PAGE190
PC334_1    2      B Q_CAP_C0805-22UF,16V,20%,X6S,CH6223MEA01    I71 @T6G_MB_LIB.T6G(SCH_1):PAGE190
 PC336    2      B Q_CAPP_THLF-270UF,16V,20%,OSCON,CC72703MD38    I73 @T6G_MB_LIB.T6G(SCH_1):PAGE190
PC6007    2      B Q_CAP_0402-0.1UF,25V,10%,X7R,CH4104K1B00    I77 @T6G_MB_LIB.T6G(SCH_1):PAGE190
PC341_1    2      B Q_CAP_C0805-22UF,4V,20%,X6S,CH622KMEA03    I80 @T6G_MB_LIB.T6G(SCH_1):PAGE190
  PU31    2   AGND ISL99390FRZTR5935-ISL99390FRZ-TR5935,SMLF,IC,AL099A    I86 @T6G_MB_LIB.T6G(SCH_1):PAGE190
  PU31    5  PGND1 ISL99390FRZTR5935-ISL99390FRZ-TR5935,SMLF,IC,AL099A    I86 @T6G_MB_LIB.T6G(SCH_1):PAGE190
  PU31 7_9-20_24  PGND2 ISL99390FRZTR5935-ISL99390FRZ-TR5935,SMLF,IC,AL099A    I86 @T6G_MB_LIB.T6G(SCH_1):PAGE190
  PU31   40  PGND3 ISL99390FRZTR5935-ISL99390FRZ-TR5935,SMLF,IC,AL099A    I86 @T6G_MB_LIB.T6G(SCH_1):PAGE190
 C8356    2      B Q_CAP_0402-1000PF,50V,5%,X7R,TMP_QCH21006JB10     I3 @T6G_MB_LIB.T6G(SCH_1):PAGE192
  PQ16    S SOURCE MOSFET_N_SMLF-BSS138K,BSS138K,IC,BAM138K0000     I6 @T6G_MB_LIB.T6G(SCH_1):PAGE192
 PR231    2      B Q_RES_0402LF-10K,1%,1/16W,CHIP,CS31002FB08     I8 @T6G_MB_LIB.T6G(SCH_1):PAGE192
 PR244    2      B Q_RES_0402LF-9.53K,1%,1/16W,CHIP,CS29532FB06    I12 @T6G_MB_LIB.T6G(SCH_1):PAGE192
 PR460    2      B Q_RES_0402LF-49.9,1%,1/16W,CHIP,CS04992FB07    I19 @T6G_MB_LIB.T6G(SCH_1):PAGE192
 PR226    2      B Q_RES_0402LF-49.9,1%,1/16W,CHIP,CS04992FB07    I23 @T6G_MB_LIB.T6G(SCH_1):PAGE192
 PR217    2      B Q_RES_0402LF-0,5%,1/16W,CHIP,CS00002JB13    I29 @T6G_MB_LIB.T6G(SCH_1):PAGE192
 R8219    2      B Q_RES_0402LF-1K,1%,1/16W,EMPTY,CS21002FB06    I30 @T6G_MB_LIB.T6G(SCH_1):PAGE192
  C308    2      B Q_CAP_0402-10PF,50V,5%,EMPTY,CH01006JB08    I31 @T6G_MB_LIB.T6G(SCH_1):PAGE192
  C309    2      B Q_CAP_0402-10PF,50V,5%,EMPTY,CH01006JB08    I32 @T6G_MB_LIB.T6G(SCH_1):PAGE192
  C310    2      B Q_CAP_0402-10PF,50V,5%,EMPTY,CH01006JB08    I33 @T6G_MB_LIB.T6G(SCH_1):PAGE192
 PC357    2      B Q_CAP_0402-0.1UF,25V,10%,X7R,CH4104K1B00    I47 @T6G_MB_LIB.T6G(SCH_1):PAGE192
 C8362    2      B Q_CAP_0402-1000PF,50V,5%,EMPTY,TMP_QCH21006JB10    I52 @T6G_MB_LIB.T6G(SCH_1):PAGE192
 PR603    2      B Q_RES_0402LF-4.99K,1%,1/16W,EMPTY,CS24992FB07    I55 @T6G_MB_LIB.T6G(SCH_1):PAGE192
 PC364    2      B Q_CAP_0402-0.1UF,25V,10%,X7R,CH4104K1B00    I56 @T6G_MB_LIB.T6G(SCH_1):PAGE192
 PC363    2      B Q_CAP_0402-1UF,6.3V,10%,X7R,CH5101K1B01    I60 @T6G_MB_LIB.T6G(SCH_1):PAGE192
 PC368    2      B Q_CAP_0402-470PF,50V,10%,X7R,TMP_QCH14706KB18    I73 @T6G_MB_LIB.T6G(SCH_1):PAGE192
 PC367    2      B Q_CAP_0402-470PF,50V,10%,X7R,TMP_QCH14706KB18    I75 @T6G_MB_LIB.T6G(SCH_1):PAGE192
 PR533    2      B Q_RES_0402LF-0,5%,1/16W,CHIP,CS00002JB13    I76 @T6G_MB_LIB.T6G(SCH_1):PAGE192
 C8359    2      B Q_CAP_0402-1000PF,50V,5%,X7R,TMP_QCH21006JB10    I85 @T6G_MB_LIB.T6G(SCH_1):PAGE192
 C8360    2      B Q_CAP_0402-1000PF,50V,5%,EMPTY,TMP_QCH21006JB10    I90 @T6G_MB_LIB.T6G(SCH_1):PAGE192
  PC93    2      B Q_CAP_0402-0.1UF,25V,10%,X7R,CH4104K1B00    I93 @T6G_MB_LIB.T6G(SCH_1):PAGE192
  PC29    2      B Q_CAP_0402-0.1UF,25V,10%,X7R,CH4104K1B00    I95 @T6G_MB_LIB.T6G(SCH_1):PAGE192
 PC366    2      B Q_CAP_C0402-10UF,6.3V,20%,X6S,CH6101MEB03    I97 @T6G_MB_LIB.T6G(SCH_1):PAGE192
 PC365    2      B Q_CAP_C0402-1UF,16V,10%,X6S,CH5103KEB01    I99 @T6G_MB_LIB.T6G(SCH_1):PAGE192
  PR12    2      B Q_RES_0402LF-0,5%,1/16W,CHIP,CS00002JB13   I127 @T6G_MB_LIB.T6G(SCH_1):PAGE192
  PU34   TH TH_GND RAA229620GNPHA0-RAA229620GNP#HA0,SMLF,IC,ARF0TGP40A   I128 @T6G_MB_LIB.T6G(SCH_1):PAGE192
 PR254    2      B Q_RES_0402LF-8.87K,1%,1/16W,EMPTY,CS28872FB01     I4 @T6G_MB_LIB.T6G(SCH_1):PAGE193
PC374_1    2      B Q_CAP_0402-0.1UF,25V,10%,X7R,CH4104K1B00    I11 @T6G_MB_LIB.T6G(SCH_1):PAGE193
 PC370    2      B Q_CAP_C0402-2.2UF,10V,10%,X6S,CH5222KEB01    I12 @T6G_MB_LIB.T6G(SCH_1):PAGE193
PC372_C1P1_2    2      B Q_CAP_C0402-2.2UF,10V,10%,X6S,CH5222KEB01    I15 @T6G_MB_LIB.T6G(SCH_1):PAGE193
 PR255    2      B Q_RES_0402LF-8.87K,1%,1/16W,EMPTY,CS28872FB01    I17 @T6G_MB_LIB.T6G(SCH_1):PAGE193
PC371_C1P1_1    2      B Q_CAP_C0402-2.2UF,10V,10%,X6S,CH5222KEB01    I29 @T6G_MB_LIB.T6G(SCH_1):PAGE193
   PU5    2   AGND ISL99390FRZTR5935-ISL99390FRZ-TR5935,SMLF,IC,AL099A    I31 @T6G_MB_LIB.T6G(SCH_1):PAGE193
   PU5    5  PGND1 ISL99390FRZTR5935-ISL99390FRZ-TR5935,SMLF,IC,AL099A    I31 @T6G_MB_LIB.T6G(SCH_1):PAGE193
   PU5 7_9-20_24  PGND2 ISL99390FRZTR5935-ISL99390FRZ-TR5935,SMLF,IC,AL099A    I31 @T6G_MB_LIB.T6G(SCH_1):PAGE193
   PU5   40  PGND3 ISL99390FRZTR5935-ISL99390FRZ-TR5935,SMLF,IC,AL099A    I31 @T6G_MB_LIB.T6G(SCH_1):PAGE193
PC376_2    2      B Q_CAP_0402-0.1UF,25V,10%,X7R,CH4104K1B00    I34 @T6G_MB_LIB.T6G(SCH_1):PAGE193
 PR513    2      B Q_RES_0402LF-1.5,1%,1/8W,EMPTY,CS-1504FB00    I36 @T6G_MB_LIB.T6G(SCH_1):PAGE193
PC378_2    2      B Q_CAP_C0402-1UF,25V,10%,X6S,CH5104KEB02    I42 @T6G_MB_LIB.T6G(SCH_1):PAGE193
PC380_2    2      B Q_CAP_C0805-22UF,16V,20%,X6S,CH6223MEA01    I43 @T6G_MB_LIB.T6G(SCH_1):PAGE193
 PR512    2      B Q_RES_0402LF-1.5,1%,1/8W,EMPTY,CS-1504FB00    I45 @T6G_MB_LIB.T6G(SCH_1):PAGE193
PC385_2    2      B Q_CAP_C0805-22UF,16V,20%,X6S,CH6223MEA01    I48 @T6G_MB_LIB.T6G(SCH_1):PAGE193
PC375_1    2      B Q_CAP_0402-0.1UF,25V,10%,X7R,CH4104K1B00    I50 @T6G_MB_LIB.T6G(SCH_1):PAGE193
PC377_1    2      B Q_CAP_C0402-1UF,25V,10%,X6S,CH5104KEB02    I53 @T6G_MB_LIB.T6G(SCH_1):PAGE193
PC379_1    2      B Q_CAP_C0805-22UF,16V,20%,X6S,CH6223MEA01    I54 @T6G_MB_LIB.T6G(SCH_1):PAGE193
PC381_1    2      B Q_CAP_C0805-22UF,16V,20%,X6S,CH6223MEA01    I58 @T6G_MB_LIB.T6G(SCH_1):PAGE193
PC384_1    2      B Q_CAP_C0805-22UF,16V,20%,X6S,CH6223MEA01    I60 @T6G_MB_LIB.T6G(SCH_1):PAGE193
PC394_2    2      B Q_CAP_C0805-22UF,4V,20%,X6S,CH622KMEA03    I68 @T6G_MB_LIB.T6G(SCH_1):PAGE193
PC397_2    2      B Q_CAP_C0805-22UF,4V,20%,X6S,CH622KMEA03    I70 @T6G_MB_LIB.T6G(SCH_1):PAGE193
 PC389    2      B Q_CAPP_SMLF-220UF,4V,20%,SPCAP,CH122KM8801    I73 @T6G_MB_LIB.T6G(SCH_1):PAGE193
 PC392    2      B Q_CAP_0402-0.1UF,25V,10%,X7R,CH4104K1B00    I82 @T6G_MB_LIB.T6G(SCH_1):PAGE193
 PC375    2      B Q_CAP_0402-0.1UF,25V,10%,X7R,CH4104K1B00    I83 @T6G_MB_LIB.T6G(SCH_1):PAGE193
PC395_1    2      B Q_CAP_C0805-22UF,4V,20%,X6S,CH622KMEA03    I85 @T6G_MB_LIB.T6G(SCH_1):PAGE193
PC398_1    2      B Q_CAP_C0805-22UF,4V,20%,X6S,CH622KMEA03    I86 @T6G_MB_LIB.T6G(SCH_1):PAGE193
  PU35    2   AGND ISL99390FRZTR5935-ISL99390FRZ-TR5935,SMLF,IC,AL099A    I91 @T6G_MB_LIB.T6G(SCH_1):PAGE193
  PU35    5  PGND1 ISL99390FRZTR5935-ISL99390FRZ-TR5935,SMLF,IC,AL099A    I91 @T6G_MB_LIB.T6G(SCH_1):PAGE193
  PU35 7_9-20_24  PGND2 ISL99390FRZTR5935-ISL99390FRZ-TR5935,SMLF,IC,AL099A    I91 @T6G_MB_LIB.T6G(SCH_1):PAGE193
  PU35   40  PGND3 ISL99390FRZTR5935-ISL99390FRZ-TR5935,SMLF,IC,AL099A    I91 @T6G_MB_LIB.T6G(SCH_1):PAGE193
 PR262    2      B Q_RES_0402LF-8.87K,1%,1/16W,EMPTY,CS28872FB01     I4 @T6G_MB_LIB.T6G(SCH_1):PAGE194
 PC399    2      B Q_CAP_C0402-2.2UF,10V,10%,X6S,CH5222KEB01     I7 @T6G_MB_LIB.T6G(SCH_1):PAGE194
PC404_3    2      B Q_CAP_0402-0.1UF,25V,10%,X7R,CH4104K1B00    I12 @T6G_MB_LIB.T6G(SCH_1):PAGE194
PC401_C1P1_4    2      B Q_CAP_C0402-2.2UF,10V,10%,X6S,CH5222KEB01    I16 @T6G_MB_LIB.T6G(SCH_1):PAGE194
 PR263    2      B Q_RES_0402LF-8.87K,1%,1/16W,EMPTY,CS28872FB01    I18 @T6G_MB_LIB.T6G(SCH_1):PAGE194
  PU36    2   AGND ISL99390FRZTR5935-ISL99390FRZ-TR5935,SMLF,IC,AL099A    I21 @T6G_MB_LIB.T6G(SCH_1):PAGE194
  PU36    5  PGND1 ISL99390FRZTR5935-ISL99390FRZ-TR5935,SMLF,IC,AL099A    I21 @T6G_MB_LIB.T6G(SCH_1):PAGE194
  PU36 7_9-20_24  PGND2 ISL99390FRZTR5935-ISL99390FRZ-TR5935,SMLF,IC,AL099A    I21 @T6G_MB_LIB.T6G(SCH_1):PAGE194
  PU36   40  PGND3 ISL99390FRZTR5935-ISL99390FRZ-TR5935,SMLF,IC,AL099A    I21 @T6G_MB_LIB.T6G(SCH_1):PAGE194
PC405_4    2      B Q_CAP_0402-0.1UF,25V,10%,X7R,CH4104K1B00    I23 @T6G_MB_LIB.T6G(SCH_1):PAGE194
 PC400    2      B Q_CAP_C0402-2.2UF,10V,10%,X6S,CH5222KEB01    I27 @T6G_MB_LIB.T6G(SCH_1):PAGE194
PC402_C1P1_3    2      B Q_CAP_C0402-2.2UF,10V,10%,X6S,CH5222KEB01    I31 @T6G_MB_LIB.T6G(SCH_1):PAGE194
PC408_3    2      B Q_CAP_0402-0.1UF,25V,10%,X7R,CH4104K1B00    I33 @T6G_MB_LIB.T6G(SCH_1):PAGE194
 PR515    2      B Q_RES_0402LF-1.5,1%,1/8W,EMPTY,CS-1504FB00    I35 @T6G_MB_LIB.T6G(SCH_1):PAGE194
PC407_4    2      B Q_CAP_C0402-1UF,25V,10%,X6S,CH5104KEB02    I41 @T6G_MB_LIB.T6G(SCH_1):PAGE194
 PR516    2      B Q_RES_0402LF-1.5,1%,1/8W,EMPTY,CS-1504FB00    I44 @T6G_MB_LIB.T6G(SCH_1):PAGE194
PC411_4    2      B Q_CAP_C0805-22UF,16V,20%,X6S,CH6223MEA01    I45 @T6G_MB_LIB.T6G(SCH_1):PAGE194
PC415_4    2      B Q_CAP_C0805-22UF,16V,20%,X6S,CH6223MEA01    I47 @T6G_MB_LIB.T6G(SCH_1):PAGE194
PC406_3    2      B Q_CAP_C0402-1UF,25V,10%,X6S,CH5104KEB02    I54 @T6G_MB_LIB.T6G(SCH_1):PAGE194
PC412_3    2      B Q_CAP_C0805-22UF,16V,20%,X6S,CH6223MEA01    I59 @T6G_MB_LIB.T6G(SCH_1):PAGE194
PC416_3    2      B Q_CAP_C0805-22UF,16V,20%,X6S,CH6223MEA01    I60 @T6G_MB_LIB.T6G(SCH_1):PAGE194
PC417_3    2      B Q_CAP_C0805-22UF,4V,20%,X6S,CH622KMEA03    I64 @T6G_MB_LIB.T6G(SCH_1):PAGE194
PC418_4    2      B Q_CAP_C0805-22UF,4V,20%,X6S,CH622KMEA03    I65 @T6G_MB_LIB.T6G(SCH_1):PAGE194
PC420_4    2      B Q_CAP_C0805-22UF,4V,20%,X6S,CH622KMEA03    I67 @T6G_MB_LIB.T6G(SCH_1):PAGE194
PC419_3    2      B Q_CAP_C0805-22UF,4V,20%,X6S,CH622KMEA03    I70 @T6G_MB_LIB.T6G(SCH_1):PAGE194
  PU37    2   AGND ISL99390FRZTR5935-ISL99390FRZ-TR5935,SMLF,IC,AL099A    I72 @T6G_MB_LIB.T6G(SCH_1):PAGE194
  PU37    5  PGND1 ISL99390FRZTR5935-ISL99390FRZ-TR5935,SMLF,IC,AL099A    I72 @T6G_MB_LIB.T6G(SCH_1):PAGE194
  PU37 7_9-20_24  PGND2 ISL99390FRZTR5935-ISL99390FRZ-TR5935,SMLF,IC,AL099A    I72 @T6G_MB_LIB.T6G(SCH_1):PAGE194
  PU37   40  PGND3 ISL99390FRZTR5935-ISL99390FRZ-TR5935,SMLF,IC,AL099A    I72 @T6G_MB_LIB.T6G(SCH_1):PAGE194
PC136_6    2      B Q_CAP_0402-0.1UF,25V,10%,X7R,CH4104K1B00     I1 @T6G_MB_LIB.T6G(SCH_1):PAGE195
 PR426    2      B Q_RES_0402LF-8.87K,1%,1/16W,EMPTY,CS28872FB01     I4 @T6G_MB_LIB.T6G(SCH_1):PAGE195
PC422_5    2      B Q_CAP_0402-0.1UF,25V,10%,X7R,CH4104K1B00    I10 @T6G_MB_LIB.T6G(SCH_1):PAGE195
 PC138    2      B Q_CAP_C0402-2.2UF,10V,10%,X6S,CH5222KEB01    I12 @T6G_MB_LIB.T6G(SCH_1):PAGE195
 PR270    2      B Q_RES_0402LF-8.87K,1%,1/16W,EMPTY,CS28872FB01    I15 @T6G_MB_LIB.T6G(SCH_1):PAGE195
  PU33    2   AGND ISL99390FRZTR5935-ISL99390FRZ-TR5935,SMLF,IC,AL099A    I19 @T6G_MB_LIB.T6G(SCH_1):PAGE195
  PU33    5  PGND1 ISL99390FRZTR5935-ISL99390FRZ-TR5935,SMLF,IC,AL099A    I19 @T6G_MB_LIB.T6G(SCH_1):PAGE195
  PU33 7_9-20_24  PGND2 ISL99390FRZTR5935-ISL99390FRZ-TR5935,SMLF,IC,AL099A    I19 @T6G_MB_LIB.T6G(SCH_1):PAGE195
  PU33   40  PGND3 ISL99390FRZTR5935-ISL99390FRZ-TR5935,SMLF,IC,AL099A    I19 @T6G_MB_LIB.T6G(SCH_1):PAGE195
PC139_C1P1_6    2      B Q_CAP_C0402-2.2UF,10V,10%,X6S,CH5222KEB01    I22 @T6G_MB_LIB.T6G(SCH_1):PAGE195
 PC421    2      B Q_CAP_C0402-2.2UF,10V,10%,X6S,CH5222KEB01    I27 @T6G_MB_LIB.T6G(SCH_1):PAGE195
 PR518    2      B Q_RES_0402LF-1.5,1%,1/8W,EMPTY,CS-1504FB00    I33 @T6G_MB_LIB.T6G(SCH_1):PAGE195
  PL39    2      2 Q_INDUCTOR_SMLF-120NH/69A,IND,CV+12^0EZ03    I37 @T6G_MB_LIB.T6G(SCH_1):PAGE195
PC141_6    2      B Q_CAP_0402-0.1UF,25V,10%,X7R,CH4104K1B00    I38 @T6G_MB_LIB.T6G(SCH_1):PAGE195
PC144_6    2      B Q_CAP_C0805-22UF,16V,20%,X6S,CH6223MEA01    I41 @T6G_MB_LIB.T6G(SCH_1):PAGE195
 PR517    2      B Q_RES_0402LF-1.5,1%,1/8W,EMPTY,CS-1504FB00    I43 @T6G_MB_LIB.T6G(SCH_1):PAGE195
PC145_6    2      B Q_CAP_C0805-22UF,16V,20%,X6S,CH6223MEA01    I44 @T6G_MB_LIB.T6G(SCH_1):PAGE195
PC147_6    2      B Q_CAP_C0805-22UF,16V,20%,X6S,CH6223MEA01    I47 @T6G_MB_LIB.T6G(SCH_1):PAGE195
PC425_5    2      B Q_CAP_0402-0.1UF,25V,10%,X7R,CH4104K1B00    I54 @T6G_MB_LIB.T6G(SCH_1):PAGE195
PC424_5    2      B Q_CAP_C0402-1UF,25V,10%,X6S,CH5104KEB02    I55 @T6G_MB_LIB.T6G(SCH_1):PAGE195
PC426_5    2      B Q_CAP_C0805-22UF,16V,20%,X6S,CH6223MEA01    I56 @T6G_MB_LIB.T6G(SCH_1):PAGE195
PC429_5    2      B Q_CAP_C0805-22UF,16V,20%,X6S,CH6223MEA01    I61 @T6G_MB_LIB.T6G(SCH_1):PAGE195
PC148_6    2      B Q_CAP_C0805-22UF,4V,20%,X6S,CH622KMEA03    I65 @T6G_MB_LIB.T6G(SCH_1):PAGE195
PC149_6    2      B Q_CAP_C0805-22UF,4V,20%,X6S,CH622KMEA03    I67 @T6G_MB_LIB.T6G(SCH_1):PAGE195
PC430_5    2      B Q_CAP_C0805-22UF,4V,20%,X6S,CH622KMEA03    I70 @T6G_MB_LIB.T6G(SCH_1):PAGE195
PC431_5    2      B Q_CAP_C0805-22UF,4V,20%,X6S,CH622KMEA03    I71 @T6G_MB_LIB.T6G(SCH_1):PAGE195
  PU38    2   AGND ISL99390FRZTR5935-ISL99390FRZ-TR5935,SMLF,IC,AL099A    I73 @T6G_MB_LIB.T6G(SCH_1):PAGE195
  PU38    5  PGND1 ISL99390FRZTR5935-ISL99390FRZ-TR5935,SMLF,IC,AL099A    I73 @T6G_MB_LIB.T6G(SCH_1):PAGE195
  PU38 7_9-20_24  PGND2 ISL99390FRZTR5935-ISL99390FRZ-TR5935,SMLF,IC,AL099A    I73 @T6G_MB_LIB.T6G(SCH_1):PAGE195
  PU38   40  PGND3 ISL99390FRZTR5935-ISL99390FRZ-TR5935,SMLF,IC,AL099A    I73 @T6G_MB_LIB.T6G(SCH_1):PAGE195
PC436_8    2      B Q_CAP_0402-0.1UF,25V,10%,X7R,CH4104K1B00     I3 @T6G_MB_LIB.T6G(SCH_1):PAGE197
PC435_7    2      B Q_CAP_0402-0.1UF,25V,10%,X7R,CH4104K1B00     I4 @T6G_MB_LIB.T6G(SCH_1):PAGE197
 PR274    2      B Q_RES_0402LF-8.87K,1%,1/16W,EMPTY,CS28872FB01     I6 @T6G_MB_LIB.T6G(SCH_1):PAGE197
 PC432    2      B Q_CAP_C0402-2.2UF,10V,10%,X6S,CH5222KEB01    I12 @T6G_MB_LIB.T6G(SCH_1):PAGE197
PC434_IOP1_2    2      B Q_CAP_C0402-2.2UF,10V,10%,X6S,CH5222KEB01    I16 @T6G_MB_LIB.T6G(SCH_1):PAGE197
 PR489    2      B Q_RES_0402LF-1.5,1%,1/8W,EMPTY,CS-1504FB00    I19 @T6G_MB_LIB.T6G(SCH_1):PAGE197
PC439_2    2      B Q_CAP_0402-0.1UF,25V,10%,X7R,CH4104K1B00    I21 @T6G_MB_LIB.T6G(SCH_1):PAGE197
PC441_2    2      B Q_CAP_C0402-1UF,25V,10%,X6S,CH5104KEB02    I23 @T6G_MB_LIB.T6G(SCH_1):PAGE197
 PR488    2      B Q_RES_0402LF-1.5,1%,1/8W,EMPTY,CS-1504FB00    I26 @T6G_MB_LIB.T6G(SCH_1):PAGE197
 PR275    2      B Q_RES_0402LF-8.87K,1%,1/16W,EMPTY,CS28872FB01    I28 @T6G_MB_LIB.T6G(SCH_1):PAGE197
 PC433    2      B Q_CAP_C0402-2.2UF,10V,10%,X6S,CH5222KEB01    I34 @T6G_MB_LIB.T6G(SCH_1):PAGE197
PC437_IOP1_1    2      B Q_CAP_C0402-2.2UF,10V,10%,X6S,CH5222KEB01    I38 @T6G_MB_LIB.T6G(SCH_1):PAGE197
  PU39    2   AGND ISL99390FRZTR5935-ISL99390FRZ-TR5935,SMLF,IC,AL099A    I39 @T6G_MB_LIB.T6G(SCH_1):PAGE197
  PU39    5  PGND1 ISL99390FRZTR5935-ISL99390FRZ-TR5935,SMLF,IC,AL099A    I39 @T6G_MB_LIB.T6G(SCH_1):PAGE197
  PU39 7_9-20_24  PGND2 ISL99390FRZTR5935-ISL99390FRZ-TR5935,SMLF,IC,AL099A    I39 @T6G_MB_LIB.T6G(SCH_1):PAGE197
  PU39   40  PGND3 ISL99390FRZTR5935-ISL99390FRZ-TR5935,SMLF,IC,AL099A    I39 @T6G_MB_LIB.T6G(SCH_1):PAGE197
PC438_1    2      B Q_CAP_0402-0.1UF,25V,10%,X7R,CH4104K1B00    I41 @T6G_MB_LIB.T6G(SCH_1):PAGE197
PC440_1    2      B Q_CAP_C0402-1UF,25V,10%,X6S,CH5104KEB02    I42 @T6G_MB_LIB.T6G(SCH_1):PAGE197
PC442_1    2      B Q_CAP_C0805-22UF,16V,20%,X6S,CH6223MEA01    I44 @T6G_MB_LIB.T6G(SCH_1):PAGE197
PC443_2    2      B Q_CAP_C0805-22UF,16V,20%,X6S,CH6223MEA01    I48 @T6G_MB_LIB.T6G(SCH_1):PAGE197
PC446_2    2      B Q_CAP_C0805-22UF,16V,20%,X6S,CH6223MEA01    I49 @T6G_MB_LIB.T6G(SCH_1):PAGE197
PC449_2    2      B Q_CAP_C0805-22UF,16V,20%,X6S,CH6223MEA01    I52 @T6G_MB_LIB.T6G(SCH_1):PAGE197
PC458_2    2      B Q_CAP_C0805-22UF,4V,20%,X6S,CH622KMEA03    I55 @T6G_MB_LIB.T6G(SCH_1):PAGE197
PC460_2    2      B Q_CAP_C0805-22UF,4V,20%,X6S,CH622KMEA03    I57 @T6G_MB_LIB.T6G(SCH_1):PAGE197
 PC450    2      B Q_CAPP_SMLF-470UF,2.5V,20%,SPCAP,CH747LM8825    I58 @T6G_MB_LIB.T6G(SCH_1):PAGE197
 PC452    2      B Q_CAPP_SMLF-470UF,2.5V,20%,SPCAP,CH747LM8825    I59 @T6G_MB_LIB.T6G(SCH_1):PAGE197
 PC455    2      B Q_CAPP_SMLF-470UF,2.5V,20%,EMPTY,CH747LM8825    I62 @T6G_MB_LIB.T6G(SCH_1):PAGE197
PC444_1    2      B Q_CAP_C0805-22UF,16V,20%,X6S,CH6223MEA01    I66 @T6G_MB_LIB.T6G(SCH_1):PAGE197
PC448_1    2      B Q_CAP_C0805-22UF,16V,20%,X6S,CH6223MEA01    I69 @T6G_MB_LIB.T6G(SCH_1):PAGE197
  PL47    3      3 Q_INDUCTOR4P_14-150NH,SMLF,IND,CV+15^0TZ04    I71 @T6G_MB_LIB.T6G(SCH_1):PAGE197
 PC438    2      B Q_CAP_0402-0.1UF,25V,10%,X7R,CH4104K1B00    I74 @T6G_MB_LIB.T6G(SCH_1):PAGE197
 PC451    2      B Q_CAP_C0402-100NF,50V,10%,X7R,CH4106K1B01    I77 @T6G_MB_LIB.T6G(SCH_1):PAGE197
PC456_1    2      B Q_CAP_C0805-22UF,4V,20%,X6S,CH622KMEA03    I78 @T6G_MB_LIB.T6G(SCH_1):PAGE197
PC459_1    2      B Q_CAP_C0805-22UF,4V,20%,X6S,CH622KMEA03    I79 @T6G_MB_LIB.T6G(SCH_1):PAGE197
 PR378    2      B Q_RES_0402LF-1K,1%,1/16W,CHIP,CS21002FB06    I81 @T6G_MB_LIB.T6G(SCH_1):PAGE197
  PU40    2   AGND ISL99390FRZTR5935-ISL99390FRZ-TR5935,SMLF,IC,AL099A    I84 @T6G_MB_LIB.T6G(SCH_1):PAGE197
  PU40    5  PGND1 ISL99390FRZTR5935-ISL99390FRZ-TR5935,SMLF,IC,AL099A    I84 @T6G_MB_LIB.T6G(SCH_1):PAGE197
  PU40 7_9-20_24  PGND2 ISL99390FRZTR5935-ISL99390FRZ-TR5935,SMLF,IC,AL099A    I84 @T6G_MB_LIB.T6G(SCH_1):PAGE197
  PU40   40  PGND3 ISL99390FRZTR5935-ISL99390FRZ-TR5935,SMLF,IC,AL099A    I84 @T6G_MB_LIB.T6G(SCH_1):PAGE197
 PR368    2      B Q_RES_0402LF-8.87K,1%,1/16W,EMPTY,CS28872FB01     I4 @T6G_MB_LIB.T6G(SCH_1):PAGE198
 PC616    2      B Q_CAP_C0402-2.2UF,10V,10%,X6S,CH5222KEB01    I10 @T6G_MB_LIB.T6G(SCH_1):PAGE198
PC618_IOP1_4    2      B Q_CAP_C0402-2.2UF,10V,10%,X6S,CH5222KEB01    I13 @T6G_MB_LIB.T6G(SCH_1):PAGE198
PC623_4    2      B Q_CAP_0402-0.1UF,25V,10%,X7R,CH4104K1B00    I18 @T6G_MB_LIB.T6G(SCH_1):PAGE198
PC620_9    2      B Q_CAP_0402-0.1UF,25V,10%,X7R,CH4104K1B00    I20 @T6G_MB_LIB.T6G(SCH_1):PAGE198
 PR369    2      B Q_RES_0402LF-8.87K,1%,1/16W,EMPTY,CS28872FB01    I22 @T6G_MB_LIB.T6G(SCH_1):PAGE198
PC619_IOP1_3    2      B Q_CAP_C0402-2.2UF,10V,10%,X6S,CH5222KEB01    I31 @T6G_MB_LIB.T6G(SCH_1):PAGE198
PC622_3    2      B Q_CAP_0402-0.1UF,25V,10%,X7R,CH4104K1B00    I35 @T6G_MB_LIB.T6G(SCH_1):PAGE198
PC624_3    2      B Q_CAP_C0402-1UF,25V,10%,X6S,CH5104KEB02    I36 @T6G_MB_LIB.T6G(SCH_1):PAGE198
 PR491    2      B Q_RES_0402LF-1.5,1%,1/8W,EMPTY,CS-1504FB00    I39 @T6G_MB_LIB.T6G(SCH_1):PAGE198
  PL46    2      2 Q_INDUCTOR_SMLF-0.22UH/33A,IND,CV+22Y0EZ00    I43 @T6G_MB_LIB.T6G(SCH_1):PAGE198
PC625_4    2      B Q_CAP_C0402-1UF,25V,10%,X6S,CH5104KEB02    I45 @T6G_MB_LIB.T6G(SCH_1):PAGE198
PC633_4    2      B Q_CAP_C0805-22UF,16V,20%,X6S,CH6223MEA01    I48 @T6G_MB_LIB.T6G(SCH_1):PAGE198
PC636_4    2      B Q_CAP_C0805-22UF,4V,20%,X6S,CH622KMEA03    I53 @T6G_MB_LIB.T6G(SCH_1):PAGE198
PC626_3    2      B Q_CAP_C0805-22UF,16V,20%,X6S,CH6223MEA01    I60 @T6G_MB_LIB.T6G(SCH_1):PAGE198
PC628_3    2      B Q_CAP_C0805-22UF,16V,20%,X6S,CH6223MEA01    I61 @T6G_MB_LIB.T6G(SCH_1):PAGE198
PC637_3    2      B Q_CAP_C0805-22UF,4V,20%,X6S,CH622KMEA03    I70 @T6G_MB_LIB.T6G(SCH_1):PAGE198
PC627_4    2      B Q_CAP_C0805-22UF,16V,20%,X6S,CH6223MEA01    I72 @T6G_MB_LIB.T6G(SCH_1):PAGE198
  PU52    2   AGND ISL99390FRZTR5935-ISL99390FRZ-TR5935,SMLF,IC,AL099A    I73 @T6G_MB_LIB.T6G(SCH_1):PAGE198
  PU52    5  PGND1 ISL99390FRZTR5935-ISL99390FRZ-TR5935,SMLF,IC,AL099A    I73 @T6G_MB_LIB.T6G(SCH_1):PAGE198
  PU52 7_9-20_24  PGND2 ISL99390FRZTR5935-ISL99390FRZ-TR5935,SMLF,IC,AL099A    I73 @T6G_MB_LIB.T6G(SCH_1):PAGE198
  PU52   40  PGND3 ISL99390FRZTR5935-ISL99390FRZ-TR5935,SMLF,IC,AL099A    I73 @T6G_MB_LIB.T6G(SCH_1):PAGE198
 PC638    2      B Q_CAP_0402-0.1UF,25V,10%,X7R,CH4104K1B00     I4 @T6G_MB_LIB.T6G(SCH_1):PAGE199
   PR6    2      B Q_RES_0402LF-10K,1%,1/16W,CHIP,CS31002FB08     I6 @T6G_MB_LIB.T6G(SCH_1):PAGE199
 PR288    2      B Q_RES_0402LF-49.9,1%,1/16W,CHIP,CS04992FB07    I15 @T6G_MB_LIB.T6G(SCH_1):PAGE199
 PR604    2      B Q_RES_0402LF-4.99K,1%,1/16W,EMPTY,CS24992FB07    I17 @T6G_MB_LIB.T6G(SCH_1):PAGE199
   PC8    2      B Q_CAP_0402-0.1UF,25V,10%,X7R,CH4104K1B00    I20 @T6G_MB_LIB.T6G(SCH_1):PAGE199
  C642    2      B Q_CAP_0402-1000PF,50V,5%,X7R,TMP_QCH21006JB10    I44 @T6G_MB_LIB.T6G(SCH_1):PAGE199
 C8641    2      B Q_CAP_0402-1000PF,50V,5%,EMPTY,TMP_QCH21006JB10    I46 @T6G_MB_LIB.T6G(SCH_1):PAGE199
 PC643    2      B Q_CAP_0402-470PF,50V,10%,X7R,TMP_QCH14706KB18    I49 @T6G_MB_LIB.T6G(SCH_1):PAGE199
 PR415    2      B Q_RES_0402LF-0,5%,1/16W,CHIP,CS00002JB13    I51 @T6G_MB_LIB.T6G(SCH_1):PAGE199
 PR409    2      B Q_RES_0402LF-0,5%,1/16W,CHIP,CS00002JB13    I52 @T6G_MB_LIB.T6G(SCH_1):PAGE199
 PR390    2      B Q_RES_0402LF-0,5%,1/16W,EMPTY,CS00002JB13    I56 @T6G_MB_LIB.T6G(SCH_1):PAGE199
 PR408    2      B Q_RES_0402LF-0,5%,1/16W,CHIP,CS00002JB13    I57 @T6G_MB_LIB.T6G(SCH_1):PAGE199
  PR14    2      B Q_RES_0402LF-0,5%,1/16W,CHIP,CS00002JB13    I58 @T6G_MB_LIB.T6G(SCH_1):PAGE199
  PR13    2      B Q_RES_0402LF-0,5%,1/16W,CHIP,CS00002JB13    I59 @T6G_MB_LIB.T6G(SCH_1):PAGE199
 PR407    2      B Q_RES_0402LF-0,5%,1/16W,CHIP,CS00002JB13    I60 @T6G_MB_LIB.T6G(SCH_1):PAGE199
 PR406    2      B Q_RES_0402LF-0,5%,1/16W,CHIP,CS00002JB13    I70 @T6G_MB_LIB.T6G(SCH_1):PAGE199
  PC96    2      B Q_CAP_0402-0.1UF,25V,10%,X7R,CH4104K1B00    I72 @T6G_MB_LIB.T6G(SCH_1):PAGE199
  PC95    2      B Q_CAP_0402-0.1UF,25V,10%,X7R,CH4104K1B00    I73 @T6G_MB_LIB.T6G(SCH_1):PAGE199
 PC644    2      B Q_CAP_C0402-10UF,6.3V,20%,X6S,CH6101MEB03    I80 @T6G_MB_LIB.T6G(SCH_1):PAGE199
 PC645    2      B Q_CAP_C0402-1UF,16V,10%,X6S,CH5103KEB01    I81 @T6G_MB_LIB.T6G(SCH_1):PAGE199
  PU54   31  RGND1 RAA229621GNPHA0-RAA229621GNP#HA0,SMLF,IC,ARF0TGP40A    I86 @T6G_MB_LIB.T6G(SCH_1):PAGE199
  PU54   18    SVC RAA229621GNPHA0-RAA229621GNP#HA0,SMLF,IC,ARF0TGP40A    I86 @T6G_MB_LIB.T6G(SCH_1):PAGE199
  PU54   17    SVD RAA229621GNPHA0-RAA229621GNP#HA0,SMLF,IC,ARF0TGP40A    I86 @T6G_MB_LIB.T6G(SCH_1):PAGE199
  PU54   20   SVTI RAA229621GNPHA0-RAA229621GNP#HA0,SMLF,IC,ARF0TGP40A    I86 @T6G_MB_LIB.T6G(SCH_1):PAGE199
  PU54   TH TH_GND RAA229621GNPHA0-RAA229621GNP#HA0,SMLF,IC,ARF0TGP40A    I86 @T6G_MB_LIB.T6G(SCH_1):PAGE199
  PU54   32  VSEN1 RAA229621GNPHA0-RAA229621GNP#HA0,SMLF,IC,ARF0TGP40A    I86 @T6G_MB_LIB.T6G(SCH_1):PAGE199
PC504_2    2      B Q_CAP_0402-0.1UF,25V,10%,X7R,CH4104K1B00     I8 @T6G_MB_LIB.T6G(SCH_1):PAGE200
 PC506    2      B Q_CAP_C0402-2.2UF,10V,10%,X6S,CH5222KEB01    I10 @T6G_MB_LIB.T6G(SCH_1):PAGE200
 PR329    1      A Q_RES_0402LF-4.87K,1%,1/16W,EMPTY,CS24872FB07    I12 @T6G_MB_LIB.T6G(SCH_1):PAGE200
PC508_11P1_2    2      B Q_CAP_C0402-2.2UF,10V,10%,X6S,CH5222KEB01    I17 @T6G_MB_LIB.T6G(SCH_1):PAGE200
  PU44    2   AGND ISL99390FRZTR5935-ISL99390FRZ-TR5935,SMLF,IC,AL099A    I22 @T6G_MB_LIB.T6G(SCH_1):PAGE200
  PU44    5  PGND1 ISL99390FRZTR5935-ISL99390FRZ-TR5935,SMLF,IC,AL099A    I22 @T6G_MB_LIB.T6G(SCH_1):PAGE200
  PU44 7_9-20_24  PGND2 ISL99390FRZTR5935-ISL99390FRZ-TR5935,SMLF,IC,AL099A    I22 @T6G_MB_LIB.T6G(SCH_1):PAGE200
  PU44   40  PGND3 ISL99390FRZTR5935-ISL99390FRZ-TR5935,SMLF,IC,AL099A    I22 @T6G_MB_LIB.T6G(SCH_1):PAGE200
PC514_2    2      B Q_CAP_C0805-22UF,16V,20%,X6S,CH6223MEA01    I30 @T6G_MB_LIB.T6G(SCH_1):PAGE200
PC516_2    2      B Q_CAP_C0805-22UF,16V,20%,X6S,CH6223MEA01    I31 @T6G_MB_LIB.T6G(SCH_1):PAGE200
 PR520    2      B Q_RES_0402LF-1.5,1%,1/8W,EMPTY,CS-1504FB00    I33 @T6G_MB_LIB.T6G(SCH_1):PAGE200
 PC505    2      B Q_CAP_C0402-2.2UF,10V,10%,X6S,CH5222KEB01    I36 @T6G_MB_LIB.T6G(SCH_1):PAGE200
PC511_1    2      B Q_CAP_C0402-1UF,25V,10%,X6S,CH5104KEB02    I45 @T6G_MB_LIB.T6G(SCH_1):PAGE200
PC513_1    2      B Q_CAP_C0805-22UF,16V,20%,X6S,CH6223MEA01    I49 @T6G_MB_LIB.T6G(SCH_1):PAGE200
PC515_1    2      B Q_CAP_C0805-22UF,16V,20%,X6S,CH6223MEA01    I50 @T6G_MB_LIB.T6G(SCH_1):PAGE200
PC517_1    2      B Q_CAP_C0805-22UF,16V,20%,X6S,CH6223MEA01    I51 @T6G_MB_LIB.T6G(SCH_1):PAGE200
PC523_2    2      B Q_CAP_C0805-22UF,4V,20%,X6S,CH622KMEA03    I56 @T6G_MB_LIB.T6G(SCH_1):PAGE200
  PC27    2      B Q_CAP_C0805-22UF,16V,20%,X6S,CH6223MEA01    I58 @T6G_MB_LIB.T6G(SCH_1):PAGE200
 PC525    2      B Q_CAPP_SMLF-470UF,2.5V,20%,SPCAP,CH747LM8825    I62 @T6G_MB_LIB.T6G(SCH_1):PAGE200
 PC802    2      B Q_CAPP_SMLF-470UF,2.5V,20%,SPCAP,CH747LM8825    I65 @T6G_MB_LIB.T6G(SCH_1):PAGE200
 PC531    2      B Q_CAPP_SMLF-390UF,2.5V,20%,ALUM,CC7390JMZ13    I72 @T6G_MB_LIB.T6G(SCH_1):PAGE200
 PC532    2      B Q_CAPP_SMLF-390UF,2.5V,20%,ALUM,CC7390JMZ13    I73 @T6G_MB_LIB.T6G(SCH_1):PAGE200
 PC803    2      B Q_CAPP_SMLF-390UF,2.5V,20%,ALUM,CC7390JMZ13    I75 @T6G_MB_LIB.T6G(SCH_1):PAGE200
PC521_1    2      B Q_CAP_C0805-22UF,16V,20%,X6S,CH6223MEA01    I80 @T6G_MB_LIB.T6G(SCH_1):PAGE200
 PC524    2      B Q_CAP_C0402-100NF,50V,10%,X7R,CH4106K1B01    I82 @T6G_MB_LIB.T6G(SCH_1):PAGE200
 PC511    2      B Q_CAP_0402-0.1UF,25V,10%,X7R,CH4104K1B00    I85 @T6G_MB_LIB.T6G(SCH_1):PAGE200
PC526_1    2      B Q_CAP_C0805-22UF,4V,20%,X6S,CH622KMEA03    I87 @T6G_MB_LIB.T6G(SCH_1):PAGE200
PC529_1    2      B Q_CAP_C0805-22UF,4V,20%,X6S,CH622KMEA03    I88 @T6G_MB_LIB.T6G(SCH_1):PAGE200
 PR395    2      B Q_RES_0402LF-1K,1%,1/16W,CHIP,CS21002FB06    I89 @T6G_MB_LIB.T6G(SCH_1):PAGE200
PC512_2    2      B Q_CAP_C0402-1UF,25V,10%,X6S,CH5104KEB02    I91 @T6G_MB_LIB.T6G(SCH_1):PAGE200
  PU45    2   AGND ISL99390FRZTR5935-ISL99390FRZ-TR5935,SMLF,IC,AL099A    I92 @T6G_MB_LIB.T6G(SCH_1):PAGE200
  PU45    5  PGND1 ISL99390FRZTR5935-ISL99390FRZ-TR5935,SMLF,IC,AL099A    I92 @T6G_MB_LIB.T6G(SCH_1):PAGE200
  PU45 7_9-20_24  PGND2 ISL99390FRZTR5935-ISL99390FRZ-TR5935,SMLF,IC,AL099A    I92 @T6G_MB_LIB.T6G(SCH_1):PAGE200
  PU45   40  PGND3 ISL99390FRZTR5935-ISL99390FRZ-TR5935,SMLF,IC,AL099A    I92 @T6G_MB_LIB.T6G(SCH_1):PAGE200
 PR398    1      A Q_RES_0402LF-0,5%,1/16W,CHIP,CS00002JB13    I14 @T6G_MB_LIB.T6G(SCH_1):PAGE201
 PR399    1      A Q_RES_0402LF-49.9,1%,1/16W,CHIP,CS04992FB07    I29 @T6G_MB_LIB.T6G(SCH_1):PAGE201
  PC84    2      B Q_CAP_C0805-22UF,4V,20%,X6S,CH622KMEA03    I40 @T6G_MB_LIB.T6G(SCH_1):PAGE201
  PC87    2      B Q_CAP_C0805-22UF,4V,20%,EMPTY,CH622KMEA03    I41 @T6G_MB_LIB.T6G(SCH_1):PAGE201
  PC21    2      B Q_CAP_0402-0.1UF,25V,10%,X7R,CH4104K1B00    I47 @T6G_MB_LIB.T6G(SCH_1):PAGE201
  PC60    2      B Q_CAP_C0805-22UF,16V,20%,X6S,CH6223MEA01    I54 @T6G_MB_LIB.T6G(SCH_1):PAGE201
   U18   A1   GND1 LCMXO3LF9400C5BG484C-LCMXO3LF-9400C-5BG484C,SMLF,IA     I1 @T6G_MB_LIB.T6G(SCH_1):PAGE81
   U18  A22   GND2 LCMXO3LF9400C5BG484C-LCMXO3LF-9400C-5BG484C,SMLF,IA     I1 @T6G_MB_LIB.T6G(SCH_1):PAGE81
   U18   B7   GND3 LCMXO3LF9400C5BG484C-LCMXO3LF-9400C-5BG484C,SMLF,IA     I1 @T6G_MB_LIB.T6G(SCH_1):PAGE81
   U18  B16   GND4 LCMXO3LF9400C5BG484C-LCMXO3LF-9400C-5BG484C,SMLF,IA     I1 @T6G_MB_LIB.T6G(SCH_1):PAGE81
   U18   C2   GND5 LCMXO3LF9400C5BG484C-LCMXO3LF-9400C-5BG484C,SMLF,IA     I1 @T6G_MB_LIB.T6G(SCH_1):PAGE81
   U18  C11   GND6 LCMXO3LF9400C5BG484C-LCMXO3LF-9400C-5BG484C,SMLF,IA     I1 @T6G_MB_LIB.T6G(SCH_1):PAGE81
   U18   E5   GND7 LCMXO3LF9400C5BG484C-LCMXO3LF-9400C-5BG484C,SMLF,IA     I1 @T6G_MB_LIB.T6G(SCH_1):PAGE81
   U18  E18   GND8 LCMXO3LF9400C5BG484C-LCMXO3LF-9400C-5BG484C,SMLF,IA     I1 @T6G_MB_LIB.T6G(SCH_1):PAGE81
   U18   F2   GND9 LCMXO3LF9400C5BG484C-LCMXO3LF-9400C-5BG484C,SMLF,IA     I1 @T6G_MB_LIB.T6G(SCH_1):PAGE81
   U18  F21  GND10 LCMXO3LF9400C5BG484C-LCMXO3LF-9400C-5BG484C,SMLF,IA     I1 @T6G_MB_LIB.T6G(SCH_1):PAGE81
   U18   H8  GND11 LCMXO3LF9400C5BG484C-LCMXO3LF-9400C-5BG484C,SMLF,IA     I1 @T6G_MB_LIB.T6G(SCH_1):PAGE81
   U18  H10  GND12 LCMXO3LF9400C5BG484C-LCMXO3LF-9400C-5BG484C,SMLF,IA     I1 @T6G_MB_LIB.T6G(SCH_1):PAGE81
   U18  H13  GND13 LCMXO3LF9400C5BG484C-LCMXO3LF-9400C-5BG484C,SMLF,IA     I1 @T6G_MB_LIB.T6G(SCH_1):PAGE81
   U18  H15  GND14 LCMXO3LF9400C5BG484C-LCMXO3LF-9400C-5BG484C,SMLF,IA     I1 @T6G_MB_LIB.T6G(SCH_1):PAGE81
   U18   J9  GND15 LCMXO3LF9400C5BG484C-LCMXO3LF-9400C-5BG484C,SMLF,IA     I1 @T6G_MB_LIB.T6G(SCH_1):PAGE81
   U18  J10  GND16 LCMXO3LF9400C5BG484C-LCMXO3LF-9400C-5BG484C,SMLF,IA     I1 @T6G_MB_LIB.T6G(SCH_1):PAGE81
   U18  J11  GND17 LCMXO3LF9400C5BG484C-LCMXO3LF-9400C-5BG484C,SMLF,IA     I1 @T6G_MB_LIB.T6G(SCH_1):PAGE81
   U18  J12  GND18 LCMXO3LF9400C5BG484C-LCMXO3LF-9400C-5BG484C,SMLF,IA     I1 @T6G_MB_LIB.T6G(SCH_1):PAGE81
   U18  J13  GND19 LCMXO3LF9400C5BG484C-LCMXO3LF-9400C-5BG484C,SMLF,IA     I1 @T6G_MB_LIB.T6G(SCH_1):PAGE81
   U18  J14  GND20 LCMXO3LF9400C5BG484C-LCMXO3LF-9400C-5BG484C,SMLF,IA     I1 @T6G_MB_LIB.T6G(SCH_1):PAGE81
   U18   K9  GND21 LCMXO3LF9400C5BG484C-LCMXO3LF-9400C-5BG484C,SMLF,IA     I1 @T6G_MB_LIB.T6G(SCH_1):PAGE81
   U18  K14  GND22 LCMXO3LF9400C5BG484C-LCMXO3LF-9400C-5BG484C,SMLF,IA     I1 @T6G_MB_LIB.T6G(SCH_1):PAGE81
   U18  K21  GND23 LCMXO3LF9400C5BG484C-LCMXO3LF-9400C-5BG484C,SMLF,IA     I1 @T6G_MB_LIB.T6G(SCH_1):PAGE81
   U18   L2  GND24 LCMXO3LF9400C5BG484C-LCMXO3LF-9400C-5BG484C,SMLF,IA     I1 @T6G_MB_LIB.T6G(SCH_1):PAGE81
   U18   L9  GND25 LCMXO3LF9400C5BG484C-LCMXO3LF-9400C-5BG484C,SMLF,IA     I1 @T6G_MB_LIB.T6G(SCH_1):PAGE81
   U18  L10  GND26 LCMXO3LF9400C5BG484C-LCMXO3LF-9400C-5BG484C,SMLF,IA     I1 @T6G_MB_LIB.T6G(SCH_1):PAGE81
   U18  L13  GND27 LCMXO3LF9400C5BG484C-LCMXO3LF-9400C-5BG484C,SMLF,IA     I1 @T6G_MB_LIB.T6G(SCH_1):PAGE81
   U18  L14  GND28 LCMXO3LF9400C5BG484C-LCMXO3LF-9400C-5BG484C,SMLF,IA     I1 @T6G_MB_LIB.T6G(SCH_1):PAGE81
   U18  L18  GND29 LCMXO3LF9400C5BG484C-LCMXO3LF-9400C-5BG484C,SMLF,IA     I1 @T6G_MB_LIB.T6G(SCH_1):PAGE81
   U18   M4  GND30 LCMXO3LF9400C5BG484C-LCMXO3LF-9400C-5BG484C,SMLF,IA     I1 @T6G_MB_LIB.T6G(SCH_1):PAGE81
   U18   M9  GND31 LCMXO3LF9400C5BG484C-LCMXO3LF-9400C-5BG484C,SMLF,IA     I1 @T6G_MB_LIB.T6G(SCH_1):PAGE81
   U18  M10  GND32 LCMXO3LF9400C5BG484C-LCMXO3LF-9400C-5BG484C,SMLF,IA     I1 @T6G_MB_LIB.T6G(SCH_1):PAGE81
   U18  M13  GND33 LCMXO3LF9400C5BG484C-LCMXO3LF-9400C-5BG484C,SMLF,IA     I1 @T6G_MB_LIB.T6G(SCH_1):PAGE81
   U18  M14  GND34 LCMXO3LF9400C5BG484C-LCMXO3LF-9400C-5BG484C,SMLF,IA     I1 @T6G_MB_LIB.T6G(SCH_1):PAGE81
   U18   N9  GND35 LCMXO3LF9400C5BG484C-LCMXO3LF-9400C-5BG484C,SMLF,IA     I1 @T6G_MB_LIB.T6G(SCH_1):PAGE81
   U18  N14  GND36 LCMXO3LF9400C5BG484C-LCMXO3LF-9400C-5BG484C,SMLF,IA     I1 @T6G_MB_LIB.T6G(SCH_1):PAGE81
   U18  N21  GND37 LCMXO3LF9400C5BG484C-LCMXO3LF-9400C-5BG484C,SMLF,IA     I1 @T6G_MB_LIB.T6G(SCH_1):PAGE81
   U18   P9  GND38 LCMXO3LF9400C5BG484C-LCMXO3LF-9400C-5BG484C,SMLF,IA     I1 @T6G_MB_LIB.T6G(SCH_1):PAGE81
   U18  P10  GND39 LCMXO3LF9400C5BG484C-LCMXO3LF-9400C-5BG484C,SMLF,IA     I1 @T6G_MB_LIB.T6G(SCH_1):PAGE81
   U18  P11  GND40 LCMXO3LF9400C5BG484C-LCMXO3LF-9400C-5BG484C,SMLF,IA     I1 @T6G_MB_LIB.T6G(SCH_1):PAGE81
   U18  P12  GND41 LCMXO3LF9400C5BG484C-LCMXO3LF-9400C-5BG484C,SMLF,IA     I1 @T6G_MB_LIB.T6G(SCH_1):PAGE81
   U18  P13  GND42 LCMXO3LF9400C5BG484C-LCMXO3LF-9400C-5BG484C,SMLF,IA     I1 @T6G_MB_LIB.T6G(SCH_1):PAGE81
   U18  P14  GND43 LCMXO3LF9400C5BG484C-LCMXO3LF-9400C-5BG484C,SMLF,IA     I1 @T6G_MB_LIB.T6G(SCH_1):PAGE81
   U18   R8  GND44 LCMXO3LF9400C5BG484C-LCMXO3LF-9400C-5BG484C,SMLF,IA     I1 @T6G_MB_LIB.T6G(SCH_1):PAGE81
   U18  R15  GND45 LCMXO3LF9400C5BG484C-LCMXO3LF-9400C-5BG484C,SMLF,IA     I1 @T6G_MB_LIB.T6G(SCH_1):PAGE81
   U18   V2  GND46 LCMXO3LF9400C5BG484C-LCMXO3LF-9400C-5BG484C,SMLF,IA     I1 @T6G_MB_LIB.T6G(SCH_1):PAGE81
   U18  V21  GND47 LCMXO3LF9400C5BG484C-LCMXO3LF-9400C-5BG484C,SMLF,IA     I1 @T6G_MB_LIB.T6G(SCH_1):PAGE81
   U18  W12  GND48 LCMXO3LF9400C5BG484C-LCMXO3LF-9400C-5BG484C,SMLF,IA     I1 @T6G_MB_LIB.T6G(SCH_1):PAGE81
   U18   Y7  GND49 LCMXO3LF9400C5BG484C-LCMXO3LF-9400C-5BG484C,SMLF,IA     I1 @T6G_MB_LIB.T6G(SCH_1):PAGE81
   U18  Y16  GND50 LCMXO3LF9400C5BG484C-LCMXO3LF-9400C-5BG484C,SMLF,IA     I1 @T6G_MB_LIB.T6G(SCH_1):PAGE81
   U18  AB1  GND51 LCMXO3LF9400C5BG484C-LCMXO3LF-9400C-5BG484C,SMLF,IA     I1 @T6G_MB_LIB.T6G(SCH_1):PAGE81
   U18 AB22  GND52 LCMXO3LF9400C5BG484C-LCMXO3LF-9400C-5BG484C,SMLF,IA     I1 @T6G_MB_LIB.T6G(SCH_1):PAGE81
 C1133    2      B Q_CAP_C0402-0.1UF,16V,10%,X7R,CH4103K1B08    I81 @T6G_MB_LIB.T6G(SCH_1):PAGE82
   R10    2      B Q_RES_0402LF-10K,1%,1/16W,CHIP,CS31002FB08    I93 @T6G_MB_LIB.T6G(SCH_1):PAGE82
   R11    2      B Q_RES_0402LF-10K,1%,1/16W,CHIP,CS31002FB08    I94 @T6G_MB_LIB.T6G(SCH_1):PAGE82
   R12    2      B Q_RES_0402LF-10K,1%,1/16W,CHIP,CS31002FB08    I95 @T6G_MB_LIB.T6G(SCH_1):PAGE82
  C362    2      B Q_CAP_C0402-0.1UF,16V,10%,X7R,CH4103K1B08   I102 @T6G_MB_LIB.T6G(SCH_1):PAGE82
  C360    2      B Q_CAP_C0402-0.1UF,16V,10%,X7R,CH4103K1B08   I103 @T6G_MB_LIB.T6G(SCH_1):PAGE82
  C361    2      B Q_CAP_C0402-0.1UF,16V,10%,X7R,CH4103K1B08   I104 @T6G_MB_LIB.T6G(SCH_1):PAGE82
  R800    2      B Q_RES_0402LF-10K,1%,1/16W,CHIP,CS31002FB08   I118 @T6G_MB_LIB.T6G(SCH_1):PAGE82
   R16    2      B Q_RES_0402LF-10K,1%,1/16W,CHIP,CS31002FB08   I124 @T6G_MB_LIB.T6G(SCH_1):PAGE82
   R17    2      B Q_RES_0402LF-10K,1%,1/16W,CHIP,CS31002FB08   I125 @T6G_MB_LIB.T6G(SCH_1):PAGE82
  C359    2      B Q_CAP_C0402-0.1UF,16V,10%,X7R,CH4103K1B08   I135 @T6G_MB_LIB.T6G(SCH_1):PAGE82
 R6144    2      B Q_RES_0402LF-1K,1%,1/16W,CHIP,CS21002FB06    I52 @T6G_MB_LIB.T6G(SCH_1):PAGE83
   Q28    1     S1 MOSFET_DUAL_6P-2N7002KDW,SMLF,IC,BAM70020047    I48 @T6G_MB_LIB.T6G(SCH_1):PAGE84
   Q28    4     S2 MOSFET_DUAL_6P-2N7002KDW,SMLF,IC,BAM70020047    I48 @T6G_MB_LIB.T6G(SCH_1):PAGE84
 R6028    2      B Q_RES_0402LF-0,5%,1/16W,CHIP,CS00002JB13   I174 @T6G_MB_LIB.T6G(SCH_1):PAGE348
   C62    2      B Q_CAP_C0402-220PF,50V,5%,C0G,CH12206JB00    I69 @T6G_MB_LIB.T6G(SCH_1):PAGE349
  R889    2      B Q_RES_0402LF-10K,5%,1/16W,EMPTY,CS31002JB08   I142 @T6G_MB_LIB.T6G(SCH_1):PAGE349
  R891    2      B Q_RES_0402LF-10K,5%,1/16W,EMPTY,CS31002JB08   I144 @T6G_MB_LIB.T6G(SCH_1):PAGE349
PC2340    2      B Q_CAP_C0402-560PF,50V,10%,X7R,CH1566K1B09     I6 @T6G_MB_LIB.T6G(SCH_1):PAGE350
   Q39    S      S MOSFET_NCH_GDS_ESD_PROTECTED-2N7002K,SMLF,IC,BAM70A     I9 @T6G_MB_LIB.T6G(SCH_1):PAGE350
  Q125    1     S1 MOSFET_NCH_DUAL-PJT138K,SMLF,IC,BAM138K0003    I22 @T6G_MB_LIB.T6G(SCH_1):PAGE350
  Q125    4     S2 MOSFET_NCH_DUAL-PJT138K,SMLF,IC,BAM138K0003    I24 @T6G_MB_LIB.T6G(SCH_1):PAGE350
 PD115    A      A DIODE_TVS-SMF14A,SMLF,IC,BCSMF14AZ01    I28 @T6G_MB_LIB.T6G(SCH_1):PAGE350
PR4005    2      B Q_RES_0402LF-30.1K,1%,1/16W,CHIP,CS33012FB03    I35 @T6G_MB_LIB.T6G(SCH_1):PAGE350
PR4011    2      B Q_RES_0402LF-10K,1%,1/16W,CHIP,CS31002FB08    I49 @T6G_MB_LIB.T6G(SCH_1):PAGE350
 PU300   A7   CDLY MAX15090BEWIT-MAX15090BEWI+T,SMLF,IC,AL015080B00    I86 @T6G_MB_LIB.T6G(SCH_1):PAGE350
 PU300   B7    EN# MAX15090BEWIT-MAX15090BEWI+T,SMLF,IC,AL015080B00    I86 @T6G_MB_LIB.T6G(SCH_1):PAGE350
 PU300   B2 GND_B2 MAX15090BEWIT-MAX15090BEWI+T,SMLF,IC,AL015080B00    I86 @T6G_MB_LIB.T6G(SCH_1):PAGE350
 PU300   C1 GND_C1 MAX15090BEWIT-MAX15090BEWI+T,SMLF,IC,AL015080B00    I86 @T6G_MB_LIB.T6G(SCH_1):PAGE350
 PU300   C2 GND_C2 MAX15090BEWIT-MAX15090BEWI+T,SMLF,IC,AL015080B00    I86 @T6G_MB_LIB.T6G(SCH_1):PAGE350
    J6    2      2 CONN6_HBC1031L200D8H-CONN6_HBC1031-L200D-8H,THLF,IA    I28 @T6G_MB_LIB.T6G(SCH_1):PAGE28
    J6    4      4 CONN6_HBC1031L200D8H-CONN6_HBC1031-L200D-8H,THLF,IA    I28 @T6G_MB_LIB.T6G(SCH_1):PAGE28
    J6    6      6 CONN6_HBC1031L200D8H-CONN6_HBC1031-L200D-8H,THLF,IA    I28 @T6G_MB_LIB.T6G(SCH_1):PAGE28
  R582    1      A Q_RES_0402LF-4.7K,5%,1/16W,EMPTY,CS24702JB10    I33 @T6G_MB_LIB.T6G(SCH_1):PAGE28
  R287    1      A Q_RES_0402LF-4.7K,5%,1/16W,EMPTY,CS24702JB10    I36 @T6G_MB_LIB.T6G(SCH_1):PAGE28
  R440    1      A Q_RES_0402LF-4.7K,5%,1/16W,EMPTY,CS24702JB10    I37 @T6G_MB_LIB.T6G(SCH_1):PAGE28
 R5026    1      A Q_RES_0402LF-4.7K,5%,1/16W,EMPTY,CS24702JB10    I40 @T6G_MB_LIB.T6G(SCH_1):PAGE28
 R5027    1      A Q_RES_0402LF-4.7K,5%,1/16W,EMPTY,CS24702JB10    I59 @T6G_MB_LIB.T6G(SCH_1):PAGE28
 R5028    1      A Q_RES_0402LF-4.7K,5%,1/16W,EMPTY,CS24702JB10    I60 @T6G_MB_LIB.T6G(SCH_1):PAGE28
 R5029    1      A Q_RES_0402LF-4.7K,5%,1/16W,EMPTY,CS24702JB10    I62 @T6G_MB_LIB.T6G(SCH_1):PAGE28
    Y2    2     G1 Q_XTAL_4P_13BI_24GND-48MHZ,SMLF,MISC,BG648000076   I103 @T6G_MB_LIB.T6G(SCH_1):PAGE28
    Y2    4     G2 Q_XTAL_4P_13BI_24GND-48MHZ,SMLF,MISC,BG648000076   I103 @T6G_MB_LIB.T6G(SCH_1):PAGE28
PC2241    2      B Q_CAP_0402-0.1UF,25V,10%,X7R,CH4104K1B00    I56 @T6G_MB_LIB.T6G(SCH_1):PAGE350
PR4002    2      B Q_RES_0402LF-15K,1%,1/16W,CHIP,CS31502FB05    I60 @T6G_MB_LIB.T6G(SCH_1):PAGE350
PC2240    2      B Q_CAP_C0805-10UF,16V,10%,X6S,CH6103KEA01    I81 @T6G_MB_LIB.T6G(SCH_1):PAGE350
PC2242    2      B Q_CAP_C0805-22UF,16V,20%,X6S,CH6223MEA01    I84 @T6G_MB_LIB.T6G(SCH_1):PAGE350
 C1274    2      B Q_CAP_0402-0.1UF,25V,10%,X7R,CH4104K1B00     I3 @T6G_MB_LIB.T6G(SCH_1):PAGE337
  OSC1    2    GND Q_OSC4P_SMLF-50MHZ,OSC,BF650000032     I4 @T6G_MB_LIB.T6G(SCH_1):PAGE337
 U8082    3    GND 74LVC1G126SE7-74LVC1G126SE-7,SMLF,IC,AL1G0126009     I8 @T6G_MB_LIB.T6G(SCH_1):PAGE337
   U90    4    GND PI6CV304LE-PI6CV304LE,SMLF,IC,AL000304K01    I16 @T6G_MB_LIB.T6G(SCH_1):PAGE337
 C1275    2      B Q_CAP_0402-0.1UF,25V,10%,X7R,CH4104K1B00    I19 @T6G_MB_LIB.T6G(SCH_1):PAGE337
  U157    3    GND 74LVC1G07GV-74LVC1G07GV,SMLF,IC,AL1G0007001    I25 @T6G_MB_LIB.T6G(SCH_1):PAGE337
   C36    2      B Q_CAP_0402-0.1UF,25V,10%,X7R,CH4104K1B00    I33 @T6G_MB_LIB.T6G(SCH_1):PAGE337
  U104    3    GND 74LVC1G07GV-74LVC1G07GV,SMLF,IC,AL1G0007001    I38 @T6G_MB_LIB.T6G(SCH_1):PAGE337
 C1663    2      B Q_CAP_0402-0.1UF,25V,10%,X7R,CH4104K1B00    I47 @T6G_MB_LIB.T6G(SCH_1):PAGE337
  U225    3    GND 74LVC1G126SE7-74LVC1G126SE-7,SMLF,IC,AL1G0126009     I9 @T6G_MB_LIB.T6G(SCH_1):PAGE342
  U217    3    GND 74LVC1G126SE7-74LVC1G126SE-7,SMLF,IC,AL1G0126009    I14 @T6G_MB_LIB.T6G(SCH_1):PAGE342
 C1822    2      B Q_CAP_0402-0.1UF,25V,10%,X7R,CH4104K1B00    I16 @T6G_MB_LIB.T6G(SCH_1):PAGE342
  U218    3    GND 74LVC1G07GV-74LVC1G07GV,SMLF,IC,AL1G0007001    I22 @T6G_MB_LIB.T6G(SCH_1):PAGE342
  U219    3    GND 74LVC1G07GV-74LVC1G07GV,SMLF,IC,AL1G0007001    I32 @T6G_MB_LIB.T6G(SCH_1):PAGE342
   U59    2    GND 74LVC2G07DW7-74LVC2G07DW-7,SMLF,IC,AL002G07003    I22 @T6G_MB_LIB.T6G(SCH_1):PAGE343
 C1810    2      B Q_CAP_0402-0.1UF,25V,10%,X7R,CH4104K1B00    I23 @T6G_MB_LIB.T6G(SCH_1):PAGE343
 C1809    2      B Q_CAP_0402-0.1UF,25V,10%,X7R,CH4104K1B00    I29 @T6G_MB_LIB.T6G(SCH_1):PAGE343
PR3828    2      B Q_RES_0402LF-15K,1%,1/16W,CHIP,CS31502FB05    I31 @T6G_MB_LIB.T6G(SCH_1):PAGE343
PC2140    2      B Q_CAP_C0402-1UF,25V,10%,X6S,CH5104KEB02    I55 @T6G_MB_LIB.T6G(SCH_1):PAGE343
PC2150    2      B Q_CAP_C0402-3900PF,50V,10%,X7R,CH23906KB14    I75 @T6G_MB_LIB.T6G(SCH_1):PAGE343
PC2151    2      B Q_CAP_C0402-6800PF,50V,10%,X7R,CH2686K1B01    I95 @T6G_MB_LIB.T6G(SCH_1):PAGE343
 PD109    A      A SCHOTTKY_AC-B340A-13-F,SMLF,IC,BC000340Z30   I106 @T6G_MB_LIB.T6G(SCH_1):PAGE343
PC2137    2      B Q_CAP_0402-0.1UF,25V,10%,X7R,CH4104K1B00   I108 @T6G_MB_LIB.T6G(SCH_1):PAGE343
PC2142    2      B Q_CAP_C0805-10UF,16V,10%,X6S,CH6103KEA01   I112 @T6G_MB_LIB.T6G(SCH_1):PAGE343
 R4568    2      B Q_RES_0402LF-4.7K,1%,1/16W,CHIP,CS24702FB06     I7 @T6G_MB_LIB.T6G(SCH_1):PAGE369
 R1791    2      B Q_RES_0402LF-9.09K,1%,1/16W,CHIP,CS29092FB05    I14 @T6G_MB_LIB.T6G(SCH_1):PAGE369
 C2049    2      B Q_CAP_0402-0.1UF,25V,10%,X7R,CH4104K1B00    I17 @T6G_MB_LIB.T6G(SCH_1):PAGE369
 R2843    2      B Q_RES_0402LF-4.7K,1%,1/16W,CHIP,CS24702FB06    I20 @T6G_MB_LIB.T6G(SCH_1):PAGE369
 R1785    2      B Q_RES_0402LF-4.7K,1%,1/16W,CHIP,CS24702FB06    I26 @T6G_MB_LIB.T6G(SCH_1):PAGE369
 C2048    2      B Q_CAP_0402-0.1UF,25V,10%,X7R,CH4104K1B00    I32 @T6G_MB_LIB.T6G(SCH_1):PAGE369
 C2050    2      B Q_CAP_0402-0.1UF,25V,10%,X7R,CH4104K1B00    I34 @T6G_MB_LIB.T6G(SCH_1):PAGE369
 C2045    2      B Q_CAP_0402-100PF,50V,5%,EMPTY,CH11006JB18    I36 @T6G_MB_LIB.T6G(SCH_1):PAGE369
 R3668    2      B Q_RES_0402LF-1K,1%,1/16W,CHIP,CS21002FB06    I38 @T6G_MB_LIB.T6G(SCH_1):PAGE369
 R3670    2      B Q_RES_0402LF-1K,1%,1/16W,CHIP,CS21002FB06    I40 @T6G_MB_LIB.T6G(SCH_1):PAGE369
 C2046    2      B Q_CAP_0402-0.1UF,25V,10%,X7R,CH4104K1B00    I44 @T6G_MB_LIB.T6G(SCH_1):PAGE369
 C1344    2      B Q_CAP_0402-100PF,50V,5%,EMPTY,CH11006JB18    I46 @T6G_MB_LIB.T6G(SCH_1):PAGE369
 C2044    2      B Q_CAP_0402-100PF,50V,5%,EMPTY,CH11006JB18    I52 @T6G_MB_LIB.T6G(SCH_1):PAGE369
 C2043    2      B Q_CAP_0402-100PF,50V,5%,EMPTY,CH11006JB18    I55 @T6G_MB_LIB.T6G(SCH_1):PAGE369
 C2051    2      B Q_CAP_0402-0.1UF,25V,10%,X7R,CH4104K1B00    I71 @T6G_MB_LIB.T6G(SCH_1):PAGE369
 C2052    2      B Q_CAP_0402-0.1UF,25V,10%,X7R,CH4104K1B00    I72 @T6G_MB_LIB.T6G(SCH_1):PAGE369
 C2194    2      B Q_CAP_0402-0.1UF,25V,10%,X7R,CH4104K1B00    I76 @T6G_MB_LIB.T6G(SCH_1):PAGE369
   C35    2      B Q_CAP_0402-100PF,50V,5%,EMPTY,CH11006JB18    I78 @T6G_MB_LIB.T6G(SCH_1):PAGE369
   C33    2      B Q_CAP_0402-0.1UF,25V,10%,X7R,CH4104K1B00    I84 @T6G_MB_LIB.T6G(SCH_1):PAGE369
   C59    2      B Q_CAP_0402-100PF,50V,5%,EMPTY,CH11006JB18    I87 @T6G_MB_LIB.T6G(SCH_1):PAGE369
 C2047    2      B Q_CAP_0402-0.1UF,25V,10%,X7R,CH4104K1B00    I98 @T6G_MB_LIB.T6G(SCH_1):PAGE369
 C2042    2      B Q_CAP_0402-100PF,50V,5%,EMPTY,CH11006JB18    I99 @T6G_MB_LIB.T6G(SCH_1):PAGE369
   C37    2      B Q_CAP_0402-0.1UF,25V,10%,X7R,CH4104K1B00   I112 @T6G_MB_LIB.T6G(SCH_1):PAGE369
 C2176    2      B Q_CAP_0402-100PF,50V,5%,EMPTY,CH11006JB18   I114 @T6G_MB_LIB.T6G(SCH_1):PAGE369
 C1347    2      B Q_CAP_0402-0.1UF,25V,10%,X7R,CH4104K1B00   I119 @T6G_MB_LIB.T6G(SCH_1):PAGE369
 C1767    2      B Q_CAP_C0805-10UF,16V,10%,X6S,CH6103KEA00   I121 @T6G_MB_LIB.T6G(SCH_1):PAGE369
 R3690    2      B Q_RES_0402LF-4.7K,1%,1/16W,EMPTY,CS24702FB06   I130 @T6G_MB_LIB.T6G(SCH_1):PAGE369
  U269    4    GND ADC128D818CIMTXNOPB-ADC128D818CIMTX/NOPB,SMLF,IC,AA   I142 @T6G_MB_LIB.T6G(SCH_1):PAGE369
 C1757    2      B Q_CAP_0402-0.1UF,25V,10%,X7R,CH4104K1B00   I162 @T6G_MB_LIB.T6G(SCH_1):PAGE369
 C1768    2      B Q_CAP_C0805-10UF,16V,10%,X6S,CH6103KEA00   I166 @T6G_MB_LIB.T6G(SCH_1):PAGE369
  U193    4   AIN8 MAX11617EEET-MAX11617EEE+T,SMLF,EMPTY,AL011617W00   I169 @T6G_MB_LIB.T6G(SCH_1):PAGE369
  U193    3   AIN9 MAX11617EEET-MAX11617EEE+T,SMLF,EMPTY,AL011617W00   I169 @T6G_MB_LIB.T6G(SCH_1):PAGE369
  U193    2  AIN10 MAX11617EEET-MAX11617EEE+T,SMLF,EMPTY,AL011617W00   I169 @T6G_MB_LIB.T6G(SCH_1):PAGE369
  U193   15    GND MAX11617EEET-MAX11617EEE+T,SMLF,EMPTY,AL011617W00   I169 @T6G_MB_LIB.T6G(SCH_1):PAGE369
   Q50    1     S1 MOSFET_NCH_DUAL-PJT138K,SMLF,IC,BAM138K0003    I65 @T6G_MB_LIB.T6G(SCH_1):PAGE84
   Q50    4     S2 MOSFET_NCH_DUAL-PJT138K,SMLF,IC,BAM138K0003    I73 @T6G_MB_LIB.T6G(SCH_1):PAGE84
 C5023    2      B Q_CAP_0402-1000PF,50V,5%,X7R,TMP_QCH21006JB10   I194 @T6G_MB_LIB.T6G(SCH_1):PAGE28
 C5024    2      B Q_CAP_0402-1000PF,50V,5%,X7R,TMP_QCH21006JB10   I388 @T6G_MB_LIB.T6G(SCH_1):PAGE55
 R6114    2      B Q_RES_0402LF-2K,1%,1/16W,CHIP,CS22002FB07   I137 @T6G_MB_LIB.T6G(SCH_1):PAGE82
   H53    1      1 HOLE_TH-EMPTY,HOLE1226     I4 @T6G_MB_LIB.T6G(SCH_1):PAGE212
   H21    1      1 HOLE_TH-EMPTY,HOLE1226     I5 @T6G_MB_LIB.T6G(SCH_1):PAGE212
 H8027    1      1 HOLE_TH-EMPTY,HOLE1226     I7 @T6G_MB_LIB.T6G(SCH_1):PAGE212
   H76    1      1 HOLE_TH-EMPTY,HOLE1187    I10 @T6G_MB_LIB.T6G(SCH_1):PAGE212
   H77    1      1 HOLE_TH-EMPTY,HOLE1187    I12 @T6G_MB_LIB.T6G(SCH_1):PAGE212
  H113    2   GND2 GND_HOLE_TH-EMPTY,GND_HOLE140    I25 @T6G_MB_LIB.T6G(SCH_1):PAGE212
  H113    3   GND3 GND_HOLE_TH-EMPTY,GND_HOLE140    I25 @T6G_MB_LIB.T6G(SCH_1):PAGE212
  H113    4   GND4 GND_HOLE_TH-EMPTY,GND_HOLE140    I25 @T6G_MB_LIB.T6G(SCH_1):PAGE212
  H113    5   GND5 GND_HOLE_TH-EMPTY,GND_HOLE140    I25 @T6G_MB_LIB.T6G(SCH_1):PAGE212
  H113    6   GND6 GND_HOLE_TH-EMPTY,GND_HOLE140    I25 @T6G_MB_LIB.T6G(SCH_1):PAGE212
  H113    7   GND7 GND_HOLE_TH-EMPTY,GND_HOLE140    I25 @T6G_MB_LIB.T6G(SCH_1):PAGE212
  H113    8   GND8 GND_HOLE_TH-EMPTY,GND_HOLE140    I25 @T6G_MB_LIB.T6G(SCH_1):PAGE212
  H113    9   GND9 GND_HOLE_TH-EMPTY,GND_HOLE140    I25 @T6G_MB_LIB.T6G(SCH_1):PAGE212
   H22    1      1 HOLE_TH-EMPTY,HOLE1226    I26 @T6G_MB_LIB.T6G(SCH_1):PAGE212
 H8028    1      1 HOLE_TH-EMPTY,HOLE1226    I27 @T6G_MB_LIB.T6G(SCH_1):PAGE212
  H114    2   GND2 GND_HOLE_TH-EMPTY,GND_HOLE140    I30 @T6G_MB_LIB.T6G(SCH_1):PAGE212
  H114    3   GND3 GND_HOLE_TH-EMPTY,GND_HOLE140    I30 @T6G_MB_LIB.T6G(SCH_1):PAGE212
  H114    4   GND4 GND_HOLE_TH-EMPTY,GND_HOLE140    I30 @T6G_MB_LIB.T6G(SCH_1):PAGE212
  H114    5   GND5 GND_HOLE_TH-EMPTY,GND_HOLE140    I30 @T6G_MB_LIB.T6G(SCH_1):PAGE212
  H114    6   GND6 GND_HOLE_TH-EMPTY,GND_HOLE140    I30 @T6G_MB_LIB.T6G(SCH_1):PAGE212
  H114    7   GND7 GND_HOLE_TH-EMPTY,GND_HOLE140    I30 @T6G_MB_LIB.T6G(SCH_1):PAGE212
  H114    8   GND8 GND_HOLE_TH-EMPTY,GND_HOLE140    I30 @T6G_MB_LIB.T6G(SCH_1):PAGE212
  H114    9   GND9 GND_HOLE_TH-EMPTY,GND_HOLE140    I30 @T6G_MB_LIB.T6G(SCH_1):PAGE212
   H34    1      1 HOLE_TH-EMPTY,HOLE1226    I31 @T6G_MB_LIB.T6G(SCH_1):PAGE212
   H38    1      1 HOLE_TH-EMPTY,HOLE1226    I33 @T6G_MB_LIB.T6G(SCH_1):PAGE212
   H33    1      1 HOLE_TH-EMPTY,HOLE1226    I36 @T6G_MB_LIB.T6G(SCH_1):PAGE212
   H37    1      1 HOLE_TH-EMPTY,HOLE1226    I38 @T6G_MB_LIB.T6G(SCH_1):PAGE212
   H43    1      1 HOLE_TH-EMPTY,HOLE1226    I40 @T6G_MB_LIB.T6G(SCH_1):PAGE212
  H115    2   GND2 GND_HOLE_TH-EMPTY,GND_HOLE514    I43 @T6G_MB_LIB.T6G(SCH_1):PAGE212
  H115    3   GND3 GND_HOLE_TH-EMPTY,GND_HOLE514    I43 @T6G_MB_LIB.T6G(SCH_1):PAGE212
  H115    4   GND4 GND_HOLE_TH-EMPTY,GND_HOLE514    I43 @T6G_MB_LIB.T6G(SCH_1):PAGE212
  H115    5   GND5 GND_HOLE_TH-EMPTY,GND_HOLE514    I43 @T6G_MB_LIB.T6G(SCH_1):PAGE212
  H115    6   GND6 GND_HOLE_TH-EMPTY,GND_HOLE514    I43 @T6G_MB_LIB.T6G(SCH_1):PAGE212
  H115    7   GND7 GND_HOLE_TH-EMPTY,GND_HOLE514    I43 @T6G_MB_LIB.T6G(SCH_1):PAGE212
  H115    8   GND8 GND_HOLE_TH-EMPTY,GND_HOLE514    I43 @T6G_MB_LIB.T6G(SCH_1):PAGE212
  H115    9   GND9 GND_HOLE_TH-EMPTY,GND_HOLE514    I43 @T6G_MB_LIB.T6G(SCH_1):PAGE212
   H44    1      1 HOLE_TH-EMPTY,HOLE1226    I45 @T6G_MB_LIB.T6G(SCH_1):PAGE212
   H49    1      1 HOLE_TH-EMPTY,HOLE1226    I46 @T6G_MB_LIB.T6G(SCH_1):PAGE212
   H50    1      1 HOLE_TH-EMPTY,HOLE1226    I49 @T6G_MB_LIB.T6G(SCH_1):PAGE212
   H54    1      1 HOLE_TH-EMPTY,HOLE1226    I52 @T6G_MB_LIB.T6G(SCH_1):PAGE212
   H13    1      1 HOLE_TH-EMPTY,HOLE1226    I55 @T6G_MB_LIB.T6G(SCH_1):PAGE212
   H11    1      1 HOLE_TH-EMPTY,HOLE1226    I87 @T6G_MB_LIB.T6G(SCH_1):PAGE212
   H31    1      1 HOLE_TH-EMPTY,HOLE1248    I91 @T6G_MB_LIB.T6G(SCH_1):PAGE212
   H32    1      1 HOLE_TH-EMPTY,HOLE1248    I93 @T6G_MB_LIB.T6G(SCH_1):PAGE212
   Q78    1     S1 MOSFET_NCH_DUAL-PJT138K,SMLF,IC,BAM138K0003    I24 @T6G_MB_LIB.T6G(SCH_1):PAGE254
 R6086    2      B Q_RES_0402LF-10K,1%,1/16W,EMPTY,CS31002FB08   I129 @T6G_MB_LIB.T6G(SCH_1):PAGE175
 R6087    2      B Q_RES_0402LF-10K,1%,1/16W,EMPTY,CS31002FB08   I135 @T6G_MB_LIB.T6G(SCH_1):PAGE185
 R6088    2      B Q_RES_0402LF-10K,1%,1/16W,EMPTY,CS31002FB08   I130 @T6G_MB_LIB.T6G(SCH_1):PAGE192
 R6089    2      B Q_RES_0402LF-10K,1%,1/16W,EMPTY,CS31002FB08   I136 @T6G_MB_LIB.T6G(SCH_1):PAGE168
 R6090    2      B Q_RES_0402LF-4.7K,5%,1/16W,CHIP,CS24702JB10    I77 @T6G_MB_LIB.T6G(SCH_1):PAGE84
   Q87    4     S2 MOSFET_NCH_DUAL-PJT138K,SMLF,IC,BAM138K0003    I35 @T6G_MB_LIB.T6G(SCH_1):PAGE254
 C1209    2      B Q_CAP_0402-100PF,50V,5%,NPO,CH11006JB00    I88 @T6G_MB_LIB.T6G(SCH_1):PAGE84
   C10    2      B Q_CAP_0402-0.1UF,25V,10%,X7R,CH4104K1B00    I61 @T6G_MB_LIB.T6G(SCH_1):PAGE337
   U75    3    GND 74LVC1G17GW-74LVC1G17GW,SMLF,IC,AL1G0017K01    I64 @T6G_MB_LIB.T6G(SCH_1):PAGE337
 C1821    2      B Q_CAP_0402-0.1UF,25V,10%,X7R,CH4104K1B00    I55 @T6G_MB_LIB.T6G(SCH_1):PAGE342
  U207    3    GND 74LVC1G17GW-74LVC1G17GW,SMLF,IC,AL1G0017K01    I58 @T6G_MB_LIB.T6G(SCH_1):PAGE342
 R6098    1      A Q_RES_0402LF-10K,5%,1/16W,EMPTY,CS31002JB08    I99 @T6G_MB_LIB.T6G(SCH_1):PAGE75
 C5022    1      A Q_CAP_0402-1000PF,50V,5%,X7R,TMP_QCH21006JB10   I131 @T6G_MB_LIB.T6G(SCH_1):PAGE192
 C5020    1      A Q_CAP_0402-1000PF,50V,5%,X7R,TMP_QCH21006JB10   I133 @T6G_MB_LIB.T6G(SCH_1):PAGE192
 C5019    1      A Q_CAP_0402-1000PF,50V,5%,X7R,TMP_QCH21006JB10   I137 @T6G_MB_LIB.T6G(SCH_1):PAGE185
 C5018    1      A Q_CAP_0402-1000PF,50V,5%,X7R,TMP_QCH21006JB10   I138 @T6G_MB_LIB.T6G(SCH_1):PAGE168
 C5017    1      A Q_CAP_0402-1000PF,50V,5%,X7R,TMP_QCH21006JB10   I139 @T6G_MB_LIB.T6G(SCH_1):PAGE168
 C5016    2      B Q_CAP_0402-1000PF,50V,5%,X7R,TMP_QCH21006JB10    I55 @T6G_MB_LIB.T6G(SCH_1):PAGE201
 C5015    2      B Q_CAP_0402-1000PF,50V,5%,EMPTY,TMP_QCH21006JB10    I68 @T6G_MB_LIB.T6G(SCH_1):PAGE245
 C5013    2      B Q_CAP_0402-1000PF,50V,5%,X7R,TMP_QCH21006JB10   I130 @T6G_MB_LIB.T6G(SCH_1):PAGE175
 C5012    2      B Q_CAP_0402-1000PF,50V,5%,X7R,TMP_QCH21006JB10   I139 @T6G_MB_LIB.T6G(SCH_1):PAGE185
 C5010    2      B Q_CAP_0402-1000PF,50V,5%,X7R,TMP_QCH21006JB10    I88 @T6G_MB_LIB.T6G(SCH_1):PAGE199
 C5011    2      B Q_CAP_0402-1000PF,50V,5%,X7R,TMP_QCH21006JB10   I142 @T6G_MB_LIB.T6G(SCH_1):PAGE168
 C5009    2      B Q_CAP_0402-1000PF,50V,5%,X7R,TMP_QCH21006JB10    I88 @T6G_MB_LIB.T6G(SCH_1):PAGE182
 C5006    1      A Q_CAP_0402-1000PF,50V,5%,X7R,TMP_QCH21006JB10   I136 @T6G_MB_LIB.T6G(SCH_1):PAGE192
 C5005    1      A Q_CAP_0402-1000PF,50V,5%,X7R,TMP_QCH21006JB10   I133 @T6G_MB_LIB.T6G(SCH_1):PAGE175
 C5004    1      A Q_CAP_0402-1000PF,50V,5%,X7R,TMP_QCH21006JB10   I135 @T6G_MB_LIB.T6G(SCH_1):PAGE175
 C5003    1      A Q_CAP_0402-1000PF,50V,5%,X7R,TMP_QCH21006JB10   I141 @T6G_MB_LIB.T6G(SCH_1):PAGE185
 C5002    2      B Q_CAP_0402-1000PF,50V,5%,X7R,TMP_QCH21006JB10    I43 @T6G_MB_LIB.T6G(SCH_1):PAGE167
 C5001    2      B Q_CAP_0402-1000PF,50V,5%,X7R,TMP_QCH21006JB10    I56 @T6G_MB_LIB.T6G(SCH_1):PAGE184
 C5000    2      B Q_CAP_0402-1000PF,50V,5%,X7R,TMP_QCH21006JB10   I124 @T6G_MB_LIB.T6G(SCH_1):PAGE34
   C86    2      B Q_CAP_C0402-0.01UF,50V,10%,EMPTY,CH31006KB18   I161 @T6G_MB_LIB.T6G(SCH_1):PAGE149
   Q87    1     S1 MOSFET_NCH_DUAL-PJT138K,SMLF,IC,BAM138K0003    I38 @T6G_MB_LIB.T6G(SCH_1):PAGE254
   Q80    4     S2 MOSFET_NCH_DUAL-PJT138K,SMLF,IC,BAM138K0003     I3 @T6G_MB_LIB.T6G(SCH_1):PAGE374
   Q80    1     S1 MOSFET_NCH_DUAL-PJT138K,SMLF,IC,BAM138K0003     I6 @T6G_MB_LIB.T6G(SCH_1):PAGE374
   Q79    4     S2 MOSFET_NCH_DUAL-PJT138K,SMLF,IC,BAM138K0003     I8 @T6G_MB_LIB.T6G(SCH_1):PAGE374
   Q79    1     S1 MOSFET_NCH_DUAL-PJT138K,SMLF,IC,BAM138K0003    I18 @T6G_MB_LIB.T6G(SCH_1):PAGE374
   Q83    1     S1 MOSFET_NCH_DUAL-PJT138K,SMLF,IC,BAM138K0003    I23 @T6G_MB_LIB.T6G(SCH_1):PAGE374
   Q81    4     S2 MOSFET_NCH_DUAL-PJT138K,SMLF,IC,BAM138K0003    I27 @T6G_MB_LIB.T6G(SCH_1):PAGE374
   Q81    1     S1 MOSFET_NCH_DUAL-PJT138K,SMLF,IC,BAM138K0003    I35 @T6G_MB_LIB.T6G(SCH_1):PAGE374
   Q85    4     S2 MOSFET_NCH_DUAL-PJT138K,SMLF,IC,BAM138K0003     I2 @T6G_MB_LIB.T6G(SCH_1):PAGE375
   Q85    1     S1 MOSFET_NCH_DUAL-PJT138K,SMLF,IC,BAM138K0003     I7 @T6G_MB_LIB.T6G(SCH_1):PAGE375
   Q84    4     S2 MOSFET_NCH_DUAL-PJT138K,SMLF,IC,BAM138K0003    I10 @T6G_MB_LIB.T6G(SCH_1):PAGE375
   Q84    1     S1 MOSFET_NCH_DUAL-PJT138K,SMLF,IC,BAM138K0003    I11 @T6G_MB_LIB.T6G(SCH_1):PAGE375
   Q86    4     S2 MOSFET_NCH_DUAL-PJT138K,SMLF,IC,BAM138K0003    I29 @T6G_MB_LIB.T6G(SCH_1):PAGE375
   Q86    1     S1 MOSFET_NCH_DUAL-PJT138K,SMLF,IC,BAM138K0003    I30 @T6G_MB_LIB.T6G(SCH_1):PAGE375
 R6115    2      B Q_RES_0402LF-2K,1%,1/16W,CHIP,CS22002FB07   I141 @T6G_MB_LIB.T6G(SCH_1):PAGE82
 R6143    2      B Q_RES_0402LF-1K,1%,1/16W,CHIP,CS21002FB06    I36 @T6G_MB_LIB.T6G(SCH_1):PAGE83
 R6127    2      B Q_RES_0402LF-1K,1%,1/16W,CHIP,CS21002FB06    I46 @T6G_MB_LIB.T6G(SCH_1):PAGE83
 R6128    2      B Q_RES_0402LF-1K,1%,1/16W,CHIP,CS21002FB06    I64 @T6G_MB_LIB.T6G(SCH_1):PAGE83
 R6129    2      B Q_RES_0402LF-1K,1%,1/16W,CHIP,CS21002FB06    I65 @T6G_MB_LIB.T6G(SCH_1):PAGE83
 U6000   25 TH_GND DS125BR111RTWR-DS125BR111RTWR,SMLF,IC,AL000125003     I1 @T6G_MB_LIB.T6G(SCH_1):PAGE111
 U6000   16 VDD_SEL DS125BR111RTWR-DS125BR111RTWR,SMLF,IC,AL000125003     I1 @T6G_MB_LIB.T6G(SCH_1):PAGE111
 C6009    2      B Q_CAP_C0402-1UF,25V,10%,X6S,CH5104KEB02     I3 @T6G_MB_LIB.T6G(SCH_1):PAGE111
 C6010    2      B Q_CAP_C0805-10UF,16V,10%,X6S,CH6103KEA00     I5 @T6G_MB_LIB.T6G(SCH_1):PAGE111
 C6011    2      B Q_CAP_0402-0.1UF,25V,10%,X7R,CH4104K1B00     I6 @T6G_MB_LIB.T6G(SCH_1):PAGE111
 C6012    2      B Q_CAP_0402-0.1UF,25V,10%,X7R,CH4104K1B00     I7 @T6G_MB_LIB.T6G(SCH_1):PAGE111
 R6160    2      B Q_RES_0402LF-1K,1%,1/16W,CHIP,CS21002FB06    I12 @T6G_MB_LIB.T6G(SCH_1):PAGE111
 R6164    2      B Q_RES_0402LF-1K,1%,1/16W,CHIP,CS21002FB06    I32 @T6G_MB_LIB.T6G(SCH_1):PAGE111
 R6166    2      B Q_RES_0402LF-1K,1%,1/16W,EMPTY,CS21002FB06    I40 @T6G_MB_LIB.T6G(SCH_1):PAGE111
 R6174    2      B Q_RES_0402LF-1K,1%,1/16W,EMPTY,CS21002FB06    I45 @T6G_MB_LIB.T6G(SCH_1):PAGE111
 R6172    2      B Q_RES_0402LF-1K,1%,1/16W,CHIP,CS21002FB06    I49 @T6G_MB_LIB.T6G(SCH_1):PAGE111
 R6168    2      B Q_RES_0402LF-1K,1%,1/16W,CHIP,CS21002FB06    I58 @T6G_MB_LIB.T6G(SCH_1):PAGE111
 R6170    2      B Q_RES_0402LF-1K,1%,1/16W,CHIP,CS21002FB06    I60 @T6G_MB_LIB.T6G(SCH_1):PAGE111
 R6176    2      B Q_RES_0402LF-1K,1%,1/16W,EMPTY,CS21002FB06    I64 @T6G_MB_LIB.T6G(SCH_1):PAGE111
 R6178    2      B Q_RES_0402LF-1K,1%,1/16W,EMPTY,CS21002FB06    I68 @T6G_MB_LIB.T6G(SCH_1):PAGE111
 R6180    2      B Q_RES_0402LF-1K,1%,1/16W,EMPTY,CS21002FB06    I73 @T6G_MB_LIB.T6G(SCH_1):PAGE111
PC2188    2      B Q_CAP_C0402-1UF,25V,10%,X6S,CH5104KEB02    I46 @T6G_MB_LIB.T6G(SCH_1):PAGE267
 PD111    1 ANODE_1 SS15P3SM386A-SS15P3S-M3/86A,SMLF,IC,BC015P3SZ00    I89 @T6G_MB_LIB.T6G(SCH_1):PAGE267
 PD111    2 ANODE_2 SS15P3SM386A-SS15P3S-M3/86A,SMLF,IC,BC015P3SZ00    I89 @T6G_MB_LIB.T6G(SCH_1):PAGE267
  PD15    A      A ZENER_AC-5.0SMDJ14A,SMLF,IC,BC0MDJ14000     I1 @T6G_MB_LIB.T6G(SCH_1):PAGE372
  PD13    A      A ZENER_AC-5.0SMDJ14A,SMLF,IC,BC0MDJ14000     I3 @T6G_MB_LIB.T6G(SCH_1):PAGE372
 C1797    2      B Q_CAP_0402-0.1UF,25V,10%,X7R,CH4104K1B00     I9 @T6G_MB_LIB.T6G(SCH_1):PAGE372
 R3907    2      B Q_RES_0402LF-33K,1%,1/16W,CHIP,CS33302FB00    I10 @T6G_MB_LIB.T6G(SCH_1):PAGE372
  U290    S      S MOSFET_NCH_GDS_ESD_PROTECTED-2N7002K,SMLF,IC,BAM70A    I11 @T6G_MB_LIB.T6G(SCH_1):PAGE372
 R2585    2      B Q_RES_0402LF-31.6K,1%,1/16W,CHIP,CS33162FB02    I13 @T6G_MB_LIB.T6G(SCH_1):PAGE372
JP4003    3      3 CONN3_210HP1030BR1-CONN3_210-HP1-030BR1,THLF,IO,DFA    I18 @T6G_MB_LIB.T6G(SCH_1):PAGE372
 C2179    2      B Q_CAP_C0402-100NF,50V,10%,X7R,CH4106K1B01    I22 @T6G_MB_LIB.T6G(SCH_1):PAGE372
  PD17    1 ANODE_1 SS15P3SM386A-SS15P3S-M3/86A,SMLF,IC,BC015P3SZ00    I72 @T6G_MB_LIB.T6G(SCH_1):PAGE302
  PD17    2 ANODE_2 SS15P3SM386A-SS15P3S-M3/86A,SMLF,IC,BC015P3SZ00    I72 @T6G_MB_LIB.T6G(SCH_1):PAGE302
 C1787    2      B Q_CAP_C0402-0.1UF,16V,10%,X7R,CH4103K1B08     I6 @T6G_MB_LIB.T6G(SCH_1):PAGE371
  U143    5    GND NCT7718W-NCT7718W,SMLF,IC,AL007718001     I8 @T6G_MB_LIB.T6G(SCH_1):PAGE371
PC1789    2      B Q_CAP_0402-0.1UF,25V,10%,X7R,CH4104K1B00    I28 @T6G_MB_LIB.T6G(SCH_1):PAGE371
   U38    2    GND SN74LVC1G11DCKR-SN74LVC1G11DCKR,SMLF,IC,ALLVC1G1000     I8 @T6G_MB_LIB.T6G(SCH_1):PAGE264
 R1441    2      B Q_RES_0402LF-16.9K,1%,1/16W,CHIP,CS31692FB03    I24 @T6G_MB_LIB.T6G(SCH_1):PAGE264
 R1443    2      B Q_RES_0402LF-16.9K,1%,1/16W,CHIP,CS31692FB03    I27 @T6G_MB_LIB.T6G(SCH_1):PAGE264
   Q19    1     S1 BSS138DW7F-BSS138DW-7-F,SMLF,IC,BAM01380032    I33 @T6G_MB_LIB.T6G(SCH_1):PAGE264
   Q19    4     S2 BSS138DW7F-BSS138DW-7-F,SMLF,IC,BAM01380032    I33 @T6G_MB_LIB.T6G(SCH_1):PAGE264
   Q18    1     S1 BSS138DW7F-BSS138DW-7-F,SMLF,IC,BAM01380032    I36 @T6G_MB_LIB.T6G(SCH_1):PAGE264
   Q18    4     S2 BSS138DW7F-BSS138DW-7-F,SMLF,IC,BAM01380032    I36 @T6G_MB_LIB.T6G(SCH_1):PAGE264
  C347    2      B Q_CAP_0402-0.1UF,25V,10%,X7R,CH4104K1B00    I47 @T6G_MB_LIB.T6G(SCH_1):PAGE264
 C5014    2      B Q_CAP_0402-1000PF,50V,5%,X7R,TMP_QCH21006JB10    I49 @T6G_MB_LIB.T6G(SCH_1):PAGE264
 H6000    1      1 HOLE_TH-EMPTY,HOLE1226   I113 @T6G_MB_LIB.T6G(SCH_1):PAGE212
 H6001    1      1 HOLE_TH-EMPTY,HOLE1226   I116 @T6G_MB_LIB.T6G(SCH_1):PAGE212
 R1318    2      B Q_RES_0402LF-4.7K,5%,1/16W,CHIP,CS24702JB10   I378 @T6G_MB_LIB.T6G(SCH_1):PAGE148
 R1313    2      B Q_RES_0402LF-4.7K,5%,1/16W,CHIP,CS24702JB10   I383 @T6G_MB_LIB.T6G(SCH_1):PAGE148
    U6    5    GND PI3CSW12ZUAEX-PI3CSW12ZUAEX,SMLF,IC,AL3CSW12000    I67 @T6G_MB_LIB.T6G(SCH_1):PAGE138
   C25    2      B Q_CAP_0402-0.1UF,25V,10%,X7R,CH4104K1B00    I69 @T6G_MB_LIB.T6G(SCH_1):PAGE138
 R6185    2      B Q_RES_0402LF-10K,1%,1/16W,CHIP,CS31002FB08   I143 @T6G_MB_LIB.T6G(SCH_1):PAGE82
 R6187    2      B Q_RES_0402LF-10K,1%,1/16W,EMPTY,CS31002FB08   I151 @T6G_MB_LIB.T6G(SCH_1):PAGE82
  PJ38   11     11 SCONN21_9193031121LF-SCONN21_91930-31121LF,SMLF,IOA    I42 @T6G_MB_LIB.T6G(SCH_1):PAGE371
  PJ38   21     21 SCONN21_9193031121LF-SCONN21_91930-31121LF,SMLF,IOA    I42 @T6G_MB_LIB.T6G(SCH_1):PAGE371
  PJ38   G1     G1 SCONN21_9193031121LF-SCONN21_91930-31121LF,SMLF,IOA    I42 @T6G_MB_LIB.T6G(SCH_1):PAGE371
  PJ38   G2     G2 SCONN21_9193031121LF-SCONN21_91930-31121LF,SMLF,IOA    I42 @T6G_MB_LIB.T6G(SCH_1):PAGE371
   U96    4    GND PCA9617ADP-PCA9617ADP,SMLF,IC,AL009617K02    I51 @T6G_MB_LIB.T6G(SCH_1):PAGE137
 U6001   TH   EPAD CYUSB330468LTXI-CYUSB3304-68LTXI,SMLF,IC,AJ0330400A     I1 @T6G_MB_LIB.T6G(SCH_1):PAGE153
 U6001   40    GND CYUSB330468LTXI-CYUSB3304-68LTXI,SMLF,IC,AJ0330400A     I1 @T6G_MB_LIB.T6G(SCH_1):PAGE153
    Y9    2     G1 Q_XTAL_4P_13BI_24GND-26MHZ,SMLF,MISC,BG626000049    I14 @T6G_MB_LIB.T6G(SCH_1):PAGE153
    Y9    4     G2 Q_XTAL_4P_13BI_24GND-26MHZ,SMLF,MISC,BG626000049    I14 @T6G_MB_LIB.T6G(SCH_1):PAGE153
 R4453    2      B Q_RES_0402LF-47K,0.1%,1/16W,EMPTY,CS34702BB05    I23 @T6G_MB_LIB.T6G(SCH_1):PAGE153
 C2317    2      B Q_CAP_C0402-1UF,25V,10%,X6S,CH5104KEB02    I25 @T6G_MB_LIB.T6G(SCH_1):PAGE153
 C6027    2      B Q_CAP_C0805-22UF,16V,20%,X6S,CH6223MEA00    I28 @T6G_MB_LIB.T6G(SCH_1):PAGE153
 C6028    2      B Q_CAP_0402-470PF,50V,10%,X7R,TMP_QCH14706KB18    I29 @T6G_MB_LIB.T6G(SCH_1):PAGE153
 R6202    1      A Q_RES_0402LF-200,1%,1/16W,CHIP,CS12002FB06    I37 @T6G_MB_LIB.T6G(SCH_1):PAGE153
 R6203    1      A Q_RES_0402LF-6.04K,1%,1/16W,CHIP,CS26042FB04    I39 @T6G_MB_LIB.T6G(SCH_1):PAGE153
 R6209    2      B Q_RES_0402LF-10K,1%,1/16W,CHIP,CS31002FB08    I48 @T6G_MB_LIB.T6G(SCH_1):PAGE153
 C6040    2      B Q_CAP_C0402-0.01UF,50V,10%,X7R,CH31006KB18     I5 @T6G_MB_LIB.T6G(SCH_1):PAGE154
 C6041    2      B Q_CAP_0402-0.1UF,25V,10%,X7R,CH4104K1B00     I7 @T6G_MB_LIB.T6G(SCH_1):PAGE154
 C6042    2      B Q_CAP_C0603-22UF,6.3V,20%,X6S,CH6221ME900     I9 @T6G_MB_LIB.T6G(SCH_1):PAGE154
 C6043    2      B Q_CAP_C0402-1UF,25V,10%,X6S,CH5104KEB02    I10 @T6G_MB_LIB.T6G(SCH_1):PAGE154
 C6044    2      B Q_CAP_0402-0.1UF,25V,10%,X7R,CH4104K1B00    I12 @T6G_MB_LIB.T6G(SCH_1):PAGE154
 C6045    2      B Q_CAP_C0402-0.01UF,50V,10%,X7R,CH31006KB18    I13 @T6G_MB_LIB.T6G(SCH_1):PAGE154
 C6046    2      B Q_CAP_C0603-22UF,6.3V,20%,X6S,CH6221ME900    I14 @T6G_MB_LIB.T6G(SCH_1):PAGE154
 C6047    2      B Q_CAP_C0402-1UF,25V,10%,X6S,CH5104KEB02    I15 @T6G_MB_LIB.T6G(SCH_1):PAGE154
 C6048    2      B Q_CAP_0402-0.1UF,25V,10%,X7R,CH4104K1B00    I17 @T6G_MB_LIB.T6G(SCH_1):PAGE154
 C6049    2      B Q_CAP_C0402-0.01UF,50V,10%,X7R,CH31006KB18    I19 @T6G_MB_LIB.T6G(SCH_1):PAGE154
 C6050    2      B Q_CAP_0402-0.1UF,25V,10%,X7R,CH4104K1B00    I20 @T6G_MB_LIB.T6G(SCH_1):PAGE154
 C6051    2      B Q_CAP_C0402-0.01UF,50V,10%,X7R,CH31006KB18    I21 @T6G_MB_LIB.T6G(SCH_1):PAGE154
 C6053    2      B Q_CAP_C0402-0.01UF,50V,10%,X7R,CH31006KB18    I22 @T6G_MB_LIB.T6G(SCH_1):PAGE154
 C6052    2      B Q_CAP_0402-0.1UF,25V,10%,X7R,CH4104K1B00    I23 @T6G_MB_LIB.T6G(SCH_1):PAGE154
 C6030    2      B Q_CAP_C0603-22UF,6.3V,20%,X6S,CH6221ME900    I27 @T6G_MB_LIB.T6G(SCH_1):PAGE154
 C6031    2      B Q_CAP_C0402-1UF,25V,10%,X6S,CH5104KEB02    I29 @T6G_MB_LIB.T6G(SCH_1):PAGE154
 C6035    2      B Q_CAP_C0402-0.01UF,50V,10%,X7R,CH31006KB18    I31 @T6G_MB_LIB.T6G(SCH_1):PAGE154
 C6034    2      B Q_CAP_0402-0.1UF,25V,10%,X7R,CH4104K1B00    I32 @T6G_MB_LIB.T6G(SCH_1):PAGE154
 C6033    2      B Q_CAP_C0402-0.01UF,50V,10%,X7R,CH31006KB18    I34 @T6G_MB_LIB.T6G(SCH_1):PAGE154
 C6032    2      B Q_CAP_0402-0.1UF,25V,10%,X7R,CH4104K1B00    I35 @T6G_MB_LIB.T6G(SCH_1):PAGE154
 C6036    2      B Q_CAP_0402-0.1UF,25V,10%,X7R,CH4104K1B00    I37 @T6G_MB_LIB.T6G(SCH_1):PAGE154
 C6037    2      B Q_CAP_C0402-0.01UF,50V,10%,X7R,CH31006KB18    I38 @T6G_MB_LIB.T6G(SCH_1):PAGE154
 C6039    2      B Q_CAP_C0402-0.01UF,50V,10%,X7R,CH31006KB18    I40 @T6G_MB_LIB.T6G(SCH_1):PAGE154
 C6038    2      B Q_CAP_0402-0.1UF,25V,10%,X7R,CH4104K1B00    I41 @T6G_MB_LIB.T6G(SCH_1):PAGE154
 C6054    2      B Q_CAP_C0402-0.001UF,50V,10%,X7R,CH30106KB19    I43 @T6G_MB_LIB.T6G(SCH_1):PAGE154
 C6055    2      B Q_CAP_C0402-0.01UF,50V,10%,X7R,CH31006KB18    I44 @T6G_MB_LIB.T6G(SCH_1):PAGE154
 C6056    2      B Q_CAP_C0402-0.001UF,50V,10%,X7R,CH30106KB19    I46 @T6G_MB_LIB.T6G(SCH_1):PAGE154
 C6057    2      B Q_CAP_C0402-0.01UF,50V,10%,X7R,CH31006KB18    I47 @T6G_MB_LIB.T6G(SCH_1):PAGE154
 C6058    2      B Q_CAP_C0402-0.001UF,50V,10%,X7R,CH30106KB19    I49 @T6G_MB_LIB.T6G(SCH_1):PAGE154
 C6059    2      B Q_CAP_C0402-0.01UF,50V,10%,X7R,CH31006KB18    I50 @T6G_MB_LIB.T6G(SCH_1):PAGE154
 C6060    2      B Q_CAP_C0402-0.001UF,50V,10%,X7R,CH30106KB19    I52 @T6G_MB_LIB.T6G(SCH_1):PAGE154
 C6061    2      B Q_CAP_C0402-0.01UF,50V,10%,X7R,CH31006KB18    I53 @T6G_MB_LIB.T6G(SCH_1):PAGE154
 C6062    2      B Q_CAP_C0402-0.001UF,50V,10%,X7R,CH30106KB19    I55 @T6G_MB_LIB.T6G(SCH_1):PAGE154
 C6063    2      B Q_CAP_C0402-0.01UF,50V,10%,X7R,CH31006KB18    I56 @T6G_MB_LIB.T6G(SCH_1):PAGE154
 C6064    2      B Q_CAP_0402-0.1UF,25V,10%,X7R,CH4104K1B00    I58 @T6G_MB_LIB.T6G(SCH_1):PAGE154
 C6065    2      B Q_CAP_C0402-1UF,25V,10%,X6S,CH5104KEB02    I59 @T6G_MB_LIB.T6G(SCH_1):PAGE154
 C6066    2      B Q_CAP_C0603-22UF,6.3V,20%,X6S,CH6221ME900    I60 @T6G_MB_LIB.T6G(SCH_1):PAGE154
 C6069    2      B Q_CAP_C0402-0.001UF,50V,10%,X7R,CH30106KB19    I63 @T6G_MB_LIB.T6G(SCH_1):PAGE154
 C6079    2      B Q_CAP_C0603-22UF,6.3V,20%,X6S,CH6221ME900    I64 @T6G_MB_LIB.T6G(SCH_1):PAGE154
 C6078    2      B Q_CAP_C0402-1UF,25V,10%,X6S,CH5104KEB02    I65 @T6G_MB_LIB.T6G(SCH_1):PAGE154
 C6077    2      B Q_CAP_0402-0.1UF,25V,10%,X7R,CH4104K1B00    I66 @T6G_MB_LIB.T6G(SCH_1):PAGE154
 C6076    2      B Q_CAP_C0402-0.01UF,50V,10%,X7R,CH31006KB18    I68 @T6G_MB_LIB.T6G(SCH_1):PAGE154
 C6075    2      B Q_CAP_C0402-0.001UF,50V,10%,X7R,CH30106KB19    I69 @T6G_MB_LIB.T6G(SCH_1):PAGE154
 C6074    2      B Q_CAP_C0402-0.01UF,50V,10%,X7R,CH31006KB18    I71 @T6G_MB_LIB.T6G(SCH_1):PAGE154
 C6073    2      B Q_CAP_C0402-0.001UF,50V,10%,X7R,CH30106KB19    I73 @T6G_MB_LIB.T6G(SCH_1):PAGE154
 C6072    2      B Q_CAP_C0402-0.01UF,50V,10%,X7R,CH31006KB18    I74 @T6G_MB_LIB.T6G(SCH_1):PAGE154
 C6071    2      B Q_CAP_C0402-0.001UF,50V,10%,X7R,CH30106KB19    I75 @T6G_MB_LIB.T6G(SCH_1):PAGE154
 C6070    2      B Q_CAP_C0402-0.01UF,50V,10%,X7R,CH31006KB18    I76 @T6G_MB_LIB.T6G(SCH_1):PAGE154
 C6068    2      B Q_CAP_C0402-0.01UF,50V,10%,X7R,CH31006KB18    I78 @T6G_MB_LIB.T6G(SCH_1):PAGE154
 C6067    2      B Q_CAP_C0402-0.001UF,50V,10%,X7R,CH30106KB19    I79 @T6G_MB_LIB.T6G(SCH_1):PAGE154
 C6080    2      B Q_CAP_C0402-0.01UF,50V,10%,X7R,CH31006KB18    I81 @T6G_MB_LIB.T6G(SCH_1):PAGE154
 C6081    2      B Q_CAP_0402-0.1UF,25V,10%,X7R,CH4104K1B00    I82 @T6G_MB_LIB.T6G(SCH_1):PAGE154
 C6082    2      B Q_CAP_C0402-1UF,25V,10%,X6S,CH5104KEB02    I83 @T6G_MB_LIB.T6G(SCH_1):PAGE154
 U6003    4    VSS M24128BWMN6TP-M24128-BWMN6TP,SMLF,IC,AKE30Z00613    I64 @T6G_MB_LIB.T6G(SCH_1):PAGE153
 R6219    2      B Q_RES_0402LF-10K,1%,1/16W,CHIP,CS31002FB08    I66 @T6G_MB_LIB.T6G(SCH_1):PAGE153
 R6221    2      B Q_RES_0402LF-10K,1%,1/16W,CHIP,CS31002FB08    I67 @T6G_MB_LIB.T6G(SCH_1):PAGE153
 R6217    2      B Q_RES_0402LF-10K,1%,1/16W,EMPTY,CS31002FB08    I68 @T6G_MB_LIB.T6G(SCH_1):PAGE153
 C6083    2      B Q_CAP_0402-0.1UF,25V,10%,X7R,CH4104K1B00    I75 @T6G_MB_LIB.T6G(SCH_1):PAGE153
 R6223    2      B Q_RES_0402LF-1K,1%,1/16W,CHIP,CS21002FB06    I77 @T6G_MB_LIB.T6G(SCH_1):PAGE153
  U142    2    GND LT6700CS61TRPBF-LT6700CS6-1#TRPBF,SMLF,EMPTY,AL006A    I50 @T6G_MB_LIB.T6G(SCH_1):PAGE371
 R6233    2      B Q_RES_0402LF-10K,1%,1/16W,EMPTY,CS31002FB08    I57 @T6G_MB_LIB.T6G(SCH_1):PAGE371
 R6235    2      B Q_RES_0402LF-10K,1%,1/16W,EMPTY,CS31002FB08    I58 @T6G_MB_LIB.T6G(SCH_1):PAGE371
 R6237    2      B Q_RES_0402LF-0,5%,1/16W,EMPTY,CS00002JB13    I66 @T6G_MB_LIB.T6G(SCH_1):PAGE371
 U6004    S      S MOSFET_NCH_GDS_ESD_PROTECTED-2N7002K,SMLF,EMPTY,BAA    I68 @T6G_MB_LIB.T6G(SCH_1):PAGE371
PC6020    2      B Q_CAP_C0402-100NF,50V,10%,X7R,CH4106K1B01     I5 @T6G_MB_LIB.T6G(SCH_1):PAGE315
PC6012    2      B Q_CAP_C0805-22UF,16V,20%,X6S,CH6223MEA01     I8 @T6G_MB_LIB.T6G(SCH_1):PAGE315
PC6014    2      B Q_CAP_C0805-22UF,16V,20%,X6S,CH6223MEA01    I10 @T6G_MB_LIB.T6G(SCH_1):PAGE315
PR6003    2      B Q_RES_0402LF-10K,1%,1/16W,CHIP,CS31002FB08    I12 @T6G_MB_LIB.T6G(SCH_1):PAGE315
PC6008    2      B Q_CAP_C0402-1UF,25V,10%,X6S,CH5104KEB02    I13 @T6G_MB_LIB.T6G(SCH_1):PAGE315
PR6006    1      A Q_RES_0402LF-60.4K,1%,1/16W,CHIP,CS36042FB04    I15 @T6G_MB_LIB.T6G(SCH_1):PAGE315
PU6000    7   AGND MPQ8626GDZ-MPQ8626GD-Z,SMLF,IC,AL008626000    I18 @T6G_MB_LIB.T6G(SCH_1):PAGE315
PU6000    1  PGND1 MPQ8626GDZ-MPQ8626GD-Z,SMLF,IC,AL008626000    I18 @T6G_MB_LIB.T6G(SCH_1):PAGE315
PU6000   14  PGND2 MPQ8626GDZ-MPQ8626GD-Z,SMLF,IC,AL008626000    I18 @T6G_MB_LIB.T6G(SCH_1):PAGE315
PC6010    2      B Q_CAP_C0402-1UF,25V,10%,X6S,CH5104KEB02    I19 @T6G_MB_LIB.T6G(SCH_1):PAGE315
 PC384    2      B Q_CAP_0402-3300PF,50V,10%,X7R,TMP_QCH2336K1B12    I21 @T6G_MB_LIB.T6G(SCH_1):PAGE315
PR6010    2      B Q_RES_0402LF-10K,1%,1/16W,CHIP,CS31002FB08    I23 @T6G_MB_LIB.T6G(SCH_1):PAGE315
PC6021    2      B Q_CAP_C0402-100NF,50V,10%,X7R,CH4106K1B01    I27 @T6G_MB_LIB.T6G(SCH_1):PAGE315
 PC865    2      B Q_CAP_C0805-22UF,4V,20%,X6S,CH622KMEA03    I29 @T6G_MB_LIB.T6G(SCH_1):PAGE315
 PC866    2      B Q_CAP_C0805-22UF,4V,20%,X6S,CH622KMEA03    I34 @T6G_MB_LIB.T6G(SCH_1):PAGE315
 PC867    2      B Q_CAP_C0805-22UF,4V,20%,X6S,CH622KMEA03    I36 @T6G_MB_LIB.T6G(SCH_1):PAGE315
 PC850    2      B Q_CAP_C0805-22UF,4V,20%,X6S,CH622KMEA03    I37 @T6G_MB_LIB.T6G(SCH_1):PAGE315
PC6013    2      B Q_CAP_C0805-22UF,16V,20%,X6S,CH6223MEA01     I3 @T6G_MB_LIB.T6G(SCH_1):PAGE380
PR6004    2      B Q_RES_0402LF-11.5K,1%,1/16W,CHIP,CS31152FB03     I6 @T6G_MB_LIB.T6G(SCH_1):PAGE380
PC6009    2      B Q_CAP_C0402-1UF,25V,10%,X6S,CH5104KEB02     I7 @T6G_MB_LIB.T6G(SCH_1):PAGE380
PC6015    2      B Q_CAP_C0805-22UF,16V,20%,X6S,CH6223MEA01    I10 @T6G_MB_LIB.T6G(SCH_1):PAGE380
PR6005    1      A Q_RES_0402LF-60.4K,1%,1/16W,CHIP,CS36042FB04    I11 @T6G_MB_LIB.T6G(SCH_1):PAGE380
PC6011    2      B Q_CAP_C0402-1UF,25V,10%,X6S,CH5104KEB02    I12 @T6G_MB_LIB.T6G(SCH_1):PAGE380
PU6001    7   AGND MPQ8626GDZ-MPQ8626GD-Z,SMLF,IC,AL008626000    I16 @T6G_MB_LIB.T6G(SCH_1):PAGE380
PU6001    1  PGND1 MPQ8626GDZ-MPQ8626GD-Z,SMLF,IC,AL008626000    I16 @T6G_MB_LIB.T6G(SCH_1):PAGE380
PU6001   14  PGND2 MPQ8626GDZ-MPQ8626GD-Z,SMLF,IC,AL008626000    I16 @T6G_MB_LIB.T6G(SCH_1):PAGE380
PC6016    2      B Q_CAP_0402-3300PF,50V,10%,X7R,TMP_QCH2336K1B12    I17 @T6G_MB_LIB.T6G(SCH_1):PAGE380
PR6011    2      B Q_RES_0402LF-10K,1%,1/16W,CHIP,CS31002FB08    I21 @T6G_MB_LIB.T6G(SCH_1):PAGE380
PC6022    2      B Q_CAP_C0402-100NF,50V,10%,X7R,CH4106K1B01    I23 @T6G_MB_LIB.T6G(SCH_1):PAGE380
PC6024    2      B Q_CAP_C0805-22UF,4V,20%,X6S,CH622KMEA03    I28 @T6G_MB_LIB.T6G(SCH_1):PAGE380
PC6025    2      B Q_CAP_C0805-22UF,4V,20%,X6S,CH622KMEA03    I29 @T6G_MB_LIB.T6G(SCH_1):PAGE380
PC6026    2      B Q_CAP_C0805-22UF,4V,20%,X6S,CH622KMEA03    I32 @T6G_MB_LIB.T6G(SCH_1):PAGE380
PC6018    2      B Q_CAP_C0805-22UF,4V,20%,X6S,CH622KMEA03    I33 @T6G_MB_LIB.T6G(SCH_1):PAGE380
PC6023    2      B Q_CAP_C0402-100NF,50V,10%,X7R,CH4106K1B01    I35 @T6G_MB_LIB.T6G(SCH_1):PAGE380
  C345    2      B Q_CAP_0402-0.1UF,25V,10%,EMPTY,CH4104K1B00    I41 @T6G_MB_LIB.T6G(SCH_1):PAGE315
 C6085    2      B Q_CAP_0402-0.1UF,25V,10%,EMPTY,CH4104K1B00    I41 @T6G_MB_LIB.T6G(SCH_1):PAGE380
 Q6000    1     S1 MOSFET_NCH_DUAL-PJT138K,SMLF,IC,BAM138K0003    I47 @T6G_MB_LIB.T6G(SCH_1):PAGE254
 C6092    2      B Q_CAP_C0402-1UF,25V,10%,X6S,CH5104KEB02    I21 @T6G_MB_LIB.T6G(SCH_1):PAGE157
 C6094    2      B Q_CAP_C0402-0.01UF,50V,10%,X7R,CH31006KB18    I22 @T6G_MB_LIB.T6G(SCH_1):PAGE157
 C6095    2      B Q_CAP_0402-0.1UF,25V,10%,X7R,CH4104K1B00    I23 @T6G_MB_LIB.T6G(SCH_1):PAGE157
 C6093    2      B Q_CAP_C0402-1PF,50V,0.05P,COG,CH-106T0B00    I24 @T6G_MB_LIB.T6G(SCH_1):PAGE157
 C6098    2      B Q_CAP_0402-0.1UF,25V,10%,X7R,CH4104K1B00    I25 @T6G_MB_LIB.T6G(SCH_1):PAGE157
 C6097    2      B Q_CAP_C0402-0.01UF,50V,10%,X7R,CH31006KB18    I26 @T6G_MB_LIB.T6G(SCH_1):PAGE157
 C6096    2      B Q_CAP_C0402-1PF,50V,0.05P,COG,CH-106T0B00    I27 @T6G_MB_LIB.T6G(SCH_1):PAGE157
 C6101    2      B Q_CAP_0402-0.1UF,25V,10%,X7R,CH4104K1B00    I28 @T6G_MB_LIB.T6G(SCH_1):PAGE157
 C6100    2      B Q_CAP_C0402-0.01UF,50V,10%,X7R,CH31006KB18    I29 @T6G_MB_LIB.T6G(SCH_1):PAGE157
 C6099    2      B Q_CAP_C0402-1PF,50V,0.05P,COG,CH-106T0B00    I30 @T6G_MB_LIB.T6G(SCH_1):PAGE157
 C6104    2      B Q_CAP_0402-0.1UF,25V,10%,X7R,CH4104K1B00    I31 @T6G_MB_LIB.T6G(SCH_1):PAGE157
 C6103    2      B Q_CAP_C0402-0.01UF,50V,10%,X7R,CH31006KB18    I32 @T6G_MB_LIB.T6G(SCH_1):PAGE157
 C6102    2      B Q_CAP_C0402-1PF,50V,0.05P,COG,CH-106T0B00    I33 @T6G_MB_LIB.T6G(SCH_1):PAGE157
 C6105    2      B Q_CAP_C0805-10UF,25V,10%,X6S,CH6104KEA00    I36 @T6G_MB_LIB.T6G(SCH_1):PAGE157
 C6108    2      B Q_CAP_0402-0.1UF,25V,10%,X7R,CH4104K1B00    I39 @T6G_MB_LIB.T6G(SCH_1):PAGE157
 C6107    2      B Q_CAP_C0402-0.01UF,50V,10%,X7R,CH31006KB18    I40 @T6G_MB_LIB.T6G(SCH_1):PAGE157
 C6106    2      B Q_CAP_C0402-1PF,50V,0.05P,COG,CH-106T0B00    I41 @T6G_MB_LIB.T6G(SCH_1):PAGE157
 C6111    2      B Q_CAP_0402-0.1UF,25V,10%,X7R,CH4104K1B00    I42 @T6G_MB_LIB.T6G(SCH_1):PAGE157
 C6110    2      B Q_CAP_C0402-0.01UF,50V,10%,X7R,CH31006KB18    I43 @T6G_MB_LIB.T6G(SCH_1):PAGE157
 C6109    2      B Q_CAP_C0402-1PF,50V,0.05P,COG,CH-106T0B00    I44 @T6G_MB_LIB.T6G(SCH_1):PAGE157
 C6114    2      B Q_CAP_0402-0.1UF,25V,10%,X7R,CH4104K1B00    I45 @T6G_MB_LIB.T6G(SCH_1):PAGE157
 C6113    2      B Q_CAP_C0402-0.01UF,50V,10%,X7R,CH31006KB18    I46 @T6G_MB_LIB.T6G(SCH_1):PAGE157
 C6112    2      B Q_CAP_C0402-1PF,50V,0.05P,COG,CH-106T0B00    I47 @T6G_MB_LIB.T6G(SCH_1):PAGE157
 C6117    2      B Q_CAP_0402-0.1UF,25V,10%,X7R,CH4104K1B00    I48 @T6G_MB_LIB.T6G(SCH_1):PAGE157
 C6116    2      B Q_CAP_C0402-0.01UF,50V,10%,X7R,CH31006KB18    I49 @T6G_MB_LIB.T6G(SCH_1):PAGE157
 C6115    2      B Q_CAP_C0402-1PF,50V,0.05P,COG,CH-106T0B00    I50 @T6G_MB_LIB.T6G(SCH_1):PAGE157
 C6121    2      B Q_CAP_0402-0.1UF,25V,10%,X7R,CH4104K1B00    I51 @T6G_MB_LIB.T6G(SCH_1):PAGE157
 C6120    2      B Q_CAP_C0402-0.01UF,50V,10%,X7R,CH31006KB18    I52 @T6G_MB_LIB.T6G(SCH_1):PAGE157
 C6119    2      B Q_CAP_C0402-1PF,50V,0.05P,COG,CH-106T0B00    I53 @T6G_MB_LIB.T6G(SCH_1):PAGE157
 C6118    2      B Q_CAP_C0805-10UF,25V,10%,X6S,CH6104KEA00    I54 @T6G_MB_LIB.T6G(SCH_1):PAGE157
 C6086    2      B Q_CAP_0402-0.1UF,25V,10%,X7R,CH4104K1B00    I11 @T6G_MB_LIB.T6G(SCH_1):PAGE271
 R6251    1      A Q_RES_0402LF-4.7K,1%,1/16W,EMPTY,CS24702FB06    I14 @T6G_MB_LIB.T6G(SCH_1):PAGE271
 C6087    2      B Q_CAP_0402-0.1UF,25V,10%,X7R,CH4104K1B00    I22 @T6G_MB_LIB.T6G(SCH_1):PAGE271
 U6005   10    GND ISL28022FRZT-ISL28022FRZ-T,SMLF,IC,AL028022003    I28 @T6G_MB_LIB.T6G(SCH_1):PAGE271
 U6005   TH TH_GND ISL28022FRZT-ISL28022FRZ-T,SMLF,IC,AL028022003    I28 @T6G_MB_LIB.T6G(SCH_1):PAGE271
 R6250    1      A Q_RES_0402LF-4.7K,1%,1/16W,CHIP,CS24702FB06    I30 @T6G_MB_LIB.T6G(SCH_1):PAGE271
 R6293    2      B Q_RES_0402LF-4.7K,1%,1/16W,CHIP,CS24702FB06    I79 @T6G_MB_LIB.T6G(SCH_1):PAGE157
 R6326    2      B Q_RES_0402LF-4.7K,1%,1/16W,CHIP,CS24702FB06    I89 @T6G_MB_LIB.T6G(SCH_1):PAGE155
    R3    2      B Q_RES_0402LF-2K,1%,1/16W,CHIP,CS22002FB07   I154 @T6G_MB_LIB.T6G(SCH_1):PAGE82
    C1    2      B Q_CAP_0402-0.1UF,25V,10%,X7R,CH4104K1B00   I110 @T6G_MB_LIB.T6G(SCH_1):PAGE361
   R44    2      B Q_RES_0402LF-1K,1%,1/16W,CHIP,CS21002FB06   I115 @T6G_MB_LIB.T6G(SCH_1):PAGE361
    U1    4    VSS M24128BWMN6TP-M24128-BWMN6TP,SMLF,IC,AKE30Z00613    I97 @T6G_MB_LIB.T6G(SCH_1):PAGE361
   R62    2      B Q_RES_0402LF-1K,1%,1/16W,CHIP,CS21002FB06   I104 @T6G_MB_LIB.T6G(SCH_1):PAGE361
   R54    2      B Q_RES_0402LF-1K,1%,1/16W,CHIP,CS21002FB06   I107 @T6G_MB_LIB.T6G(SCH_1):PAGE361
   R69    2      B Q_RES_0402LF-10K,1%,1/16W,CHIP,CS31002FB08   I121 @T6G_MB_LIB.T6G(SCH_1):PAGE361
  R136    2      B Q_RES_0402LF-10K,1%,1/16W,EMPTY,CS31002FB08   I162 @T6G_MB_LIB.T6G(SCH_1):PAGE82
  R126    2      B Q_RES_0402LF-10K,1%,1/16W,CHIP,CS31002FB08   I163 @T6G_MB_LIB.T6G(SCH_1):PAGE82
   C11    2      B Q_CAP_0402-0.1UF,25V,10%,X7R,CH4104K1B00    I89 @T6G_MB_LIB.T6G(SCH_1):PAGE138
    C3    2      B Q_CAP_0402-0.1UF,25V,10%,X7R,CH4104K1B00    I56 @T6G_MB_LIB.T6G(SCH_1):PAGE137
    C2    2      B Q_CAP_0402-0.1UF,25V,10%,X7R,CH4104K1B00    I59 @T6G_MB_LIB.T6G(SCH_1):PAGE137
  R339    2      B Q_RES_0201LF-49.9,1%,1/20W,EMPTY,CS04991FE06   I120 @T6G_MB_LIB.T6G(SCH_1):PAGE158
  R340    2      B Q_RES_0201LF-49.9,1%,1/20W,EMPTY,CS04991FE06   I121 @T6G_MB_LIB.T6G(SCH_1):PAGE158
  R345    2      B Q_RES_0201LF-49.9,1%,1/20W,EMPTY,CS04991FE06   I124 @T6G_MB_LIB.T6G(SCH_1):PAGE158
  R343    2      B Q_RES_0201LF-49.9,1%,1/20W,EMPTY,CS04991FE06   I125 @T6G_MB_LIB.T6G(SCH_1):PAGE158
  R346    2      B Q_RES_0201LF-49.9,1%,1/20W,EMPTY,CS04991FE06   I126 @T6G_MB_LIB.T6G(SCH_1):PAGE158
  R344    2      B Q_RES_0201LF-49.9,1%,1/20W,EMPTY,CS04991FE06   I127 @T6G_MB_LIB.T6G(SCH_1):PAGE158
   PJ1    1      1 CONN3_210HP1030BR1-CONN3_210-HP1-030BR1,THLF,IO,DFA   I143 @T6G_MB_LIB.T6G(SCH_1):PAGE168
 R6214    2      B Q_RES_0402LF-10K,1%,1/16W,EMPTY,CS31002FB08    I88 @T6G_MB_LIB.T6G(SCH_1):PAGE153
 R6216    2      B Q_RES_0402LF-10K,1%,1/16W,EMPTY,CS31002FB08    I90 @T6G_MB_LIB.T6G(SCH_1):PAGE153
  R341    2      B Q_RES_0402LF-51,5%,1/16W,EMPTY,CS05102JB04   I145 @T6G_MB_LIB.T6G(SCH_1):PAGE158
  R342    2      B Q_RES_0402LF-51,5%,1/16W,EMPTY,CS05102JB04   I146 @T6G_MB_LIB.T6G(SCH_1):PAGE158
 PR159    2      B Q_RES_0402LF-5.23K,1%,1/16W,CHIP,CS25232FB08   I142 @T6G_MB_LIB.T6G(SCH_1):PAGE185
PR3002    1      A Q_RES_0402LF-0,5%,1/16W,CHIP,CS00002JB13    I27 @T6G_MB_LIB.T6G(SCH_1):PAGE372
 R2227    2      B Q_RES_0402LF-10K,1%,1/16W,EMPTY,CS31002FB08    I29 @T6G_MB_LIB.T6G(SCH_1):PAGE372
 R2222    2      B Q_RES_0402LF-1K,1%,1/16W,EMPTY,CS21002FB06    I33 @T6G_MB_LIB.T6G(SCH_1):PAGE372
  U325    S SOURCE MOSFET_N_SMLF-BSS138K,BSS138K,EMPTY,BAM138K0000    I42 @T6G_MB_LIB.T6G(SCH_1):PAGE372
  U206    2    GND LT6700CS61TRPBF-LT6700CS6-1#TRPBF,SMLF,EMPTY,AL006A    I49 @T6G_MB_LIB.T6G(SCH_1):PAGE372
   J45   B3     B3 CONN60_101062636003K02LF-CONN60_10106263-6003K02LFA   I466 @T6G_MB_LIB.T6G(SCH_1):PAGE363
   J45 P1_1   P1_1 CONN60_101062636003K02LF-CONN60_10106263-6003K02LFA   I466 @T6G_MB_LIB.T6G(SCH_1):PAGE363
   J45 P1_2   P1_2 CONN60_101062636003K02LF-CONN60_10106263-6003K02LFA   I466 @T6G_MB_LIB.T6G(SCH_1):PAGE363
   J45 P1_3   P1_3 CONN60_101062636003K02LF-CONN60_10106263-6003K02LFA   I466 @T6G_MB_LIB.T6G(SCH_1):PAGE363
   J45 P1_4   P1_4 CONN60_101062636003K02LF-CONN60_10106263-6003K02LFA   I466 @T6G_MB_LIB.T6G(SCH_1):PAGE363
   J45 P1_5   P1_5 CONN60_101062636003K02LF-CONN60_10106263-6003K02LFA   I466 @T6G_MB_LIB.T6G(SCH_1):PAGE363
   J45 P1_6   P1_6 CONN60_101062636003K02LF-CONN60_10106263-6003K02LFA   I466 @T6G_MB_LIB.T6G(SCH_1):PAGE363
   J45 P1_7   P1_7 CONN60_101062636003K02LF-CONN60_10106263-6003K02LFA   I466 @T6G_MB_LIB.T6G(SCH_1):PAGE363
   J45 P1_8   P1_8 CONN60_101062636003K02LF-CONN60_10106263-6003K02LFA   I466 @T6G_MB_LIB.T6G(SCH_1):PAGE363
   J45 P2_1   P2_1 CONN60_101062636003K02LF-CONN60_10106263-6003K02LFA   I466 @T6G_MB_LIB.T6G(SCH_1):PAGE363
   J45 P2_2   P2_2 CONN60_101062636003K02LF-CONN60_10106263-6003K02LFA   I466 @T6G_MB_LIB.T6G(SCH_1):PAGE363
   J45 P2_3   P2_3 CONN60_101062636003K02LF-CONN60_10106263-6003K02LFA   I466 @T6G_MB_LIB.T6G(SCH_1):PAGE363
   J45 P2_4   P2_4 CONN60_101062636003K02LF-CONN60_10106263-6003K02LFA   I466 @T6G_MB_LIB.T6G(SCH_1):PAGE363
   J45 P2_5   P2_5 CONN60_101062636003K02LF-CONN60_10106263-6003K02LFA   I466 @T6G_MB_LIB.T6G(SCH_1):PAGE363
   J45 P2_6   P2_6 CONN60_101062636003K02LF-CONN60_10106263-6003K02LFA   I466 @T6G_MB_LIB.T6G(SCH_1):PAGE363
   J45 P2_7   P2_7 CONN60_101062636003K02LF-CONN60_10106263-6003K02LFA   I466 @T6G_MB_LIB.T6G(SCH_1):PAGE363
   J45 P2_8   P2_8 CONN60_101062636003K02LF-CONN60_10106263-6003K02LFA   I466 @T6G_MB_LIB.T6G(SCH_1):PAGE363
   J45 P3_1   P3_1 CONN60_101062636003K02LF-CONN60_10106263-6003K02LFA   I466 @T6G_MB_LIB.T6G(SCH_1):PAGE363
   J45 P3_2   P3_2 CONN60_101062636003K02LF-CONN60_10106263-6003K02LFA   I466 @T6G_MB_LIB.T6G(SCH_1):PAGE363
   J45 P3_3   P3_3 CONN60_101062636003K02LF-CONN60_10106263-6003K02LFA   I466 @T6G_MB_LIB.T6G(SCH_1):PAGE363
   J45 P3_4   P3_4 CONN60_101062636003K02LF-CONN60_10106263-6003K02LFA   I466 @T6G_MB_LIB.T6G(SCH_1):PAGE363
   J45 P3_5   P3_5 CONN60_101062636003K02LF-CONN60_10106263-6003K02LFA   I466 @T6G_MB_LIB.T6G(SCH_1):PAGE363
   J45 P3_6   P3_6 CONN60_101062636003K02LF-CONN60_10106263-6003K02LFA   I466 @T6G_MB_LIB.T6G(SCH_1):PAGE363
   J45 P3_7   P3_7 CONN60_101062636003K02LF-CONN60_10106263-6003K02LFA   I466 @T6G_MB_LIB.T6G(SCH_1):PAGE363
   J45 P3_8   P3_8 CONN60_101062636003K02LF-CONN60_10106263-6003K02LFA   I466 @T6G_MB_LIB.T6G(SCH_1):PAGE363
 R6125    2      B Q_RES_0402LF-1K,1%,1/16W,EMPTY,CS21002FB06   I116 @T6G_MB_LIB.T6G(SCH_1):PAGE83
 R6141    2      B Q_RES_0402LF-1K,1%,1/16W,EMPTY,CS21002FB06   I118 @T6G_MB_LIB.T6G(SCH_1):PAGE83
 R6126    2      B Q_RES_0402LF-1K,1%,1/16W,CHIP,CS21002FB06   I119 @T6G_MB_LIB.T6G(SCH_1):PAGE83
 R6142    2      B Q_RES_0402LF-1K,1%,1/16W,CHIP,CS21002FB06   I122 @T6G_MB_LIB.T6G(SCH_1):PAGE83
PC2167    2      B Q_CAP_0402-100PF,50V,5%,NPO,CH11006JB00    I58 @T6G_MB_LIB.T6G(SCH_1):PAGE344
   J48    2      2 SCONN8_G802M0083150RD3HR-SCONN8_G802M0083150RD3HR,A   I424 @T6G_MB_LIB.T6G(SCH_1):PAGE27
   J48    4      4 SCONN8_G802M0083150RD3HR-SCONN8_G802M0083150RD3HR,A   I424 @T6G_MB_LIB.T6G(SCH_1):PAGE27
   J48    6      6 SCONN8_G802M0083150RD3HR-SCONN8_G802M0083150RD3HR,A   I424 @T6G_MB_LIB.T6G(SCH_1):PAGE27
   J48    8      8 SCONN8_G802M0083150RD3HR-SCONN8_G802M0083150RD3HR,A   I424 @T6G_MB_LIB.T6G(SCH_1):PAGE27
    J5    2      2 SCONN8_G802M0083150RD3HR-SCONN8_G802M0083150RD3HR,A   I425 @T6G_MB_LIB.T6G(SCH_1):PAGE27
    J5    4      4 SCONN8_G802M0083150RD3HR-SCONN8_G802M0083150RD3HR,A   I425 @T6G_MB_LIB.T6G(SCH_1):PAGE27
    J5    6      6 SCONN8_G802M0083150RD3HR-SCONN8_G802M0083150RD3HR,A   I425 @T6G_MB_LIB.T6G(SCH_1):PAGE27
    J5    8      8 SCONN8_G802M0083150RD3HR-SCONN8_G802M0083150RD3HR,A   I425 @T6G_MB_LIB.T6G(SCH_1):PAGE27
    J7    2      2 SCONN8_G802M0083150RD3HR-SCONN8_G802M0083150RD3HR,A   I418 @T6G_MB_LIB.T6G(SCH_1):PAGE54
    J7    4      4 SCONN8_G802M0083150RD3HR-SCONN8_G802M0083150RD3HR,A   I418 @T6G_MB_LIB.T6G(SCH_1):PAGE54
    J7    6      6 SCONN8_G802M0083150RD3HR-SCONN8_G802M0083150RD3HR,A   I418 @T6G_MB_LIB.T6G(SCH_1):PAGE54
    J7    8      8 SCONN8_G802M0083150RD3HR-SCONN8_G802M0083150RD3HR,A   I418 @T6G_MB_LIB.T6G(SCH_1):PAGE54
   J49    2      2 SCONN8_G802M0083150RD3HR-SCONN8_G802M0083150RD3HR,A   I419 @T6G_MB_LIB.T6G(SCH_1):PAGE54
   J49    4      4 SCONN8_G802M0083150RD3HR-SCONN8_G802M0083150RD3HR,A   I419 @T6G_MB_LIB.T6G(SCH_1):PAGE54
   J49    6      6 SCONN8_G802M0083150RD3HR-SCONN8_G802M0083150RD3HR,A   I419 @T6G_MB_LIB.T6G(SCH_1):PAGE54
   J49    8      8 SCONN8_G802M0083150RD3HR-SCONN8_G802M0083150RD3HR,A   I419 @T6G_MB_LIB.T6G(SCH_1):PAGE54
 Y8004    2     G1 Q_XTAL_4P_13BI_24GND-12MHZ,SMLF,MISC,BG6120000B0   I210 @T6G_MB_LIB.T6G(SCH_1):PAGE358
 Y8004    4     G2 Q_XTAL_4P_13BI_24GND-12MHZ,SMLF,MISC,BG6120000B0   I210 @T6G_MB_LIB.T6G(SCH_1):PAGE358
 PR464    1      A Q_RES_0402LF-13.7K,1%,1/16W,CHIP,CS31372FB03    I89 @T6G_MB_LIB.T6G(SCH_1):PAGE199
 U6002   TH TH_VSS TUSB8042AIRGCR-TUSB8042AIRGCR,SMLF,IC,AL008042000   I101 @T6G_MB_LIB.T6G(SCH_1):PAGE155
 R6272    2      B Q_RES_0402LF-200K,1%,1/16W,CHIP,CS42002FB05   I105 @T6G_MB_LIB.T6G(SCH_1):PAGE155
 R6333    2      B Q_RES_0402LF-47K,0.1%,1/16W,EMPTY,CS34702BB05   I111 @T6G_MB_LIB.T6G(SCH_1):PAGE155
 R6325    2      B Q_RES_0402LF-10K,1%,1/16W,CHIP,CS31002FB08   I116 @T6G_MB_LIB.T6G(SCH_1):PAGE155
 R6319    2      B Q_RES_0402LF-10K,1%,1/16W,CHIP,CS31002FB08   I121 @T6G_MB_LIB.T6G(SCH_1):PAGE155
 C6088    2      B Q_CAP_C0805-10UF,16V,10%,X6S,CH6103KEA00   I127 @T6G_MB_LIB.T6G(SCH_1):PAGE155
 R6321    2      B Q_RES_0402LF-47K,0.1%,1/16W,EMPTY,CS34702BB05   I129 @T6G_MB_LIB.T6G(SCH_1):PAGE155
 R6278    2      B Q_RES_0402LF-10K,1%,1/16W,EMPTY,CS31002FB08   I124 @T6G_MB_LIB.T6G(SCH_1):PAGE157
 C6089    2      B Q_CAP_C0402-1UF,25V,10%,X6S,CH5104KEB02   I145 @T6G_MB_LIB.T6G(SCH_1):PAGE155
 R6281    2      B Q_RES_0402LF-1K,1%,1/16W,EMPTY,CS21002FB06   I139 @T6G_MB_LIB.T6G(SCH_1):PAGE157
 R6302    2      B Q_RES_0402LF-200K,1%,1/16W,CHIP,CS42002FB05   I175 @T6G_MB_LIB.T6G(SCH_1):PAGE155
 R6307    2      B Q_RES_0402LF-4.7K,1%,1/16W,EMPTY,CS24702FB06   I156 @T6G_MB_LIB.T6G(SCH_1):PAGE157
 R6309    2      B Q_RES_0402LF-200K,1%,1/16W,CHIP,CS42002FB05   I158 @T6G_MB_LIB.T6G(SCH_1):PAGE157
 R6330    1      A Q_RES_0402LF-4.7K,1%,1/16W,CHIP,CS24702FB06   I188 @T6G_MB_LIB.T6G(SCH_1):PAGE155
 Y6000    2     G1 Q_XTAL_4P_13BI_24GND-24MHZ,SMLF,MISC,BG624000101   I164 @T6G_MB_LIB.T6G(SCH_1):PAGE157
 Y6000    4     G2 Q_XTAL_4P_13BI_24GND-24MHZ,SMLF,MISC,BG624000101   I164 @T6G_MB_LIB.T6G(SCH_1):PAGE157
 R6288    2      B Q_RES_0402LF-1K,1%,1/16W,EMPTY,CS21002FB06   I198 @T6G_MB_LIB.T6G(SCH_1):PAGE155
 R6331    2      B Q_RES_0402LF-9.53K,1%,1/16W,CHIP,CS29532FB06   I207 @T6G_MB_LIB.T6G(SCH_1):PAGE155
 R6332    2      B Q_RES_0402LF-12K,1%,1/16W,CHIP,CS31202FB04   I208 @T6G_MB_LIB.T6G(SCH_1):PAGE155
  U100    2    GND RT9818C44GV-RT9818C-44GV,SMLF,IC,AL009818001    I77 @T6G_MB_LIB.T6G(SCH_1):PAGE273
 C6122    2      B Q_CAP_C0402-100NF,50V,10%,X7R,CH4106K1B01    I79 @T6G_MB_LIB.T6G(SCH_1):PAGE273
  R480    2      B Q_RES_0402LF-100K,1%,1/16W,CHIP,CS41002FB09    I84 @T6G_MB_LIB.T6G(SCH_1):PAGE273
 R6050    2      B Q_RES_0402LF-100K,1%,1/16W,EMPTY,CS41002FB09    I91 @T6G_MB_LIB.T6G(SCH_1):PAGE273
    Q1    1     S1 MOSFET_NCH_DUAL-PJT138K,SMLF,IC,BAM138K0003    I97 @T6G_MB_LIB.T6G(SCH_1):PAGE273
    Q1    4     S2 MOSFET_NCH_DUAL-PJT138K,SMLF,IC,BAM138K0003    I98 @T6G_MB_LIB.T6G(SCH_1):PAGE273
    Q3    1     S1 MOSFET_NCH_DUAL-PJT138K,SMLF,IC,BAM138K0003   I107 @T6G_MB_LIB.T6G(SCH_1):PAGE273
    Q3    4     S2 MOSFET_NCH_DUAL-PJT138K,SMLF,IC,BAM138K0003   I108 @T6G_MB_LIB.T6G(SCH_1):PAGE273
   C29    2      B Q_CAP_C0402-0.22UF,25V,10%,X7R,CH4224K1B01   I116 @T6G_MB_LIB.T6G(SCH_1):PAGE273
   Q27    1     S1 BSS138DW7F-BSS138DW-7-F,SMLF,IC,BAM01380032   I123 @T6G_MB_LIB.T6G(SCH_1):PAGE273
   Q27    4     S2 BSS138DW7F-BSS138DW-7-F,SMLF,IC,BAM01380032   I123 @T6G_MB_LIB.T6G(SCH_1):PAGE273
 U6006    1    GND APX80929SAG7-APX809-29SAG-7,SMLF,IC,AL080929000   I131 @T6G_MB_LIB.T6G(SCH_1):PAGE273
 C6500    2      B Q_CAP_0402-0.1UF,25V,10%,X7R,CH4104K1B00   I133 @T6G_MB_LIB.T6G(SCH_1):PAGE273
 R6501    2      B Q_RES_0402LF-100K,1%,1/16W,CHIP,CS41002FB09   I139 @T6G_MB_LIB.T6G(SCH_1):PAGE273
  H111    2   GND2 GND_HOLE_TH-EMPTY,TMP-QGND_HOLE12   I120 @T6G_MB_LIB.T6G(SCH_1):PAGE212
  H111    3   GND3 GND_HOLE_TH-EMPTY,TMP-QGND_HOLE12   I120 @T6G_MB_LIB.T6G(SCH_1):PAGE212
  H111    4   GND4 GND_HOLE_TH-EMPTY,TMP-QGND_HOLE12   I120 @T6G_MB_LIB.T6G(SCH_1):PAGE212
  H111    5   GND5 GND_HOLE_TH-EMPTY,TMP-QGND_HOLE12   I120 @T6G_MB_LIB.T6G(SCH_1):PAGE212
  H111    6   GND6 GND_HOLE_TH-EMPTY,TMP-QGND_HOLE12   I120 @T6G_MB_LIB.T6G(SCH_1):PAGE212
  H111    7   GND7 GND_HOLE_TH-EMPTY,TMP-QGND_HOLE12   I120 @T6G_MB_LIB.T6G(SCH_1):PAGE212
  H111    8   GND8 GND_HOLE_TH-EMPTY,TMP-QGND_HOLE12   I120 @T6G_MB_LIB.T6G(SCH_1):PAGE212
  H111    9   GND9 GND_HOLE_TH-EMPTY,TMP-QGND_HOLE12   I120 @T6G_MB_LIB.T6G(SCH_1):PAGE212
  H112    2   GND2 GND_HOLE_TH-EMPTY,TMP-QGND_HOLE12   I123 @T6G_MB_LIB.T6G(SCH_1):PAGE212
  H112    3   GND3 GND_HOLE_TH-EMPTY,TMP-QGND_HOLE12   I123 @T6G_MB_LIB.T6G(SCH_1):PAGE212
  H112    4   GND4 GND_HOLE_TH-EMPTY,TMP-QGND_HOLE12   I123 @T6G_MB_LIB.T6G(SCH_1):PAGE212
  H112    5   GND5 GND_HOLE_TH-EMPTY,TMP-QGND_HOLE12   I123 @T6G_MB_LIB.T6G(SCH_1):PAGE212
  H112    6   GND6 GND_HOLE_TH-EMPTY,TMP-QGND_HOLE12   I123 @T6G_MB_LIB.T6G(SCH_1):PAGE212
  H112    7   GND7 GND_HOLE_TH-EMPTY,TMP-QGND_HOLE12   I123 @T6G_MB_LIB.T6G(SCH_1):PAGE212
  H112    8   GND8 GND_HOLE_TH-EMPTY,TMP-QGND_HOLE12   I123 @T6G_MB_LIB.T6G(SCH_1):PAGE212
  H112    9   GND9 GND_HOLE_TH-EMPTY,TMP-QGND_HOLE12   I123 @T6G_MB_LIB.T6G(SCH_1):PAGE212
 R6502    2      B Q_RES_0402LF-2.2K,5%,1/16W,CHIP,CS22202JB07   I224 @T6G_MB_LIB.T6G(SCH_1):PAGE28
 R6503    2      B Q_RES_0402LF-2.2K,5%,1/16W,CHIP,CS22202JB07   I392 @T6G_MB_LIB.T6G(SCH_1):PAGE55
  U320    3    GND 74LVC1G66GV-74LVC1G66GV,SMLF,IC,AL001G66000    I82 @T6G_MB_LIB.T6G(SCH_1):PAGE337
  U321    3    GND 74LVC1G66GV-74LVC1G66GV,SMLF,IC,AL001G66000    I76 @T6G_MB_LIB.T6G(SCH_1):PAGE342
   H86    1      1 HOLE_TH-EMPTY,HOLE596   I125 @T6G_MB_LIB.T6G(SCH_1):PAGE212
   H87    1      1 HOLE_TH-EMPTY,HOLE596   I127 @T6G_MB_LIB.T6G(SCH_1):PAGE212
   H88    1      1 HOLE_TH-EMPTY,HOLE596   I129 @T6G_MB_LIB.T6G(SCH_1):PAGE212
   H89    1      1 HOLE_TH-EMPTY,HOLE596   I132 @T6G_MB_LIB.T6G(SCH_1):PAGE212
   H91    1      1 HOLE_TH-EMPTY,HOLE596   I133 @T6G_MB_LIB.T6G(SCH_1):PAGE212
   H92    1      1 HOLE_TH-EMPTY,HOLE596   I135 @T6G_MB_LIB.T6G(SCH_1):PAGE212
   H93    1      1 HOLE_TH-EMPTY,HOLE596   I138 @T6G_MB_LIB.T6G(SCH_1):PAGE212
   H94    1      1 HOLE_TH-EMPTY,HOLE596   I140 @T6G_MB_LIB.T6G(SCH_1):PAGE212
   H95    1      1 HOLE_TH-EMPTY,HOLE596   I141 @T6G_MB_LIB.T6G(SCH_1):PAGE212
   H96    1      1 HOLE_TH-EMPTY,HOLE596   I142 @T6G_MB_LIB.T6G(SCH_1):PAGE212
   H97    1      1 HOLE_TH-EMPTY,HOLE596   I145 @T6G_MB_LIB.T6G(SCH_1):PAGE212
   H98    1      1 HOLE_TH-EMPTY,HOLE596   I147 @T6G_MB_LIB.T6G(SCH_1):PAGE212
   H99    1      1 HOLE_TH-EMPTY,HOLE596   I149 @T6G_MB_LIB.T6G(SCH_1):PAGE212
  H100    1      1 HOLE_TH-EMPTY,HOLE596   I152 @T6G_MB_LIB.T6G(SCH_1):PAGE212
  H101    1      1 HOLE_TH-EMPTY,HOLE596   I153 @T6G_MB_LIB.T6G(SCH_1):PAGE212
  H102    1      1 HOLE_TH-EMPTY,HOLE596   I156 @T6G_MB_LIB.T6G(SCH_1):PAGE212
  H103    1      1 HOLE_TH-EMPTY,HOLE596   I157 @T6G_MB_LIB.T6G(SCH_1):PAGE212
  H104    1      1 HOLE_TH-EMPTY,HOLE596   I159 @T6G_MB_LIB.T6G(SCH_1):PAGE212
  H105    1      1 HOLE_TH-EMPTY,HOLE596   I161 @T6G_MB_LIB.T6G(SCH_1):PAGE212
  H106    1      1 HOLE_TH-EMPTY,HOLE596   I163 @T6G_MB_LIB.T6G(SCH_1):PAGE212
  H128    1      1 HOLE_TH-EMPTY,HOLE596   I166 @T6G_MB_LIB.T6G(SCH_1):PAGE212
 H6002    1      1 HOLE_TH-EMPTY,HOLE1195   I168 @T6G_MB_LIB.T6G(SCH_1):PAGE212
 Q9000    1     S1 MOSFET_NCH_DUAL-PJT138K,SMLF,IC,BAM138K0003    I21 @T6G_MB_LIB.T6G(SCH_1):PAGE330
 Q8000    4     S2 MOSFET_NCH_DUAL-PJT138K,SMLF,IC,BAM138K0003    I30 @T6G_MB_LIB.T6G(SCH_1):PAGE330
 C8001    2      B Q_CAP_0402-0.1UF,25V,10%,EMPTY,CH4104K1B00    I68 @T6G_MB_LIB.T6G(SCH_1):PAGE258
 C8002    2      B Q_CAP_0402-0.1UF,25V,10%,EMPTY,CH4104K1B00    I70 @T6G_MB_LIB.T6G(SCH_1):PAGE258
 C8003    2      B Q_CAP_0402-0.1UF,25V,10%,EMPTY,CH4104K1B00    I72 @T6G_MB_LIB.T6G(SCH_1):PAGE258
 C8004    2      B Q_CAP_0402-0.1UF,25V,10%,EMPTY,CH4104K1B00    I74 @T6G_MB_LIB.T6G(SCH_1):PAGE258
 D8000    C      C Q_LED_SMLF-LED_BLUE,LTST-C281TBKT-5A,IC,BEBL0172Z00    I42 @T6G_MB_LIB.T6G(SCH_1):PAGE375
 D8001    C      C Q_LED_SMLF-LED_BLUE,LTST-C281TBKT-5A,IC,BEBL0172Z00    I52 @T6G_MB_LIB.T6G(SCH_1):PAGE375
 Q8001    1     S1 MOSFET_NCH_DUAL-PJT138K,SMLF,IC,BAM138K0003    I57 @T6G_MB_LIB.T6G(SCH_1):PAGE375
 Q8001    4     S2 MOSFET_NCH_DUAL-PJT138K,SMLF,IC,BAM138K0003    I58 @T6G_MB_LIB.T6G(SCH_1):PAGE375
 R1800    2      B Q_RES_0402LF-1.21K,1%,1/16W,CHIP,CS21212FB05   I170 @T6G_MB_LIB.T6G(SCH_1):PAGE369
 C8005    2      B Q_CAP_0402-0.1UF,25V,10%,X7R,CH4104K1B00   I101 @T6G_MB_LIB.T6G(SCH_1):PAGE84
    C6    2      B Q_CAP_0402-0.1UF,25V,10%,EMPTY,CH4104K1B00   I111 @T6G_MB_LIB.T6G(SCH_1):PAGE331
 C8006    2      B Q_CAP_0402-0.1UF,25V,10%,X7R,CH4104K1B00   I163 @T6G_MB_LIB.T6G(SCH_1):PAGE149
 R1895    2      B Q_RES_0402LF-0,5%,1/16W,CHIP,CS00002JB13   I169 @T6G_MB_LIB.T6G(SCH_1):PAGE335
 U8000    2    GND NC7SB3157P6X-NC7SB3157P6X,SMLF,IC,ALSB3157000     I1 @T6G_MB_LIB.T6G(SCH_1):PAGE130
 C8007    2      B Q_CAP_0402-0.1UF,25V,10%,X7R,CH4104K1B00     I4 @T6G_MB_LIB.T6G(SCH_1):PAGE130
 R8033    2      B Q_RES_0402LF-1K,1%,1/16W,CHIP,CS21002FB06   I170 @T6G_MB_LIB.T6G(SCH_1):PAGE82
 C8010    2      B Q_CAP_0402-0.1UF,25V,10%,X7R,CH4104K1B00    I64 @T6G_MB_LIB.T6G(SCH_1):PAGE323
 U8003    1    GND APX80929SAG7-APX809-29SAG-7,SMLF,IC,AL080929000    I65 @T6G_MB_LIB.T6G(SCH_1):PAGE323
 R8099    2      B Q_RES_0402LF-100K,1%,1/16W,CHIP,CS41002FB09    I68 @T6G_MB_LIB.T6G(SCH_1):PAGE323
 C8011    2      B Q_CAP_0402-0.1UF,25V,10%,EMPTY,CH4104K1B00   I469 @T6G_MB_LIB.T6G(SCH_1):PAGE363
 U8004    3     2A 74LVC2G07DW7-74LVC2G07DW-7,SMLF,EMPTY,AL002G07003    I16 @T6G_MB_LIB.T6G(SCH_1):PAGE365
 U8004    2    GND 74LVC2G07DW7-74LVC2G07DW-7,SMLF,EMPTY,AL002G07003    I16 @T6G_MB_LIB.T6G(SCH_1):PAGE365
 C8013    2      B Q_CAP_0402-0.1UF,25V,10%,EMPTY,CH4104K1B00    I23 @T6G_MB_LIB.T6G(SCH_1):PAGE365
 C8012    2      B Q_CAP_C0402-1UF,25V,10%,EMPTY,CH5104KEB02    I25 @T6G_MB_LIB.T6G(SCH_1):PAGE365
 C2030    2      B Q_CAP_0402-15PF,50V,5%,C0G,CH01506JB06   I211 @T6G_MB_LIB.T6G(SCH_1):PAGE358
 C2029    2      B Q_CAP_0402-15PF,50V,5%,C0G,CH01506JB06   I212 @T6G_MB_LIB.T6G(SCH_1):PAGE358
   C91    2      B Q_CAP_C0402-12PF,50V,5%,C0G,CH01206JB05    I92 @T6G_MB_LIB.T6G(SCH_1):PAGE153
 R8109    2      B Q_RES_0402LF-10K,1%,1/16W,EMPTY,CS31002FB08    I82 @T6G_MB_LIB.T6G(SCH_1):PAGE371
 C8014    2      B Q_CAP_C0402-100NF,50V,10%,EMPTY,CH4106K1B01    I87 @T6G_MB_LIB.T6G(SCH_1):PAGE371
 C8015    2      B Q_CAP_C0402-100NF,50V,10%,EMPTY,CH4106K1B01    I89 @T6G_MB_LIB.T6G(SCH_1):PAGE371
 C8016    2      B Q_CAP_C0402-100NF,50V,10%,EMPTY,CH4106K1B01    I95 @T6G_MB_LIB.T6G(SCH_1):PAGE371
 U8005    2     2- LM4040AIM3X25NOPB-LM4040AIM3X-2.5/NOPB,SMLF,EMPTY,A   I101 @T6G_MB_LIB.T6G(SCH_1):PAGE371
 U8006    2    GND AP331AWG7-AP331AWG-7,SMLF,EMPTY,AL000331011   I104 @T6G_MB_LIB.T6G(SCH_1):PAGE371
 U8007    2     2- LM4040AIM3X25NOPB-LM4040AIM3X-2.5/NOPB,SMLF,IC,AL4A    I51 @T6G_MB_LIB.T6G(SCH_1):PAGE372
 R8115    2      B Q_RES_0402LF-5.11K,1%,1/16W,CHIP,CS25112FB04    I55 @T6G_MB_LIB.T6G(SCH_1):PAGE372
 C8017    2      B Q_CAP_C0402-100NF,50V,10%,EMPTY,CH4106K1B01    I59 @T6G_MB_LIB.T6G(SCH_1):PAGE372
 C8018    2      B Q_CAP_C0402-100NF,50V,10%,EMPTY,CH4106K1B01    I61 @T6G_MB_LIB.T6G(SCH_1):PAGE372
 C8019    2      B Q_CAP_C0402-100NF,50V,10%,X7R,CH4106K1B01    I66 @T6G_MB_LIB.T6G(SCH_1):PAGE372
 U8008    2    GND AP331AWG7-AP331AWG-7,SMLF,IC,AL000331011    I71 @T6G_MB_LIB.T6G(SCH_1):PAGE372
 R8122    2      B Q_RES_0402LF-5.11K,1%,1/16W,CHIP,CS25112FB04    I75 @T6G_MB_LIB.T6G(SCH_1):PAGE372
 C8020    2      B Q_CAP_C0402-100NF,50V,10%,EMPTY,CH4106K1B01    I79 @T6G_MB_LIB.T6G(SCH_1):PAGE372
 U8010    2    GND AP331AWG7-AP331AWG-7,SMLF,IC,AL000331011    I80 @T6G_MB_LIB.T6G(SCH_1):PAGE372
 C8022    2      B Q_CAP_C0402-100NF,50V,10%,X7R,CH4106K1B01    I84 @T6G_MB_LIB.T6G(SCH_1):PAGE372
 C8021    2      B Q_CAP_C0402-100NF,50V,10%,EMPTY,CH4106K1B01    I92 @T6G_MB_LIB.T6G(SCH_1):PAGE372
 U8009    2     2- LM4040AIM3X25NOPB-LM4040AIM3X-2.5/NOPB,SMLF,IC,AL4A    I93 @T6G_MB_LIB.T6G(SCH_1):PAGE372
PC8000    2      B Q_CAP_C0805-22UF,16V,20%,X6S,CH6223MEA01    I44 @T6G_MB_LIB.T6G(SCH_1):PAGE167
PC8001    2      B Q_CAP_C0805-22UF,16V,20%,X6S,CH6223MEA01    I45 @T6G_MB_LIB.T6G(SCH_1):PAGE167
PC8002    2      B Q_CAP_C0805-22UF,16V,20%,X6S,CH6223MEA01    I57 @T6G_MB_LIB.T6G(SCH_1):PAGE184
PC8003    2      B Q_CAP_C0805-22UF,16V,20%,X6S,CH6223MEA01    I57 @T6G_MB_LIB.T6G(SCH_1):PAGE201
PC8004    2      B Q_CAP_C0805-22UF,16V,20%,X6S,CH6223MEA01    I93 @T6G_MB_LIB.T6G(SCH_1):PAGE183
PC8005    2      B Q_CAP_C0805-22UF,16V,20%,X6S,CH6223MEA01    I94 @T6G_MB_LIB.T6G(SCH_1):PAGE183
PC8006    2      B Q_CAP_C0805-22UF,16V,20%,X6S,CH6223MEA01    I93 @T6G_MB_LIB.T6G(SCH_1):PAGE200
PC8007    2      B Q_CAP_C0805-22UF,16V,20%,X6S,CH6223MEA01    I94 @T6G_MB_LIB.T6G(SCH_1):PAGE200
PC8009    2      B Q_CAP_C0805-22UF,16V,20%,X6S,CH6223MEA01    I87 @T6G_MB_LIB.T6G(SCH_1):PAGE173
PC8010    2      B Q_CAP_C0805-22UF,16V,20%,X6S,CH6223MEA01    I88 @T6G_MB_LIB.T6G(SCH_1):PAGE173
PC8011    2      B Q_CAP_C0805-22UF,16V,20%,X6S,CH6223MEA01    I87 @T6G_MB_LIB.T6G(SCH_1):PAGE190
PC8012    2      B Q_CAP_C0805-22UF,16V,20%,X6S,CH6223MEA01    I88 @T6G_MB_LIB.T6G(SCH_1):PAGE190
PC8013    2      B Q_CAP_C0805-22UF,16V,20%,X6S,CH6223MEA01    I70 @T6G_MB_LIB.T6G(SCH_1):PAGE245
PC8014    2      B Q_CAP_C0805-22UF,16V,20%,X6S,CH6223MEA01    I71 @T6G_MB_LIB.T6G(SCH_1):PAGE245
 U6014 AC13   GND1 PT5161LRS-PT5161LRS,SMLF,IC,AJ051610U03     I2 @T6G_MB_LIB.T6G(SCH_1):PAGE400
 U6014 AC22   GND2 PT5161LRS-PT5161LRS,SMLF,IC,AJ051610U03     I2 @T6G_MB_LIB.T6G(SCH_1):PAGE400
 U6014 AC32   GND3 PT5161LRS-PT5161LRS,SMLF,IC,AJ051610U03     I2 @T6G_MB_LIB.T6G(SCH_1):PAGE400
 U6014  AC4   GND4 PT5161LRS-PT5161LRS,SMLF,IC,AJ051610U03     I2 @T6G_MB_LIB.T6G(SCH_1):PAGE400
 U6014  AD2   GND5 PT5161LRS-PT5161LRS,SMLF,IC,AJ051610U03     I2 @T6G_MB_LIB.T6G(SCH_1):PAGE400
 U6014 AD34   GND6 PT5161LRS-PT5161LRS,SMLF,IC,AJ051610U03     I2 @T6G_MB_LIB.T6G(SCH_1):PAGE400
 U6014  AE1   GND7 PT5161LRS-PT5161LRS,SMLF,IC,AJ051610U03     I2 @T6G_MB_LIB.T6G(SCH_1):PAGE400
 U6014 AE35   GND8 PT5161LRS-PT5161LRS,SMLF,IC,AJ051610U03     I2 @T6G_MB_LIB.T6G(SCH_1):PAGE400
 U6014 AK13   GND9 PT5161LRS-PT5161LRS,SMLF,IC,AJ051610U03     I2 @T6G_MB_LIB.T6G(SCH_1):PAGE400
 U6014 AK22  GND10 PT5161LRS-PT5161LRS,SMLF,IC,AJ051610U03     I2 @T6G_MB_LIB.T6G(SCH_1):PAGE400
 U6014 AK32  GND11 PT5161LRS-PT5161LRS,SMLF,IC,AJ051610U03     I2 @T6G_MB_LIB.T6G(SCH_1):PAGE400
 U6014  AK4  GND12 PT5161LRS-PT5161LRS,SMLF,IC,AJ051610U03     I2 @T6G_MB_LIB.T6G(SCH_1):PAGE400
 U6014  AL2  GND13 PT5161LRS-PT5161LRS,SMLF,IC,AJ051610U03     I2 @T6G_MB_LIB.T6G(SCH_1):PAGE400
 U6014 AL34  GND14 PT5161LRS-PT5161LRS,SMLF,IC,AJ051610U03     I2 @T6G_MB_LIB.T6G(SCH_1):PAGE400
 U6014  AM1  GND15 PT5161LRS-PT5161LRS,SMLF,IC,AJ051610U03     I2 @T6G_MB_LIB.T6G(SCH_1):PAGE400
 U6014 AM35  GND16 PT5161LRS-PT5161LRS,SMLF,IC,AJ051610U03     I2 @T6G_MB_LIB.T6G(SCH_1):PAGE400
 U6014 AU13  GND17 PT5161LRS-PT5161LRS,SMLF,IC,AJ051610U03     I2 @T6G_MB_LIB.T6G(SCH_1):PAGE400
 U6014 AU22  GND18 PT5161LRS-PT5161LRS,SMLF,IC,AJ051610U03     I2 @T6G_MB_LIB.T6G(SCH_1):PAGE400
 U6014 AU32  GND19 PT5161LRS-PT5161LRS,SMLF,IC,AJ051610U03     I2 @T6G_MB_LIB.T6G(SCH_1):PAGE400
 U6014  AU4  GND20 PT5161LRS-PT5161LRS,SMLF,IC,AJ051610U03     I2 @T6G_MB_LIB.T6G(SCH_1):PAGE400
 U6014  AV2  GND21 PT5161LRS-PT5161LRS,SMLF,IC,AJ051610U03     I2 @T6G_MB_LIB.T6G(SCH_1):PAGE400
 U6014 AV34  GND22 PT5161LRS-PT5161LRS,SMLF,IC,AJ051610U03     I2 @T6G_MB_LIB.T6G(SCH_1):PAGE400
 U6014  AW1  GND23 PT5161LRS-PT5161LRS,SMLF,IC,AJ051610U03     I2 @T6G_MB_LIB.T6G(SCH_1):PAGE400
 U6014 AW35  GND24 PT5161LRS-PT5161LRS,SMLF,IC,AJ051610U03     I2 @T6G_MB_LIB.T6G(SCH_1):PAGE400
 U6014  B19  GND25 PT5161LRS-PT5161LRS,SMLF,IC,AJ051610U03     I2 @T6G_MB_LIB.T6G(SCH_1):PAGE400
 U6014 BD13  GND26 PT5161LRS-PT5161LRS,SMLF,IC,AJ051610U03     I2 @T6G_MB_LIB.T6G(SCH_1):PAGE400
 U6014 BD22  GND27 PT5161LRS-PT5161LRS,SMLF,IC,AJ051610U03     I2 @T6G_MB_LIB.T6G(SCH_1):PAGE400
 U6014 BD32  GND28 PT5161LRS-PT5161LRS,SMLF,IC,AJ051610U03     I2 @T6G_MB_LIB.T6G(SCH_1):PAGE400
 U6014  BD4  GND29 PT5161LRS-PT5161LRS,SMLF,IC,AJ051610U03     I2 @T6G_MB_LIB.T6G(SCH_1):PAGE400
 U6014  BE2  GND30 PT5161LRS-PT5161LRS,SMLF,IC,AJ051610U03     I2 @T6G_MB_LIB.T6G(SCH_1):PAGE400
 U6014 BE34  GND31 PT5161LRS-PT5161LRS,SMLF,IC,AJ051610U03     I2 @T6G_MB_LIB.T6G(SCH_1):PAGE400
 U6014  BF1  GND32 PT5161LRS-PT5161LRS,SMLF,IC,AJ051610U03     I2 @T6G_MB_LIB.T6G(SCH_1):PAGE400
 U6014 BF35  GND33 PT5161LRS-PT5161LRS,SMLF,IC,AJ051610U03     I2 @T6G_MB_LIB.T6G(SCH_1):PAGE400
 U6014 BL13  GND34 PT5161LRS-PT5161LRS,SMLF,IC,AJ051610U03     I2 @T6G_MB_LIB.T6G(SCH_1):PAGE400
 U6014 BL22  GND35 PT5161LRS-PT5161LRS,SMLF,IC,AJ051610U03     I2 @T6G_MB_LIB.T6G(SCH_1):PAGE400
 U6014 BL32  GND36 PT5161LRS-PT5161LRS,SMLF,IC,AJ051610U03     I2 @T6G_MB_LIB.T6G(SCH_1):PAGE400
 U6014  BL4  GND37 PT5161LRS-PT5161LRS,SMLF,IC,AJ051610U03     I2 @T6G_MB_LIB.T6G(SCH_1):PAGE400
 U6014  BM2  GND38 PT5161LRS-PT5161LRS,SMLF,IC,AJ051610U03     I2 @T6G_MB_LIB.T6G(SCH_1):PAGE400
 U6014 BM34  GND39 PT5161LRS-PT5161LRS,SMLF,IC,AJ051610U03     I2 @T6G_MB_LIB.T6G(SCH_1):PAGE400
 U6014  BN1  GND40 PT5161LRS-PT5161LRS,SMLF,IC,AJ051610U03     I2 @T6G_MB_LIB.T6G(SCH_1):PAGE400
 U6014 BN35  GND41 PT5161LRS-PT5161LRS,SMLF,IC,AJ051610U03     I2 @T6G_MB_LIB.T6G(SCH_1):PAGE400
 U6014 BV13  GND42 PT5161LRS-PT5161LRS,SMLF,IC,AJ051610U03     I2 @T6G_MB_LIB.T6G(SCH_1):PAGE400
 U6014 BV22  GND43 PT5161LRS-PT5161LRS,SMLF,IC,AJ051610U03     I2 @T6G_MB_LIB.T6G(SCH_1):PAGE400
 U6014 BV32  GND44 PT5161LRS-PT5161LRS,SMLF,IC,AJ051610U03     I2 @T6G_MB_LIB.T6G(SCH_1):PAGE400
 U6014  BV4  GND45 PT5161LRS-PT5161LRS,SMLF,IC,AJ051610U03     I2 @T6G_MB_LIB.T6G(SCH_1):PAGE400
 U6014  BW2  GND46 PT5161LRS-PT5161LRS,SMLF,IC,AJ051610U03     I2 @T6G_MB_LIB.T6G(SCH_1):PAGE400
 U6014 BW34  GND47 PT5161LRS-PT5161LRS,SMLF,IC,AJ051610U03     I2 @T6G_MB_LIB.T6G(SCH_1):PAGE400
 U6014  BY1  GND48 PT5161LRS-PT5161LRS,SMLF,IC,AJ051610U03     I2 @T6G_MB_LIB.T6G(SCH_1):PAGE400
 U6014 BY35  GND49 PT5161LRS-PT5161LRS,SMLF,IC,AJ051610U03     I2 @T6G_MB_LIB.T6G(SCH_1):PAGE400
 U6014 CE13  GND50 PT5161LRS-PT5161LRS,SMLF,IC,AJ051610U03     I2 @T6G_MB_LIB.T6G(SCH_1):PAGE400
 U6014 CE22  GND51 PT5161LRS-PT5161LRS,SMLF,IC,AJ051610U03     I2 @T6G_MB_LIB.T6G(SCH_1):PAGE400
 U6014 CE32  GND52 PT5161LRS-PT5161LRS,SMLF,IC,AJ051610U03     I2 @T6G_MB_LIB.T6G(SCH_1):PAGE400
 U6014  CE4  GND53 PT5161LRS-PT5161LRS,SMLF,IC,AJ051610U03     I2 @T6G_MB_LIB.T6G(SCH_1):PAGE400
 U6014  CF2  GND54 PT5161LRS-PT5161LRS,SMLF,IC,AJ051610U03     I2 @T6G_MB_LIB.T6G(SCH_1):PAGE400
 U6014 CF34  GND55 PT5161LRS-PT5161LRS,SMLF,IC,AJ051610U03     I2 @T6G_MB_LIB.T6G(SCH_1):PAGE400
 U6014  CG1  GND56 PT5161LRS-PT5161LRS,SMLF,IC,AJ051610U03     I2 @T6G_MB_LIB.T6G(SCH_1):PAGE400
 U6014 CG35  GND57 PT5161LRS-PT5161LRS,SMLF,IC,AJ051610U03     I2 @T6G_MB_LIB.T6G(SCH_1):PAGE400
 U6014 CM13  GND58 PT5161LRS-PT5161LRS,SMLF,IC,AJ051610U03     I2 @T6G_MB_LIB.T6G(SCH_1):PAGE400
 U6014 CM22  GND59 PT5161LRS-PT5161LRS,SMLF,IC,AJ051610U03     I2 @T6G_MB_LIB.T6G(SCH_1):PAGE400
 U6014 CM32  GND60 PT5161LRS-PT5161LRS,SMLF,IC,AJ051610U03     I2 @T6G_MB_LIB.T6G(SCH_1):PAGE400
 U6014  CM4  GND61 PT5161LRS-PT5161LRS,SMLF,IC,AJ051610U03     I2 @T6G_MB_LIB.T6G(SCH_1):PAGE400
 U6014  CN2  GND62 PT5161LRS-PT5161LRS,SMLF,IC,AJ051610U03     I2 @T6G_MB_LIB.T6G(SCH_1):PAGE400
 U6014 CN34  GND63 PT5161LRS-PT5161LRS,SMLF,IC,AJ051610U03     I2 @T6G_MB_LIB.T6G(SCH_1):PAGE400
 U6014  CP1  GND64 PT5161LRS-PT5161LRS,SMLF,IC,AJ051610U03     I2 @T6G_MB_LIB.T6G(SCH_1):PAGE400
 U6014 CP35  GND65 PT5161LRS-PT5161LRS,SMLF,IC,AJ051610U03     I2 @T6G_MB_LIB.T6G(SCH_1):PAGE400
 U6014 CW13  GND66 PT5161LRS-PT5161LRS,SMLF,IC,AJ051610U03     I2 @T6G_MB_LIB.T6G(SCH_1):PAGE400
 U6014 CW22  GND67 PT5161LRS-PT5161LRS,SMLF,IC,AJ051610U03     I2 @T6G_MB_LIB.T6G(SCH_1):PAGE400
 U6014 CW32  GND68 PT5161LRS-PT5161LRS,SMLF,IC,AJ051610U03     I2 @T6G_MB_LIB.T6G(SCH_1):PAGE400
 U6014  CW4  GND69 PT5161LRS-PT5161LRS,SMLF,IC,AJ051610U03     I2 @T6G_MB_LIB.T6G(SCH_1):PAGE400
 U6014  CY2  GND70 PT5161LRS-PT5161LRS,SMLF,IC,AJ051610U03     I2 @T6G_MB_LIB.T6G(SCH_1):PAGE400
 U6014 CY34  GND71 PT5161LRS-PT5161LRS,SMLF,IC,AJ051610U03     I2 @T6G_MB_LIB.T6G(SCH_1):PAGE400
 U6014  DA1  GND72 PT5161LRS-PT5161LRS,SMLF,IC,AJ051610U03     I2 @T6G_MB_LIB.T6G(SCH_1):PAGE400
 U6014 DA35  GND73 PT5161LRS-PT5161LRS,SMLF,IC,AJ051610U03     I2 @T6G_MB_LIB.T6G(SCH_1):PAGE400
 U6014 DF13  GND74 PT5161LRS-PT5161LRS,SMLF,IC,AJ051610U03     I2 @T6G_MB_LIB.T6G(SCH_1):PAGE400
 U6014 DF22  GND75 PT5161LRS-PT5161LRS,SMLF,IC,AJ051610U03     I2 @T6G_MB_LIB.T6G(SCH_1):PAGE400
 U6014 DF32  GND76 PT5161LRS-PT5161LRS,SMLF,IC,AJ051610U03     I2 @T6G_MB_LIB.T6G(SCH_1):PAGE400
 U6014  DF4  GND77 PT5161LRS-PT5161LRS,SMLF,IC,AJ051610U03     I2 @T6G_MB_LIB.T6G(SCH_1):PAGE400
 U6014  DG2  GND78 PT5161LRS-PT5161LRS,SMLF,IC,AJ051610U03     I2 @T6G_MB_LIB.T6G(SCH_1):PAGE400
 U6014 DG34  GND79 PT5161LRS-PT5161LRS,SMLF,IC,AJ051610U03     I2 @T6G_MB_LIB.T6G(SCH_1):PAGE400
 U6014  DH1  GND80 PT5161LRS-PT5161LRS,SMLF,IC,AJ051610U03     I2 @T6G_MB_LIB.T6G(SCH_1):PAGE400
 U6014 DH35  GND81 PT5161LRS-PT5161LRS,SMLF,IC,AJ051610U03     I2 @T6G_MB_LIB.T6G(SCH_1):PAGE400
 U6014 DN13  GND82 PT5161LRS-PT5161LRS,SMLF,IC,AJ051610U03     I2 @T6G_MB_LIB.T6G(SCH_1):PAGE400
 U6014 DN22  GND83 PT5161LRS-PT5161LRS,SMLF,IC,AJ051610U03     I2 @T6G_MB_LIB.T6G(SCH_1):PAGE400
 U6014 DN32  GND84 PT5161LRS-PT5161LRS,SMLF,IC,AJ051610U03     I2 @T6G_MB_LIB.T6G(SCH_1):PAGE400
 U6014  DN4  GND85 PT5161LRS-PT5161LRS,SMLF,IC,AJ051610U03     I2 @T6G_MB_LIB.T6G(SCH_1):PAGE400
 U6014  DP2  GND86 PT5161LRS-PT5161LRS,SMLF,IC,AJ051610U03     I2 @T6G_MB_LIB.T6G(SCH_1):PAGE400
 U6014 DP34  GND87 PT5161LRS-PT5161LRS,SMLF,IC,AJ051610U03     I2 @T6G_MB_LIB.T6G(SCH_1):PAGE400
 U6014  DR1  GND88 PT5161LRS-PT5161LRS,SMLF,IC,AJ051610U03     I2 @T6G_MB_LIB.T6G(SCH_1):PAGE400
 U6014 DR35  GND89 PT5161LRS-PT5161LRS,SMLF,IC,AJ051610U03     I2 @T6G_MB_LIB.T6G(SCH_1):PAGE400
 U6014 DY13  GND90 PT5161LRS-PT5161LRS,SMLF,IC,AJ051610U03     I2 @T6G_MB_LIB.T6G(SCH_1):PAGE400
 U6014 DY22  GND91 PT5161LRS-PT5161LRS,SMLF,IC,AJ051610U03     I2 @T6G_MB_LIB.T6G(SCH_1):PAGE400
 U6014 DY32  GND92 PT5161LRS-PT5161LRS,SMLF,IC,AJ051610U03     I2 @T6G_MB_LIB.T6G(SCH_1):PAGE400
 U6014  DY4  GND93 PT5161LRS-PT5161LRS,SMLF,IC,AJ051610U03     I2 @T6G_MB_LIB.T6G(SCH_1):PAGE400
 U6014  E14  GND94 PT5161LRS-PT5161LRS,SMLF,IC,AJ051610U03     I2 @T6G_MB_LIB.T6G(SCH_1):PAGE400
 U6014  E27  GND95 PT5161LRS-PT5161LRS,SMLF,IC,AJ051610U03     I2 @T6G_MB_LIB.T6G(SCH_1):PAGE400
 U6014  E33  GND96 PT5161LRS-PT5161LRS,SMLF,IC,AJ051610U03     I2 @T6G_MB_LIB.T6G(SCH_1):PAGE400
 U6014  EA2  GND97 PT5161LRS-PT5161LRS,SMLF,IC,AJ051610U03     I2 @T6G_MB_LIB.T6G(SCH_1):PAGE400
 U6014 EA34  GND98 PT5161LRS-PT5161LRS,SMLF,IC,AJ051610U03     I2 @T6G_MB_LIB.T6G(SCH_1):PAGE400
 U6014  EB1  GND99 PT5161LRS-PT5161LRS,SMLF,IC,AJ051610U03     I2 @T6G_MB_LIB.T6G(SCH_1):PAGE400
 U6014 EB35 GND100 PT5161LRS-PT5161LRS,SMLF,IC,AJ051610U03     I2 @T6G_MB_LIB.T6G(SCH_1):PAGE400
 U6014 EG13 GND101 PT5161LRS-PT5161LRS,SMLF,IC,AJ051610U03     I2 @T6G_MB_LIB.T6G(SCH_1):PAGE400
 U6014 EG22 GND102 PT5161LRS-PT5161LRS,SMLF,IC,AJ051610U03     I2 @T6G_MB_LIB.T6G(SCH_1):PAGE400
 U6014 EG32 GND103 PT5161LRS-PT5161LRS,SMLF,IC,AJ051610U03     I2 @T6G_MB_LIB.T6G(SCH_1):PAGE400
 U6014  EG4 GND104 PT5161LRS-PT5161LRS,SMLF,IC,AJ051610U03     I2 @T6G_MB_LIB.T6G(SCH_1):PAGE400
 U6014  EH2 GND105 PT5161LRS-PT5161LRS,SMLF,IC,AJ051610U03     I2 @T6G_MB_LIB.T6G(SCH_1):PAGE400
 U6014 EH34 GND106 PT5161LRS-PT5161LRS,SMLF,IC,AJ051610U03     I2 @T6G_MB_LIB.T6G(SCH_1):PAGE400
 U6014  EJ1 GND107 PT5161LRS-PT5161LRS,SMLF,IC,AJ051610U03     I2 @T6G_MB_LIB.T6G(SCH_1):PAGE400
 U6014 EJ35 GND108 PT5161LRS-PT5161LRS,SMLF,IC,AJ051610U03     I2 @T6G_MB_LIB.T6G(SCH_1):PAGE400
 U6014 EP13 GND109 PT5161LRS-PT5161LRS,SMLF,IC,AJ051610U03     I2 @T6G_MB_LIB.T6G(SCH_1):PAGE400
 U6014 EP22 GND110 PT5161LRS-PT5161LRS,SMLF,IC,AJ051610U03     I2 @T6G_MB_LIB.T6G(SCH_1):PAGE400
 U6014 EP32 GND111 PT5161LRS-PT5161LRS,SMLF,IC,AJ051610U03     I2 @T6G_MB_LIB.T6G(SCH_1):PAGE400
 U6014  EP4 GND112 PT5161LRS-PT5161LRS,SMLF,IC,AJ051610U03     I2 @T6G_MB_LIB.T6G(SCH_1):PAGE400
 U6014  ER2 GND113 PT5161LRS-PT5161LRS,SMLF,IC,AJ051610U03     I2 @T6G_MB_LIB.T6G(SCH_1):PAGE400
 U6014 ER34 GND114 PT5161LRS-PT5161LRS,SMLF,IC,AJ051610U03     I2 @T6G_MB_LIB.T6G(SCH_1):PAGE400
 U6014  ET1 GND115 PT5161LRS-PT5161LRS,SMLF,IC,AJ051610U03     I2 @T6G_MB_LIB.T6G(SCH_1):PAGE400
 U6014 ET35 GND116 PT5161LRS-PT5161LRS,SMLF,IC,AJ051610U03     I2 @T6G_MB_LIB.T6G(SCH_1):PAGE400
 U6014 FA15 GND117 PT5161LRS-PT5161LRS,SMLF,IC,AJ051610U03     I2 @T6G_MB_LIB.T6G(SCH_1):PAGE400
 U6014 FA32 GND118 PT5161LRS-PT5161LRS,SMLF,IC,AJ051610U03     I2 @T6G_MB_LIB.T6G(SCH_1):PAGE400
 U6014  FB2 GND119 PT5161LRS-PT5161LRS,SMLF,IC,AJ051610U03     I2 @T6G_MB_LIB.T6G(SCH_1):PAGE400
 U6014 FB34 GND120 PT5161LRS-PT5161LRS,SMLF,IC,AJ051610U03     I2 @T6G_MB_LIB.T6G(SCH_1):PAGE400
 U6014 FC19 GND121 PT5161LRS-PT5161LRS,SMLF,IC,AJ051610U03     I2 @T6G_MB_LIB.T6G(SCH_1):PAGE400
 U6014 FC23 GND122 PT5161LRS-PT5161LRS,SMLF,IC,AJ051610U03     I2 @T6G_MB_LIB.T6G(SCH_1):PAGE400
 U6014 FC25 GND123 PT5161LRS-PT5161LRS,SMLF,IC,AJ051610U03     I2 @T6G_MB_LIB.T6G(SCH_1):PAGE400
 U6014 FC28 GND124 PT5161LRS-PT5161LRS,SMLF,IC,AJ051610U03     I2 @T6G_MB_LIB.T6G(SCH_1):PAGE400
 U6014  FC3 GND125 PT5161LRS-PT5161LRS,SMLF,IC,AJ051610U03     I2 @T6G_MB_LIB.T6G(SCH_1):PAGE400
 U6014  FC6 GND126 PT5161LRS-PT5161LRS,SMLF,IC,AJ051610U03     I2 @T6G_MB_LIB.T6G(SCH_1):PAGE400
 U6014  FC9 GND127 PT5161LRS-PT5161LRS,SMLF,IC,AJ051610U03     I2 @T6G_MB_LIB.T6G(SCH_1):PAGE400
 U6014  FD1 GND128 PT5161LRS-PT5161LRS,SMLF,IC,AJ051610U03     I2 @T6G_MB_LIB.T6G(SCH_1):PAGE400
 U6014 FD35 GND129 PT5161LRS-PT5161LRS,SMLF,IC,AJ051610U03     I2 @T6G_MB_LIB.T6G(SCH_1):PAGE400
 U6014 FF14 GND130 PT5161LRS-PT5161LRS,SMLF,IC,AJ051610U03     I2 @T6G_MB_LIB.T6G(SCH_1):PAGE400
 U6014 FF21 GND131 PT5161LRS-PT5161LRS,SMLF,IC,AJ051610U03     I2 @T6G_MB_LIB.T6G(SCH_1):PAGE400
 U6014 FJ12 GND132 PT5161LRS-PT5161LRS,SMLF,IC,AJ051610U03     I2 @T6G_MB_LIB.T6G(SCH_1):PAGE400
 U6014 FJ19 GND133 PT5161LRS-PT5161LRS,SMLF,IC,AJ051610U03     I2 @T6G_MB_LIB.T6G(SCH_1):PAGE400
 U6014  H12 GND134 PT5161LRS-PT5161LRS,SMLF,IC,AJ051610U03     I2 @T6G_MB_LIB.T6G(SCH_1):PAGE400
 U6014  H16 GND135 PT5161LRS-PT5161LRS,SMLF,IC,AJ051610U03     I2 @T6G_MB_LIB.T6G(SCH_1):PAGE400
 U6014  H19 GND136 PT5161LRS-PT5161LRS,SMLF,IC,AJ051610U03     I2 @T6G_MB_LIB.T6G(SCH_1):PAGE400
 U6014  H31 GND137 PT5161LRS-PT5161LRS,SMLF,IC,AJ051610U03     I2 @T6G_MB_LIB.T6G(SCH_1):PAGE400
 U6014  J22 GND138 PT5161LRS-PT5161LRS,SMLF,IC,AJ051610U03     I2 @T6G_MB_LIB.T6G(SCH_1):PAGE400
 U6014   J4 GND139 PT5161LRS-PT5161LRS,SMLF,IC,AJ051610U03     I2 @T6G_MB_LIB.T6G(SCH_1):PAGE400
 U6014   K2 GND140 PT5161LRS-PT5161LRS,SMLF,IC,AJ051610U03     I2 @T6G_MB_LIB.T6G(SCH_1):PAGE400
 U6014  K34 GND141 PT5161LRS-PT5161LRS,SMLF,IC,AJ051610U03     I2 @T6G_MB_LIB.T6G(SCH_1):PAGE400
 U6014   L1 GND142 PT5161LRS-PT5161LRS,SMLF,IC,AJ051610U03     I2 @T6G_MB_LIB.T6G(SCH_1):PAGE400
 U6014  L35 GND143 PT5161LRS-PT5161LRS,SMLF,IC,AJ051610U03     I2 @T6G_MB_LIB.T6G(SCH_1):PAGE400
 U6014  T13 GND144 PT5161LRS-PT5161LRS,SMLF,IC,AJ051610U03     I2 @T6G_MB_LIB.T6G(SCH_1):PAGE400
 U6014  T22 GND145 PT5161LRS-PT5161LRS,SMLF,IC,AJ051610U03     I2 @T6G_MB_LIB.T6G(SCH_1):PAGE400
 U6014  T32 GND146 PT5161LRS-PT5161LRS,SMLF,IC,AJ051610U03     I2 @T6G_MB_LIB.T6G(SCH_1):PAGE400
 U6014   T4 GND147 PT5161LRS-PT5161LRS,SMLF,IC,AJ051610U03     I2 @T6G_MB_LIB.T6G(SCH_1):PAGE400
 U6014   U2 GND148 PT5161LRS-PT5161LRS,SMLF,IC,AJ051610U03     I2 @T6G_MB_LIB.T6G(SCH_1):PAGE400
 U6014  U34 GND149 PT5161LRS-PT5161LRS,SMLF,IC,AJ051610U03     I2 @T6G_MB_LIB.T6G(SCH_1):PAGE400
 U6014   V1 GND150 PT5161LRS-PT5161LRS,SMLF,IC,AJ051610U03     I2 @T6G_MB_LIB.T6G(SCH_1):PAGE400
 U6014  V35 GND151 PT5161LRS-PT5161LRS,SMLF,IC,AJ051610U03     I2 @T6G_MB_LIB.T6G(SCH_1):PAGE400
 U6014  E30 T_SENSE PT5161LRS-PT5161LRS,SMLF,IC,AJ051610U03     I1 @T6G_MB_LIB.T6G(SCH_1):PAGE401
 R4490    2      B Q_RES_0402LF-4.75K,1%,1/16W,EMPTY,CS24752FB03     I2 @T6G_MB_LIB.T6G(SCH_1):PAGE160
   C78    2      B Q_CAP_0402-0.1UF,25V,10%,X7R,CH4104K1B00    I18 @T6G_MB_LIB.T6G(SCH_1):PAGE160
 C2334    2      B Q_CAP_0402-0.1UF,25V,10%,X7R,CH4104K1B00    I20 @T6G_MB_LIB.T6G(SCH_1):PAGE160
 R4492    2      B Q_RES_0402LF-10K,1%,1/16W,CHIP,CS31002FB08    I29 @T6G_MB_LIB.T6G(SCH_1):PAGE160
 C2329    2      B Q_CAP_0402-0.1UF,25V,10%,X7R,CH4104K1B00    I40 @T6G_MB_LIB.T6G(SCH_1):PAGE160
   C79    2      B Q_CAP_0402-0.1UF,25V,10%,X7R,CH4104K1B00    I41 @T6G_MB_LIB.T6G(SCH_1):PAGE160
   C80    2      B Q_CAP_0402-0.1UF,25V,10%,X7R,CH4104K1B00    I44 @T6G_MB_LIB.T6G(SCH_1):PAGE160
   C81    2      B Q_CAP_0402-0.1UF,25V,10%,X7R,CH4104K1B00    I45 @T6G_MB_LIB.T6G(SCH_1):PAGE160
 C2339    2      B Q_CAP_0402-0.1UF,25V,10%,X7R,CH4104K1B00    I47 @T6G_MB_LIB.T6G(SCH_1):PAGE160
 R4518    2      B Q_RES_0402LF-10K,1%,1/16W,CHIP,CS31002FB08    I52 @T6G_MB_LIB.T6G(SCH_1):PAGE160
 R4519    2      B Q_RES_0402LF-10K,1%,1/16W,CHIP,CS31002FB08    I53 @T6G_MB_LIB.T6G(SCH_1):PAGE160
 R4520    2      B Q_RES_0402LF-10K,1%,1/16W,CHIP,CS31002FB08    I55 @T6G_MB_LIB.T6G(SCH_1):PAGE160
  U314   33 EPAD_GND 9ZXL0451EKILFT-9ZXL0451EKILFT,SMLF,IC,AL000451003    I63 @T6G_MB_LIB.T6G(SCH_1):PAGE160
  R585    2      B Q_RES_0402LF-10K,1%,1/16W,CHIP,CS31002FB08    I15 @T6G_MB_LIB.T6G(SCH_1):PAGE379
   C68    2      B Q_CAP_0402-0.1UF,25V,10%,X7R,CH4104K1B00    I24 @T6G_MB_LIB.T6G(SCH_1):PAGE379
   C84    2      B Q_CAP_0402-0.1UF,25V,10%,X7R,CH4104K1B00    I26 @T6G_MB_LIB.T6G(SCH_1):PAGE379
   C58    2      B Q_CAP_0402-0.1UF,25V,10%,X7R,CH4104K1B00    I34 @T6G_MB_LIB.T6G(SCH_1):PAGE379
   C90    2      B Q_CAP_0402-0.1UF,25V,10%,X7R,CH4104K1B00    I35 @T6G_MB_LIB.T6G(SCH_1):PAGE379
   C98    2      B Q_CAP_0402-0.1UF,25V,10%,X7R,CH4104K1B00    I36 @T6G_MB_LIB.T6G(SCH_1):PAGE379
  R592    2      B Q_RES_0402LF-10K,1%,1/16W,CHIP,CS31002FB08    I49 @T6G_MB_LIB.T6G(SCH_1):PAGE379
  R593    2      B Q_RES_0402LF-10K,1%,1/16W,CHIP,CS31002FB08    I50 @T6G_MB_LIB.T6G(SCH_1):PAGE379
  R594    2      B Q_RES_0402LF-10K,1%,1/16W,CHIP,CS31002FB08    I51 @T6G_MB_LIB.T6G(SCH_1):PAGE379
   C99    2      B Q_CAP_0402-0.1UF,25V,10%,X7R,CH4104K1B00    I58 @T6G_MB_LIB.T6G(SCH_1):PAGE379
   C75    2      B Q_CAP_0402-0.1UF,25V,10%,X7R,CH4104K1B00    I60 @T6G_MB_LIB.T6G(SCH_1):PAGE379
   U10   33 EPAD_GND 9ZXL0451EKILFT-9ZXL0451EKILFT,SMLF,IC,AL000451003    I63 @T6G_MB_LIB.T6G(SCH_1):PAGE379
  R579    2      B Q_RES_0402LF-4.75K,1%,1/16W,CHIP,CS24752FB03    I64 @T6G_MB_LIB.T6G(SCH_1):PAGE379
 R1070    2      B Q_RES_0201LF-10K,1%,1/20W,CHIP,CS31001FE17     I7 @T6G_MB_LIB.T6G(SCH_1):PAGE419
 R1074    2      B Q_RES_0201LF-4.7K,5%,1/20W,CHIP,CS24701JE04     I9 @T6G_MB_LIB.T6G(SCH_1):PAGE419
 R1112    2      B Q_RES_0201LF-10K,1%,1/20W,CHIP,CS31001FE17     I7 @T6G_MB_LIB.T6G(SCH_1):PAGE430
 R1113    2      B Q_RES_0201LF-10K,1%,1/20W,CHIP,CS31001FE17     I8 @T6G_MB_LIB.T6G(SCH_1):PAGE430
 R1115    2      B Q_RES_0201LF-4.7K,5%,1/20W,CHIP,CS24701JE04     I9 @T6G_MB_LIB.T6G(SCH_1):PAGE430
  J106   A6     A6 CONN112_10137002101LF-CONN112_10137002-101LF,THLF,A    I19 @T6G_MB_LIB.T6G(SCH_1):PAGE327
  J106   A8     A8 CONN112_10137002101LF-CONN112_10137002-101LF,THLF,A    I19 @T6G_MB_LIB.T6G(SCH_1):PAGE327
  J106   B5     B5 CONN112_10137002101LF-CONN112_10137002-101LF,THLF,A    I19 @T6G_MB_LIB.T6G(SCH_1):PAGE327
  J106   B7     B7 CONN112_10137002101LF-CONN112_10137002-101LF,THLF,A    I19 @T6G_MB_LIB.T6G(SCH_1):PAGE327
  J106   D6     D6 CONN112_10137002101LF-CONN112_10137002-101LF,THLF,A    I19 @T6G_MB_LIB.T6G(SCH_1):PAGE327
  J106   D8     D8 CONN112_10137002101LF-CONN112_10137002-101LF,THLF,A    I19 @T6G_MB_LIB.T6G(SCH_1):PAGE327
  J106   E5     E5 CONN112_10137002101LF-CONN112_10137002-101LF,THLF,A    I19 @T6G_MB_LIB.T6G(SCH_1):PAGE327
  J106   E7     E7 CONN112_10137002101LF-CONN112_10137002-101LF,THLF,A    I19 @T6G_MB_LIB.T6G(SCH_1):PAGE327
  J106   G6     G6 CONN112_10137002101LF-CONN112_10137002-101LF,THLF,A    I19 @T6G_MB_LIB.T6G(SCH_1):PAGE327
  J106   G8     G8 CONN112_10137002101LF-CONN112_10137002-101LF,THLF,A    I19 @T6G_MB_LIB.T6G(SCH_1):PAGE327
  J106   H5     H5 CONN112_10137002101LF-CONN112_10137002-101LF,THLF,A    I19 @T6G_MB_LIB.T6G(SCH_1):PAGE327
  J106   H7     H7 CONN112_10137002101LF-CONN112_10137002-101LF,THLF,A    I19 @T6G_MB_LIB.T6G(SCH_1):PAGE327
  J106   J6     J6 CONN112_10137002101LF-CONN112_10137002-101LF,THLF,A    I19 @T6G_MB_LIB.T6G(SCH_1):PAGE327
  J106   J8     J8 CONN112_10137002101LF-CONN112_10137002-101LF,THLF,A    I19 @T6G_MB_LIB.T6G(SCH_1):PAGE327
  J106   K5     K5 CONN112_10137002101LF-CONN112_10137002-101LF,THLF,A    I19 @T6G_MB_LIB.T6G(SCH_1):PAGE327
  J106   K7     K7 CONN112_10137002101LF-CONN112_10137002-101LF,THLF,A    I19 @T6G_MB_LIB.T6G(SCH_1):PAGE327
  J106   M6     M6 CONN112_10137002101LF-CONN112_10137002-101LF,THLF,A    I19 @T6G_MB_LIB.T6G(SCH_1):PAGE327
  J106   M8     M8 CONN112_10137002101LF-CONN112_10137002-101LF,THLF,A    I19 @T6G_MB_LIB.T6G(SCH_1):PAGE327
  J106   N5     N5 CONN112_10137002101LF-CONN112_10137002-101LF,THLF,A    I19 @T6G_MB_LIB.T6G(SCH_1):PAGE327
  J106   N7     N7 CONN112_10137002101LF-CONN112_10137002-101LF,THLF,A    I19 @T6G_MB_LIB.T6G(SCH_1):PAGE327
  J106   A2     A2 CONN112_10137002101LF-CONN112_10137002-101LF,THLF,A    I74 @T6G_MB_LIB.T6G(SCH_1):PAGE327
  J106   A4     A4 CONN112_10137002101LF-CONN112_10137002-101LF,THLF,A    I74 @T6G_MB_LIB.T6G(SCH_1):PAGE327
  J106   B1     B1 CONN112_10137002101LF-CONN112_10137002-101LF,THLF,A    I74 @T6G_MB_LIB.T6G(SCH_1):PAGE327
  J106   B3     B3 CONN112_10137002101LF-CONN112_10137002-101LF,THLF,A    I74 @T6G_MB_LIB.T6G(SCH_1):PAGE327
  J106   D2     D2 CONN112_10137002101LF-CONN112_10137002-101LF,THLF,A    I74 @T6G_MB_LIB.T6G(SCH_1):PAGE327
  J106   D4     D4 CONN112_10137002101LF-CONN112_10137002-101LF,THLF,A    I74 @T6G_MB_LIB.T6G(SCH_1):PAGE327
  J106   E1     E1 CONN112_10137002101LF-CONN112_10137002-101LF,THLF,A    I74 @T6G_MB_LIB.T6G(SCH_1):PAGE327
  J106   E3     E3 CONN112_10137002101LF-CONN112_10137002-101LF,THLF,A    I74 @T6G_MB_LIB.T6G(SCH_1):PAGE327
  J106   G2     G2 CONN112_10137002101LF-CONN112_10137002-101LF,THLF,A    I74 @T6G_MB_LIB.T6G(SCH_1):PAGE327
  J106   G4     G4 CONN112_10137002101LF-CONN112_10137002-101LF,THLF,A    I74 @T6G_MB_LIB.T6G(SCH_1):PAGE327
  J106   H1     H1 CONN112_10137002101LF-CONN112_10137002-101LF,THLF,A    I74 @T6G_MB_LIB.T6G(SCH_1):PAGE327
  J106   H3     H3 CONN112_10137002101LF-CONN112_10137002-101LF,THLF,A    I74 @T6G_MB_LIB.T6G(SCH_1):PAGE327
  J106   J2     J2 CONN112_10137002101LF-CONN112_10137002-101LF,THLF,A    I74 @T6G_MB_LIB.T6G(SCH_1):PAGE327
  J106   J4     J4 CONN112_10137002101LF-CONN112_10137002-101LF,THLF,A    I74 @T6G_MB_LIB.T6G(SCH_1):PAGE327
  J106   K1     K1 CONN112_10137002101LF-CONN112_10137002-101LF,THLF,A    I74 @T6G_MB_LIB.T6G(SCH_1):PAGE327
  J106   K3     K3 CONN112_10137002101LF-CONN112_10137002-101LF,THLF,A    I74 @T6G_MB_LIB.T6G(SCH_1):PAGE327
  J106   M2     M2 CONN112_10137002101LF-CONN112_10137002-101LF,THLF,A    I74 @T6G_MB_LIB.T6G(SCH_1):PAGE327
  J106   M4     M4 CONN112_10137002101LF-CONN112_10137002-101LF,THLF,A    I74 @T6G_MB_LIB.T6G(SCH_1):PAGE327
  J106   N1     N1 CONN112_10137002101LF-CONN112_10137002-101LF,THLF,A    I74 @T6G_MB_LIB.T6G(SCH_1):PAGE327
  J106   N3     N3 CONN112_10137002101LF-CONN112_10137002-101LF,THLF,A    I74 @T6G_MB_LIB.T6G(SCH_1):PAGE327
  J105   A2     A2 CONN112_10137002101LF-CONN112_10137002-101LF,THLF,A    I75 @T6G_MB_LIB.T6G(SCH_1):PAGE326
  J105   A4     A4 CONN112_10137002101LF-CONN112_10137002-101LF,THLF,A    I75 @T6G_MB_LIB.T6G(SCH_1):PAGE326
  J105   B1     B1 CONN112_10137002101LF-CONN112_10137002-101LF,THLF,A    I75 @T6G_MB_LIB.T6G(SCH_1):PAGE326
  J105   B3     B3 CONN112_10137002101LF-CONN112_10137002-101LF,THLF,A    I75 @T6G_MB_LIB.T6G(SCH_1):PAGE326
  J105   D2     D2 CONN112_10137002101LF-CONN112_10137002-101LF,THLF,A    I75 @T6G_MB_LIB.T6G(SCH_1):PAGE326
  J105   D4     D4 CONN112_10137002101LF-CONN112_10137002-101LF,THLF,A    I75 @T6G_MB_LIB.T6G(SCH_1):PAGE326
  J105   E1     E1 CONN112_10137002101LF-CONN112_10137002-101LF,THLF,A    I75 @T6G_MB_LIB.T6G(SCH_1):PAGE326
  J105   E3     E3 CONN112_10137002101LF-CONN112_10137002-101LF,THLF,A    I75 @T6G_MB_LIB.T6G(SCH_1):PAGE326
  J105   G2     G2 CONN112_10137002101LF-CONN112_10137002-101LF,THLF,A    I75 @T6G_MB_LIB.T6G(SCH_1):PAGE326
  J105   G4     G4 CONN112_10137002101LF-CONN112_10137002-101LF,THLF,A    I75 @T6G_MB_LIB.T6G(SCH_1):PAGE326
  J105   H1     H1 CONN112_10137002101LF-CONN112_10137002-101LF,THLF,A    I75 @T6G_MB_LIB.T6G(SCH_1):PAGE326
  J105   H3     H3 CONN112_10137002101LF-CONN112_10137002-101LF,THLF,A    I75 @T6G_MB_LIB.T6G(SCH_1):PAGE326
  J105   J2     J2 CONN112_10137002101LF-CONN112_10137002-101LF,THLF,A    I75 @T6G_MB_LIB.T6G(SCH_1):PAGE326
  J105   J4     J4 CONN112_10137002101LF-CONN112_10137002-101LF,THLF,A    I75 @T6G_MB_LIB.T6G(SCH_1):PAGE326
  J105   K1     K1 CONN112_10137002101LF-CONN112_10137002-101LF,THLF,A    I75 @T6G_MB_LIB.T6G(SCH_1):PAGE326
  J105   K3     K3 CONN112_10137002101LF-CONN112_10137002-101LF,THLF,A    I75 @T6G_MB_LIB.T6G(SCH_1):PAGE326
  J105   M2     M2 CONN112_10137002101LF-CONN112_10137002-101LF,THLF,A    I75 @T6G_MB_LIB.T6G(SCH_1):PAGE326
  J105   M4     M4 CONN112_10137002101LF-CONN112_10137002-101LF,THLF,A    I75 @T6G_MB_LIB.T6G(SCH_1):PAGE326
  J105   N1     N1 CONN112_10137002101LF-CONN112_10137002-101LF,THLF,A    I75 @T6G_MB_LIB.T6G(SCH_1):PAGE326
  J105   N3     N3 CONN112_10137002101LF-CONN112_10137002-101LF,THLF,A    I75 @T6G_MB_LIB.T6G(SCH_1):PAGE326
  J105   A6     A6 CONN112_10137002101LF-CONN112_10137002-101LF,THLF,A    I76 @T6G_MB_LIB.T6G(SCH_1):PAGE326
  J105   A8     A8 CONN112_10137002101LF-CONN112_10137002-101LF,THLF,A    I76 @T6G_MB_LIB.T6G(SCH_1):PAGE326
  J105   B5     B5 CONN112_10137002101LF-CONN112_10137002-101LF,THLF,A    I76 @T6G_MB_LIB.T6G(SCH_1):PAGE326
  J105   B7     B7 CONN112_10137002101LF-CONN112_10137002-101LF,THLF,A    I76 @T6G_MB_LIB.T6G(SCH_1):PAGE326
  J105   D6     D6 CONN112_10137002101LF-CONN112_10137002-101LF,THLF,A    I76 @T6G_MB_LIB.T6G(SCH_1):PAGE326
  J105   D8     D8 CONN112_10137002101LF-CONN112_10137002-101LF,THLF,A    I76 @T6G_MB_LIB.T6G(SCH_1):PAGE326
  J105   E5     E5 CONN112_10137002101LF-CONN112_10137002-101LF,THLF,A    I76 @T6G_MB_LIB.T6G(SCH_1):PAGE326
  J105   E7     E7 CONN112_10137002101LF-CONN112_10137002-101LF,THLF,A    I76 @T6G_MB_LIB.T6G(SCH_1):PAGE326
  J105   G6     G6 CONN112_10137002101LF-CONN112_10137002-101LF,THLF,A    I76 @T6G_MB_LIB.T6G(SCH_1):PAGE326
  J105   G8     G8 CONN112_10137002101LF-CONN112_10137002-101LF,THLF,A    I76 @T6G_MB_LIB.T6G(SCH_1):PAGE326
  J105   H5     H5 CONN112_10137002101LF-CONN112_10137002-101LF,THLF,A    I76 @T6G_MB_LIB.T6G(SCH_1):PAGE326
  J105   H7     H7 CONN112_10137002101LF-CONN112_10137002-101LF,THLF,A    I76 @T6G_MB_LIB.T6G(SCH_1):PAGE326
  J105   J6     J6 CONN112_10137002101LF-CONN112_10137002-101LF,THLF,A    I76 @T6G_MB_LIB.T6G(SCH_1):PAGE326
  J105   J8     J8 CONN112_10137002101LF-CONN112_10137002-101LF,THLF,A    I76 @T6G_MB_LIB.T6G(SCH_1):PAGE326
  J105   K5     K5 CONN112_10137002101LF-CONN112_10137002-101LF,THLF,A    I76 @T6G_MB_LIB.T6G(SCH_1):PAGE326
  J105   K7     K7 CONN112_10137002101LF-CONN112_10137002-101LF,THLF,A    I76 @T6G_MB_LIB.T6G(SCH_1):PAGE326
  J105   M6     M6 CONN112_10137002101LF-CONN112_10137002-101LF,THLF,A    I76 @T6G_MB_LIB.T6G(SCH_1):PAGE326
  J105   M8     M8 CONN112_10137002101LF-CONN112_10137002-101LF,THLF,A    I76 @T6G_MB_LIB.T6G(SCH_1):PAGE326
  J105   N5     N5 CONN112_10137002101LF-CONN112_10137002-101LF,THLF,A    I76 @T6G_MB_LIB.T6G(SCH_1):PAGE326
  J105   N7     N7 CONN112_10137002101LF-CONN112_10137002-101LF,THLF,A    I76 @T6G_MB_LIB.T6G(SCH_1):PAGE326
  J107   A2     A2 CONN112_10137002101LF-CONN112_10137002-101LF,THLF,A    I49 @T6G_MB_LIB.T6G(SCH_1):PAGE317
  J107   A4     A4 CONN112_10137002101LF-CONN112_10137002-101LF,THLF,A    I49 @T6G_MB_LIB.T6G(SCH_1):PAGE317
  J107   B1     B1 CONN112_10137002101LF-CONN112_10137002-101LF,THLF,A    I49 @T6G_MB_LIB.T6G(SCH_1):PAGE317
  J107   B3     B3 CONN112_10137002101LF-CONN112_10137002-101LF,THLF,A    I49 @T6G_MB_LIB.T6G(SCH_1):PAGE317
  J107   D2     D2 CONN112_10137002101LF-CONN112_10137002-101LF,THLF,A    I49 @T6G_MB_LIB.T6G(SCH_1):PAGE317
  J107   D4     D4 CONN112_10137002101LF-CONN112_10137002-101LF,THLF,A    I49 @T6G_MB_LIB.T6G(SCH_1):PAGE317
  J107   E1     E1 CONN112_10137002101LF-CONN112_10137002-101LF,THLF,A    I49 @T6G_MB_LIB.T6G(SCH_1):PAGE317
  J107   E3     E3 CONN112_10137002101LF-CONN112_10137002-101LF,THLF,A    I49 @T6G_MB_LIB.T6G(SCH_1):PAGE317
  J107   G2     G2 CONN112_10137002101LF-CONN112_10137002-101LF,THLF,A    I49 @T6G_MB_LIB.T6G(SCH_1):PAGE317
  J107   G4     G4 CONN112_10137002101LF-CONN112_10137002-101LF,THLF,A    I49 @T6G_MB_LIB.T6G(SCH_1):PAGE317
  J107   H1     H1 CONN112_10137002101LF-CONN112_10137002-101LF,THLF,A    I49 @T6G_MB_LIB.T6G(SCH_1):PAGE317
  J107   H3     H3 CONN112_10137002101LF-CONN112_10137002-101LF,THLF,A    I49 @T6G_MB_LIB.T6G(SCH_1):PAGE317
  J107   J2     J2 CONN112_10137002101LF-CONN112_10137002-101LF,THLF,A    I49 @T6G_MB_LIB.T6G(SCH_1):PAGE317
  J107   J4     J4 CONN112_10137002101LF-CONN112_10137002-101LF,THLF,A    I49 @T6G_MB_LIB.T6G(SCH_1):PAGE317
  J107   K1     K1 CONN112_10137002101LF-CONN112_10137002-101LF,THLF,A    I49 @T6G_MB_LIB.T6G(SCH_1):PAGE317
  J107   K3     K3 CONN112_10137002101LF-CONN112_10137002-101LF,THLF,A    I49 @T6G_MB_LIB.T6G(SCH_1):PAGE317
  J107   M2     M2 CONN112_10137002101LF-CONN112_10137002-101LF,THLF,A    I49 @T6G_MB_LIB.T6G(SCH_1):PAGE317
  J107   M4     M4 CONN112_10137002101LF-CONN112_10137002-101LF,THLF,A    I49 @T6G_MB_LIB.T6G(SCH_1):PAGE317
  J107   N1     N1 CONN112_10137002101LF-CONN112_10137002-101LF,THLF,A    I49 @T6G_MB_LIB.T6G(SCH_1):PAGE317
  J107   N3     N3 CONN112_10137002101LF-CONN112_10137002-101LF,THLF,A    I49 @T6G_MB_LIB.T6G(SCH_1):PAGE317
  J107   A6     A6 CONN112_10137002101LF-CONN112_10137002-101LF,THLF,A    I70 @T6G_MB_LIB.T6G(SCH_1):PAGE317
  J107   A8     A8 CONN112_10137002101LF-CONN112_10137002-101LF,THLF,A    I70 @T6G_MB_LIB.T6G(SCH_1):PAGE317
  J107   B5     B5 CONN112_10137002101LF-CONN112_10137002-101LF,THLF,A    I70 @T6G_MB_LIB.T6G(SCH_1):PAGE317
  J107   B7     B7 CONN112_10137002101LF-CONN112_10137002-101LF,THLF,A    I70 @T6G_MB_LIB.T6G(SCH_1):PAGE317
  J107   D6     D6 CONN112_10137002101LF-CONN112_10137002-101LF,THLF,A    I70 @T6G_MB_LIB.T6G(SCH_1):PAGE317
  J107   D8     D8 CONN112_10137002101LF-CONN112_10137002-101LF,THLF,A    I70 @T6G_MB_LIB.T6G(SCH_1):PAGE317
  J107   E5     E5 CONN112_10137002101LF-CONN112_10137002-101LF,THLF,A    I70 @T6G_MB_LIB.T6G(SCH_1):PAGE317
  J107   E7     E7 CONN112_10137002101LF-CONN112_10137002-101LF,THLF,A    I70 @T6G_MB_LIB.T6G(SCH_1):PAGE317
  J107   G6     G6 CONN112_10137002101LF-CONN112_10137002-101LF,THLF,A    I70 @T6G_MB_LIB.T6G(SCH_1):PAGE317
  J107   G8     G8 CONN112_10137002101LF-CONN112_10137002-101LF,THLF,A    I70 @T6G_MB_LIB.T6G(SCH_1):PAGE317
  J107   H5     H5 CONN112_10137002101LF-CONN112_10137002-101LF,THLF,A    I70 @T6G_MB_LIB.T6G(SCH_1):PAGE317
  J107   H7     H7 CONN112_10137002101LF-CONN112_10137002-101LF,THLF,A    I70 @T6G_MB_LIB.T6G(SCH_1):PAGE317
  J107   J6     J6 CONN112_10137002101LF-CONN112_10137002-101LF,THLF,A    I70 @T6G_MB_LIB.T6G(SCH_1):PAGE317
  J107   J8     J8 CONN112_10137002101LF-CONN112_10137002-101LF,THLF,A    I70 @T6G_MB_LIB.T6G(SCH_1):PAGE317
  J107   K5     K5 CONN112_10137002101LF-CONN112_10137002-101LF,THLF,A    I70 @T6G_MB_LIB.T6G(SCH_1):PAGE317
  J107   K7     K7 CONN112_10137002101LF-CONN112_10137002-101LF,THLF,A    I70 @T6G_MB_LIB.T6G(SCH_1):PAGE317
  J107   M6     M6 CONN112_10137002101LF-CONN112_10137002-101LF,THLF,A    I70 @T6G_MB_LIB.T6G(SCH_1):PAGE317
  J107   M8     M8 CONN112_10137002101LF-CONN112_10137002-101LF,THLF,A    I70 @T6G_MB_LIB.T6G(SCH_1):PAGE317
  J107   N5     N5 CONN112_10137002101LF-CONN112_10137002-101LF,THLF,A    I70 @T6G_MB_LIB.T6G(SCH_1):PAGE317
  J107   N7     N7 CONN112_10137002101LF-CONN112_10137002-101LF,THLF,A    I70 @T6G_MB_LIB.T6G(SCH_1):PAGE317
  J108   A6     A6 CONN112_10137002101LF-CONN112_10137002-101LF,THLF,A    I15 @T6G_MB_LIB.T6G(SCH_1):PAGE320
  J108   A8     A8 CONN112_10137002101LF-CONN112_10137002-101LF,THLF,A    I15 @T6G_MB_LIB.T6G(SCH_1):PAGE320
  J108   B5     B5 CONN112_10137002101LF-CONN112_10137002-101LF,THLF,A    I15 @T6G_MB_LIB.T6G(SCH_1):PAGE320
  J108   B7     B7 CONN112_10137002101LF-CONN112_10137002-101LF,THLF,A    I15 @T6G_MB_LIB.T6G(SCH_1):PAGE320
  J108   D6     D6 CONN112_10137002101LF-CONN112_10137002-101LF,THLF,A    I15 @T6G_MB_LIB.T6G(SCH_1):PAGE320
  J108   D8     D8 CONN112_10137002101LF-CONN112_10137002-101LF,THLF,A    I15 @T6G_MB_LIB.T6G(SCH_1):PAGE320
  J108   E5     E5 CONN112_10137002101LF-CONN112_10137002-101LF,THLF,A    I15 @T6G_MB_LIB.T6G(SCH_1):PAGE320
  J108   E7     E7 CONN112_10137002101LF-CONN112_10137002-101LF,THLF,A    I15 @T6G_MB_LIB.T6G(SCH_1):PAGE320
  J108   G6     G6 CONN112_10137002101LF-CONN112_10137002-101LF,THLF,A    I15 @T6G_MB_LIB.T6G(SCH_1):PAGE320
  J108   G8     G8 CONN112_10137002101LF-CONN112_10137002-101LF,THLF,A    I15 @T6G_MB_LIB.T6G(SCH_1):PAGE320
  J108   H5     H5 CONN112_10137002101LF-CONN112_10137002-101LF,THLF,A    I15 @T6G_MB_LIB.T6G(SCH_1):PAGE320
  J108   H7     H7 CONN112_10137002101LF-CONN112_10137002-101LF,THLF,A    I15 @T6G_MB_LIB.T6G(SCH_1):PAGE320
  J108   J6     J6 CONN112_10137002101LF-CONN112_10137002-101LF,THLF,A    I15 @T6G_MB_LIB.T6G(SCH_1):PAGE320
  J108   J8     J8 CONN112_10137002101LF-CONN112_10137002-101LF,THLF,A    I15 @T6G_MB_LIB.T6G(SCH_1):PAGE320
  J108   K5     K5 CONN112_10137002101LF-CONN112_10137002-101LF,THLF,A    I15 @T6G_MB_LIB.T6G(SCH_1):PAGE320
  J108   K7     K7 CONN112_10137002101LF-CONN112_10137002-101LF,THLF,A    I15 @T6G_MB_LIB.T6G(SCH_1):PAGE320
  J108   M6     M6 CONN112_10137002101LF-CONN112_10137002-101LF,THLF,A    I15 @T6G_MB_LIB.T6G(SCH_1):PAGE320
  J108   M8     M8 CONN112_10137002101LF-CONN112_10137002-101LF,THLF,A    I15 @T6G_MB_LIB.T6G(SCH_1):PAGE320
  J108   N5     N5 CONN112_10137002101LF-CONN112_10137002-101LF,THLF,A    I15 @T6G_MB_LIB.T6G(SCH_1):PAGE320
  J108   N7     N7 CONN112_10137002101LF-CONN112_10137002-101LF,THLF,A    I15 @T6G_MB_LIB.T6G(SCH_1):PAGE320
  J108   A2     A2 CONN112_10137002101LF-CONN112_10137002-101LF,THLF,A    I72 @T6G_MB_LIB.T6G(SCH_1):PAGE320
  J108   A4     A4 CONN112_10137002101LF-CONN112_10137002-101LF,THLF,A    I72 @T6G_MB_LIB.T6G(SCH_1):PAGE320
  J108   B1     B1 CONN112_10137002101LF-CONN112_10137002-101LF,THLF,A    I72 @T6G_MB_LIB.T6G(SCH_1):PAGE320
  J108   B3     B3 CONN112_10137002101LF-CONN112_10137002-101LF,THLF,A    I72 @T6G_MB_LIB.T6G(SCH_1):PAGE320
  J108   D2     D2 CONN112_10137002101LF-CONN112_10137002-101LF,THLF,A    I72 @T6G_MB_LIB.T6G(SCH_1):PAGE320
  J108   D4     D4 CONN112_10137002101LF-CONN112_10137002-101LF,THLF,A    I72 @T6G_MB_LIB.T6G(SCH_1):PAGE320
  J108   E1     E1 CONN112_10137002101LF-CONN112_10137002-101LF,THLF,A    I72 @T6G_MB_LIB.T6G(SCH_1):PAGE320
  J108   E3     E3 CONN112_10137002101LF-CONN112_10137002-101LF,THLF,A    I72 @T6G_MB_LIB.T6G(SCH_1):PAGE320
  J108   G2     G2 CONN112_10137002101LF-CONN112_10137002-101LF,THLF,A    I72 @T6G_MB_LIB.T6G(SCH_1):PAGE320
  J108   G4     G4 CONN112_10137002101LF-CONN112_10137002-101LF,THLF,A    I72 @T6G_MB_LIB.T6G(SCH_1):PAGE320
  J108   H1     H1 CONN112_10137002101LF-CONN112_10137002-101LF,THLF,A    I72 @T6G_MB_LIB.T6G(SCH_1):PAGE320
  J108   H3     H3 CONN112_10137002101LF-CONN112_10137002-101LF,THLF,A    I72 @T6G_MB_LIB.T6G(SCH_1):PAGE320
  J108   J2     J2 CONN112_10137002101LF-CONN112_10137002-101LF,THLF,A    I72 @T6G_MB_LIB.T6G(SCH_1):PAGE320
  J108   J4     J4 CONN112_10137002101LF-CONN112_10137002-101LF,THLF,A    I72 @T6G_MB_LIB.T6G(SCH_1):PAGE320
  J108   K1     K1 CONN112_10137002101LF-CONN112_10137002-101LF,THLF,A    I72 @T6G_MB_LIB.T6G(SCH_1):PAGE320
  J108   K3     K3 CONN112_10137002101LF-CONN112_10137002-101LF,THLF,A    I72 @T6G_MB_LIB.T6G(SCH_1):PAGE320
  J108   M2     M2 CONN112_10137002101LF-CONN112_10137002-101LF,THLF,A    I72 @T6G_MB_LIB.T6G(SCH_1):PAGE320
  J108   M4     M4 CONN112_10137002101LF-CONN112_10137002-101LF,THLF,A    I72 @T6G_MB_LIB.T6G(SCH_1):PAGE320
  J108   N1     N1 CONN112_10137002101LF-CONN112_10137002-101LF,THLF,A    I72 @T6G_MB_LIB.T6G(SCH_1):PAGE320
  J108   N3     N3 CONN112_10137002101LF-CONN112_10137002-101LF,THLF,A    I72 @T6G_MB_LIB.T6G(SCH_1):PAGE320
  J109   A6     A6 CONN112_10137002101LF-CONN112_10137002-101LF,THLF,A    I16 @T6G_MB_LIB.T6G(SCH_1):PAGE319
  J109   A8     A8 CONN112_10137002101LF-CONN112_10137002-101LF,THLF,A    I16 @T6G_MB_LIB.T6G(SCH_1):PAGE319
  J109   B5     B5 CONN112_10137002101LF-CONN112_10137002-101LF,THLF,A    I16 @T6G_MB_LIB.T6G(SCH_1):PAGE319
  J109   B7     B7 CONN112_10137002101LF-CONN112_10137002-101LF,THLF,A    I16 @T6G_MB_LIB.T6G(SCH_1):PAGE319
  J109   D6     D6 CONN112_10137002101LF-CONN112_10137002-101LF,THLF,A    I16 @T6G_MB_LIB.T6G(SCH_1):PAGE319
  J109   D8     D8 CONN112_10137002101LF-CONN112_10137002-101LF,THLF,A    I16 @T6G_MB_LIB.T6G(SCH_1):PAGE319
  J109   E5     E5 CONN112_10137002101LF-CONN112_10137002-101LF,THLF,A    I16 @T6G_MB_LIB.T6G(SCH_1):PAGE319
  J109   E7     E7 CONN112_10137002101LF-CONN112_10137002-101LF,THLF,A    I16 @T6G_MB_LIB.T6G(SCH_1):PAGE319
  J109   G6     G6 CONN112_10137002101LF-CONN112_10137002-101LF,THLF,A    I16 @T6G_MB_LIB.T6G(SCH_1):PAGE319
  J109   G8     G8 CONN112_10137002101LF-CONN112_10137002-101LF,THLF,A    I16 @T6G_MB_LIB.T6G(SCH_1):PAGE319
  J109   H5     H5 CONN112_10137002101LF-CONN112_10137002-101LF,THLF,A    I16 @T6G_MB_LIB.T6G(SCH_1):PAGE319
  J109   H7     H7 CONN112_10137002101LF-CONN112_10137002-101LF,THLF,A    I16 @T6G_MB_LIB.T6G(SCH_1):PAGE319
  J109   J6     J6 CONN112_10137002101LF-CONN112_10137002-101LF,THLF,A    I16 @T6G_MB_LIB.T6G(SCH_1):PAGE319
  J109   J8     J8 CONN112_10137002101LF-CONN112_10137002-101LF,THLF,A    I16 @T6G_MB_LIB.T6G(SCH_1):PAGE319
  J109   K5     K5 CONN112_10137002101LF-CONN112_10137002-101LF,THLF,A    I16 @T6G_MB_LIB.T6G(SCH_1):PAGE319
  J109   K7     K7 CONN112_10137002101LF-CONN112_10137002-101LF,THLF,A    I16 @T6G_MB_LIB.T6G(SCH_1):PAGE319
  J109   M6     M6 CONN112_10137002101LF-CONN112_10137002-101LF,THLF,A    I16 @T6G_MB_LIB.T6G(SCH_1):PAGE319
  J109   M8     M8 CONN112_10137002101LF-CONN112_10137002-101LF,THLF,A    I16 @T6G_MB_LIB.T6G(SCH_1):PAGE319
  J109   N5     N5 CONN112_10137002101LF-CONN112_10137002-101LF,THLF,A    I16 @T6G_MB_LIB.T6G(SCH_1):PAGE319
  J109   N7     N7 CONN112_10137002101LF-CONN112_10137002-101LF,THLF,A    I16 @T6G_MB_LIB.T6G(SCH_1):PAGE319
  J109   A2     A2 CONN112_10137002101LF-CONN112_10137002-101LF,THLF,A    I76 @T6G_MB_LIB.T6G(SCH_1):PAGE319
  J109   A4     A4 CONN112_10137002101LF-CONN112_10137002-101LF,THLF,A    I76 @T6G_MB_LIB.T6G(SCH_1):PAGE319
  J109   B1     B1 CONN112_10137002101LF-CONN112_10137002-101LF,THLF,A    I76 @T6G_MB_LIB.T6G(SCH_1):PAGE319
  J109   B3     B3 CONN112_10137002101LF-CONN112_10137002-101LF,THLF,A    I76 @T6G_MB_LIB.T6G(SCH_1):PAGE319
  J109   D2     D2 CONN112_10137002101LF-CONN112_10137002-101LF,THLF,A    I76 @T6G_MB_LIB.T6G(SCH_1):PAGE319
  J109   D4     D4 CONN112_10137002101LF-CONN112_10137002-101LF,THLF,A    I76 @T6G_MB_LIB.T6G(SCH_1):PAGE319
  J109   E1     E1 CONN112_10137002101LF-CONN112_10137002-101LF,THLF,A    I76 @T6G_MB_LIB.T6G(SCH_1):PAGE319
  J109   E3     E3 CONN112_10137002101LF-CONN112_10137002-101LF,THLF,A    I76 @T6G_MB_LIB.T6G(SCH_1):PAGE319
  J109   G2     G2 CONN112_10137002101LF-CONN112_10137002-101LF,THLF,A    I76 @T6G_MB_LIB.T6G(SCH_1):PAGE319
  J109   G4     G4 CONN112_10137002101LF-CONN112_10137002-101LF,THLF,A    I76 @T6G_MB_LIB.T6G(SCH_1):PAGE319
  J109   H1     H1 CONN112_10137002101LF-CONN112_10137002-101LF,THLF,A    I76 @T6G_MB_LIB.T6G(SCH_1):PAGE319
  J109   H3     H3 CONN112_10137002101LF-CONN112_10137002-101LF,THLF,A    I76 @T6G_MB_LIB.T6G(SCH_1):PAGE319
  J109   J2     J2 CONN112_10137002101LF-CONN112_10137002-101LF,THLF,A    I76 @T6G_MB_LIB.T6G(SCH_1):PAGE319
  J109   J4     J4 CONN112_10137002101LF-CONN112_10137002-101LF,THLF,A    I76 @T6G_MB_LIB.T6G(SCH_1):PAGE319
  J109   K1     K1 CONN112_10137002101LF-CONN112_10137002-101LF,THLF,A    I76 @T6G_MB_LIB.T6G(SCH_1):PAGE319
  J109   K3     K3 CONN112_10137002101LF-CONN112_10137002-101LF,THLF,A    I76 @T6G_MB_LIB.T6G(SCH_1):PAGE319
  J109   M2     M2 CONN112_10137002101LF-CONN112_10137002-101LF,THLF,A    I76 @T6G_MB_LIB.T6G(SCH_1):PAGE319
  J109   M4     M4 CONN112_10137002101LF-CONN112_10137002-101LF,THLF,A    I76 @T6G_MB_LIB.T6G(SCH_1):PAGE319
  J109   N1     N1 CONN112_10137002101LF-CONN112_10137002-101LF,THLF,A    I76 @T6G_MB_LIB.T6G(SCH_1):PAGE319
  J109   N3     N3 CONN112_10137002101LF-CONN112_10137002-101LF,THLF,A    I76 @T6G_MB_LIB.T6G(SCH_1):PAGE319
  J110   A6     A6 CONN112_10137002101LF-CONN112_10137002-101LF,THLF,A    I16 @T6G_MB_LIB.T6G(SCH_1):PAGE318
  J110   A8     A8 CONN112_10137002101LF-CONN112_10137002-101LF,THLF,A    I16 @T6G_MB_LIB.T6G(SCH_1):PAGE318
  J110   B5     B5 CONN112_10137002101LF-CONN112_10137002-101LF,THLF,A    I16 @T6G_MB_LIB.T6G(SCH_1):PAGE318
  J110   B7     B7 CONN112_10137002101LF-CONN112_10137002-101LF,THLF,A    I16 @T6G_MB_LIB.T6G(SCH_1):PAGE318
  J110   D6     D6 CONN112_10137002101LF-CONN112_10137002-101LF,THLF,A    I16 @T6G_MB_LIB.T6G(SCH_1):PAGE318
  J110   D8     D8 CONN112_10137002101LF-CONN112_10137002-101LF,THLF,A    I16 @T6G_MB_LIB.T6G(SCH_1):PAGE318
  J110   E5     E5 CONN112_10137002101LF-CONN112_10137002-101LF,THLF,A    I16 @T6G_MB_LIB.T6G(SCH_1):PAGE318
  J110   E7     E7 CONN112_10137002101LF-CONN112_10137002-101LF,THLF,A    I16 @T6G_MB_LIB.T6G(SCH_1):PAGE318
  J110   G6     G6 CONN112_10137002101LF-CONN112_10137002-101LF,THLF,A    I16 @T6G_MB_LIB.T6G(SCH_1):PAGE318
  J110   G8     G8 CONN112_10137002101LF-CONN112_10137002-101LF,THLF,A    I16 @T6G_MB_LIB.T6G(SCH_1):PAGE318
  J110   H5     H5 CONN112_10137002101LF-CONN112_10137002-101LF,THLF,A    I16 @T6G_MB_LIB.T6G(SCH_1):PAGE318
  J110   H7     H7 CONN112_10137002101LF-CONN112_10137002-101LF,THLF,A    I16 @T6G_MB_LIB.T6G(SCH_1):PAGE318
  J110   J6     J6 CONN112_10137002101LF-CONN112_10137002-101LF,THLF,A    I16 @T6G_MB_LIB.T6G(SCH_1):PAGE318
  J110   J8     J8 CONN112_10137002101LF-CONN112_10137002-101LF,THLF,A    I16 @T6G_MB_LIB.T6G(SCH_1):PAGE318
  J110   K5     K5 CONN112_10137002101LF-CONN112_10137002-101LF,THLF,A    I16 @T6G_MB_LIB.T6G(SCH_1):PAGE318
  J110   K7     K7 CONN112_10137002101LF-CONN112_10137002-101LF,THLF,A    I16 @T6G_MB_LIB.T6G(SCH_1):PAGE318
  J110   M6     M6 CONN112_10137002101LF-CONN112_10137002-101LF,THLF,A    I16 @T6G_MB_LIB.T6G(SCH_1):PAGE318
  J110   M8     M8 CONN112_10137002101LF-CONN112_10137002-101LF,THLF,A    I16 @T6G_MB_LIB.T6G(SCH_1):PAGE318
  J110   N5     N5 CONN112_10137002101LF-CONN112_10137002-101LF,THLF,A    I16 @T6G_MB_LIB.T6G(SCH_1):PAGE318
  J110   N7     N7 CONN112_10137002101LF-CONN112_10137002-101LF,THLF,A    I16 @T6G_MB_LIB.T6G(SCH_1):PAGE318
  J110   A2     A2 CONN112_10137002101LF-CONN112_10137002-101LF,THLF,A    I76 @T6G_MB_LIB.T6G(SCH_1):PAGE318
  J110   A4     A4 CONN112_10137002101LF-CONN112_10137002-101LF,THLF,A    I76 @T6G_MB_LIB.T6G(SCH_1):PAGE318
  J110   B1     B1 CONN112_10137002101LF-CONN112_10137002-101LF,THLF,A    I76 @T6G_MB_LIB.T6G(SCH_1):PAGE318
  J110   B3     B3 CONN112_10137002101LF-CONN112_10137002-101LF,THLF,A    I76 @T6G_MB_LIB.T6G(SCH_1):PAGE318
  J110   D2     D2 CONN112_10137002101LF-CONN112_10137002-101LF,THLF,A    I76 @T6G_MB_LIB.T6G(SCH_1):PAGE318
  J110   D4     D4 CONN112_10137002101LF-CONN112_10137002-101LF,THLF,A    I76 @T6G_MB_LIB.T6G(SCH_1):PAGE318
  J110   E1     E1 CONN112_10137002101LF-CONN112_10137002-101LF,THLF,A    I76 @T6G_MB_LIB.T6G(SCH_1):PAGE318
  J110   E3     E3 CONN112_10137002101LF-CONN112_10137002-101LF,THLF,A    I76 @T6G_MB_LIB.T6G(SCH_1):PAGE318
  J110   G2     G2 CONN112_10137002101LF-CONN112_10137002-101LF,THLF,A    I76 @T6G_MB_LIB.T6G(SCH_1):PAGE318
  J110   G4     G4 CONN112_10137002101LF-CONN112_10137002-101LF,THLF,A    I76 @T6G_MB_LIB.T6G(SCH_1):PAGE318
  J110   H1     H1 CONN112_10137002101LF-CONN112_10137002-101LF,THLF,A    I76 @T6G_MB_LIB.T6G(SCH_1):PAGE318
  J110   H3     H3 CONN112_10137002101LF-CONN112_10137002-101LF,THLF,A    I76 @T6G_MB_LIB.T6G(SCH_1):PAGE318
  J110   J2     J2 CONN112_10137002101LF-CONN112_10137002-101LF,THLF,A    I76 @T6G_MB_LIB.T6G(SCH_1):PAGE318
  J110   J4     J4 CONN112_10137002101LF-CONN112_10137002-101LF,THLF,A    I76 @T6G_MB_LIB.T6G(SCH_1):PAGE318
  J110   K1     K1 CONN112_10137002101LF-CONN112_10137002-101LF,THLF,A    I76 @T6G_MB_LIB.T6G(SCH_1):PAGE318
  J110   K3     K3 CONN112_10137002101LF-CONN112_10137002-101LF,THLF,A    I76 @T6G_MB_LIB.T6G(SCH_1):PAGE318
  J110   M2     M2 CONN112_10137002101LF-CONN112_10137002-101LF,THLF,A    I76 @T6G_MB_LIB.T6G(SCH_1):PAGE318
  J110   M4     M4 CONN112_10137002101LF-CONN112_10137002-101LF,THLF,A    I76 @T6G_MB_LIB.T6G(SCH_1):PAGE318
  J110   N1     N1 CONN112_10137002101LF-CONN112_10137002-101LF,THLF,A    I76 @T6G_MB_LIB.T6G(SCH_1):PAGE318
  J110   N3     N3 CONN112_10137002101LF-CONN112_10137002-101LF,THLF,A    I76 @T6G_MB_LIB.T6G(SCH_1):PAGE318
  J111   A6     A6 CONN112_10137002101LF-CONN112_10137002-101LF,THLF,A    I38 @T6G_MB_LIB.T6G(SCH_1):PAGE328
  J111   A8     A8 CONN112_10137002101LF-CONN112_10137002-101LF,THLF,A    I38 @T6G_MB_LIB.T6G(SCH_1):PAGE328
  J111   B5     B5 CONN112_10137002101LF-CONN112_10137002-101LF,THLF,A    I38 @T6G_MB_LIB.T6G(SCH_1):PAGE328
  J111   B7     B7 CONN112_10137002101LF-CONN112_10137002-101LF,THLF,A    I38 @T6G_MB_LIB.T6G(SCH_1):PAGE328
  J111   D6     D6 CONN112_10137002101LF-CONN112_10137002-101LF,THLF,A    I38 @T6G_MB_LIB.T6G(SCH_1):PAGE328
  J111   D8     D8 CONN112_10137002101LF-CONN112_10137002-101LF,THLF,A    I38 @T6G_MB_LIB.T6G(SCH_1):PAGE328
  J111   E5     E5 CONN112_10137002101LF-CONN112_10137002-101LF,THLF,A    I38 @T6G_MB_LIB.T6G(SCH_1):PAGE328
  J111   E7     E7 CONN112_10137002101LF-CONN112_10137002-101LF,THLF,A    I38 @T6G_MB_LIB.T6G(SCH_1):PAGE328
  J111   G6     G6 CONN112_10137002101LF-CONN112_10137002-101LF,THLF,A    I38 @T6G_MB_LIB.T6G(SCH_1):PAGE328
  J111   G8     G8 CONN112_10137002101LF-CONN112_10137002-101LF,THLF,A    I38 @T6G_MB_LIB.T6G(SCH_1):PAGE328
  J111   H5     H5 CONN112_10137002101LF-CONN112_10137002-101LF,THLF,A    I38 @T6G_MB_LIB.T6G(SCH_1):PAGE328
  J111   H7     H7 CONN112_10137002101LF-CONN112_10137002-101LF,THLF,A    I38 @T6G_MB_LIB.T6G(SCH_1):PAGE328
  J111   J6     J6 CONN112_10137002101LF-CONN112_10137002-101LF,THLF,A    I38 @T6G_MB_LIB.T6G(SCH_1):PAGE328
  J111   J8     J8 CONN112_10137002101LF-CONN112_10137002-101LF,THLF,A    I38 @T6G_MB_LIB.T6G(SCH_1):PAGE328
  J111   K5     K5 CONN112_10137002101LF-CONN112_10137002-101LF,THLF,A    I38 @T6G_MB_LIB.T6G(SCH_1):PAGE328
  J111   K7     K7 CONN112_10137002101LF-CONN112_10137002-101LF,THLF,A    I38 @T6G_MB_LIB.T6G(SCH_1):PAGE328
  J111   M6     M6 CONN112_10137002101LF-CONN112_10137002-101LF,THLF,A    I38 @T6G_MB_LIB.T6G(SCH_1):PAGE328
  J111   M8     M8 CONN112_10137002101LF-CONN112_10137002-101LF,THLF,A    I38 @T6G_MB_LIB.T6G(SCH_1):PAGE328
  J111   N5     N5 CONN112_10137002101LF-CONN112_10137002-101LF,THLF,A    I38 @T6G_MB_LIB.T6G(SCH_1):PAGE328
  J111   N7     N7 CONN112_10137002101LF-CONN112_10137002-101LF,THLF,A    I38 @T6G_MB_LIB.T6G(SCH_1):PAGE328
  J111   A2     A2 CONN112_10137002101LF-CONN112_10137002-101LF,THLF,A    I76 @T6G_MB_LIB.T6G(SCH_1):PAGE328
  J111   A4     A4 CONN112_10137002101LF-CONN112_10137002-101LF,THLF,A    I76 @T6G_MB_LIB.T6G(SCH_1):PAGE328
  J111   B1     B1 CONN112_10137002101LF-CONN112_10137002-101LF,THLF,A    I76 @T6G_MB_LIB.T6G(SCH_1):PAGE328
  J111   B3     B3 CONN112_10137002101LF-CONN112_10137002-101LF,THLF,A    I76 @T6G_MB_LIB.T6G(SCH_1):PAGE328
  J111   D2     D2 CONN112_10137002101LF-CONN112_10137002-101LF,THLF,A    I76 @T6G_MB_LIB.T6G(SCH_1):PAGE328
  J111   D4     D4 CONN112_10137002101LF-CONN112_10137002-101LF,THLF,A    I76 @T6G_MB_LIB.T6G(SCH_1):PAGE328
  J111   E1     E1 CONN112_10137002101LF-CONN112_10137002-101LF,THLF,A    I76 @T6G_MB_LIB.T6G(SCH_1):PAGE328
  J111   E3     E3 CONN112_10137002101LF-CONN112_10137002-101LF,THLF,A    I76 @T6G_MB_LIB.T6G(SCH_1):PAGE328
  J111   G2     G2 CONN112_10137002101LF-CONN112_10137002-101LF,THLF,A    I76 @T6G_MB_LIB.T6G(SCH_1):PAGE328
  J111   G4     G4 CONN112_10137002101LF-CONN112_10137002-101LF,THLF,A    I76 @T6G_MB_LIB.T6G(SCH_1):PAGE328
  J111   H1     H1 CONN112_10137002101LF-CONN112_10137002-101LF,THLF,A    I76 @T6G_MB_LIB.T6G(SCH_1):PAGE328
  J111   H3     H3 CONN112_10137002101LF-CONN112_10137002-101LF,THLF,A    I76 @T6G_MB_LIB.T6G(SCH_1):PAGE328
  J111   J2     J2 CONN112_10137002101LF-CONN112_10137002-101LF,THLF,A    I76 @T6G_MB_LIB.T6G(SCH_1):PAGE328
  J111   J4     J4 CONN112_10137002101LF-CONN112_10137002-101LF,THLF,A    I76 @T6G_MB_LIB.T6G(SCH_1):PAGE328
  J111   K1     K1 CONN112_10137002101LF-CONN112_10137002-101LF,THLF,A    I76 @T6G_MB_LIB.T6G(SCH_1):PAGE328
  J111   K3     K3 CONN112_10137002101LF-CONN112_10137002-101LF,THLF,A    I76 @T6G_MB_LIB.T6G(SCH_1):PAGE328
  J111   M2     M2 CONN112_10137002101LF-CONN112_10137002-101LF,THLF,A    I76 @T6G_MB_LIB.T6G(SCH_1):PAGE328
  J111   M4     M4 CONN112_10137002101LF-CONN112_10137002-101LF,THLF,A    I76 @T6G_MB_LIB.T6G(SCH_1):PAGE328
  J111   N1     N1 CONN112_10137002101LF-CONN112_10137002-101LF,THLF,A    I76 @T6G_MB_LIB.T6G(SCH_1):PAGE328
  J111   N3     N3 CONN112_10137002101LF-CONN112_10137002-101LF,THLF,A    I76 @T6G_MB_LIB.T6G(SCH_1):PAGE328
  J112   A6     A6 CONN160_10131762101LF-CONN160_10131762-101LF,THLF,A     I7 @T6G_MB_LIB.T6G(SCH_1):PAGE329
  J112   A8     A8 CONN160_10131762101LF-CONN160_10131762-101LF,THLF,A     I7 @T6G_MB_LIB.T6G(SCH_1):PAGE329
  J112   B5     B5 CONN160_10131762101LF-CONN160_10131762-101LF,THLF,A     I7 @T6G_MB_LIB.T6G(SCH_1):PAGE329
  J112   B7     B7 CONN160_10131762101LF-CONN160_10131762-101LF,THLF,A     I7 @T6G_MB_LIB.T6G(SCH_1):PAGE329
  J112   D6     D6 CONN160_10131762101LF-CONN160_10131762-101LF,THLF,A     I7 @T6G_MB_LIB.T6G(SCH_1):PAGE329
  J112   D8     D8 CONN160_10131762101LF-CONN160_10131762-101LF,THLF,A     I7 @T6G_MB_LIB.T6G(SCH_1):PAGE329
  J112   E5     E5 CONN160_10131762101LF-CONN160_10131762-101LF,THLF,A     I7 @T6G_MB_LIB.T6G(SCH_1):PAGE329
  J112   E7     E7 CONN160_10131762101LF-CONN160_10131762-101LF,THLF,A     I7 @T6G_MB_LIB.T6G(SCH_1):PAGE329
  J112   G6     G6 CONN160_10131762101LF-CONN160_10131762-101LF,THLF,A     I7 @T6G_MB_LIB.T6G(SCH_1):PAGE329
  J112   G8     G8 CONN160_10131762101LF-CONN160_10131762-101LF,THLF,A     I7 @T6G_MB_LIB.T6G(SCH_1):PAGE329
  J112   H5     H5 CONN160_10131762101LF-CONN160_10131762-101LF,THLF,A     I7 @T6G_MB_LIB.T6G(SCH_1):PAGE329
  J112   H7     H7 CONN160_10131762101LF-CONN160_10131762-101LF,THLF,A     I7 @T6G_MB_LIB.T6G(SCH_1):PAGE329
  J112   J6     J6 CONN160_10131762101LF-CONN160_10131762-101LF,THLF,A     I7 @T6G_MB_LIB.T6G(SCH_1):PAGE329
  J112   J8     J8 CONN160_10131762101LF-CONN160_10131762-101LF,THLF,A     I7 @T6G_MB_LIB.T6G(SCH_1):PAGE329
  J112   K5     K5 CONN160_10131762101LF-CONN160_10131762-101LF,THLF,A     I7 @T6G_MB_LIB.T6G(SCH_1):PAGE329
  J112   K7     K7 CONN160_10131762101LF-CONN160_10131762-101LF,THLF,A     I7 @T6G_MB_LIB.T6G(SCH_1):PAGE329
  J112   M6     M6 CONN160_10131762101LF-CONN160_10131762-101LF,THLF,A     I7 @T6G_MB_LIB.T6G(SCH_1):PAGE329
  J112   M8     M8 CONN160_10131762101LF-CONN160_10131762-101LF,THLF,A     I7 @T6G_MB_LIB.T6G(SCH_1):PAGE329
  J112   N5     N5 CONN160_10131762101LF-CONN160_10131762-101LF,THLF,A     I7 @T6G_MB_LIB.T6G(SCH_1):PAGE329
  J112   N7     N7 CONN160_10131762101LF-CONN160_10131762-101LF,THLF,A     I7 @T6G_MB_LIB.T6G(SCH_1):PAGE329
  J112   P6     P6 CONN160_10131762101LF-CONN160_10131762-101LF,THLF,A     I7 @T6G_MB_LIB.T6G(SCH_1):PAGE329
  J112   P8     P8 CONN160_10131762101LF-CONN160_10131762-101LF,THLF,A     I7 @T6G_MB_LIB.T6G(SCH_1):PAGE329
  J112   Q5     Q5 CONN160_10131762101LF-CONN160_10131762-101LF,THLF,A     I7 @T6G_MB_LIB.T6G(SCH_1):PAGE329
  J112   Q7     Q7 CONN160_10131762101LF-CONN160_10131762-101LF,THLF,A     I7 @T6G_MB_LIB.T6G(SCH_1):PAGE329
  J112   S6     S6 CONN160_10131762101LF-CONN160_10131762-101LF,THLF,A     I7 @T6G_MB_LIB.T6G(SCH_1):PAGE329
  J112   S8     S8 CONN160_10131762101LF-CONN160_10131762-101LF,THLF,A     I7 @T6G_MB_LIB.T6G(SCH_1):PAGE329
  J112   T5     T5 CONN160_10131762101LF-CONN160_10131762-101LF,THLF,A     I7 @T6G_MB_LIB.T6G(SCH_1):PAGE329
  J112   T7     T7 CONN160_10131762101LF-CONN160_10131762-101LF,THLF,A     I7 @T6G_MB_LIB.T6G(SCH_1):PAGE329
  J112   A2     A2 CONN160_10131762101LF-CONN160_10131762-101LF,THLF,A   I102 @T6G_MB_LIB.T6G(SCH_1):PAGE329
  J112   A4     A4 CONN160_10131762101LF-CONN160_10131762-101LF,THLF,A   I102 @T6G_MB_LIB.T6G(SCH_1):PAGE329
  J112   B1     B1 CONN160_10131762101LF-CONN160_10131762-101LF,THLF,A   I102 @T6G_MB_LIB.T6G(SCH_1):PAGE329
  J112   B3     B3 CONN160_10131762101LF-CONN160_10131762-101LF,THLF,A   I102 @T6G_MB_LIB.T6G(SCH_1):PAGE329
  J112   D2     D2 CONN160_10131762101LF-CONN160_10131762-101LF,THLF,A   I102 @T6G_MB_LIB.T6G(SCH_1):PAGE329
  J112   D4     D4 CONN160_10131762101LF-CONN160_10131762-101LF,THLF,A   I102 @T6G_MB_LIB.T6G(SCH_1):PAGE329
  J112   E1     E1 CONN160_10131762101LF-CONN160_10131762-101LF,THLF,A   I102 @T6G_MB_LIB.T6G(SCH_1):PAGE329
  J112   E3     E3 CONN160_10131762101LF-CONN160_10131762-101LF,THLF,A   I102 @T6G_MB_LIB.T6G(SCH_1):PAGE329
  J112   G2     G2 CONN160_10131762101LF-CONN160_10131762-101LF,THLF,A   I102 @T6G_MB_LIB.T6G(SCH_1):PAGE329
  J112   G4     G4 CONN160_10131762101LF-CONN160_10131762-101LF,THLF,A   I102 @T6G_MB_LIB.T6G(SCH_1):PAGE329
  J112   H1     H1 CONN160_10131762101LF-CONN160_10131762-101LF,THLF,A   I102 @T6G_MB_LIB.T6G(SCH_1):PAGE329
  J112   H3     H3 CONN160_10131762101LF-CONN160_10131762-101LF,THLF,A   I102 @T6G_MB_LIB.T6G(SCH_1):PAGE329
  J112   J2     J2 CONN160_10131762101LF-CONN160_10131762-101LF,THLF,A   I102 @T6G_MB_LIB.T6G(SCH_1):PAGE329
  J112   J4     J4 CONN160_10131762101LF-CONN160_10131762-101LF,THLF,A   I102 @T6G_MB_LIB.T6G(SCH_1):PAGE329
  J112   K1     K1 CONN160_10131762101LF-CONN160_10131762-101LF,THLF,A   I102 @T6G_MB_LIB.T6G(SCH_1):PAGE329
  J112   K3     K3 CONN160_10131762101LF-CONN160_10131762-101LF,THLF,A   I102 @T6G_MB_LIB.T6G(SCH_1):PAGE329
  J112   M2     M2 CONN160_10131762101LF-CONN160_10131762-101LF,THLF,A   I102 @T6G_MB_LIB.T6G(SCH_1):PAGE329
  J112   M4     M4 CONN160_10131762101LF-CONN160_10131762-101LF,THLF,A   I102 @T6G_MB_LIB.T6G(SCH_1):PAGE329
  J112   N1     N1 CONN160_10131762101LF-CONN160_10131762-101LF,THLF,A   I102 @T6G_MB_LIB.T6G(SCH_1):PAGE329
  J112   N3     N3 CONN160_10131762101LF-CONN160_10131762-101LF,THLF,A   I102 @T6G_MB_LIB.T6G(SCH_1):PAGE329
  J112   P2     P2 CONN160_10131762101LF-CONN160_10131762-101LF,THLF,A   I102 @T6G_MB_LIB.T6G(SCH_1):PAGE329
  J112   P4     P4 CONN160_10131762101LF-CONN160_10131762-101LF,THLF,A   I102 @T6G_MB_LIB.T6G(SCH_1):PAGE329
  J112   Q1     Q1 CONN160_10131762101LF-CONN160_10131762-101LF,THLF,A   I102 @T6G_MB_LIB.T6G(SCH_1):PAGE329
  J112   Q3     Q3 CONN160_10131762101LF-CONN160_10131762-101LF,THLF,A   I102 @T6G_MB_LIB.T6G(SCH_1):PAGE329
  J112   S2     S2 CONN160_10131762101LF-CONN160_10131762-101LF,THLF,A   I102 @T6G_MB_LIB.T6G(SCH_1):PAGE329
  J112   S4     S4 CONN160_10131762101LF-CONN160_10131762-101LF,THLF,A   I102 @T6G_MB_LIB.T6G(SCH_1):PAGE329
  J112   T1     T1 CONN160_10131762101LF-CONN160_10131762-101LF,THLF,A   I102 @T6G_MB_LIB.T6G(SCH_1):PAGE329
  J112   T3     T3 CONN160_10131762101LF-CONN160_10131762-101LF,THLF,A   I102 @T6G_MB_LIB.T6G(SCH_1):PAGE329
   U11    4    VSS M24M02DRMN6TP-M24M02-DRMN6TP,SMLF,IC,AKE33Z00600     I3 @T6G_MB_LIB.T6G(SCH_1):PAGE387
   U11    7   WC_N M24M02DRMN6TP-M24M02-DRMN6TP,SMLF,IC,AKE33Z00600     I3 @T6G_MB_LIB.T6G(SCH_1):PAGE387
   U15    4    VSS M24M02DRMN6TP-M24M02-DRMN6TP,SMLF,IC,AKE33Z00600     I5 @T6G_MB_LIB.T6G(SCH_1):PAGE410
   U15    7   WC_N M24M02DRMN6TP-M24M02-DRMN6TP,SMLF,IC,AKE33Z00600     I5 @T6G_MB_LIB.T6G(SCH_1):PAGE410
   U16    4    VSS M24M02DRMN6TP-M24M02-DRMN6TP,SMLF,IC,AKE33Z00600     I5 @T6G_MB_LIB.T6G(SCH_1):PAGE421
   U16    7   WC_N M24M02DRMN6TP-M24M02-DRMN6TP,SMLF,IC,AKE33Z00600     I5 @T6G_MB_LIB.T6G(SCH_1):PAGE421
   U17    4    VSS M24M02DRMN6TP-M24M02-DRMN6TP,SMLF,IC,AKE33Z00600     I5 @T6G_MB_LIB.T6G(SCH_1):PAGE432
   U17    7   WC_N M24M02DRMN6TP-M24M02-DRMN6TP,SMLF,IC,AKE33Z00600     I5 @T6G_MB_LIB.T6G(SCH_1):PAGE432
   U12    4    VSS M24M02DRMN6TP-M24M02-DRMN6TP,SMLF,IC,AKE33Z00600     I5 @T6G_MB_LIB.T6G(SCH_1):PAGE399
   U12    7   WC_N M24M02DRMN6TP-M24M02-DRMN6TP,SMLF,IC,AKE33Z00600     I5 @T6G_MB_LIB.T6G(SCH_1):PAGE399
   U19    4    VSS M24M02DRMN6TP-M24M02-DRMN6TP,SMLF,IC,AKE33Z00600     I5 @T6G_MB_LIB.T6G(SCH_1):PAGE442
   U19    7   WC_N M24M02DRMN6TP-M24M02-DRMN6TP,SMLF,IC,AKE33Z00600     I5 @T6G_MB_LIB.T6G(SCH_1):PAGE442
   U20    4    VSS M24M02DRMN6TP-M24M02-DRMN6TP,SMLF,IC,AKE33Z00600     I5 @T6G_MB_LIB.T6G(SCH_1):PAGE453
   U20    7   WC_N M24M02DRMN6TP-M24M02-DRMN6TP,SMLF,IC,AKE33Z00600     I5 @T6G_MB_LIB.T6G(SCH_1):PAGE453
   U21    4    VSS M24M02DRMN6TP-M24M02-DRMN6TP,SMLF,IC,AKE33Z00600     I5 @T6G_MB_LIB.T6G(SCH_1):PAGE464
   U21    7   WC_N M24M02DRMN6TP-M24M02-DRMN6TP,SMLF,IC,AKE33Z00600     I5 @T6G_MB_LIB.T6G(SCH_1):PAGE464
  C114    2      B Q_CAP_C0805-100UF,4V,20%,X6S,CH710KMEA01     I4 @T6G_MB_LIB.T6G(SCH_1):PAGE398
  C117    2      B Q_CAP_C0402-22UF,4V,20%,X6S,CH622KMEB02     I5 @T6G_MB_LIB.T6G(SCH_1):PAGE398
  C121    2      B Q_CAP_0402-4.7UF,6.3V,20%,X6S,CH5471MEB01     I7 @T6G_MB_LIB.T6G(SCH_1):PAGE398
  C126    2      B Q_CAP_0201-1UF,4V,20%,X6S,CH-10KMEE00     I9 @T6G_MB_LIB.T6G(SCH_1):PAGE398
  C113    2      B Q_CAP_C0805-100UF,4V,20%,X6S,CH710KMEA01    I12 @T6G_MB_LIB.T6G(SCH_1):PAGE398
  C118    2      B Q_CAP_C0402-10UF,6.3V,20%,X6S,CH6101MEB01    I14 @T6G_MB_LIB.T6G(SCH_1):PAGE398
  C122    2      B Q_CAP_0402-4.7UF,6.3V,20%,X6S,CH5471MEB01    I15 @T6G_MB_LIB.T6G(SCH_1):PAGE398
PC6500    2      B Q_CAP_C0402-0.1UF,25V,10%,X6S,CH4104KEB00     I4 @T6G_MB_LIB.T6G(SCH_1):PAGE469
 C6757    2      B Q_CAP_0402-0.1UF,25V,10%,EMPTY,CH4104K1B00     I5 @T6G_MB_LIB.T6G(SCH_1):PAGE469
PC6800    2      B Q_CAPP_SMLF-270UF,16V,20%,OSCON,CC72703MZ11     I6 @T6G_MB_LIB.T6G(SCH_1):PAGE469
PC6802    2      B Q_CAP_C0805-22UF,16V,20%,X6S,CH6223MEA01     I7 @T6G_MB_LIB.T6G(SCH_1):PAGE469
PC6506    2      B Q_CAP_C0402-1UF,25V,10%,X6S,CH5104KEB02    I12 @T6G_MB_LIB.T6G(SCH_1):PAGE469
PC6501    2      B Q_CAP_C0805-22UF,16V,20%,X6S,CH6223MEA01    I16 @T6G_MB_LIB.T6G(SCH_1):PAGE469
PC6502    2      B Q_CAP_C0805-22UF,16V,20%,X6S,CH6223MEA01    I17 @T6G_MB_LIB.T6G(SCH_1):PAGE469
PC6503    2      B Q_CAP_C0805-22UF,16V,20%,X6S,CH6223MEA01    I18 @T6G_MB_LIB.T6G(SCH_1):PAGE469
PR6502    2      B Q_RES_0402LF-7.15K,1%,1/16W,CHIP,CS27152FB03    I20 @T6G_MB_LIB.T6G(SCH_1):PAGE469
PR6500    1      A Q_RES_0402LF-0,5%,1/16W,CHIP,CS00002JB13    I21 @T6G_MB_LIB.T6G(SCH_1):PAGE469
PC6504    2      B Q_CAP_C0805-22UF,16V,20%,X6S,CH6223MEA01    I22 @T6G_MB_LIB.T6G(SCH_1):PAGE469
PC6505    2      B Q_CAP_C0402-1UF,25V,10%,X6S,CH5104KEB02    I23 @T6G_MB_LIB.T6G(SCH_1):PAGE469
PC6518    2      B Q_CAP_0402-0.1UF,25V,10%,X7R,CH4104K1B00    I26 @T6G_MB_LIB.T6G(SCH_1):PAGE469
PR6507    2      B Q_RES_0402LF-10K,1%,1/16W,CHIP,CS31002FB08    I33 @T6G_MB_LIB.T6G(SCH_1):PAGE469
PC6508    2      B Q_CAP_C0805-22UF,4V,20%,X6S,CH622KMEA03    I38 @T6G_MB_LIB.T6G(SCH_1):PAGE469
PC6509    2      B Q_CAP_C0805-22UF,4V,20%,X6S,CH622KMEA03    I39 @T6G_MB_LIB.T6G(SCH_1):PAGE469
PC6510    2      B Q_CAP_C0805-22UF,4V,20%,X6S,CH622KMEA03    I40 @T6G_MB_LIB.T6G(SCH_1):PAGE469
 C6758    2      B Q_CAP_0402-1000PF,50V,5%,X7R,TMP_QCH21006JB10    I42 @T6G_MB_LIB.T6G(SCH_1):PAGE469
PC6511    2      B Q_CAP_C0805-22UF,4V,20%,X6S,CH622KMEA03    I44 @T6G_MB_LIB.T6G(SCH_1):PAGE469
PC6513    2      B Q_CAPP_SMLF-390UF,2.5V,20%,ALUM,CC7390JMZ13    I46 @T6G_MB_LIB.T6G(SCH_1):PAGE469
PC6805    2      B Q_CAPP_SMLF-390UF,2.5V,20%,ALUM,CC7390JMZ13    I48 @T6G_MB_LIB.T6G(SCH_1):PAGE469
PC6514    2      B Q_CAP_0402-0.1UF,25V,10%,X7R,CH4104K1B00    I49 @T6G_MB_LIB.T6G(SCH_1):PAGE469
PU6500    2   AGND MPQ8633BGLEC838Z-MPQ8633BGLE-C838-Z,SMLF,IC,AL0086A    I51 @T6G_MB_LIB.T6G(SCH_1):PAGE469
PU6500 11_18   PGND MPQ8633BGLEC838Z-MPQ8633BGLE-C838-Z,SMLF,IC,AL0086A    I51 @T6G_MB_LIB.T6G(SCH_1):PAGE469
PU6500    6   RGND MPQ8633BGLEC838Z-MPQ8633BGLE-C838-Z,SMLF,IC,AL0086A    I51 @T6G_MB_LIB.T6G(SCH_1):PAGE469
PC6519    2      B Q_CAP_C0402-0.1UF,25V,10%,X6S,CH4104KEB00     I3 @T6G_MB_LIB.T6G(SCH_1):PAGE470
  C105    2      B Q_CAP_0402-0.1UF,25V,10%,EMPTY,CH4104K1B00     I5 @T6G_MB_LIB.T6G(SCH_1):PAGE470
PC6801    2      B Q_CAPP_SMLF-270UF,16V,20%,OSCON,CC72703MZ11     I6 @T6G_MB_LIB.T6G(SCH_1):PAGE470
PC6803    2      B Q_CAP_C0805-22UF,16V,20%,X6S,CH6223MEA01     I7 @T6G_MB_LIB.T6G(SCH_1):PAGE470
PC6525    2      B Q_CAP_C0402-1UF,25V,10%,X6S,CH5104KEB02    I12 @T6G_MB_LIB.T6G(SCH_1):PAGE470
PC6520    2      B Q_CAP_C0805-22UF,16V,20%,X6S,CH6223MEA01    I16 @T6G_MB_LIB.T6G(SCH_1):PAGE470
PC6521    2      B Q_CAP_C0805-22UF,16V,20%,X6S,CH6223MEA01    I17 @T6G_MB_LIB.T6G(SCH_1):PAGE470
PC6522    2      B Q_CAP_C0805-22UF,16V,20%,X6S,CH6223MEA01    I18 @T6G_MB_LIB.T6G(SCH_1):PAGE470
PR6522    2      B Q_RES_0402LF-7.15K,1%,1/16W,CHIP,CS27152FB03    I20 @T6G_MB_LIB.T6G(SCH_1):PAGE470
PR6520    1      A Q_RES_0402LF-0,5%,1/16W,CHIP,CS00002JB13    I21 @T6G_MB_LIB.T6G(SCH_1):PAGE470
PC6523    2      B Q_CAP_C0805-22UF,16V,20%,X6S,CH6223MEA01    I22 @T6G_MB_LIB.T6G(SCH_1):PAGE470
PC6524    2      B Q_CAP_C0402-1UF,25V,10%,X6S,CH5104KEB02    I23 @T6G_MB_LIB.T6G(SCH_1):PAGE470
PC6537    2      B Q_CAP_0402-0.1UF,25V,10%,X7R,CH4104K1B00    I25 @T6G_MB_LIB.T6G(SCH_1):PAGE470
PR6526    2      B Q_RES_0402LF-10K,1%,1/16W,CHIP,CS31002FB08    I32 @T6G_MB_LIB.T6G(SCH_1):PAGE470
PC6527    2      B Q_CAP_C0805-22UF,4V,20%,X6S,CH622KMEA03    I38 @T6G_MB_LIB.T6G(SCH_1):PAGE470
  C109    2      B Q_CAP_0402-1000PF,50V,5%,X7R,TMP_QCH21006JB10    I39 @T6G_MB_LIB.T6G(SCH_1):PAGE470
PC6528    2      B Q_CAP_C0805-22UF,4V,20%,X6S,CH622KMEA03    I41 @T6G_MB_LIB.T6G(SCH_1):PAGE470
PC6529    2      B Q_CAP_C0805-22UF,4V,20%,X6S,CH622KMEA03    I42 @T6G_MB_LIB.T6G(SCH_1):PAGE470
PC6530    2      B Q_CAP_C0805-22UF,4V,20%,X6S,CH622KMEA03    I44 @T6G_MB_LIB.T6G(SCH_1):PAGE470
PC6531    2      B Q_CAP_C0805-22UF,4V,20%,X6S,CH622KMEA03    I45 @T6G_MB_LIB.T6G(SCH_1):PAGE470
PC6532    2      B Q_CAPP_SMLF-390UF,2.5V,20%,ALUM,CC7390JMZ13    I46 @T6G_MB_LIB.T6G(SCH_1):PAGE470
PC6804    2      B Q_CAPP_SMLF-390UF,2.5V,20%,ALUM,CC7390JMZ13    I47 @T6G_MB_LIB.T6G(SCH_1):PAGE470
PC6533    2      B Q_CAP_0402-0.1UF,25V,10%,X7R,CH4104K1B00    I49 @T6G_MB_LIB.T6G(SCH_1):PAGE470
PU6501    2   AGND MPQ8633BGLEC838Z-MPQ8633BGLE-C838-Z,SMLF,IC,AL0086A    I51 @T6G_MB_LIB.T6G(SCH_1):PAGE470
PU6501 11_18   PGND MPQ8633BGLEC838Z-MPQ8633BGLE-C838-Z,SMLF,IC,AL0086A    I51 @T6G_MB_LIB.T6G(SCH_1):PAGE470
PU6501    6   RGND MPQ8633BGLEC838Z-MPQ8633BGLE-C838-Z,SMLF,IC,AL0086A    I51 @T6G_MB_LIB.T6G(SCH_1):PAGE470
PC6512    2      B Q_CAP_C0805-22UF,4V,20%,X6S,CH622KMEA03    I52 @T6G_MB_LIB.T6G(SCH_1):PAGE469
PR6532    2      B Q_RES_0402LF-49.9,1%,1/16W,CHIP,CS04992FB07    I32 @T6G_MB_LIB.T6G(SCH_1):PAGE475
PU6502   31  RGND1 ISL69260IRAZT-ISL69260IRAZ-T,SMLF,IC,AL069260000    I42 @T6G_MB_LIB.T6G(SCH_1):PAGE475
PU6502   TH TH_GND ISL69260IRAZT-ISL69260IRAZ-T,SMLF,IC,AL069260000    I42 @T6G_MB_LIB.T6G(SCH_1):PAGE475
PU6502   32  VSEN1 ISL69260IRAZT-ISL69260IRAZ-T,SMLF,IC,AL069260000    I42 @T6G_MB_LIB.T6G(SCH_1):PAGE475
  C101    2      B Q_CAP_0402-1000PF,50V,5%,EMPTY,TMP_QCH21006JB10   I118 @T6G_MB_LIB.T6G(SCH_1):PAGE475
PC6602    2      B Q_CAP_0402-0.1UF,25V,10%,X7R,CH4104K1B00   I123 @T6G_MB_LIB.T6G(SCH_1):PAGE475
PR6607    2      B Q_RES_0402LF-1K,1%,1/16W,EMPTY,CS21002FB06   I125 @T6G_MB_LIB.T6G(SCH_1):PAGE475
PC6604    2      B Q_CAP_C0402-1UF,16V,10%,X6S,CH5103KEB01   I132 @T6G_MB_LIB.T6G(SCH_1):PAGE475
PR6814    2      B Q_RES_0402LF-10K,1%,1/16W,EMPTY,CS31002FB08   I138 @T6G_MB_LIB.T6G(SCH_1):PAGE475
PC6603    2      B Q_CAP_C0402-100NF,50V,10%,X7R,CH4106K1B01   I144 @T6G_MB_LIB.T6G(SCH_1):PAGE475
PC6606    2      B Q_CAP_C0402-10UF,6.3V,20%,X6S,CH6101MEB03   I145 @T6G_MB_LIB.T6G(SCH_1):PAGE475
PC6605    2      B Q_CAP_C0402-1UF,16V,10%,X6S,CH5103KEB01   I146 @T6G_MB_LIB.T6G(SCH_1):PAGE475
PC6607    2      B Q_CAP_0402-470PF,50V,10%,X7R,TMP_QCH14706KB18   I148 @T6G_MB_LIB.T6G(SCH_1):PAGE475
PR6605    2      B Q_RES_0402LF-0,5%,1/16W,CHIP,CS00002JB13   I150 @T6G_MB_LIB.T6G(SCH_1):PAGE475
PC6601    2      B Q_CAP_0402-0.1UF,25V,10%,EMPTY,CH4104K1B00   I151 @T6G_MB_LIB.T6G(SCH_1):PAGE475
 R6801    1      A Q_RES_0402LF-0,5%,1/16W,CHIP,CS00002JB13   I161 @T6G_MB_LIB.T6G(SCH_1):PAGE475
PR6810    2      B Q_RES_0402LF-0,5%,1/16W,CHIP,CS00002JB13   I165 @T6G_MB_LIB.T6G(SCH_1):PAGE475
PR6819    2      B Q_RES_0402LF-0,5%,1/16W,CHIP,CS00002JB13   I168 @T6G_MB_LIB.T6G(SCH_1):PAGE475
PR6603    1      A Q_RES_0402LF-0,5%,1/16W,CHIP,CS00002JB13   I183 @T6G_MB_LIB.T6G(SCH_1):PAGE475
PR6609    2      B Q_RES_0402LF-0,5%,1/16W,CHIP,CS00002JB13   I188 @T6G_MB_LIB.T6G(SCH_1):PAGE475
PR6610    2      B Q_RES_0402LF-0,5%,1/16W,CHIP,CS00002JB13   I190 @T6G_MB_LIB.T6G(SCH_1):PAGE475
PR6611    2      B Q_RES_0402LF-0,5%,1/16W,CHIP,CS00002JB13   I191 @T6G_MB_LIB.T6G(SCH_1):PAGE475
PR6612    2      B Q_RES_0402LF-0,5%,1/16W,CHIP,CS00002JB13   I192 @T6G_MB_LIB.T6G(SCH_1):PAGE475
PR6613    2      B Q_RES_0402LF-0,5%,1/16W,CHIP,CS00002JB13   I193 @T6G_MB_LIB.T6G(SCH_1):PAGE475
PR6614    2      B Q_RES_0402LF-0,5%,1/16W,CHIP,CS00002JB13   I198 @T6G_MB_LIB.T6G(SCH_1):PAGE475
PR6618    2      B Q_RES_0402LF-0,5%,1/16W,CHIP,CS00002JB13   I204 @T6G_MB_LIB.T6G(SCH_1):PAGE475
PC6555_1    2      B Q_CAP_0402-3300PF,50V,10%,X7R,TMP_QCH2336K1B12     I6 @T6G_MB_LIB.T6G(SCH_1):PAGE476
PC6558_1    2      B Q_CAP_C0805-22UF,16V,20%,X6S,CH6223MEA01    I21 @T6G_MB_LIB.T6G(SCH_1):PAGE476
PC6557_1    2      B Q_CAP_C0805-22UF,16V,20%,X6S,CH6223MEA01    I24 @T6G_MB_LIB.T6G(SCH_1):PAGE476
PC6556_1    2      B Q_CAP_C0805-22UF,16V,20%,X6S,CH6223MEA01    I27 @T6G_MB_LIB.T6G(SCH_1):PAGE476
PC6554_1    2      B Q_CAP_C0402-1UF,25V,10%,X6S,CH5104KEB02    I29 @T6G_MB_LIB.T6G(SCH_1):PAGE476
PC6565    2      B Q_CAP_C0402-100NF,50V,10%,X7R,CH4106K1B01    I33 @T6G_MB_LIB.T6G(SCH_1):PAGE476
PC6550_09P0_1    2      B Q_CAP_C0402-2.2UF,10V,10%,X6S,CH5222KEB01    I47 @T6G_MB_LIB.T6G(SCH_1):PAGE476
PC6552    2      B Q_CAP_C0402-2.2UF,10V,10%,X6S,CH5222KEB01    I48 @T6G_MB_LIB.T6G(SCH_1):PAGE476
PU6503    2   AGND ISL99390FRZTR5935-ISL99390FRZ-TR5935,SMLF,IC,AL099A    I53 @T6G_MB_LIB.T6G(SCH_1):PAGE476
PU6503    5  PGND1 ISL99390FRZTR5935-ISL99390FRZ-TR5935,SMLF,IC,AL099A    I53 @T6G_MB_LIB.T6G(SCH_1):PAGE476
PU6503 7_9-20_24  PGND2 ISL99390FRZTR5935-ISL99390FRZ-TR5935,SMLF,IC,AL099A    I53 @T6G_MB_LIB.T6G(SCH_1):PAGE476
PU6503   40  PGND3 ISL99390FRZTR5935-ISL99390FRZ-TR5935,SMLF,IC,AL099A    I53 @T6G_MB_LIB.T6G(SCH_1):PAGE476
PC6553_1    2      B Q_CAP_C0402-100NF,50V,10%,X7R,CH4106K1B01    I68 @T6G_MB_LIB.T6G(SCH_1):PAGE476
PR6557    2      B Q_RES_0603LF-499,1%,1/10W,CHIP,CS14993F901   I187 @T6G_MB_LIB.T6G(SCH_1):PAGE476
PC6566_1    2      B Q_CAP_C0805-22UF,4V,20%,X6S,CH622KMEA03   I202 @T6G_MB_LIB.T6G(SCH_1):PAGE476
PC6561    2      B Q_CAPP_SMLF-100UF,16V,20%,OSCON,CC71003MZ30   I209 @T6G_MB_LIB.T6G(SCH_1):PAGE476
PC6559_1    2      B Q_CAP_C0805-22UF,16V,20%,X6S,CH6223MEA01   I210 @T6G_MB_LIB.T6G(SCH_1):PAGE476
PC6816    2      B Q_CAP_C0805-22UF,16V,20%,X6S,CH6223MEA01   I216 @T6G_MB_LIB.T6G(SCH_1):PAGE476
PC6560    2      B Q_CAP_C0805-22UF,16V,20%,X6S,CH6223MEA01   I217 @T6G_MB_LIB.T6G(SCH_1):PAGE476
PR6553    2      B Q_RES_0402LF-8.87K,1%,1/16W,EMPTY,CS28872FB01   I220 @T6G_MB_LIB.T6G(SCH_1):PAGE476
PC6572    2      B Q_CAPP_SMLF-390UF,2.5V,20%,ALUM,CC7390JMZ13   I222 @T6G_MB_LIB.T6G(SCH_1):PAGE476
PC6567_1    2      B Q_CAP_C0805-22UF,4V,20%,X6S,CH622KMEA03   I223 @T6G_MB_LIB.T6G(SCH_1):PAGE476
PC6568    2      B Q_CAPP_SMLF-470UF,2.5V,20%,SPCAP,CH747LM8818   I224 @T6G_MB_LIB.T6G(SCH_1):PAGE476
PC6569    2      B Q_CAPP_SMLF-470UF,2.5V,20%,SPCAP,CH747LM8818   I225 @T6G_MB_LIB.T6G(SCH_1):PAGE476
PC6570    2      B Q_CAPP_SMLF-470UF,2.5V,20%,SPCAP,CH747LM8818   I226 @T6G_MB_LIB.T6G(SCH_1):PAGE476
PC6571    2      B Q_CAPP_SMLF-390UF,2.5V,20%,ALUM,CC7390JMZ13   I227 @T6G_MB_LIB.T6G(SCH_1):PAGE476
PC6810    2      B Q_CAPP_SMLF-100UF,16V,20%,OSCON,CC71003MZ30   I231 @T6G_MB_LIB.T6G(SCH_1):PAGE476
PC6817    2      B Q_CAP_C0805-22UF,16V,20%,X6S,CH6223MEA01   I232 @T6G_MB_LIB.T6G(SCH_1):PAGE476
PC6574    2      B Q_CAPP_SMLF-390UF,2.5V,20%,ALUM,CC7390JMZ13   I236 @T6G_MB_LIB.T6G(SCH_1):PAGE476
PC6573    2      B Q_CAPP_SMLF-390UF,2.5V,20%,ALUM,CC7390JMZ13   I238 @T6G_MB_LIB.T6G(SCH_1):PAGE476
 PC534    2      B Q_CAPP_SMLF-470UF,2.5V,20%,SPCAP,CH747LM8818   I239 @T6G_MB_LIB.T6G(SCH_1):PAGE476
PC6583    2      B Q_CAP_C0805-22UF,16V,20%,X6S,CH6223MEA01   I241 @T6G_MB_LIB.T6G(SCH_1):PAGE476
PC6582_2    2      B Q_CAP_C0805-22UF,16V,20%,X6S,CH6223MEA01   I242 @T6G_MB_LIB.T6G(SCH_1):PAGE476
PC6581_2    2      B Q_CAP_C0805-22UF,16V,20%,X6S,CH6223MEA01   I243 @T6G_MB_LIB.T6G(SCH_1):PAGE476
PC6580_2    2      B Q_CAP_C0805-22UF,16V,20%,X6S,CH6223MEA01   I244 @T6G_MB_LIB.T6G(SCH_1):PAGE476
PC6579_2    2      B Q_CAP_C0805-22UF,16V,20%,X6S,CH6223MEA01   I245 @T6G_MB_LIB.T6G(SCH_1):PAGE476
PC6811    2      B Q_CAPP_SMLF-470UF,2.5V,20%,SPCAP,CH747LM8818   I247 @T6G_MB_LIB.T6G(SCH_1):PAGE476
PC6812    2      B Q_CAPP_SMLF-470UF,2.5V,20%,SPCAP,CH747LM8818   I248 @T6G_MB_LIB.T6G(SCH_1):PAGE476
PC6587_2    2      B Q_CAP_C0805-22UF,4V,20%,X6S,CH622KMEA03   I250 @T6G_MB_LIB.T6G(SCH_1):PAGE476
PC6586_2    2      B Q_CAP_C0805-22UF,4V,20%,X6S,CH622KMEA03   I251 @T6G_MB_LIB.T6G(SCH_1):PAGE476
PC6806    2      B Q_CAP_C0402-100NF,50V,10%,X7R,CH4106K1B01   I255 @T6G_MB_LIB.T6G(SCH_1):PAGE476
PC6577_2    2      B Q_CAP_C0402-1UF,25V,10%,X6S,CH5104KEB02   I258 @T6G_MB_LIB.T6G(SCH_1):PAGE476
PC6578_2    2      B Q_CAP_0402-3300PF,50V,10%,X7R,TMP_QCH2336K1B12   I259 @T6G_MB_LIB.T6G(SCH_1):PAGE476
PC6551_09P0_2    2      B Q_CAP_C0402-2.2UF,10V,10%,X6S,CH5222KEB01   I267 @T6G_MB_LIB.T6G(SCH_1):PAGE476
PU6504    2   AGND ISL99390FRZTR5935-ISL99390FRZ-TR5935,SMLF,IC,AL099A   I270 @T6G_MB_LIB.T6G(SCH_1):PAGE476
PU6504    5  PGND1 ISL99390FRZTR5935-ISL99390FRZ-TR5935,SMLF,IC,AL099A   I270 @T6G_MB_LIB.T6G(SCH_1):PAGE476
PU6504 7_9-20_24  PGND2 ISL99390FRZTR5935-ISL99390FRZ-TR5935,SMLF,IC,AL099A   I270 @T6G_MB_LIB.T6G(SCH_1):PAGE476
PU6504   40  PGND3 ISL99390FRZTR5935-ISL99390FRZ-TR5935,SMLF,IC,AL099A   I270 @T6G_MB_LIB.T6G(SCH_1):PAGE476
PC6575    2      B Q_CAP_C0402-2.2UF,10V,10%,X6S,CH5222KEB01   I271 @T6G_MB_LIB.T6G(SCH_1):PAGE476
PR6561    2      B Q_RES_0402LF-8.87K,1%,1/16W,EMPTY,CS28872FB01   I276 @T6G_MB_LIB.T6G(SCH_1):PAGE476
PC6576    2      B Q_CAP_C0402-100NF,50V,10%,X7R,CH4106K1B01   I281 @T6G_MB_LIB.T6G(SCH_1):PAGE476
PR6555    2      B Q_RES_0402LF-1.5,1%,1/8W,EMPTY,CS-1504FB00   I283 @T6G_MB_LIB.T6G(SCH_1):PAGE476
PR6563    2      B Q_RES_0402LF-1.5,1%,1/8W,EMPTY,CS-1504FB00   I286 @T6G_MB_LIB.T6G(SCH_1):PAGE476
PC6562    2      B Q_CAP_0402-0.1UF,25V,10%,X7R,CH4104K1B00   I291 @T6G_MB_LIB.T6G(SCH_1):PAGE476
 R6800    1      A Q_RES_0402LF-0,5%,1/16W,CHIP,CS00002JB13     I2 @T6G_MB_LIB.T6G(SCH_1):PAGE477
PR6821    2      B Q_RES_0402LF-0,5%,1/16W,CHIP,CS00002JB13     I3 @T6G_MB_LIB.T6G(SCH_1):PAGE477
 PC514    2      B Q_CAP_0402-0.1UF,25V,10%,EMPTY,CH4104K1B00     I5 @T6G_MB_LIB.T6G(SCH_1):PAGE477
PR6533    1      A Q_RES_0402LF-22.1K,1%,1/16W,CHIP,CS32212FB02    I13 @T6G_MB_LIB.T6G(SCH_1):PAGE477
PR6602    2      B Q_RES_0402LF-49.9,1%,1/16W,CHIP,CS04992FB07    I22 @T6G_MB_LIB.T6G(SCH_1):PAGE477
PR6811    2      B Q_RES_0402LF-0,5%,1/16W,CHIP,CS00002JB13    I42 @T6G_MB_LIB.T6G(SCH_1):PAGE477
PR6820    2      B Q_RES_0402LF-0,5%,1/16W,CHIP,CS00002JB13    I43 @T6G_MB_LIB.T6G(SCH_1):PAGE477
PR6802    2      B Q_RES_0402LF-0,5%,1/16W,EMPTY,CS00002JB13    I44 @T6G_MB_LIB.T6G(SCH_1):PAGE477
  C107    2      B Q_CAP_0402-1000PF,50V,5%,EMPTY,TMP_QCH21006JB10    I45 @T6G_MB_LIB.T6G(SCH_1):PAGE477
PR6813    2      B Q_RES_0402LF-1K,1%,1/16W,EMPTY,CS21002FB06    I46 @T6G_MB_LIB.T6G(SCH_1):PAGE477
 PC819    2      B Q_CAP_0402-0.1UF,25V,10%,X7R,CH4104K1B00    I48 @T6G_MB_LIB.T6G(SCH_1):PAGE477
 PC523    2      B Q_CAP_0402-470PF,50V,10%,X7R,TMP_QCH14706KB18    I51 @T6G_MB_LIB.T6G(SCH_1):PAGE477
PR6548    2      B Q_RES_0402LF-0,5%,1/16W,CHIP,CS00002JB13    I52 @T6G_MB_LIB.T6G(SCH_1):PAGE477
PR6815    2      B Q_RES_0402LF-10K,1%,1/16W,EMPTY,CS31002FB08    I54 @T6G_MB_LIB.T6G(SCH_1):PAGE477
PR6544    2      B Q_RES_0402LF-0,5%,1/16W,CHIP,CS00002JB13    I57 @T6G_MB_LIB.T6G(SCH_1):PAGE477
PR6543    2      B Q_RES_0402LF-0,5%,1/16W,CHIP,CS00002JB13    I58 @T6G_MB_LIB.T6G(SCH_1):PAGE477
PR6542    2      B Q_RES_0402LF-0,5%,1/16W,CHIP,CS00002JB13    I64 @T6G_MB_LIB.T6G(SCH_1):PAGE477
PR6541    2      B Q_RES_0402LF-0,5%,1/16W,CHIP,CS00002JB13    I65 @T6G_MB_LIB.T6G(SCH_1):PAGE477
PR6540    2      B Q_RES_0402LF-0,5%,1/16W,CHIP,CS00002JB13    I68 @T6G_MB_LIB.T6G(SCH_1):PAGE477
PR6539    2      B Q_RES_0402LF-0,5%,1/16W,CHIP,CS00002JB13    I69 @T6G_MB_LIB.T6G(SCH_1):PAGE477
PC6546    2      B Q_CAP_C0402-10UF,6.3V,20%,X6S,CH6101MEB03    I72 @T6G_MB_LIB.T6G(SCH_1):PAGE477
PC6545    2      B Q_CAP_C0402-1UF,16V,10%,X6S,CH5103KEB01    I73 @T6G_MB_LIB.T6G(SCH_1):PAGE477
PC6543    2      B Q_CAP_C0402-100NF,50V,10%,X7R,CH4106K1B01    I74 @T6G_MB_LIB.T6G(SCH_1):PAGE477
PC6544    2      B Q_CAP_C0402-1UF,16V,10%,X6S,CH5103KEB01    I75 @T6G_MB_LIB.T6G(SCH_1):PAGE477
PU6510   31  RGND1 ISL69260IRAZT-ISL69260IRAZ-T,SMLF,IC,AL069260000    I88 @T6G_MB_LIB.T6G(SCH_1):PAGE477
PU6510   TH TH_GND ISL69260IRAZT-ISL69260IRAZ-T,SMLF,IC,AL069260000    I88 @T6G_MB_LIB.T6G(SCH_1):PAGE477
PU6510   32  VSEN1 ISL69260IRAZT-ISL69260IRAZ-T,SMLF,IC,AL069260000    I88 @T6G_MB_LIB.T6G(SCH_1):PAGE477
PC6646    2      B Q_CAP_C0402-100NF,50V,10%,X7R,CH4106K1B01     I2 @T6G_MB_LIB.T6G(SCH_1):PAGE478
PR6628    2      B Q_RES_0402LF-8.87K,1%,1/16W,EMPTY,CS28872FB01     I5 @T6G_MB_LIB.T6G(SCH_1):PAGE478
PC6645    2      B Q_CAP_C0402-2.2UF,10V,10%,X6S,CH5222KEB01    I10 @T6G_MB_LIB.T6G(SCH_1):PAGE478
PU6512    2   AGND ISL99390FRZTR5935-ISL99390FRZ-TR5935,SMLF,IC,AL099A    I12 @T6G_MB_LIB.T6G(SCH_1):PAGE478
PU6512    5  PGND1 ISL99390FRZTR5935-ISL99390FRZ-TR5935,SMLF,IC,AL099A    I12 @T6G_MB_LIB.T6G(SCH_1):PAGE478
PU6512 7_9-20_24  PGND2 ISL99390FRZTR5935-ISL99390FRZ-TR5935,SMLF,IC,AL099A    I12 @T6G_MB_LIB.T6G(SCH_1):PAGE478
PU6512   40  PGND3 ISL99390FRZTR5935-ISL99390FRZ-TR5935,SMLF,IC,AL099A    I12 @T6G_MB_LIB.T6G(SCH_1):PAGE478
PC6644_09P1_2    2      B Q_CAP_C0402-2.2UF,10V,10%,X6S,CH5222KEB01    I14 @T6G_MB_LIB.T6G(SCH_1):PAGE478
PC6634_2    2      B Q_CAP_0402-3300PF,50V,10%,X7R,TMP_QCH2336K1B12    I18 @T6G_MB_LIB.T6G(SCH_1):PAGE478
PC6633_2    2      B Q_CAP_C0402-1UF,25V,10%,X6S,CH5104KEB02    I21 @T6G_MB_LIB.T6G(SCH_1):PAGE478
PC6807    2      B Q_CAP_C0402-100NF,50V,10%,X7R,CH4106K1B01    I23 @T6G_MB_LIB.T6G(SCH_1):PAGE478
PC6635_2    2      B Q_CAP_C0805-22UF,16V,20%,X6S,CH6223MEA01    I25 @T6G_MB_LIB.T6G(SCH_1):PAGE478
PC6636_2    2      B Q_CAP_C0805-22UF,16V,20%,X6S,CH6223MEA01    I28 @T6G_MB_LIB.T6G(SCH_1):PAGE478
PC6642_2    2      B Q_CAP_C0805-22UF,4V,20%,X6S,CH622KMEA03    I29 @T6G_MB_LIB.T6G(SCH_1):PAGE478
PC6643_2    2      B Q_CAP_C0805-22UF,4V,20%,X6S,CH622KMEA03    I30 @T6G_MB_LIB.T6G(SCH_1):PAGE478
PC6813    2      B Q_CAPP_SMLF-470UF,2.5V,20%,SPCAP,CH747LM8818    I31 @T6G_MB_LIB.T6G(SCH_1):PAGE478
PC6814    2      B Q_CAPP_SMLF-470UF,2.5V,20%,SPCAP,CH747LM8818    I32 @T6G_MB_LIB.T6G(SCH_1):PAGE478
PC6637_2    2      B Q_CAP_C0805-22UF,16V,20%,X6S,CH6223MEA01    I35 @T6G_MB_LIB.T6G(SCH_1):PAGE478
PC6638_2    2      B Q_CAP_C0805-22UF,16V,20%,X6S,CH6223MEA01    I36 @T6G_MB_LIB.T6G(SCH_1):PAGE478
PC6639    2      B Q_CAP_C0805-22UF,16V,20%,X6S,CH6223MEA01    I38 @T6G_MB_LIB.T6G(SCH_1):PAGE478
PC6611_1    2      B Q_CAP_C0402-100NF,50V,10%,X7R,CH4106K1B01    I39 @T6G_MB_LIB.T6G(SCH_1):PAGE478
PR6622    2      B Q_RES_0402LF-8.87K,1%,1/16W,EMPTY,CS28872FB01    I46 @T6G_MB_LIB.T6G(SCH_1):PAGE478
PU6511    2   AGND ISL99390FRZTR5935-ISL99390FRZ-TR5935,SMLF,IC,AL099A    I51 @T6G_MB_LIB.T6G(SCH_1):PAGE478
PU6511    5  PGND1 ISL99390FRZTR5935-ISL99390FRZ-TR5935,SMLF,IC,AL099A    I51 @T6G_MB_LIB.T6G(SCH_1):PAGE478
PU6511 7_9-20_24  PGND2 ISL99390FRZTR5935-ISL99390FRZ-TR5935,SMLF,IC,AL099A    I51 @T6G_MB_LIB.T6G(SCH_1):PAGE478
PU6511   40  PGND3 ISL99390FRZTR5935-ISL99390FRZ-TR5935,SMLF,IC,AL099A    I51 @T6G_MB_LIB.T6G(SCH_1):PAGE478
PC6610    2      B Q_CAP_C0402-2.2UF,10V,10%,X6S,CH5222KEB01    I52 @T6G_MB_LIB.T6G(SCH_1):PAGE478
PC6609_09P1_1    2      B Q_CAP_C0402-2.2UF,10V,10%,X6S,CH5222KEB01    I55 @T6G_MB_LIB.T6G(SCH_1):PAGE478
PC6613_1    2      B Q_CAP_0402-3300PF,50V,10%,X7R,TMP_QCH2336K1B12    I61 @T6G_MB_LIB.T6G(SCH_1):PAGE478
PC6612_1    2      B Q_CAP_C0402-1UF,25V,10%,X6S,CH5104KEB02    I64 @T6G_MB_LIB.T6G(SCH_1):PAGE478
PC6623    2      B Q_CAP_C0402-100NF,50V,10%,X7R,CH4106K1B01    I66 @T6G_MB_LIB.T6G(SCH_1):PAGE478
PC6624_1    2      B Q_CAP_C0805-22UF,4V,20%,X6S,CH622KMEA03    I67 @T6G_MB_LIB.T6G(SCH_1):PAGE478
PC6625_1    2      B Q_CAP_C0805-22UF,4V,20%,X6S,CH622KMEA03    I68 @T6G_MB_LIB.T6G(SCH_1):PAGE478
PC6626    2      B Q_CAPP_SMLF-470UF,2.5V,20%,SPCAP,CH747LM8818    I69 @T6G_MB_LIB.T6G(SCH_1):PAGE478
PC6627    2      B Q_CAPP_SMLF-470UF,2.5V,20%,SPCAP,CH747LM8818    I70 @T6G_MB_LIB.T6G(SCH_1):PAGE478
PC6614_1    2      B Q_CAP_C0805-22UF,16V,20%,X6S,CH6223MEA01    I72 @T6G_MB_LIB.T6G(SCH_1):PAGE478
PC6615_1    2      B Q_CAP_C0805-22UF,16V,20%,X6S,CH6223MEA01    I74 @T6G_MB_LIB.T6G(SCH_1):PAGE478
PC6616_1    2      B Q_CAP_C0805-22UF,16V,20%,X6S,CH6223MEA01    I77 @T6G_MB_LIB.T6G(SCH_1):PAGE478
PC6617_1    2      B Q_CAP_C0805-22UF,16V,20%,X6S,CH6223MEA01    I79 @T6G_MB_LIB.T6G(SCH_1):PAGE478
PC6618    2      B Q_CAP_C0805-22UF,16V,20%,X6S,CH6223MEA01    I80 @T6G_MB_LIB.T6G(SCH_1):PAGE478
PC6815    2      B Q_CAPP_SMLF-470UF,2.5V,20%,SPCAP,CH747LM8818    I82 @T6G_MB_LIB.T6G(SCH_1):PAGE478
PC6631    2      B Q_CAPP_SMLF-390UF,2.5V,20%,ALUM,CC7390JMZ13    I83 @T6G_MB_LIB.T6G(SCH_1):PAGE478
PC6632    2      B Q_CAPP_SMLF-390UF,2.5V,20%,ALUM,CC7390JMZ13    I84 @T6G_MB_LIB.T6G(SCH_1):PAGE478
PC6818    2      B Q_CAP_C0805-22UF,16V,20%,X6S,CH6223MEA01    I86 @T6G_MB_LIB.T6G(SCH_1):PAGE478
 PC473    2      B Q_CAPP_SMLF-100UF,16V,20%,OSCON,CC71003MZ30    I88 @T6G_MB_LIB.T6G(SCH_1):PAGE478
PC6628    2      B Q_CAPP_SMLF-470UF,2.5V,20%,SPCAP,CH747LM8818    I93 @T6G_MB_LIB.T6G(SCH_1):PAGE478
PC6629    2      B Q_CAPP_SMLF-390UF,2.5V,20%,ALUM,CC7390JMZ13    I94 @T6G_MB_LIB.T6G(SCH_1):PAGE478
PC6630    2      B Q_CAPP_SMLF-390UF,2.5V,20%,ALUM,CC7390JMZ13    I95 @T6G_MB_LIB.T6G(SCH_1):PAGE478
PR6625    2      B Q_RES_0603LF-499,1%,1/10W,CHIP,CS14993F901    I97 @T6G_MB_LIB.T6G(SCH_1):PAGE478
PC6819    2      B Q_CAP_C0805-22UF,16V,20%,X6S,CH6223MEA01   I100 @T6G_MB_LIB.T6G(SCH_1):PAGE478
PC6619    2      B Q_CAPP_SMLF-100UF,16V,20%,OSCON,CC71003MZ30   I102 @T6G_MB_LIB.T6G(SCH_1):PAGE478
PR6624    2      B Q_RES_0402LF-1.5,1%,1/8W,EMPTY,CS-1504FB00   I106 @T6G_MB_LIB.T6G(SCH_1):PAGE478
PR6630    2      B Q_RES_0402LF-1.5,1%,1/8W,EMPTY,CS-1504FB00   I110 @T6G_MB_LIB.T6G(SCH_1):PAGE478
PC6620    2      B Q_CAP_0402-0.1UF,25V,10%,X7R,CH4104K1B00   I114 @T6G_MB_LIB.T6G(SCH_1):PAGE478
    H2    1      1 HOLE_TH-EMPTY,HOLE1226   I170 @T6G_MB_LIB.T6G(SCH_1):PAGE212
    H8    1      1 HOLE_TH-EMPTY,HOLE1226   I176 @T6G_MB_LIB.T6G(SCH_1):PAGE212
   H10    1      1 HOLE_TH-EMPTY,HOLE1226   I178 @T6G_MB_LIB.T6G(SCH_1):PAGE212
   H12    1      1 HOLE_TH-EMPTY,HOLE1226   I187 @T6G_MB_LIB.T6G(SCH_1):PAGE212
    H5    1      1 HOLE_TH-EMPTY,HOLE1226   I193 @T6G_MB_LIB.T6G(SCH_1):PAGE212
    H3    1      1 HOLE_TH-EMPTY,HOLE1226   I195 @T6G_MB_LIB.T6G(SCH_1):PAGE212
  C123    2      B Q_CAP_0201-1UF,4V,20%,X6S,CH-10KMEE00    I18 @T6G_MB_LIB.T6G(SCH_1):PAGE398
  C125    2      B Q_CAP_0201-1UF,4V,20%,X6S,CH-10KMEE00    I19 @T6G_MB_LIB.T6G(SCH_1):PAGE398
  C119    2      B Q_CAP_C0402-10UF,6.3V,20%,X6S,CH6101MEB01    I20 @T6G_MB_LIB.T6G(SCH_1):PAGE398
  C115    2      B Q_CAP_C0402-22UF,4V,20%,X6S,CH622KMEB02    I21 @T6G_MB_LIB.T6G(SCH_1):PAGE398
 R6802    2      B Q_RES_0402LF-10K,1%,1/16W,CHIP,CS31002FB08    I68 @T6G_MB_LIB.T6G(SCH_1):PAGE160
 R6803    2      B Q_RES_0402LF-10K,1%,1/16W,CHIP,CS31002FB08    I76 @T6G_MB_LIB.T6G(SCH_1):PAGE379
 U6020   12    GND TCA9548APWR-TCA9548APWR,SMLF,IC,AL009548K02     I1 @T6G_MB_LIB.T6G(SCH_1):PAGE378
   C76    2      B Q_CAP_C0402-10UF,6.3V,20%,X6S,CH6101MEB01    I69 @T6G_MB_LIB.T6G(SCH_1):PAGE160
   C77    2      B Q_CAP_C0402-10UF,6.3V,20%,X6S,CH6101MEB01    I70 @T6G_MB_LIB.T6G(SCH_1):PAGE160
 C2328    2      B Q_CAP_C0402-10UF,6.3V,20%,X6S,CH6101MEB01    I71 @T6G_MB_LIB.T6G(SCH_1):PAGE160
   C82    2      B Q_CAP_C0402-10UF,6.3V,20%,X6S,CH6101MEB01    I77 @T6G_MB_LIB.T6G(SCH_1):PAGE379
   C83    2      B Q_CAP_C0402-10UF,6.3V,20%,X6S,CH6101MEB01    I78 @T6G_MB_LIB.T6G(SCH_1):PAGE379
   C28    2      B Q_CAP_C0402-10UF,6.3V,20%,X6S,CH6101MEB01    I79 @T6G_MB_LIB.T6G(SCH_1):PAGE379
  R629    2      B Q_RES_0201LF-51.1,1%,1/20W,EMPTY,CS05111FE00    I18 @T6G_MB_LIB.T6G(SCH_1):PAGE408
  R630    2      B Q_RES_0201LF-51.1,1%,1/20W,EMPTY,CS05111FE00    I19 @T6G_MB_LIB.T6G(SCH_1):PAGE408
  R627    2      B Q_RES_0201LF-51.1,1%,1/20W,EMPTY,CS05111FE00    I23 @T6G_MB_LIB.T6G(SCH_1):PAGE401
  R628    2      B Q_RES_0201LF-51.1,1%,1/20W,EMPTY,CS05111FE00    I24 @T6G_MB_LIB.T6G(SCH_1):PAGE401
  R711    2      B Q_RES_0201LF-0,5%,1/20W,CHIP,CS00001JE10   I102 @T6G_MB_LIB.T6G(SCH_1):PAGE400
  R709    2      B Q_RES_0201LF-0,5%,1/20W,CHIP,CS00001JE10   I103 @T6G_MB_LIB.T6G(SCH_1):PAGE400
  R725    2      B Q_RES_0201LF-4.7K,5%,1/20W,CHIP,CS24701JE04    I32 @T6G_MB_LIB.T6G(SCH_1):PAGE401
  R723    2      B Q_RES_0201LF-4.7K,5%,1/20W,CHIP,CS24701JE04    I33 @T6G_MB_LIB.T6G(SCH_1):PAGE401
  R719    2      B Q_RES_0201LF-4.7K,5%,1/20W,CHIP,CS24701JE04    I34 @T6G_MB_LIB.T6G(SCH_1):PAGE401
  R715    2      B Q_RES_0201LF-10K,1%,1/20W,CHIP,CS31001FE17    I35 @T6G_MB_LIB.T6G(SCH_1):PAGE401
  R707    2      B Q_RES_0201LF-10K,1%,1/20W,CHIP,CS31001FE17    I36 @T6G_MB_LIB.T6G(SCH_1):PAGE401
  R728    2      B Q_RES_0201LF-4.7K,5%,1/20W,EMPTY,CS24701JE04    I55 @T6G_MB_LIB.T6G(SCH_1):PAGE401
   BT2    2      2 CONN2_AAABAT029Y19-CONN2_AAA-BAT-029-Y19,THLF,IO,DA    I86 @T6G_MB_LIB.T6G(SCH_1):PAGE156
    U9    2    GND TPS71715DCKR-TPS71715DCKR,SMLF,EMPTY,AL071715001    I91 @T6G_MB_LIB.T6G(SCH_1):PAGE156
 R1776    2      B Q_RES_0402LF-1K,1%,1/16W,CHIP,CS21002FB06    I94 @T6G_MB_LIB.T6G(SCH_1):PAGE156
 C1563    2      B Q_CAP_C0402-0.1UF,16V,10%,X7R,CH4103K1B08    I95 @T6G_MB_LIB.T6G(SCH_1):PAGE156
    Q8    1     S1 MOSFET_DUAL_6P-2N7002KDW,SMLF,IC,BAM70020047   I104 @T6G_MB_LIB.T6G(SCH_1):PAGE156
    Q8    4     S2 MOSFET_DUAL_6P-2N7002KDW,SMLF,IC,BAM70020047   I104 @T6G_MB_LIB.T6G(SCH_1):PAGE156
   C45    2      B Q_CAP_C0402-1UF,25V,10%,X6S,CH5104KEB02   I107 @T6G_MB_LIB.T6G(SCH_1):PAGE156
  C193    2      B Q_CAP_C0402-100NF,50V,10%,X7R,CH4106K1B01   I108 @T6G_MB_LIB.T6G(SCH_1):PAGE156
   C22    2      B Q_CAP_C0402-0.01UF,50V,10%,EMPTY,CH31006KB18   I113 @T6G_MB_LIB.T6G(SCH_1):PAGE156
 C1564    2      B Q_CAP_C0402-1UF,25V,10%,X6S,CH5104KEB02   I118 @T6G_MB_LIB.T6G(SCH_1):PAGE156
 C1567    2      B Q_CAP_C0402-1UF,25V,10%,X6S,CH5104KEB02   I125 @T6G_MB_LIB.T6G(SCH_1):PAGE156
 C5032    2      B Q_CAP_C0805-10UF,25V,10%,X6S,CH6104KEA00   I126 @T6G_MB_LIB.T6G(SCH_1):PAGE156
  JP12    3      3 CONN3_210HP1030BR1-CONN3_210-HP1-030BR1,THLF,IO,DFA   I128 @T6G_MB_LIB.T6G(SCH_1):PAGE156
 R5056    2      B Q_RES_0402LF-10K,5%,1/16W,EMPTY,CS31002JB08   I428 @T6G_MB_LIB.T6G(SCH_1):PAGE27
  C129    2      B Q_CAP_C0201-0.1UF,10V,10%,X7S,CH4102K6E00    I23 @T6G_MB_LIB.T6G(SCH_1):PAGE398
  C131    2      B Q_CAP_C0201-0.1UF,10V,10%,X7S,CH4102K6E00    I24 @T6G_MB_LIB.T6G(SCH_1):PAGE398
  C133    2      B Q_CAP_C0201-0.1UF,10V,10%,X7S,CH4102K6E00    I25 @T6G_MB_LIB.T6G(SCH_1):PAGE398
  C134    2      B Q_CAP_C0201-0.1UF,10V,10%,X7S,CH4102K6E00    I26 @T6G_MB_LIB.T6G(SCH_1):PAGE398
  C130    2      B Q_CAP_C0201-0.1UF,10V,10%,X7S,CH4102K6E00    I27 @T6G_MB_LIB.T6G(SCH_1):PAGE398
  C229    2      B Q_CAP_C0805-100UF,4V,20%,X6S,CH710KMEA01    I34 @T6G_MB_LIB.T6G(SCH_1):PAGE398
  C244    2      B Q_CAP_C0402-22UF,4V,20%,X6S,CH622KMEB02    I35 @T6G_MB_LIB.T6G(SCH_1):PAGE398
  C261    2      B Q_CAP_C0402-10UF,6.3V,20%,X6S,CH6101MEB01    I36 @T6G_MB_LIB.T6G(SCH_1):PAGE398
  C256    2      B Q_CAP_0402-4.7UF,6.3V,20%,X6S,CH5471MEB01    I39 @T6G_MB_LIB.T6G(SCH_1):PAGE398
  C185    2      B Q_CAP_0201-1UF,4V,20%,X6S,CH-10KMEE00    I40 @T6G_MB_LIB.T6G(SCH_1):PAGE398
  C222    2      B Q_CAP_0201-1UF,4V,20%,X6S,CH-10KMEE00    I42 @T6G_MB_LIB.T6G(SCH_1):PAGE398
  C220    2      B Q_CAP_C0805-100UF,4V,20%,X6S,CH710KMEA01    I44 @T6G_MB_LIB.T6G(SCH_1):PAGE398
  C135    2      B Q_CAP_0201-1UF,4V,20%,X6S,CH-10KMEE00    I46 @T6G_MB_LIB.T6G(SCH_1):PAGE398
  C243    2      B Q_CAP_0201-1UF,4V,20%,X6S,CH-10KMEE00    I47 @T6G_MB_LIB.T6G(SCH_1):PAGE398
  C138    2      B Q_CAP_0201-1UF,4V,20%,X6S,CH-10KMEE00    I48 @T6G_MB_LIB.T6G(SCH_1):PAGE398
  C257    2      B Q_CAP_0201-1UF,4V,20%,X6S,CH-10KMEE00    I49 @T6G_MB_LIB.T6G(SCH_1):PAGE398
  C221    2      B Q_CAP_0402-4.7UF,6.3V,20%,X6S,CH5471MEB01    I50 @T6G_MB_LIB.T6G(SCH_1):PAGE398
  C258    2      B Q_CAP_0402-4.7UF,6.3V,20%,X6S,CH5471MEB01    I51 @T6G_MB_LIB.T6G(SCH_1):PAGE398
  C225    2      B Q_CAP_C0805-100UF,4V,20%,X6S,CH710KMEA01    I52 @T6G_MB_LIB.T6G(SCH_1):PAGE398
  C240    2      B Q_CAP_C0805-100UF,4V,20%,X6S,CH710KMEA01    I53 @T6G_MB_LIB.T6G(SCH_1):PAGE398
  C284    2      B Q_CAP_C0402-22UF,4V,20%,X6S,CH622KMEB02    I54 @T6G_MB_LIB.T6G(SCH_1):PAGE398
  C188    2      B Q_CAP_0201-1UF,4V,20%,X6S,CH-10KMEE00    I55 @T6G_MB_LIB.T6G(SCH_1):PAGE398
  C265    2      B Q_CAP_0201-1UF,4V,20%,X6S,CH-10KMEE00    I56 @T6G_MB_LIB.T6G(SCH_1):PAGE398
  C227    2      B Q_CAP_0402-4.7UF,6.3V,20%,X6S,CH5471MEB01    I57 @T6G_MB_LIB.T6G(SCH_1):PAGE398
  C186    2      B Q_CAP_0201-1UF,4V,20%,X6S,CH-10KMEE00    I58 @T6G_MB_LIB.T6G(SCH_1):PAGE398
  C280    2      B Q_CAP_0201-1UF,4V,20%,X6S,CH-10KMEE00    I59 @T6G_MB_LIB.T6G(SCH_1):PAGE398
  C190    2      B Q_CAP_0201-1UF,4V,20%,X6S,CH-10KMEE00    I62 @T6G_MB_LIB.T6G(SCH_1):PAGE398
  C285    2      B Q_CAP_0201-1UF,4V,20%,X6S,CH-10KMEE00    I63 @T6G_MB_LIB.T6G(SCH_1):PAGE398
  C255    2      B Q_CAP_C0402-22UF,4V,20%,X6S,CH622KMEB02    I64 @T6G_MB_LIB.T6G(SCH_1):PAGE398
  C262    2      B Q_CAP_C0402-22UF,4V,20%,X6S,CH622KMEB02    I65 @T6G_MB_LIB.T6G(SCH_1):PAGE398
  C259    2      B Q_CAP_C0402-22UF,4V,20%,X6S,CH622KMEB02    I66 @T6G_MB_LIB.T6G(SCH_1):PAGE398
  C254    2      B Q_CAP_C0402-10UF,6.3V,20%,X6S,CH6101MEB01    I67 @T6G_MB_LIB.T6G(SCH_1):PAGE398
  C286    2      B Q_CAP_C0402-10UF,6.3V,20%,X6S,CH6101MEB01    I68 @T6G_MB_LIB.T6G(SCH_1):PAGE398
  C250    2      B Q_CAP_C0402-10UF,6.3V,20%,X6S,CH6101MEB01    I70 @T6G_MB_LIB.T6G(SCH_1):PAGE398
  C269    2      B Q_CAP_C0402-10UF,6.3V,20%,X6S,CH6101MEB01    I71 @T6G_MB_LIB.T6G(SCH_1):PAGE398
  C241    2      B Q_CAP_0402-4.7UF,6.3V,20%,X6S,CH5471MEB01    I72 @T6G_MB_LIB.T6G(SCH_1):PAGE398
  C247    2      B Q_CAP_C0805-100UF,4V,20%,X6S,CH710KMEA01    I73 @T6G_MB_LIB.T6G(SCH_1):PAGE398
  C189    2      B Q_CAP_C0201-0.1UF,10V,10%,X7S,CH4102K6E00    I75 @T6G_MB_LIB.T6G(SCH_1):PAGE398
  C266    2      B Q_CAP_C0201-0.1UF,10V,10%,X7S,CH4102K6E00    I76 @T6G_MB_LIB.T6G(SCH_1):PAGE398
  C139    2      B Q_CAP_C0201-0.1UF,10V,10%,X7S,CH4102K6E00    I77 @T6G_MB_LIB.T6G(SCH_1):PAGE398
  C137    2      B Q_CAP_C0201-0.1UF,10V,10%,X7S,CH4102K6E00    I78 @T6G_MB_LIB.T6G(SCH_1):PAGE398
  C282    2      B Q_CAP_C0201-0.1UF,10V,10%,X7S,CH4102K6E00    I80 @T6G_MB_LIB.T6G(SCH_1):PAGE398
  C264    2      B Q_CAP_C0201-0.1UF,10V,10%,X7S,CH4102K6E00    I81 @T6G_MB_LIB.T6G(SCH_1):PAGE398
  C141    2      B Q_CAP_C0201-0.1UF,10V,10%,X7S,CH4102K6E00    I82 @T6G_MB_LIB.T6G(SCH_1):PAGE398
  C192    2      B Q_CAP_C0201-0.1UF,10V,10%,X7S,CH4102K6E00    I83 @T6G_MB_LIB.T6G(SCH_1):PAGE398
  C260    2      B Q_CAP_C0201-0.1UF,10V,10%,X7S,CH4102K6E00    I84 @T6G_MB_LIB.T6G(SCH_1):PAGE398
  C184    2      B Q_CAP_C0201-0.1UF,10V,10%,X7S,CH4102K6E00    I85 @T6G_MB_LIB.T6G(SCH_1):PAGE398
  C253    2      B Q_CAP_C0201-0.1UF,10V,10%,X7S,CH4102K6E00    I86 @T6G_MB_LIB.T6G(SCH_1):PAGE398
  C228    2      B Q_CAP_C0201-0.1UF,10V,10%,X7S,CH4102K6E00    I87 @T6G_MB_LIB.T6G(SCH_1):PAGE398
  C198    2      B Q_CAP_C0201-0.1UF,10V,10%,X7S,CH4102K6E00    I92 @T6G_MB_LIB.T6G(SCH_1):PAGE398
  C191    2      B Q_CAP_C0201-0.1UF,10V,10%,X7S,CH4102K6E00    I93 @T6G_MB_LIB.T6G(SCH_1):PAGE398
  R726    2      B Q_RES_0201LF-4.7K,5%,1/20W,CHIP,CS24701JE04    I90 @T6G_MB_LIB.T6G(SCH_1):PAGE401
 R6721    2      B Q_RES_0201LF-10K,1%,1/20W,CHIP,CS31001FE17    I96 @T6G_MB_LIB.T6G(SCH_1):PAGE401
 R6720    2      B Q_RES_0201LF-10K,1%,1/20W,CHIP,CS31001FE17    I97 @T6G_MB_LIB.T6G(SCH_1):PAGE401
 R6733    2      B Q_RES_0201LF-0,5%,1/20W,CHIP,CS00001JE10    I15 @T6G_MB_LIB.T6G(SCH_1):PAGE391
 R6732    2      B Q_RES_0201LF-0,5%,1/20W,CHIP,CS00001JE10    I16 @T6G_MB_LIB.T6G(SCH_1):PAGE391
 U6015 AC13   GND1 PT5161LRS-PT5161LRS,SMLF,IC,AJ051610U03    I19 @T6G_MB_LIB.T6G(SCH_1):PAGE391
 U6015 AC22   GND2 PT5161LRS-PT5161LRS,SMLF,IC,AJ051610U03    I19 @T6G_MB_LIB.T6G(SCH_1):PAGE391
 U6015 AC32   GND3 PT5161LRS-PT5161LRS,SMLF,IC,AJ051610U03    I19 @T6G_MB_LIB.T6G(SCH_1):PAGE391
 U6015  AC4   GND4 PT5161LRS-PT5161LRS,SMLF,IC,AJ051610U03    I19 @T6G_MB_LIB.T6G(SCH_1):PAGE391
 U6015  AD2   GND5 PT5161LRS-PT5161LRS,SMLF,IC,AJ051610U03    I19 @T6G_MB_LIB.T6G(SCH_1):PAGE391
 U6015 AD34   GND6 PT5161LRS-PT5161LRS,SMLF,IC,AJ051610U03    I19 @T6G_MB_LIB.T6G(SCH_1):PAGE391
 U6015  AE1   GND7 PT5161LRS-PT5161LRS,SMLF,IC,AJ051610U03    I19 @T6G_MB_LIB.T6G(SCH_1):PAGE391
 U6015 AE35   GND8 PT5161LRS-PT5161LRS,SMLF,IC,AJ051610U03    I19 @T6G_MB_LIB.T6G(SCH_1):PAGE391
 U6015 AK13   GND9 PT5161LRS-PT5161LRS,SMLF,IC,AJ051610U03    I19 @T6G_MB_LIB.T6G(SCH_1):PAGE391
 U6015 AK22  GND10 PT5161LRS-PT5161LRS,SMLF,IC,AJ051610U03    I19 @T6G_MB_LIB.T6G(SCH_1):PAGE391
 U6015 AK32  GND11 PT5161LRS-PT5161LRS,SMLF,IC,AJ051610U03    I19 @T6G_MB_LIB.T6G(SCH_1):PAGE391
 U6015  AK4  GND12 PT5161LRS-PT5161LRS,SMLF,IC,AJ051610U03    I19 @T6G_MB_LIB.T6G(SCH_1):PAGE391
 U6015  AL2  GND13 PT5161LRS-PT5161LRS,SMLF,IC,AJ051610U03    I19 @T6G_MB_LIB.T6G(SCH_1):PAGE391
 U6015 AL34  GND14 PT5161LRS-PT5161LRS,SMLF,IC,AJ051610U03    I19 @T6G_MB_LIB.T6G(SCH_1):PAGE391
 U6015  AM1  GND15 PT5161LRS-PT5161LRS,SMLF,IC,AJ051610U03    I19 @T6G_MB_LIB.T6G(SCH_1):PAGE391
 U6015 AM35  GND16 PT5161LRS-PT5161LRS,SMLF,IC,AJ051610U03    I19 @T6G_MB_LIB.T6G(SCH_1):PAGE391
 U6015 AU13  GND17 PT5161LRS-PT5161LRS,SMLF,IC,AJ051610U03    I19 @T6G_MB_LIB.T6G(SCH_1):PAGE391
 U6015 AU22  GND18 PT5161LRS-PT5161LRS,SMLF,IC,AJ051610U03    I19 @T6G_MB_LIB.T6G(SCH_1):PAGE391
 U6015 AU32  GND19 PT5161LRS-PT5161LRS,SMLF,IC,AJ051610U03    I19 @T6G_MB_LIB.T6G(SCH_1):PAGE391
 U6015  AU4  GND20 PT5161LRS-PT5161LRS,SMLF,IC,AJ051610U03    I19 @T6G_MB_LIB.T6G(SCH_1):PAGE391
 U6015  AV2  GND21 PT5161LRS-PT5161LRS,SMLF,IC,AJ051610U03    I19 @T6G_MB_LIB.T6G(SCH_1):PAGE391
 U6015 AV34  GND22 PT5161LRS-PT5161LRS,SMLF,IC,AJ051610U03    I19 @T6G_MB_LIB.T6G(SCH_1):PAGE391
 U6015  AW1  GND23 PT5161LRS-PT5161LRS,SMLF,IC,AJ051610U03    I19 @T6G_MB_LIB.T6G(SCH_1):PAGE391
 U6015 AW35  GND24 PT5161LRS-PT5161LRS,SMLF,IC,AJ051610U03    I19 @T6G_MB_LIB.T6G(SCH_1):PAGE391
 U6015  B19  GND25 PT5161LRS-PT5161LRS,SMLF,IC,AJ051610U03    I19 @T6G_MB_LIB.T6G(SCH_1):PAGE391
 U6015 BD13  GND26 PT5161LRS-PT5161LRS,SMLF,IC,AJ051610U03    I19 @T6G_MB_LIB.T6G(SCH_1):PAGE391
 U6015 BD22  GND27 PT5161LRS-PT5161LRS,SMLF,IC,AJ051610U03    I19 @T6G_MB_LIB.T6G(SCH_1):PAGE391
 U6015 BD32  GND28 PT5161LRS-PT5161LRS,SMLF,IC,AJ051610U03    I19 @T6G_MB_LIB.T6G(SCH_1):PAGE391
 U6015  BD4  GND29 PT5161LRS-PT5161LRS,SMLF,IC,AJ051610U03    I19 @T6G_MB_LIB.T6G(SCH_1):PAGE391
 U6015  BE2  GND30 PT5161LRS-PT5161LRS,SMLF,IC,AJ051610U03    I19 @T6G_MB_LIB.T6G(SCH_1):PAGE391
 U6015 BE34  GND31 PT5161LRS-PT5161LRS,SMLF,IC,AJ051610U03    I19 @T6G_MB_LIB.T6G(SCH_1):PAGE391
 U6015  BF1  GND32 PT5161LRS-PT5161LRS,SMLF,IC,AJ051610U03    I19 @T6G_MB_LIB.T6G(SCH_1):PAGE391
 U6015 BF35  GND33 PT5161LRS-PT5161LRS,SMLF,IC,AJ051610U03    I19 @T6G_MB_LIB.T6G(SCH_1):PAGE391
 U6015 BL13  GND34 PT5161LRS-PT5161LRS,SMLF,IC,AJ051610U03    I19 @T6G_MB_LIB.T6G(SCH_1):PAGE391
 U6015 BL22  GND35 PT5161LRS-PT5161LRS,SMLF,IC,AJ051610U03    I19 @T6G_MB_LIB.T6G(SCH_1):PAGE391
 U6015 BL32  GND36 PT5161LRS-PT5161LRS,SMLF,IC,AJ051610U03    I19 @T6G_MB_LIB.T6G(SCH_1):PAGE391
 U6015  BL4  GND37 PT5161LRS-PT5161LRS,SMLF,IC,AJ051610U03    I19 @T6G_MB_LIB.T6G(SCH_1):PAGE391
 U6015  BM2  GND38 PT5161LRS-PT5161LRS,SMLF,IC,AJ051610U03    I19 @T6G_MB_LIB.T6G(SCH_1):PAGE391
 U6015 BM34  GND39 PT5161LRS-PT5161LRS,SMLF,IC,AJ051610U03    I19 @T6G_MB_LIB.T6G(SCH_1):PAGE391
 U6015  BN1  GND40 PT5161LRS-PT5161LRS,SMLF,IC,AJ051610U03    I19 @T6G_MB_LIB.T6G(SCH_1):PAGE391
 U6015 BN35  GND41 PT5161LRS-PT5161LRS,SMLF,IC,AJ051610U03    I19 @T6G_MB_LIB.T6G(SCH_1):PAGE391
 U6015 BV13  GND42 PT5161LRS-PT5161LRS,SMLF,IC,AJ051610U03    I19 @T6G_MB_LIB.T6G(SCH_1):PAGE391
 U6015 BV22  GND43 PT5161LRS-PT5161LRS,SMLF,IC,AJ051610U03    I19 @T6G_MB_LIB.T6G(SCH_1):PAGE391
 U6015 BV32  GND44 PT5161LRS-PT5161LRS,SMLF,IC,AJ051610U03    I19 @T6G_MB_LIB.T6G(SCH_1):PAGE391
 U6015  BV4  GND45 PT5161LRS-PT5161LRS,SMLF,IC,AJ051610U03    I19 @T6G_MB_LIB.T6G(SCH_1):PAGE391
 U6015  BW2  GND46 PT5161LRS-PT5161LRS,SMLF,IC,AJ051610U03    I19 @T6G_MB_LIB.T6G(SCH_1):PAGE391
 U6015 BW34  GND47 PT5161LRS-PT5161LRS,SMLF,IC,AJ051610U03    I19 @T6G_MB_LIB.T6G(SCH_1):PAGE391
 U6015  BY1  GND48 PT5161LRS-PT5161LRS,SMLF,IC,AJ051610U03    I19 @T6G_MB_LIB.T6G(SCH_1):PAGE391
 U6015 BY35  GND49 PT5161LRS-PT5161LRS,SMLF,IC,AJ051610U03    I19 @T6G_MB_LIB.T6G(SCH_1):PAGE391
 U6015 CE13  GND50 PT5161LRS-PT5161LRS,SMLF,IC,AJ051610U03    I19 @T6G_MB_LIB.T6G(SCH_1):PAGE391
 U6015 CE22  GND51 PT5161LRS-PT5161LRS,SMLF,IC,AJ051610U03    I19 @T6G_MB_LIB.T6G(SCH_1):PAGE391
 U6015 CE32  GND52 PT5161LRS-PT5161LRS,SMLF,IC,AJ051610U03    I19 @T6G_MB_LIB.T6G(SCH_1):PAGE391
 U6015  CE4  GND53 PT5161LRS-PT5161LRS,SMLF,IC,AJ051610U03    I19 @T6G_MB_LIB.T6G(SCH_1):PAGE391
 U6015  CF2  GND54 PT5161LRS-PT5161LRS,SMLF,IC,AJ051610U03    I19 @T6G_MB_LIB.T6G(SCH_1):PAGE391
 U6015 CF34  GND55 PT5161LRS-PT5161LRS,SMLF,IC,AJ051610U03    I19 @T6G_MB_LIB.T6G(SCH_1):PAGE391
 U6015  CG1  GND56 PT5161LRS-PT5161LRS,SMLF,IC,AJ051610U03    I19 @T6G_MB_LIB.T6G(SCH_1):PAGE391
 U6015 CG35  GND57 PT5161LRS-PT5161LRS,SMLF,IC,AJ051610U03    I19 @T6G_MB_LIB.T6G(SCH_1):PAGE391
 U6015 CM13  GND58 PT5161LRS-PT5161LRS,SMLF,IC,AJ051610U03    I19 @T6G_MB_LIB.T6G(SCH_1):PAGE391
 U6015 CM22  GND59 PT5161LRS-PT5161LRS,SMLF,IC,AJ051610U03    I19 @T6G_MB_LIB.T6G(SCH_1):PAGE391
 U6015 CM32  GND60 PT5161LRS-PT5161LRS,SMLF,IC,AJ051610U03    I19 @T6G_MB_LIB.T6G(SCH_1):PAGE391
 U6015  CM4  GND61 PT5161LRS-PT5161LRS,SMLF,IC,AJ051610U03    I19 @T6G_MB_LIB.T6G(SCH_1):PAGE391
 U6015  CN2  GND62 PT5161LRS-PT5161LRS,SMLF,IC,AJ051610U03    I19 @T6G_MB_LIB.T6G(SCH_1):PAGE391
 U6015 CN34  GND63 PT5161LRS-PT5161LRS,SMLF,IC,AJ051610U03    I19 @T6G_MB_LIB.T6G(SCH_1):PAGE391
 U6015  CP1  GND64 PT5161LRS-PT5161LRS,SMLF,IC,AJ051610U03    I19 @T6G_MB_LIB.T6G(SCH_1):PAGE391
 U6015 CP35  GND65 PT5161LRS-PT5161LRS,SMLF,IC,AJ051610U03    I19 @T6G_MB_LIB.T6G(SCH_1):PAGE391
 U6015 CW13  GND66 PT5161LRS-PT5161LRS,SMLF,IC,AJ051610U03    I19 @T6G_MB_LIB.T6G(SCH_1):PAGE391
 U6015 CW22  GND67 PT5161LRS-PT5161LRS,SMLF,IC,AJ051610U03    I19 @T6G_MB_LIB.T6G(SCH_1):PAGE391
 U6015 CW32  GND68 PT5161LRS-PT5161LRS,SMLF,IC,AJ051610U03    I19 @T6G_MB_LIB.T6G(SCH_1):PAGE391
 U6015  CW4  GND69 PT5161LRS-PT5161LRS,SMLF,IC,AJ051610U03    I19 @T6G_MB_LIB.T6G(SCH_1):PAGE391
 U6015  CY2  GND70 PT5161LRS-PT5161LRS,SMLF,IC,AJ051610U03    I19 @T6G_MB_LIB.T6G(SCH_1):PAGE391
 U6015 CY34  GND71 PT5161LRS-PT5161LRS,SMLF,IC,AJ051610U03    I19 @T6G_MB_LIB.T6G(SCH_1):PAGE391
 U6015  DA1  GND72 PT5161LRS-PT5161LRS,SMLF,IC,AJ051610U03    I19 @T6G_MB_LIB.T6G(SCH_1):PAGE391
 U6015 DA35  GND73 PT5161LRS-PT5161LRS,SMLF,IC,AJ051610U03    I19 @T6G_MB_LIB.T6G(SCH_1):PAGE391
 U6015 DF13  GND74 PT5161LRS-PT5161LRS,SMLF,IC,AJ051610U03    I19 @T6G_MB_LIB.T6G(SCH_1):PAGE391
 U6015 DF22  GND75 PT5161LRS-PT5161LRS,SMLF,IC,AJ051610U03    I19 @T6G_MB_LIB.T6G(SCH_1):PAGE391
 U6015 DF32  GND76 PT5161LRS-PT5161LRS,SMLF,IC,AJ051610U03    I19 @T6G_MB_LIB.T6G(SCH_1):PAGE391
 U6015  DF4  GND77 PT5161LRS-PT5161LRS,SMLF,IC,AJ051610U03    I19 @T6G_MB_LIB.T6G(SCH_1):PAGE391
 U6015  DG2  GND78 PT5161LRS-PT5161LRS,SMLF,IC,AJ051610U03    I19 @T6G_MB_LIB.T6G(SCH_1):PAGE391
 U6015 DG34  GND79 PT5161LRS-PT5161LRS,SMLF,IC,AJ051610U03    I19 @T6G_MB_LIB.T6G(SCH_1):PAGE391
 U6015  DH1  GND80 PT5161LRS-PT5161LRS,SMLF,IC,AJ051610U03    I19 @T6G_MB_LIB.T6G(SCH_1):PAGE391
 U6015 DH35  GND81 PT5161LRS-PT5161LRS,SMLF,IC,AJ051610U03    I19 @T6G_MB_LIB.T6G(SCH_1):PAGE391
 U6015 DN13  GND82 PT5161LRS-PT5161LRS,SMLF,IC,AJ051610U03    I19 @T6G_MB_LIB.T6G(SCH_1):PAGE391
 U6015 DN22  GND83 PT5161LRS-PT5161LRS,SMLF,IC,AJ051610U03    I19 @T6G_MB_LIB.T6G(SCH_1):PAGE391
 U6015 DN32  GND84 PT5161LRS-PT5161LRS,SMLF,IC,AJ051610U03    I19 @T6G_MB_LIB.T6G(SCH_1):PAGE391
 U6015  DN4  GND85 PT5161LRS-PT5161LRS,SMLF,IC,AJ051610U03    I19 @T6G_MB_LIB.T6G(SCH_1):PAGE391
 U6015  DP2  GND86 PT5161LRS-PT5161LRS,SMLF,IC,AJ051610U03    I19 @T6G_MB_LIB.T6G(SCH_1):PAGE391
 U6015 DP34  GND87 PT5161LRS-PT5161LRS,SMLF,IC,AJ051610U03    I19 @T6G_MB_LIB.T6G(SCH_1):PAGE391
 U6015  DR1  GND88 PT5161LRS-PT5161LRS,SMLF,IC,AJ051610U03    I19 @T6G_MB_LIB.T6G(SCH_1):PAGE391
 U6015 DR35  GND89 PT5161LRS-PT5161LRS,SMLF,IC,AJ051610U03    I19 @T6G_MB_LIB.T6G(SCH_1):PAGE391
 U6015 DY13  GND90 PT5161LRS-PT5161LRS,SMLF,IC,AJ051610U03    I19 @T6G_MB_LIB.T6G(SCH_1):PAGE391
 U6015 DY22  GND91 PT5161LRS-PT5161LRS,SMLF,IC,AJ051610U03    I19 @T6G_MB_LIB.T6G(SCH_1):PAGE391
 U6015 DY32  GND92 PT5161LRS-PT5161LRS,SMLF,IC,AJ051610U03    I19 @T6G_MB_LIB.T6G(SCH_1):PAGE391
 U6015  DY4  GND93 PT5161LRS-PT5161LRS,SMLF,IC,AJ051610U03    I19 @T6G_MB_LIB.T6G(SCH_1):PAGE391
 U6015  E14  GND94 PT5161LRS-PT5161LRS,SMLF,IC,AJ051610U03    I19 @T6G_MB_LIB.T6G(SCH_1):PAGE391
 U6015  E27  GND95 PT5161LRS-PT5161LRS,SMLF,IC,AJ051610U03    I19 @T6G_MB_LIB.T6G(SCH_1):PAGE391
 U6015  E33  GND96 PT5161LRS-PT5161LRS,SMLF,IC,AJ051610U03    I19 @T6G_MB_LIB.T6G(SCH_1):PAGE391
 U6015  EA2  GND97 PT5161LRS-PT5161LRS,SMLF,IC,AJ051610U03    I19 @T6G_MB_LIB.T6G(SCH_1):PAGE391
 U6015 EA34  GND98 PT5161LRS-PT5161LRS,SMLF,IC,AJ051610U03    I19 @T6G_MB_LIB.T6G(SCH_1):PAGE391
 U6015  EB1  GND99 PT5161LRS-PT5161LRS,SMLF,IC,AJ051610U03    I19 @T6G_MB_LIB.T6G(SCH_1):PAGE391
 U6015 EB35 GND100 PT5161LRS-PT5161LRS,SMLF,IC,AJ051610U03    I19 @T6G_MB_LIB.T6G(SCH_1):PAGE391
 U6015 EG13 GND101 PT5161LRS-PT5161LRS,SMLF,IC,AJ051610U03    I19 @T6G_MB_LIB.T6G(SCH_1):PAGE391
 U6015 EG22 GND102 PT5161LRS-PT5161LRS,SMLF,IC,AJ051610U03    I19 @T6G_MB_LIB.T6G(SCH_1):PAGE391
 U6015 EG32 GND103 PT5161LRS-PT5161LRS,SMLF,IC,AJ051610U03    I19 @T6G_MB_LIB.T6G(SCH_1):PAGE391
 U6015  EG4 GND104 PT5161LRS-PT5161LRS,SMLF,IC,AJ051610U03    I19 @T6G_MB_LIB.T6G(SCH_1):PAGE391
 U6015  EH2 GND105 PT5161LRS-PT5161LRS,SMLF,IC,AJ051610U03    I19 @T6G_MB_LIB.T6G(SCH_1):PAGE391
 U6015 EH34 GND106 PT5161LRS-PT5161LRS,SMLF,IC,AJ051610U03    I19 @T6G_MB_LIB.T6G(SCH_1):PAGE391
 U6015  EJ1 GND107 PT5161LRS-PT5161LRS,SMLF,IC,AJ051610U03    I19 @T6G_MB_LIB.T6G(SCH_1):PAGE391
 U6015 EJ35 GND108 PT5161LRS-PT5161LRS,SMLF,IC,AJ051610U03    I19 @T6G_MB_LIB.T6G(SCH_1):PAGE391
 U6015 EP13 GND109 PT5161LRS-PT5161LRS,SMLF,IC,AJ051610U03    I19 @T6G_MB_LIB.T6G(SCH_1):PAGE391
 U6015 EP22 GND110 PT5161LRS-PT5161LRS,SMLF,IC,AJ051610U03    I19 @T6G_MB_LIB.T6G(SCH_1):PAGE391
 U6015 EP32 GND111 PT5161LRS-PT5161LRS,SMLF,IC,AJ051610U03    I19 @T6G_MB_LIB.T6G(SCH_1):PAGE391
 U6015  EP4 GND112 PT5161LRS-PT5161LRS,SMLF,IC,AJ051610U03    I19 @T6G_MB_LIB.T6G(SCH_1):PAGE391
 U6015  ER2 GND113 PT5161LRS-PT5161LRS,SMLF,IC,AJ051610U03    I19 @T6G_MB_LIB.T6G(SCH_1):PAGE391
 U6015 ER34 GND114 PT5161LRS-PT5161LRS,SMLF,IC,AJ051610U03    I19 @T6G_MB_LIB.T6G(SCH_1):PAGE391
 U6015  ET1 GND115 PT5161LRS-PT5161LRS,SMLF,IC,AJ051610U03    I19 @T6G_MB_LIB.T6G(SCH_1):PAGE391
 U6015 ET35 GND116 PT5161LRS-PT5161LRS,SMLF,IC,AJ051610U03    I19 @T6G_MB_LIB.T6G(SCH_1):PAGE391
 U6015 FA15 GND117 PT5161LRS-PT5161LRS,SMLF,IC,AJ051610U03    I19 @T6G_MB_LIB.T6G(SCH_1):PAGE391
 U6015 FA32 GND118 PT5161LRS-PT5161LRS,SMLF,IC,AJ051610U03    I19 @T6G_MB_LIB.T6G(SCH_1):PAGE391
 U6015  FB2 GND119 PT5161LRS-PT5161LRS,SMLF,IC,AJ051610U03    I19 @T6G_MB_LIB.T6G(SCH_1):PAGE391
 U6015 FB34 GND120 PT5161LRS-PT5161LRS,SMLF,IC,AJ051610U03    I19 @T6G_MB_LIB.T6G(SCH_1):PAGE391
 U6015 FC19 GND121 PT5161LRS-PT5161LRS,SMLF,IC,AJ051610U03    I19 @T6G_MB_LIB.T6G(SCH_1):PAGE391
 U6015 FC23 GND122 PT5161LRS-PT5161LRS,SMLF,IC,AJ051610U03    I19 @T6G_MB_LIB.T6G(SCH_1):PAGE391
 U6015 FC25 GND123 PT5161LRS-PT5161LRS,SMLF,IC,AJ051610U03    I19 @T6G_MB_LIB.T6G(SCH_1):PAGE391
 U6015 FC28 GND124 PT5161LRS-PT5161LRS,SMLF,IC,AJ051610U03    I19 @T6G_MB_LIB.T6G(SCH_1):PAGE391
 U6015  FC3 GND125 PT5161LRS-PT5161LRS,SMLF,IC,AJ051610U03    I19 @T6G_MB_LIB.T6G(SCH_1):PAGE391
 U6015  FC6 GND126 PT5161LRS-PT5161LRS,SMLF,IC,AJ051610U03    I19 @T6G_MB_LIB.T6G(SCH_1):PAGE391
 U6015  FC9 GND127 PT5161LRS-PT5161LRS,SMLF,IC,AJ051610U03    I19 @T6G_MB_LIB.T6G(SCH_1):PAGE391
 U6015  FD1 GND128 PT5161LRS-PT5161LRS,SMLF,IC,AJ051610U03    I19 @T6G_MB_LIB.T6G(SCH_1):PAGE391
 U6015 FD35 GND129 PT5161LRS-PT5161LRS,SMLF,IC,AJ051610U03    I19 @T6G_MB_LIB.T6G(SCH_1):PAGE391
 U6015 FF14 GND130 PT5161LRS-PT5161LRS,SMLF,IC,AJ051610U03    I19 @T6G_MB_LIB.T6G(SCH_1):PAGE391
 U6015 FF21 GND131 PT5161LRS-PT5161LRS,SMLF,IC,AJ051610U03    I19 @T6G_MB_LIB.T6G(SCH_1):PAGE391
 U6015 FJ12 GND132 PT5161LRS-PT5161LRS,SMLF,IC,AJ051610U03    I19 @T6G_MB_LIB.T6G(SCH_1):PAGE391
 U6015 FJ19 GND133 PT5161LRS-PT5161LRS,SMLF,IC,AJ051610U03    I19 @T6G_MB_LIB.T6G(SCH_1):PAGE391
 U6015  H12 GND134 PT5161LRS-PT5161LRS,SMLF,IC,AJ051610U03    I19 @T6G_MB_LIB.T6G(SCH_1):PAGE391
 U6015  H16 GND135 PT5161LRS-PT5161LRS,SMLF,IC,AJ051610U03    I19 @T6G_MB_LIB.T6G(SCH_1):PAGE391
 U6015  H19 GND136 PT5161LRS-PT5161LRS,SMLF,IC,AJ051610U03    I19 @T6G_MB_LIB.T6G(SCH_1):PAGE391
 U6015  H31 GND137 PT5161LRS-PT5161LRS,SMLF,IC,AJ051610U03    I19 @T6G_MB_LIB.T6G(SCH_1):PAGE391
 U6015  J22 GND138 PT5161LRS-PT5161LRS,SMLF,IC,AJ051610U03    I19 @T6G_MB_LIB.T6G(SCH_1):PAGE391
 U6015   J4 GND139 PT5161LRS-PT5161LRS,SMLF,IC,AJ051610U03    I19 @T6G_MB_LIB.T6G(SCH_1):PAGE391
 U6015   K2 GND140 PT5161LRS-PT5161LRS,SMLF,IC,AJ051610U03    I19 @T6G_MB_LIB.T6G(SCH_1):PAGE391
 U6015  K34 GND141 PT5161LRS-PT5161LRS,SMLF,IC,AJ051610U03    I19 @T6G_MB_LIB.T6G(SCH_1):PAGE391
 U6015   L1 GND142 PT5161LRS-PT5161LRS,SMLF,IC,AJ051610U03    I19 @T6G_MB_LIB.T6G(SCH_1):PAGE391
 U6015  L35 GND143 PT5161LRS-PT5161LRS,SMLF,IC,AJ051610U03    I19 @T6G_MB_LIB.T6G(SCH_1):PAGE391
 U6015  T13 GND144 PT5161LRS-PT5161LRS,SMLF,IC,AJ051610U03    I19 @T6G_MB_LIB.T6G(SCH_1):PAGE391
 U6015  T22 GND145 PT5161LRS-PT5161LRS,SMLF,IC,AJ051610U03    I19 @T6G_MB_LIB.T6G(SCH_1):PAGE391
 U6015  T32 GND146 PT5161LRS-PT5161LRS,SMLF,IC,AJ051610U03    I19 @T6G_MB_LIB.T6G(SCH_1):PAGE391
 U6015   T4 GND147 PT5161LRS-PT5161LRS,SMLF,IC,AJ051610U03    I19 @T6G_MB_LIB.T6G(SCH_1):PAGE391
 U6015   U2 GND148 PT5161LRS-PT5161LRS,SMLF,IC,AJ051610U03    I19 @T6G_MB_LIB.T6G(SCH_1):PAGE391
 U6015  U34 GND149 PT5161LRS-PT5161LRS,SMLF,IC,AJ051610U03    I19 @T6G_MB_LIB.T6G(SCH_1):PAGE391
 U6015   V1 GND150 PT5161LRS-PT5161LRS,SMLF,IC,AJ051610U03    I19 @T6G_MB_LIB.T6G(SCH_1):PAGE391
 U6015  V35 GND151 PT5161LRS-PT5161LRS,SMLF,IC,AJ051610U03    I19 @T6G_MB_LIB.T6G(SCH_1):PAGE391
  C203    2      B Q_CAP_0201-1UF,4V,20%,X6S,CH-10KMEE00     I8 @T6G_MB_LIB.T6G(SCH_1):PAGE443
  C206    2      B Q_CAP_C0201-0.1UF,10V,10%,X7S,CH4102K6E00     I9 @T6G_MB_LIB.T6G(SCH_1):PAGE443
  C103    2      B Q_CAP_C0805-100UF,4V,20%,X6S,CH710KMEA01    I13 @T6G_MB_LIB.T6G(SCH_1):PAGE443
  C111    2      B Q_CAP_C0402-22UF,4V,20%,X6S,CH622KMEB02    I14 @T6G_MB_LIB.T6G(SCH_1):PAGE443
  C102    2      B Q_CAP_C0805-100UF,4V,20%,X6S,CH710KMEA01    I16 @T6G_MB_LIB.T6G(SCH_1):PAGE443
  C199    2      B Q_CAP_C0402-10UF,6.3V,20%,X6S,CH6101MEB01    I17 @T6G_MB_LIB.T6G(SCH_1):PAGE443
  C195    2      B Q_CAP_0402-4.7UF,6.3V,20%,X6S,CH5471MEB01    I18 @T6G_MB_LIB.T6G(SCH_1):PAGE443
  C202    2      B Q_CAP_0201-1UF,4V,20%,X6S,CH-10KMEE00    I20 @T6G_MB_LIB.T6G(SCH_1):PAGE443
  C204    2      B Q_CAP_0201-1UF,4V,20%,X6S,CH-10KMEE00    I22 @T6G_MB_LIB.T6G(SCH_1):PAGE443
  C205    2      B Q_CAP_C0201-0.1UF,10V,10%,X7S,CH4102K6E00    I23 @T6G_MB_LIB.T6G(SCH_1):PAGE443
  C110    2      B Q_CAP_C0402-22UF,4V,20%,X6S,CH622KMEB02    I24 @T6G_MB_LIB.T6G(SCH_1):PAGE443
  C127    2      B Q_CAP_C0402-10UF,6.3V,20%,X6S,CH6101MEB01    I25 @T6G_MB_LIB.T6G(SCH_1):PAGE443
  C200    2      B Q_CAP_0402-4.7UF,6.3V,20%,X6S,CH5471MEB01    I26 @T6G_MB_LIB.T6G(SCH_1):PAGE443
  C217    2      B Q_CAP_C0201-0.1UF,10V,10%,X7S,CH4102K6E00    I27 @T6G_MB_LIB.T6G(SCH_1):PAGE443
  C287    2      B Q_CAP_C0201-0.1UF,10V,10%,X7S,CH4102K6E00    I28 @T6G_MB_LIB.T6G(SCH_1):PAGE443
  C288    2      B Q_CAP_C0201-0.1UF,10V,10%,X7S,CH4102K6E00    I29 @T6G_MB_LIB.T6G(SCH_1):PAGE443
  C313    2      B Q_CAP_C0201-0.1UF,10V,10%,X7S,CH4102K6E00    I34 @T6G_MB_LIB.T6G(SCH_1):PAGE443
  C316    2      B Q_CAP_C0201-0.1UF,10V,10%,X7S,CH4102K6E00    I37 @T6G_MB_LIB.T6G(SCH_1):PAGE443
  C340    2      B Q_CAP_C0201-0.1UF,10V,10%,X7S,CH4102K6E00    I38 @T6G_MB_LIB.T6G(SCH_1):PAGE443
  C344    2      B Q_CAP_C0201-0.1UF,10V,10%,X7S,CH4102K6E00    I39 @T6G_MB_LIB.T6G(SCH_1):PAGE443
  C294    2      B Q_CAP_0201-1UF,4V,20%,X6S,CH-10KMEE00    I40 @T6G_MB_LIB.T6G(SCH_1):PAGE443
  C332    2      B Q_CAP_C0402-10UF,6.3V,20%,X6S,CH6101MEB01    I41 @T6G_MB_LIB.T6G(SCH_1):PAGE443
  C307    2      B Q_CAP_0201-1UF,4V,20%,X6S,CH-10KMEE00    I42 @T6G_MB_LIB.T6G(SCH_1):PAGE443
  C326    2      B Q_CAP_0201-1UF,4V,20%,X6S,CH-10KMEE00    I43 @T6G_MB_LIB.T6G(SCH_1):PAGE443
  C321    2      B Q_CAP_C0402-10UF,6.3V,20%,X6S,CH6101MEB01    I44 @T6G_MB_LIB.T6G(SCH_1):PAGE443
  C325    2      B Q_CAP_0402-4.7UF,6.3V,20%,X6S,CH5471MEB01    I45 @T6G_MB_LIB.T6G(SCH_1):PAGE443
  C331    2      B Q_CAP_0402-4.7UF,6.3V,20%,X6S,CH5471MEB01    I46 @T6G_MB_LIB.T6G(SCH_1):PAGE443
  C330    2      B Q_CAP_0201-1UF,4V,20%,X6S,CH-10KMEE00    I47 @T6G_MB_LIB.T6G(SCH_1):PAGE443
  C312    2      B Q_CAP_C0201-0.1UF,10V,10%,X7S,CH4102K6E00    I48 @T6G_MB_LIB.T6G(SCH_1):PAGE443
  C349    2      B Q_CAP_C0201-0.1UF,10V,10%,X7S,CH4102K6E00    I49 @T6G_MB_LIB.T6G(SCH_1):PAGE443
  C291    2      B Q_CAP_C0201-0.1UF,10V,10%,X7S,CH4102K6E00    I50 @T6G_MB_LIB.T6G(SCH_1):PAGE443
  C319    2      B Q_CAP_C0201-0.1UF,10V,10%,X7S,CH4102K6E00    I51 @T6G_MB_LIB.T6G(SCH_1):PAGE443
  C314    2      B Q_CAP_0201-1UF,4V,20%,X6S,CH-10KMEE00    I52 @T6G_MB_LIB.T6G(SCH_1):PAGE443
  C337    2      B Q_CAP_0201-1UF,4V,20%,X6S,CH-10KMEE00    I53 @T6G_MB_LIB.T6G(SCH_1):PAGE443
  C343    2      B Q_CAP_0402-4.7UF,6.3V,20%,X6S,CH5471MEB01    I54 @T6G_MB_LIB.T6G(SCH_1):PAGE443
  C336    2      B Q_CAP_0402-4.7UF,6.3V,20%,X6S,CH5471MEB01    I55 @T6G_MB_LIB.T6G(SCH_1):PAGE443
  C346    2      B Q_CAP_0201-1UF,4V,20%,X6S,CH-10KMEE00    I57 @T6G_MB_LIB.T6G(SCH_1):PAGE443
  C293    2      B Q_CAP_0201-1UF,4V,20%,X6S,CH-10KMEE00    I58 @T6G_MB_LIB.T6G(SCH_1):PAGE443
  C301    2      B Q_CAP_0201-1UF,4V,20%,X6S,CH-10KMEE00    I59 @T6G_MB_LIB.T6G(SCH_1):PAGE443
  C322    2      B Q_CAP_C0201-0.1UF,10V,10%,X7S,CH4102K6E00    I60 @T6G_MB_LIB.T6G(SCH_1):PAGE443
  C334    2      B Q_CAP_C0201-0.1UF,10V,10%,X7S,CH4102K6E00    I62 @T6G_MB_LIB.T6G(SCH_1):PAGE443
  C289    2      B Q_CAP_0201-1UF,4V,20%,X6S,CH-10KMEE00    I65 @T6G_MB_LIB.T6G(SCH_1):PAGE443
  C353    2      B Q_CAP_0201-1UF,4V,20%,X6S,CH-10KMEE00    I66 @T6G_MB_LIB.T6G(SCH_1):PAGE443
  C317    2      B Q_CAP_C0805-100UF,4V,20%,X6S,CH710KMEA01    I67 @T6G_MB_LIB.T6G(SCH_1):PAGE443
  C320    2      B Q_CAP_C0805-100UF,4V,20%,X6S,CH710KMEA01    I69 @T6G_MB_LIB.T6G(SCH_1):PAGE443
  C324    2      B Q_CAP_C0805-100UF,4V,20%,X6S,CH710KMEA01    I70 @T6G_MB_LIB.T6G(SCH_1):PAGE443
  C328    2      B Q_CAP_C0805-100UF,4V,20%,X6S,CH710KMEA01    I71 @T6G_MB_LIB.T6G(SCH_1):PAGE443
  C323    2      B Q_CAP_C0805-100UF,4V,20%,X6S,CH710KMEA01    I72 @T6G_MB_LIB.T6G(SCH_1):PAGE443
  C327    2      B Q_CAP_C0402-22UF,4V,20%,X6S,CH622KMEB02    I73 @T6G_MB_LIB.T6G(SCH_1):PAGE443
  C329    2      B Q_CAP_C0402-22UF,4V,20%,X6S,CH622KMEB02    I74 @T6G_MB_LIB.T6G(SCH_1):PAGE443
  C335    2      B Q_CAP_C0402-22UF,4V,20%,X6S,CH622KMEB02    I75 @T6G_MB_LIB.T6G(SCH_1):PAGE443
  C351    2      B Q_CAP_C0402-22UF,4V,20%,X6S,CH622KMEB02    I76 @T6G_MB_LIB.T6G(SCH_1):PAGE443
  C318    2      B Q_CAP_C0402-22UF,4V,20%,X6S,CH622KMEB02    I77 @T6G_MB_LIB.T6G(SCH_1):PAGE443
  C338    2      B Q_CAP_0402-4.7UF,6.3V,20%,X6S,CH5471MEB01    I78 @T6G_MB_LIB.T6G(SCH_1):PAGE443
  C342    2      B Q_CAP_0201-1UF,4V,20%,X6S,CH-10KMEE00    I79 @T6G_MB_LIB.T6G(SCH_1):PAGE443
  C339    2      B Q_CAP_C0402-10UF,6.3V,20%,X6S,CH6101MEB01    I80 @T6G_MB_LIB.T6G(SCH_1):PAGE443
  C354    2      B Q_CAP_C0402-10UF,6.3V,20%,X6S,CH6101MEB01    I81 @T6G_MB_LIB.T6G(SCH_1):PAGE443
  C300    2      B Q_CAP_C0201-0.1UF,10V,10%,X7S,CH4102K6E00    I82 @T6G_MB_LIB.T6G(SCH_1):PAGE443
  C311    2      B Q_CAP_C0201-0.1UF,10V,10%,X7S,CH4102K6E00    I84 @T6G_MB_LIB.T6G(SCH_1):PAGE443
  C292    2      B Q_CAP_C0201-0.1UF,10V,10%,X7S,CH4102K6E00    I85 @T6G_MB_LIB.T6G(SCH_1):PAGE443
  C290    2      B Q_CAP_C0201-0.1UF,10V,10%,X7S,CH4102K6E00    I86 @T6G_MB_LIB.T6G(SCH_1):PAGE443
  C333    2      B Q_CAP_C0402-10UF,6.3V,20%,X6S,CH6101MEB01    I87 @T6G_MB_LIB.T6G(SCH_1):PAGE443
  R782    2      B Q_RES_0201LF-10K,1%,1/20W,CHIP,CS31001FE17    I21 @T6G_MB_LIB.T6G(SCH_1):PAGE392
  R783    2      B Q_RES_0201LF-10K,1%,1/20W,CHIP,CS31001FE17    I22 @T6G_MB_LIB.T6G(SCH_1):PAGE392
  R785    2      B Q_RES_0201LF-4.7K,5%,1/20W,CHIP,CS24701JE04    I23 @T6G_MB_LIB.T6G(SCH_1):PAGE392
  R625    2      B Q_RES_0201LF-51.1,1%,1/20W,EMPTY,CS05111FE00    I31 @T6G_MB_LIB.T6G(SCH_1):PAGE392
  R626    2      B Q_RES_0201LF-51.1,1%,1/20W,EMPTY,CS05111FE00    I32 @T6G_MB_LIB.T6G(SCH_1):PAGE392
 U6015  E30 T_SENSE PT5161LRS-PT5161LRS,SMLF,IC,AJ051610U03    I47 @T6G_MB_LIB.T6G(SCH_1):PAGE392
  R787    2      B Q_RES_0201LF-4.7K,5%,1/20W,CHIP,CS24701JE04    I51 @T6G_MB_LIB.T6G(SCH_1):PAGE392
  R791    2      B Q_RES_0201LF-4.7K,5%,1/20W,CHIP,CS24701JE04    I52 @T6G_MB_LIB.T6G(SCH_1):PAGE392
  R792    2      B Q_RES_0201LF-4.7K,5%,1/20W,CHIP,CS24701JE04    I54 @T6G_MB_LIB.T6G(SCH_1):PAGE392
  R794    2      B Q_RES_0201LF-4.7K,5%,1/20W,EMPTY,CS24701JE04    I65 @T6G_MB_LIB.T6G(SCH_1):PAGE392
  R752    2      B Q_RES_0201LF-10K,1%,1/20W,CHIP,CS31001FE17    I92 @T6G_MB_LIB.T6G(SCH_1):PAGE392
  R749    2      B Q_RES_0201LF-10K,1%,1/20W,CHIP,CS31001FE17    I93 @T6G_MB_LIB.T6G(SCH_1):PAGE392
 R6744    2      B Q_RES_0402LF-1K,1%,1/16W,CHIP,CS21002FB06     I2 @T6G_MB_LIB.T6G(SCH_1):PAGE467
 R6745    2      B Q_RES_0402LF-1K,1%,1/16W,CHIP,CS21002FB06     I4 @T6G_MB_LIB.T6G(SCH_1):PAGE467
 C7500    2      B Q_CAP_C0201-0.1UF,10V,10%,X7S,CH4102K6E00    I88 @T6G_MB_LIB.T6G(SCH_1):PAGE378
 R6773    2      B Q_RES_0201LF-4.7K,5%,1/20W,CHIP,CS24701JE04    I94 @T6G_MB_LIB.T6G(SCH_1):PAGE378
 R6774    2      B Q_RES_0201LF-4.7K,5%,1/20W,CHIP,CS24701JE04    I95 @T6G_MB_LIB.T6G(SCH_1):PAGE378
 R6775    2      B Q_RES_0201LF-4.7K,5%,1/20W,CHIP,CS24701JE04    I97 @T6G_MB_LIB.T6G(SCH_1):PAGE378
 R6778    2      B Q_RES_0201LF-10K,1%,1/20W,CHIP,CS31001FE17   I107 @T6G_MB_LIB.T6G(SCH_1):PAGE378
  R845    2      B Q_RES_0201LF-4.7K,5%,1/20W,CHIP,CS24701JE04     I2 @T6G_MB_LIB.T6G(SCH_1):PAGE377
  R846    2      B Q_RES_0201LF-4.7K,5%,1/20W,CHIP,CS24701JE04     I3 @T6G_MB_LIB.T6G(SCH_1):PAGE377
  R847    2      B Q_RES_0201LF-4.7K,5%,1/20W,CHIP,CS24701JE04     I8 @T6G_MB_LIB.T6G(SCH_1):PAGE377
  R849    2      B Q_RES_0201LF-10K,1%,1/20W,CHIP,CS31001FE17    I16 @T6G_MB_LIB.T6G(SCH_1):PAGE377
  C365    2      B Q_CAP_C0201-0.1UF,10V,10%,X7S,CH4102K6E00    I55 @T6G_MB_LIB.T6G(SCH_1):PAGE377
   U22   12    GND TCA9548APWR-TCA9548APWR,SMLF,IC,AL009548K02    I94 @T6G_MB_LIB.T6G(SCH_1):PAGE377
 R6786    2      B Q_RES_0402LF-1K,1%,1/16W,CHIP,CS21002FB06   I208 @T6G_MB_LIB.T6G(SCH_1):PAGE475
 R6787    2      B Q_RES_0402LF-1K,1%,1/16W,CHIP,CS21002FB06    I90 @T6G_MB_LIB.T6G(SCH_1):PAGE477
 R6713    2      B Q_RES_0201LF-1K,1%,1/20W,EMPTY,CS21001FE07   I103 @T6G_MB_LIB.T6G(SCH_1):PAGE401
 R6715    2      B Q_RES_0201LF-20K,1%,1/20W,CHIP,CS32001FE00   I105 @T6G_MB_LIB.T6G(SCH_1):PAGE401
 R6717    2      B Q_RES_0201LF-1K,1%,1/20W,CHIP,CS21001FE07   I106 @T6G_MB_LIB.T6G(SCH_1):PAGE401
  R741    2      B Q_RES_0201LF-1K,1%,1/20W,EMPTY,CS21001FE07   I101 @T6G_MB_LIB.T6G(SCH_1):PAGE392
  R746    2      B Q_RES_0201LF-20K,1%,1/20W,CHIP,CS32001FE00   I102 @T6G_MB_LIB.T6G(SCH_1):PAGE392
  R796    2      B Q_RES_0201LF-1K,1%,1/20W,CHIP,CS21001FE07   I105 @T6G_MB_LIB.T6G(SCH_1):PAGE392
 C7501    2      B Q_CAP_C0201-0.1UF,10V,10%,X7S,CH4102K6E00    I11 @T6G_MB_LIB.T6G(SCH_1):PAGE399
 R6788    2      B Q_RES_0201LF-1K,1%,1/20W,CHIP,CS21001FE07    I13 @T6G_MB_LIB.T6G(SCH_1):PAGE399
 R6789    2      B Q_RES_0201LF-1K,1%,1/20W,CHIP,CS21001FE07    I19 @T6G_MB_LIB.T6G(SCH_1):PAGE442
 C7502    2      B Q_CAP_C0201-0.1UF,10V,10%,X7S,CH4102K6E00    I22 @T6G_MB_LIB.T6G(SCH_1):PAGE442
 R6790    2      B Q_RES_0201LF-1K,1%,1/20W,CHIP,CS21001FE07    I19 @T6G_MB_LIB.T6G(SCH_1):PAGE453
 C7503    2      B Q_CAP_C0201-0.1UF,10V,10%,X7S,CH4102K6E00    I23 @T6G_MB_LIB.T6G(SCH_1):PAGE453
 C7504    2      B Q_CAP_C0201-0.1UF,10V,10%,X7S,CH4102K6E00    I19 @T6G_MB_LIB.T6G(SCH_1):PAGE464
 R6791    2      B Q_RES_0201LF-1K,1%,1/20W,CHIP,CS21001FE07    I22 @T6G_MB_LIB.T6G(SCH_1):PAGE464
  R875    2      B Q_RES_0201LF-10K,1%,1/20W,CHIP,CS31001FE17    I19 @T6G_MB_LIB.T6G(SCH_1):PAGE451
  R876    2      B Q_RES_0201LF-10K,1%,1/20W,CHIP,CS31001FE17    I20 @T6G_MB_LIB.T6G(SCH_1):PAGE451
  R640    2      B Q_RES_0201LF-51.1,1%,1/20W,EMPTY,CS05111FE00    I36 @T6G_MB_LIB.T6G(SCH_1):PAGE451
  R879    2      B Q_RES_0201LF-4.7K,5%,1/20W,CHIP,CS24701JE04    I42 @T6G_MB_LIB.T6G(SCH_1):PAGE451
  R881    2      B Q_RES_0201LF-4.7K,5%,1/20W,CHIP,CS24701JE04    I43 @T6G_MB_LIB.T6G(SCH_1):PAGE451
  R883    2      B Q_RES_0201LF-4.7K,5%,1/20W,CHIP,CS24701JE04    I45 @T6G_MB_LIB.T6G(SCH_1):PAGE451
  R884    2      B Q_RES_0201LF-4.7K,5%,1/20W,CHIP,CS24701JE04    I46 @T6G_MB_LIB.T6G(SCH_1):PAGE451
  R886    2      B Q_RES_0201LF-4.7K,5%,1/20W,EMPTY,CS24701JE04    I58 @T6G_MB_LIB.T6G(SCH_1):PAGE451
  R863    2      B Q_RES_0201LF-1K,1%,1/20W,EMPTY,CS21001FE07    I71 @T6G_MB_LIB.T6G(SCH_1):PAGE451
  R865    2      B Q_RES_0201LF-20K,1%,1/20W,CHIP,CS32001FE00    I72 @T6G_MB_LIB.T6G(SCH_1):PAGE451
  R892    2      B Q_RES_0201LF-1K,1%,1/20W,CHIP,CS21001FE07    I76 @T6G_MB_LIB.T6G(SCH_1):PAGE451
  R867    2      B Q_RES_0201LF-10K,1%,1/20W,CHIP,CS31001FE17    I80 @T6G_MB_LIB.T6G(SCH_1):PAGE451
  R866    2      B Q_RES_0201LF-10K,1%,1/20W,CHIP,CS31001FE17    I82 @T6G_MB_LIB.T6G(SCH_1):PAGE451
  R637    2      B Q_RES_0201LF-51.1,1%,1/20W,EMPTY,CS05111FE00    I92 @T6G_MB_LIB.T6G(SCH_1):PAGE451
 U6016  E30 T_SENSE PT5161LRS-PT5161LRS,SMLF,IC,AJ051610U03    I97 @T6G_MB_LIB.T6G(SCH_1):PAGE451
 R6797    2      B Q_RES_0201LF-0,5%,1/20W,CHIP,CS00001JE10    I15 @T6G_MB_LIB.T6G(SCH_1):PAGE452
 R6796    2      B Q_RES_0201LF-0,5%,1/20W,CHIP,CS00001JE10    I18 @T6G_MB_LIB.T6G(SCH_1):PAGE452
 U6016 AC13   GND1 PT5161LRS-PT5161LRS,SMLF,IC,AJ051610U03    I19 @T6G_MB_LIB.T6G(SCH_1):PAGE452
 U6016 AC22   GND2 PT5161LRS-PT5161LRS,SMLF,IC,AJ051610U03    I19 @T6G_MB_LIB.T6G(SCH_1):PAGE452
 U6016 AC32   GND3 PT5161LRS-PT5161LRS,SMLF,IC,AJ051610U03    I19 @T6G_MB_LIB.T6G(SCH_1):PAGE452
 U6016  AC4   GND4 PT5161LRS-PT5161LRS,SMLF,IC,AJ051610U03    I19 @T6G_MB_LIB.T6G(SCH_1):PAGE452
 U6016  AD2   GND5 PT5161LRS-PT5161LRS,SMLF,IC,AJ051610U03    I19 @T6G_MB_LIB.T6G(SCH_1):PAGE452
 U6016 AD34   GND6 PT5161LRS-PT5161LRS,SMLF,IC,AJ051610U03    I19 @T6G_MB_LIB.T6G(SCH_1):PAGE452
 U6016  AE1   GND7 PT5161LRS-PT5161LRS,SMLF,IC,AJ051610U03    I19 @T6G_MB_LIB.T6G(SCH_1):PAGE452
 U6016 AE35   GND8 PT5161LRS-PT5161LRS,SMLF,IC,AJ051610U03    I19 @T6G_MB_LIB.T6G(SCH_1):PAGE452
 U6016 AK13   GND9 PT5161LRS-PT5161LRS,SMLF,IC,AJ051610U03    I19 @T6G_MB_LIB.T6G(SCH_1):PAGE452
 U6016 AK22  GND10 PT5161LRS-PT5161LRS,SMLF,IC,AJ051610U03    I19 @T6G_MB_LIB.T6G(SCH_1):PAGE452
 U6016 AK32  GND11 PT5161LRS-PT5161LRS,SMLF,IC,AJ051610U03    I19 @T6G_MB_LIB.T6G(SCH_1):PAGE452
 U6016  AK4  GND12 PT5161LRS-PT5161LRS,SMLF,IC,AJ051610U03    I19 @T6G_MB_LIB.T6G(SCH_1):PAGE452
 U6016  AL2  GND13 PT5161LRS-PT5161LRS,SMLF,IC,AJ051610U03    I19 @T6G_MB_LIB.T6G(SCH_1):PAGE452
 U6016 AL34  GND14 PT5161LRS-PT5161LRS,SMLF,IC,AJ051610U03    I19 @T6G_MB_LIB.T6G(SCH_1):PAGE452
 U6016  AM1  GND15 PT5161LRS-PT5161LRS,SMLF,IC,AJ051610U03    I19 @T6G_MB_LIB.T6G(SCH_1):PAGE452
 U6016 AM35  GND16 PT5161LRS-PT5161LRS,SMLF,IC,AJ051610U03    I19 @T6G_MB_LIB.T6G(SCH_1):PAGE452
 U6016 AU13  GND17 PT5161LRS-PT5161LRS,SMLF,IC,AJ051610U03    I19 @T6G_MB_LIB.T6G(SCH_1):PAGE452
 U6016 AU22  GND18 PT5161LRS-PT5161LRS,SMLF,IC,AJ051610U03    I19 @T6G_MB_LIB.T6G(SCH_1):PAGE452
 U6016 AU32  GND19 PT5161LRS-PT5161LRS,SMLF,IC,AJ051610U03    I19 @T6G_MB_LIB.T6G(SCH_1):PAGE452
 U6016  AU4  GND20 PT5161LRS-PT5161LRS,SMLF,IC,AJ051610U03    I19 @T6G_MB_LIB.T6G(SCH_1):PAGE452
 U6016  AV2  GND21 PT5161LRS-PT5161LRS,SMLF,IC,AJ051610U03    I19 @T6G_MB_LIB.T6G(SCH_1):PAGE452
 U6016 AV34  GND22 PT5161LRS-PT5161LRS,SMLF,IC,AJ051610U03    I19 @T6G_MB_LIB.T6G(SCH_1):PAGE452
 U6016  AW1  GND23 PT5161LRS-PT5161LRS,SMLF,IC,AJ051610U03    I19 @T6G_MB_LIB.T6G(SCH_1):PAGE452
 U6016 AW35  GND24 PT5161LRS-PT5161LRS,SMLF,IC,AJ051610U03    I19 @T6G_MB_LIB.T6G(SCH_1):PAGE452
 U6016  B19  GND25 PT5161LRS-PT5161LRS,SMLF,IC,AJ051610U03    I19 @T6G_MB_LIB.T6G(SCH_1):PAGE452
 U6016 BD13  GND26 PT5161LRS-PT5161LRS,SMLF,IC,AJ051610U03    I19 @T6G_MB_LIB.T6G(SCH_1):PAGE452
 U6016 BD22  GND27 PT5161LRS-PT5161LRS,SMLF,IC,AJ051610U03    I19 @T6G_MB_LIB.T6G(SCH_1):PAGE452
 U6016 BD32  GND28 PT5161LRS-PT5161LRS,SMLF,IC,AJ051610U03    I19 @T6G_MB_LIB.T6G(SCH_1):PAGE452
 U6016  BD4  GND29 PT5161LRS-PT5161LRS,SMLF,IC,AJ051610U03    I19 @T6G_MB_LIB.T6G(SCH_1):PAGE452
 U6016  BE2  GND30 PT5161LRS-PT5161LRS,SMLF,IC,AJ051610U03    I19 @T6G_MB_LIB.T6G(SCH_1):PAGE452
 U6016 BE34  GND31 PT5161LRS-PT5161LRS,SMLF,IC,AJ051610U03    I19 @T6G_MB_LIB.T6G(SCH_1):PAGE452
 U6016  BF1  GND32 PT5161LRS-PT5161LRS,SMLF,IC,AJ051610U03    I19 @T6G_MB_LIB.T6G(SCH_1):PAGE452
 U6016 BF35  GND33 PT5161LRS-PT5161LRS,SMLF,IC,AJ051610U03    I19 @T6G_MB_LIB.T6G(SCH_1):PAGE452
 U6016 BL13  GND34 PT5161LRS-PT5161LRS,SMLF,IC,AJ051610U03    I19 @T6G_MB_LIB.T6G(SCH_1):PAGE452
 U6016 BL22  GND35 PT5161LRS-PT5161LRS,SMLF,IC,AJ051610U03    I19 @T6G_MB_LIB.T6G(SCH_1):PAGE452
 U6016 BL32  GND36 PT5161LRS-PT5161LRS,SMLF,IC,AJ051610U03    I19 @T6G_MB_LIB.T6G(SCH_1):PAGE452
 U6016  BL4  GND37 PT5161LRS-PT5161LRS,SMLF,IC,AJ051610U03    I19 @T6G_MB_LIB.T6G(SCH_1):PAGE452
 U6016  BM2  GND38 PT5161LRS-PT5161LRS,SMLF,IC,AJ051610U03    I19 @T6G_MB_LIB.T6G(SCH_1):PAGE452
 U6016 BM34  GND39 PT5161LRS-PT5161LRS,SMLF,IC,AJ051610U03    I19 @T6G_MB_LIB.T6G(SCH_1):PAGE452
 U6016  BN1  GND40 PT5161LRS-PT5161LRS,SMLF,IC,AJ051610U03    I19 @T6G_MB_LIB.T6G(SCH_1):PAGE452
 U6016 BN35  GND41 PT5161LRS-PT5161LRS,SMLF,IC,AJ051610U03    I19 @T6G_MB_LIB.T6G(SCH_1):PAGE452
 U6016 BV13  GND42 PT5161LRS-PT5161LRS,SMLF,IC,AJ051610U03    I19 @T6G_MB_LIB.T6G(SCH_1):PAGE452
 U6016 BV22  GND43 PT5161LRS-PT5161LRS,SMLF,IC,AJ051610U03    I19 @T6G_MB_LIB.T6G(SCH_1):PAGE452
 U6016 BV32  GND44 PT5161LRS-PT5161LRS,SMLF,IC,AJ051610U03    I19 @T6G_MB_LIB.T6G(SCH_1):PAGE452
 U6016  BV4  GND45 PT5161LRS-PT5161LRS,SMLF,IC,AJ051610U03    I19 @T6G_MB_LIB.T6G(SCH_1):PAGE452
 U6016  BW2  GND46 PT5161LRS-PT5161LRS,SMLF,IC,AJ051610U03    I19 @T6G_MB_LIB.T6G(SCH_1):PAGE452
 U6016 BW34  GND47 PT5161LRS-PT5161LRS,SMLF,IC,AJ051610U03    I19 @T6G_MB_LIB.T6G(SCH_1):PAGE452
 U6016  BY1  GND48 PT5161LRS-PT5161LRS,SMLF,IC,AJ051610U03    I19 @T6G_MB_LIB.T6G(SCH_1):PAGE452
 U6016 BY35  GND49 PT5161LRS-PT5161LRS,SMLF,IC,AJ051610U03    I19 @T6G_MB_LIB.T6G(SCH_1):PAGE452
 U6016 CE13  GND50 PT5161LRS-PT5161LRS,SMLF,IC,AJ051610U03    I19 @T6G_MB_LIB.T6G(SCH_1):PAGE452
 U6016 CE22  GND51 PT5161LRS-PT5161LRS,SMLF,IC,AJ051610U03    I19 @T6G_MB_LIB.T6G(SCH_1):PAGE452
 U6016 CE32  GND52 PT5161LRS-PT5161LRS,SMLF,IC,AJ051610U03    I19 @T6G_MB_LIB.T6G(SCH_1):PAGE452
 U6016  CE4  GND53 PT5161LRS-PT5161LRS,SMLF,IC,AJ051610U03    I19 @T6G_MB_LIB.T6G(SCH_1):PAGE452
 U6016  CF2  GND54 PT5161LRS-PT5161LRS,SMLF,IC,AJ051610U03    I19 @T6G_MB_LIB.T6G(SCH_1):PAGE452
 U6016 CF34  GND55 PT5161LRS-PT5161LRS,SMLF,IC,AJ051610U03    I19 @T6G_MB_LIB.T6G(SCH_1):PAGE452
 U6016  CG1  GND56 PT5161LRS-PT5161LRS,SMLF,IC,AJ051610U03    I19 @T6G_MB_LIB.T6G(SCH_1):PAGE452
 U6016 CG35  GND57 PT5161LRS-PT5161LRS,SMLF,IC,AJ051610U03    I19 @T6G_MB_LIB.T6G(SCH_1):PAGE452
 U6016 CM13  GND58 PT5161LRS-PT5161LRS,SMLF,IC,AJ051610U03    I19 @T6G_MB_LIB.T6G(SCH_1):PAGE452
 U6016 CM22  GND59 PT5161LRS-PT5161LRS,SMLF,IC,AJ051610U03    I19 @T6G_MB_LIB.T6G(SCH_1):PAGE452
 U6016 CM32  GND60 PT5161LRS-PT5161LRS,SMLF,IC,AJ051610U03    I19 @T6G_MB_LIB.T6G(SCH_1):PAGE452
 U6016  CM4  GND61 PT5161LRS-PT5161LRS,SMLF,IC,AJ051610U03    I19 @T6G_MB_LIB.T6G(SCH_1):PAGE452
 U6016  CN2  GND62 PT5161LRS-PT5161LRS,SMLF,IC,AJ051610U03    I19 @T6G_MB_LIB.T6G(SCH_1):PAGE452
 U6016 CN34  GND63 PT5161LRS-PT5161LRS,SMLF,IC,AJ051610U03    I19 @T6G_MB_LIB.T6G(SCH_1):PAGE452
 U6016  CP1  GND64 PT5161LRS-PT5161LRS,SMLF,IC,AJ051610U03    I19 @T6G_MB_LIB.T6G(SCH_1):PAGE452
 U6016 CP35  GND65 PT5161LRS-PT5161LRS,SMLF,IC,AJ051610U03    I19 @T6G_MB_LIB.T6G(SCH_1):PAGE452
 U6016 CW13  GND66 PT5161LRS-PT5161LRS,SMLF,IC,AJ051610U03    I19 @T6G_MB_LIB.T6G(SCH_1):PAGE452
 U6016 CW22  GND67 PT5161LRS-PT5161LRS,SMLF,IC,AJ051610U03    I19 @T6G_MB_LIB.T6G(SCH_1):PAGE452
 U6016 CW32  GND68 PT5161LRS-PT5161LRS,SMLF,IC,AJ051610U03    I19 @T6G_MB_LIB.T6G(SCH_1):PAGE452
 U6016  CW4  GND69 PT5161LRS-PT5161LRS,SMLF,IC,AJ051610U03    I19 @T6G_MB_LIB.T6G(SCH_1):PAGE452
 U6016  CY2  GND70 PT5161LRS-PT5161LRS,SMLF,IC,AJ051610U03    I19 @T6G_MB_LIB.T6G(SCH_1):PAGE452
 U6016 CY34  GND71 PT5161LRS-PT5161LRS,SMLF,IC,AJ051610U03    I19 @T6G_MB_LIB.T6G(SCH_1):PAGE452
 U6016  DA1  GND72 PT5161LRS-PT5161LRS,SMLF,IC,AJ051610U03    I19 @T6G_MB_LIB.T6G(SCH_1):PAGE452
 U6016 DA35  GND73 PT5161LRS-PT5161LRS,SMLF,IC,AJ051610U03    I19 @T6G_MB_LIB.T6G(SCH_1):PAGE452
 U6016 DF13  GND74 PT5161LRS-PT5161LRS,SMLF,IC,AJ051610U03    I19 @T6G_MB_LIB.T6G(SCH_1):PAGE452
 U6016 DF22  GND75 PT5161LRS-PT5161LRS,SMLF,IC,AJ051610U03    I19 @T6G_MB_LIB.T6G(SCH_1):PAGE452
 U6016 DF32  GND76 PT5161LRS-PT5161LRS,SMLF,IC,AJ051610U03    I19 @T6G_MB_LIB.T6G(SCH_1):PAGE452
 U6016  DF4  GND77 PT5161LRS-PT5161LRS,SMLF,IC,AJ051610U03    I19 @T6G_MB_LIB.T6G(SCH_1):PAGE452
 U6016  DG2  GND78 PT5161LRS-PT5161LRS,SMLF,IC,AJ051610U03    I19 @T6G_MB_LIB.T6G(SCH_1):PAGE452
 U6016 DG34  GND79 PT5161LRS-PT5161LRS,SMLF,IC,AJ051610U03    I19 @T6G_MB_LIB.T6G(SCH_1):PAGE452
 U6016  DH1  GND80 PT5161LRS-PT5161LRS,SMLF,IC,AJ051610U03    I19 @T6G_MB_LIB.T6G(SCH_1):PAGE452
 U6016 DH35  GND81 PT5161LRS-PT5161LRS,SMLF,IC,AJ051610U03    I19 @T6G_MB_LIB.T6G(SCH_1):PAGE452
 U6016 DN13  GND82 PT5161LRS-PT5161LRS,SMLF,IC,AJ051610U03    I19 @T6G_MB_LIB.T6G(SCH_1):PAGE452
 U6016 DN22  GND83 PT5161LRS-PT5161LRS,SMLF,IC,AJ051610U03    I19 @T6G_MB_LIB.T6G(SCH_1):PAGE452
 U6016 DN32  GND84 PT5161LRS-PT5161LRS,SMLF,IC,AJ051610U03    I19 @T6G_MB_LIB.T6G(SCH_1):PAGE452
 U6016  DN4  GND85 PT5161LRS-PT5161LRS,SMLF,IC,AJ051610U03    I19 @T6G_MB_LIB.T6G(SCH_1):PAGE452
 U6016  DP2  GND86 PT5161LRS-PT5161LRS,SMLF,IC,AJ051610U03    I19 @T6G_MB_LIB.T6G(SCH_1):PAGE452
 U6016 DP34  GND87 PT5161LRS-PT5161LRS,SMLF,IC,AJ051610U03    I19 @T6G_MB_LIB.T6G(SCH_1):PAGE452
 U6016  DR1  GND88 PT5161LRS-PT5161LRS,SMLF,IC,AJ051610U03    I19 @T6G_MB_LIB.T6G(SCH_1):PAGE452
 U6016 DR35  GND89 PT5161LRS-PT5161LRS,SMLF,IC,AJ051610U03    I19 @T6G_MB_LIB.T6G(SCH_1):PAGE452
 U6016 DY13  GND90 PT5161LRS-PT5161LRS,SMLF,IC,AJ051610U03    I19 @T6G_MB_LIB.T6G(SCH_1):PAGE452
 U6016 DY22  GND91 PT5161LRS-PT5161LRS,SMLF,IC,AJ051610U03    I19 @T6G_MB_LIB.T6G(SCH_1):PAGE452
 U6016 DY32  GND92 PT5161LRS-PT5161LRS,SMLF,IC,AJ051610U03    I19 @T6G_MB_LIB.T6G(SCH_1):PAGE452
 U6016  DY4  GND93 PT5161LRS-PT5161LRS,SMLF,IC,AJ051610U03    I19 @T6G_MB_LIB.T6G(SCH_1):PAGE452
 U6016  E14  GND94 PT5161LRS-PT5161LRS,SMLF,IC,AJ051610U03    I19 @T6G_MB_LIB.T6G(SCH_1):PAGE452
 U6016  E27  GND95 PT5161LRS-PT5161LRS,SMLF,IC,AJ051610U03    I19 @T6G_MB_LIB.T6G(SCH_1):PAGE452
 U6016  E33  GND96 PT5161LRS-PT5161LRS,SMLF,IC,AJ051610U03    I19 @T6G_MB_LIB.T6G(SCH_1):PAGE452
 U6016  EA2  GND97 PT5161LRS-PT5161LRS,SMLF,IC,AJ051610U03    I19 @T6G_MB_LIB.T6G(SCH_1):PAGE452
 U6016 EA34  GND98 PT5161LRS-PT5161LRS,SMLF,IC,AJ051610U03    I19 @T6G_MB_LIB.T6G(SCH_1):PAGE452
 U6016  EB1  GND99 PT5161LRS-PT5161LRS,SMLF,IC,AJ051610U03    I19 @T6G_MB_LIB.T6G(SCH_1):PAGE452
 U6016 EB35 GND100 PT5161LRS-PT5161LRS,SMLF,IC,AJ051610U03    I19 @T6G_MB_LIB.T6G(SCH_1):PAGE452
 U6016 EG13 GND101 PT5161LRS-PT5161LRS,SMLF,IC,AJ051610U03    I19 @T6G_MB_LIB.T6G(SCH_1):PAGE452
 U6016 EG22 GND102 PT5161LRS-PT5161LRS,SMLF,IC,AJ051610U03    I19 @T6G_MB_LIB.T6G(SCH_1):PAGE452
 U6016 EG32 GND103 PT5161LRS-PT5161LRS,SMLF,IC,AJ051610U03    I19 @T6G_MB_LIB.T6G(SCH_1):PAGE452
 U6016  EG4 GND104 PT5161LRS-PT5161LRS,SMLF,IC,AJ051610U03    I19 @T6G_MB_LIB.T6G(SCH_1):PAGE452
 U6016  EH2 GND105 PT5161LRS-PT5161LRS,SMLF,IC,AJ051610U03    I19 @T6G_MB_LIB.T6G(SCH_1):PAGE452
 U6016 EH34 GND106 PT5161LRS-PT5161LRS,SMLF,IC,AJ051610U03    I19 @T6G_MB_LIB.T6G(SCH_1):PAGE452
 U6016  EJ1 GND107 PT5161LRS-PT5161LRS,SMLF,IC,AJ051610U03    I19 @T6G_MB_LIB.T6G(SCH_1):PAGE452
 U6016 EJ35 GND108 PT5161LRS-PT5161LRS,SMLF,IC,AJ051610U03    I19 @T6G_MB_LIB.T6G(SCH_1):PAGE452
 U6016 EP13 GND109 PT5161LRS-PT5161LRS,SMLF,IC,AJ051610U03    I19 @T6G_MB_LIB.T6G(SCH_1):PAGE452
 U6016 EP22 GND110 PT5161LRS-PT5161LRS,SMLF,IC,AJ051610U03    I19 @T6G_MB_LIB.T6G(SCH_1):PAGE452
 U6016 EP32 GND111 PT5161LRS-PT5161LRS,SMLF,IC,AJ051610U03    I19 @T6G_MB_LIB.T6G(SCH_1):PAGE452
 U6016  EP4 GND112 PT5161LRS-PT5161LRS,SMLF,IC,AJ051610U03    I19 @T6G_MB_LIB.T6G(SCH_1):PAGE452
 U6016  ER2 GND113 PT5161LRS-PT5161LRS,SMLF,IC,AJ051610U03    I19 @T6G_MB_LIB.T6G(SCH_1):PAGE452
 U6016 ER34 GND114 PT5161LRS-PT5161LRS,SMLF,IC,AJ051610U03    I19 @T6G_MB_LIB.T6G(SCH_1):PAGE452
 U6016  ET1 GND115 PT5161LRS-PT5161LRS,SMLF,IC,AJ051610U03    I19 @T6G_MB_LIB.T6G(SCH_1):PAGE452
 U6016 ET35 GND116 PT5161LRS-PT5161LRS,SMLF,IC,AJ051610U03    I19 @T6G_MB_LIB.T6G(SCH_1):PAGE452
 U6016 FA15 GND117 PT5161LRS-PT5161LRS,SMLF,IC,AJ051610U03    I19 @T6G_MB_LIB.T6G(SCH_1):PAGE452
 U6016 FA32 GND118 PT5161LRS-PT5161LRS,SMLF,IC,AJ051610U03    I19 @T6G_MB_LIB.T6G(SCH_1):PAGE452
 U6016  FB2 GND119 PT5161LRS-PT5161LRS,SMLF,IC,AJ051610U03    I19 @T6G_MB_LIB.T6G(SCH_1):PAGE452
 U6016 FB34 GND120 PT5161LRS-PT5161LRS,SMLF,IC,AJ051610U03    I19 @T6G_MB_LIB.T6G(SCH_1):PAGE452
 U6016 FC19 GND121 PT5161LRS-PT5161LRS,SMLF,IC,AJ051610U03    I19 @T6G_MB_LIB.T6G(SCH_1):PAGE452
 U6016 FC23 GND122 PT5161LRS-PT5161LRS,SMLF,IC,AJ051610U03    I19 @T6G_MB_LIB.T6G(SCH_1):PAGE452
 U6016 FC25 GND123 PT5161LRS-PT5161LRS,SMLF,IC,AJ051610U03    I19 @T6G_MB_LIB.T6G(SCH_1):PAGE452
 U6016 FC28 GND124 PT5161LRS-PT5161LRS,SMLF,IC,AJ051610U03    I19 @T6G_MB_LIB.T6G(SCH_1):PAGE452
 U6016  FC3 GND125 PT5161LRS-PT5161LRS,SMLF,IC,AJ051610U03    I19 @T6G_MB_LIB.T6G(SCH_1):PAGE452
 U6016  FC6 GND126 PT5161LRS-PT5161LRS,SMLF,IC,AJ051610U03    I19 @T6G_MB_LIB.T6G(SCH_1):PAGE452
 U6016  FC9 GND127 PT5161LRS-PT5161LRS,SMLF,IC,AJ051610U03    I19 @T6G_MB_LIB.T6G(SCH_1):PAGE452
 U6016  FD1 GND128 PT5161LRS-PT5161LRS,SMLF,IC,AJ051610U03    I19 @T6G_MB_LIB.T6G(SCH_1):PAGE452
 U6016 FD35 GND129 PT5161LRS-PT5161LRS,SMLF,IC,AJ051610U03    I19 @T6G_MB_LIB.T6G(SCH_1):PAGE452
 U6016 FF14 GND130 PT5161LRS-PT5161LRS,SMLF,IC,AJ051610U03    I19 @T6G_MB_LIB.T6G(SCH_1):PAGE452
 U6016 FF21 GND131 PT5161LRS-PT5161LRS,SMLF,IC,AJ051610U03    I19 @T6G_MB_LIB.T6G(SCH_1):PAGE452
 U6016 FJ12 GND132 PT5161LRS-PT5161LRS,SMLF,IC,AJ051610U03    I19 @T6G_MB_LIB.T6G(SCH_1):PAGE452
 U6016 FJ19 GND133 PT5161LRS-PT5161LRS,SMLF,IC,AJ051610U03    I19 @T6G_MB_LIB.T6G(SCH_1):PAGE452
 U6016  H12 GND134 PT5161LRS-PT5161LRS,SMLF,IC,AJ051610U03    I19 @T6G_MB_LIB.T6G(SCH_1):PAGE452
 U6016  H16 GND135 PT5161LRS-PT5161LRS,SMLF,IC,AJ051610U03    I19 @T6G_MB_LIB.T6G(SCH_1):PAGE452
 U6016  H19 GND136 PT5161LRS-PT5161LRS,SMLF,IC,AJ051610U03    I19 @T6G_MB_LIB.T6G(SCH_1):PAGE452
 U6016  H31 GND137 PT5161LRS-PT5161LRS,SMLF,IC,AJ051610U03    I19 @T6G_MB_LIB.T6G(SCH_1):PAGE452
 U6016  J22 GND138 PT5161LRS-PT5161LRS,SMLF,IC,AJ051610U03    I19 @T6G_MB_LIB.T6G(SCH_1):PAGE452
 U6016   J4 GND139 PT5161LRS-PT5161LRS,SMLF,IC,AJ051610U03    I19 @T6G_MB_LIB.T6G(SCH_1):PAGE452
 U6016   K2 GND140 PT5161LRS-PT5161LRS,SMLF,IC,AJ051610U03    I19 @T6G_MB_LIB.T6G(SCH_1):PAGE452
 U6016  K34 GND141 PT5161LRS-PT5161LRS,SMLF,IC,AJ051610U03    I19 @T6G_MB_LIB.T6G(SCH_1):PAGE452
 U6016   L1 GND142 PT5161LRS-PT5161LRS,SMLF,IC,AJ051610U03    I19 @T6G_MB_LIB.T6G(SCH_1):PAGE452
 U6016  L35 GND143 PT5161LRS-PT5161LRS,SMLF,IC,AJ051610U03    I19 @T6G_MB_LIB.T6G(SCH_1):PAGE452
 U6016  T13 GND144 PT5161LRS-PT5161LRS,SMLF,IC,AJ051610U03    I19 @T6G_MB_LIB.T6G(SCH_1):PAGE452
 U6016  T22 GND145 PT5161LRS-PT5161LRS,SMLF,IC,AJ051610U03    I19 @T6G_MB_LIB.T6G(SCH_1):PAGE452
 U6016  T32 GND146 PT5161LRS-PT5161LRS,SMLF,IC,AJ051610U03    I19 @T6G_MB_LIB.T6G(SCH_1):PAGE452
 U6016   T4 GND147 PT5161LRS-PT5161LRS,SMLF,IC,AJ051610U03    I19 @T6G_MB_LIB.T6G(SCH_1):PAGE452
 U6016   U2 GND148 PT5161LRS-PT5161LRS,SMLF,IC,AJ051610U03    I19 @T6G_MB_LIB.T6G(SCH_1):PAGE452
 U6016  U34 GND149 PT5161LRS-PT5161LRS,SMLF,IC,AJ051610U03    I19 @T6G_MB_LIB.T6G(SCH_1):PAGE452
 U6016   V1 GND150 PT5161LRS-PT5161LRS,SMLF,IC,AJ051610U03    I19 @T6G_MB_LIB.T6G(SCH_1):PAGE452
 U6016  V35 GND151 PT5161LRS-PT5161LRS,SMLF,IC,AJ051610U03    I19 @T6G_MB_LIB.T6G(SCH_1):PAGE452
  C367    2      B Q_CAP_C0805-100UF,4V,20%,X6S,CH710KMEA01     I5 @T6G_MB_LIB.T6G(SCH_1):PAGE454
  C375    2      B Q_CAP_0201-1UF,4V,20%,X6S,CH-10KMEE00     I6 @T6G_MB_LIB.T6G(SCH_1):PAGE454
  C378    2      B Q_CAP_C0201-0.1UF,10V,10%,X7S,CH4102K6E00     I8 @T6G_MB_LIB.T6G(SCH_1):PAGE454
  C369    2      B Q_CAP_C0402-22UF,4V,20%,X6S,CH622KMEB02    I10 @T6G_MB_LIB.T6G(SCH_1):PAGE454
  C372    2      B Q_CAP_C0402-10UF,6.3V,20%,X6S,CH6101MEB01    I11 @T6G_MB_LIB.T6G(SCH_1):PAGE454
  C371    2      B Q_CAP_0402-4.7UF,6.3V,20%,X6S,CH5471MEB01    I12 @T6G_MB_LIB.T6G(SCH_1):PAGE454
  C374    2      B Q_CAP_0201-1UF,4V,20%,X6S,CH-10KMEE00    I13 @T6G_MB_LIB.T6G(SCH_1):PAGE454
  C376    2      B Q_CAP_0201-1UF,4V,20%,X6S,CH-10KMEE00    I15 @T6G_MB_LIB.T6G(SCH_1):PAGE454
  C377    2      B Q_CAP_C0201-0.1UF,10V,10%,X7S,CH4102K6E00    I16 @T6G_MB_LIB.T6G(SCH_1):PAGE454
  C379    2      B Q_CAP_C0201-0.1UF,10V,10%,X7S,CH4102K6E00    I17 @T6G_MB_LIB.T6G(SCH_1):PAGE454
  C380    2      B Q_CAP_C0201-0.1UF,10V,10%,X7S,CH4102K6E00    I18 @T6G_MB_LIB.T6G(SCH_1):PAGE454
  C381    2      B Q_CAP_C0201-0.1UF,10V,10%,X7S,CH4102K6E00    I19 @T6G_MB_LIB.T6G(SCH_1):PAGE454
  C366    2      B Q_CAP_C0805-100UF,4V,20%,X6S,CH710KMEA01    I24 @T6G_MB_LIB.T6G(SCH_1):PAGE454
  C368    2      B Q_CAP_C0402-22UF,4V,20%,X6S,CH622KMEB02    I25 @T6G_MB_LIB.T6G(SCH_1):PAGE454
  C370    2      B Q_CAP_C0402-10UF,6.3V,20%,X6S,CH6101MEB01    I27 @T6G_MB_LIB.T6G(SCH_1):PAGE454
  C373    2      B Q_CAP_0402-4.7UF,6.3V,20%,X6S,CH5471MEB01    I28 @T6G_MB_LIB.T6G(SCH_1):PAGE454
  C421    2      B Q_CAP_C0201-0.1UF,10V,10%,X7S,CH4102K6E00    I31 @T6G_MB_LIB.T6G(SCH_1):PAGE454
  C396    2      B Q_CAP_C0201-0.1UF,10V,10%,X7S,CH4102K6E00    I35 @T6G_MB_LIB.T6G(SCH_1):PAGE454
  C397    2      B Q_CAP_C0201-0.1UF,10V,10%,X7S,CH4102K6E00    I36 @T6G_MB_LIB.T6G(SCH_1):PAGE454
  C427    2      B Q_CAP_C0201-0.1UF,10V,10%,X7S,CH4102K6E00    I37 @T6G_MB_LIB.T6G(SCH_1):PAGE454
  C393    2      B Q_CAP_C0201-0.1UF,10V,10%,X7S,CH4102K6E00    I38 @T6G_MB_LIB.T6G(SCH_1):PAGE454
  C430    2      B Q_CAP_C0201-0.1UF,10V,10%,X7S,CH4102K6E00    I39 @T6G_MB_LIB.T6G(SCH_1):PAGE454
  C400    2      B Q_CAP_C0201-0.1UF,10V,10%,X7S,CH4102K6E00    I40 @T6G_MB_LIB.T6G(SCH_1):PAGE454
  C384    2      B Q_CAP_0201-1UF,4V,20%,X6S,CH-10KMEE00    I42 @T6G_MB_LIB.T6G(SCH_1):PAGE454
  C387    2      B Q_CAP_0201-1UF,4V,20%,X6S,CH-10KMEE00    I43 @T6G_MB_LIB.T6G(SCH_1):PAGE454
  C410    2      B Q_CAP_C0402-10UF,6.3V,20%,X6S,CH6101MEB01    I44 @T6G_MB_LIB.T6G(SCH_1):PAGE454
  C420    2      B Q_CAP_C0402-10UF,6.3V,20%,X6S,CH6101MEB01    I45 @T6G_MB_LIB.T6G(SCH_1):PAGE454
  C398    2      B Q_CAP_C0805-100UF,4V,20%,X6S,CH710KMEA01    I46 @T6G_MB_LIB.T6G(SCH_1):PAGE454
  C401    2      B Q_CAP_C0805-100UF,4V,20%,X6S,CH710KMEA01    I47 @T6G_MB_LIB.T6G(SCH_1):PAGE454
  C406    2      B Q_CAP_0402-4.7UF,6.3V,20%,X6S,CH5471MEB01    I48 @T6G_MB_LIB.T6G(SCH_1):PAGE454
  C407    2      B Q_CAP_0201-1UF,4V,20%,X6S,CH-10KMEE00    I49 @T6G_MB_LIB.T6G(SCH_1):PAGE454
  C391    2      B Q_CAP_0201-1UF,4V,20%,X6S,CH-10KMEE00    I50 @T6G_MB_LIB.T6G(SCH_1):PAGE454
  C415    2      B Q_CAP_0201-1UF,4V,20%,X6S,CH-10KMEE00    I51 @T6G_MB_LIB.T6G(SCH_1):PAGE454
  C418    2      B Q_CAP_0201-1UF,4V,20%,X6S,CH-10KMEE00    I52 @T6G_MB_LIB.T6G(SCH_1):PAGE454
  C422    2      B Q_CAP_0201-1UF,4V,20%,X6S,CH-10KMEE00    I53 @T6G_MB_LIB.T6G(SCH_1):PAGE454
  C416    2      B Q_CAP_0402-4.7UF,6.3V,20%,X6S,CH5471MEB01    I54 @T6G_MB_LIB.T6G(SCH_1):PAGE454
  C413    2      B Q_CAP_0402-4.7UF,6.3V,20%,X6S,CH5471MEB01    I55 @T6G_MB_LIB.T6G(SCH_1):PAGE454
  C417    2      B Q_CAP_C0402-22UF,4V,20%,X6S,CH622KMEB02    I56 @T6G_MB_LIB.T6G(SCH_1):PAGE454
  C412    2      B Q_CAP_0402-4.7UF,6.3V,20%,X6S,CH5471MEB01    I57 @T6G_MB_LIB.T6G(SCH_1):PAGE454
  C386    2      B Q_CAP_0201-1UF,4V,20%,X6S,CH-10KMEE00    I58 @T6G_MB_LIB.T6G(SCH_1):PAGE454
  C399    2      B Q_CAP_C0402-22UF,4V,20%,X6S,CH622KMEB02    I59 @T6G_MB_LIB.T6G(SCH_1):PAGE454
  C402    2      B Q_CAP_C0402-22UF,4V,20%,X6S,CH622KMEB02    I60 @T6G_MB_LIB.T6G(SCH_1):PAGE454
  C403    2      B Q_CAP_C0201-0.1UF,10V,10%,X7S,CH4102K6E00    I61 @T6G_MB_LIB.T6G(SCH_1):PAGE454
  C411    2      B Q_CAP_C0201-0.1UF,10V,10%,X7S,CH4102K6E00    I62 @T6G_MB_LIB.T6G(SCH_1):PAGE454
  C395    2      B Q_CAP_C0201-0.1UF,10V,10%,X7S,CH4102K6E00    I64 @T6G_MB_LIB.T6G(SCH_1):PAGE454
  C425    2      B Q_CAP_0201-1UF,4V,20%,X6S,CH-10KMEE00    I67 @T6G_MB_LIB.T6G(SCH_1):PAGE454
  C389    2      B Q_CAP_0201-1UF,4V,20%,X6S,CH-10KMEE00    I68 @T6G_MB_LIB.T6G(SCH_1):PAGE454
  C424    2      B Q_CAP_C0402-22UF,4V,20%,X6S,CH622KMEB02    I69 @T6G_MB_LIB.T6G(SCH_1):PAGE454
  C429    2      B Q_CAP_C0402-10UF,6.3V,20%,X6S,CH6101MEB01    I70 @T6G_MB_LIB.T6G(SCH_1):PAGE454
  C382    2      B Q_CAP_0201-1UF,4V,20%,X6S,CH-10KMEE00    I71 @T6G_MB_LIB.T6G(SCH_1):PAGE454
  C431    2      B Q_CAP_C0402-10UF,6.3V,20%,X6S,CH6101MEB01    I72 @T6G_MB_LIB.T6G(SCH_1):PAGE454
  C404    2      B Q_CAP_C0805-100UF,4V,20%,X6S,CH710KMEA01    I76 @T6G_MB_LIB.T6G(SCH_1):PAGE454
  C408    2      B Q_CAP_C0402-22UF,4V,20%,X6S,CH622KMEB02    I77 @T6G_MB_LIB.T6G(SCH_1):PAGE454
  C414    2      B Q_CAP_C0402-10UF,6.3V,20%,X6S,CH6101MEB01    I78 @T6G_MB_LIB.T6G(SCH_1):PAGE454
  C419    2      B Q_CAP_0402-4.7UF,6.3V,20%,X6S,CH5471MEB01    I79 @T6G_MB_LIB.T6G(SCH_1):PAGE454
  C423    2      B Q_CAP_0201-1UF,4V,20%,X6S,CH-10KMEE00    I80 @T6G_MB_LIB.T6G(SCH_1):PAGE454
  C383    2      B Q_CAP_C0201-0.1UF,10V,10%,X7S,CH4102K6E00    I82 @T6G_MB_LIB.T6G(SCH_1):PAGE454
  C385    2      B Q_CAP_C0201-0.1UF,10V,10%,X7S,CH4102K6E00    I83 @T6G_MB_LIB.T6G(SCH_1):PAGE454
  C388    2      B Q_CAP_C0201-0.1UF,10V,10%,X7S,CH4102K6E00    I84 @T6G_MB_LIB.T6G(SCH_1):PAGE454
  C392    2      B Q_CAP_C0201-0.1UF,10V,10%,X7S,CH4102K6E00    I85 @T6G_MB_LIB.T6G(SCH_1):PAGE454
  C405    2      B Q_CAP_C0805-100UF,4V,20%,X6S,CH710KMEA01    I86 @T6G_MB_LIB.T6G(SCH_1):PAGE454
  C409    2      B Q_CAP_C0805-100UF,4V,20%,X6S,CH710KMEA01    I87 @T6G_MB_LIB.T6G(SCH_1):PAGE454
  R916    2      B Q_RES_0201LF-10K,1%,1/20W,CHIP,CS31001FE17    I19 @T6G_MB_LIB.T6G(SCH_1):PAGE462
  R917    2      B Q_RES_0201LF-10K,1%,1/20W,CHIP,CS31001FE17    I20 @T6G_MB_LIB.T6G(SCH_1):PAGE462
  R919    2      B Q_RES_0201LF-4.7K,5%,1/20W,CHIP,CS24701JE04    I21 @T6G_MB_LIB.T6G(SCH_1):PAGE462
  R641    2      B Q_RES_0201LF-51.1,1%,1/20W,EMPTY,CS05111FE00    I30 @T6G_MB_LIB.T6G(SCH_1):PAGE462
  R642    2      B Q_RES_0201LF-51.1,1%,1/20W,EMPTY,CS05111FE00    I46 @T6G_MB_LIB.T6G(SCH_1):PAGE462
  R921    2      B Q_RES_0201LF-4.7K,5%,1/20W,CHIP,CS24701JE04    I50 @T6G_MB_LIB.T6G(SCH_1):PAGE462
  R923    2      B Q_RES_0201LF-4.7K,5%,1/20W,CHIP,CS24701JE04    I51 @T6G_MB_LIB.T6G(SCH_1):PAGE462
  R924    2      B Q_RES_0201LF-4.7K,5%,1/20W,CHIP,CS24701JE04    I53 @T6G_MB_LIB.T6G(SCH_1):PAGE462
  R926    2      B Q_RES_0201LF-4.7K,5%,1/20W,EMPTY,CS24701JE04    I64 @T6G_MB_LIB.T6G(SCH_1):PAGE462
  R903    2      B Q_RES_0201LF-1K,1%,1/20W,EMPTY,CS21001FE07    I79 @T6G_MB_LIB.T6G(SCH_1):PAGE462
  R906    2      B Q_RES_0201LF-20K,1%,1/20W,CHIP,CS32001FE00    I81 @T6G_MB_LIB.T6G(SCH_1):PAGE462
  R949    2      B Q_RES_0201LF-1K,1%,1/20W,CHIP,CS21001FE07    I83 @T6G_MB_LIB.T6G(SCH_1):PAGE462
  R908    2      B Q_RES_0201LF-10K,1%,1/20W,CHIP,CS31001FE17    I90 @T6G_MB_LIB.T6G(SCH_1):PAGE462
  R907    2      B Q_RES_0201LF-10K,1%,1/20W,CHIP,CS31001FE17    I92 @T6G_MB_LIB.T6G(SCH_1):PAGE462
 U6017  E30 T_SENSE PT5161LRS-PT5161LRS,SMLF,IC,AJ051610U03    I97 @T6G_MB_LIB.T6G(SCH_1):PAGE462
 R6903    2      B Q_RES_0201LF-0,5%,1/20W,CHIP,CS00001JE10    I13 @T6G_MB_LIB.T6G(SCH_1):PAGE463
 R6902    2      B Q_RES_0201LF-0,5%,1/20W,CHIP,CS00001JE10    I15 @T6G_MB_LIB.T6G(SCH_1):PAGE463
 U6017 AC13   GND1 PT5161LRS-PT5161LRS,SMLF,IC,AJ051610U03    I17 @T6G_MB_LIB.T6G(SCH_1):PAGE463
 U6017 AC22   GND2 PT5161LRS-PT5161LRS,SMLF,IC,AJ051610U03    I17 @T6G_MB_LIB.T6G(SCH_1):PAGE463
 U6017 AC32   GND3 PT5161LRS-PT5161LRS,SMLF,IC,AJ051610U03    I17 @T6G_MB_LIB.T6G(SCH_1):PAGE463
 U6017  AC4   GND4 PT5161LRS-PT5161LRS,SMLF,IC,AJ051610U03    I17 @T6G_MB_LIB.T6G(SCH_1):PAGE463
 U6017  AD2   GND5 PT5161LRS-PT5161LRS,SMLF,IC,AJ051610U03    I17 @T6G_MB_LIB.T6G(SCH_1):PAGE463
 U6017 AD34   GND6 PT5161LRS-PT5161LRS,SMLF,IC,AJ051610U03    I17 @T6G_MB_LIB.T6G(SCH_1):PAGE463
 U6017  AE1   GND7 PT5161LRS-PT5161LRS,SMLF,IC,AJ051610U03    I17 @T6G_MB_LIB.T6G(SCH_1):PAGE463
 U6017 AE35   GND8 PT5161LRS-PT5161LRS,SMLF,IC,AJ051610U03    I17 @T6G_MB_LIB.T6G(SCH_1):PAGE463
 U6017 AK13   GND9 PT5161LRS-PT5161LRS,SMLF,IC,AJ051610U03    I17 @T6G_MB_LIB.T6G(SCH_1):PAGE463
 U6017 AK22  GND10 PT5161LRS-PT5161LRS,SMLF,IC,AJ051610U03    I17 @T6G_MB_LIB.T6G(SCH_1):PAGE463
 U6017 AK32  GND11 PT5161LRS-PT5161LRS,SMLF,IC,AJ051610U03    I17 @T6G_MB_LIB.T6G(SCH_1):PAGE463
 U6017  AK4  GND12 PT5161LRS-PT5161LRS,SMLF,IC,AJ051610U03    I17 @T6G_MB_LIB.T6G(SCH_1):PAGE463
 U6017  AL2  GND13 PT5161LRS-PT5161LRS,SMLF,IC,AJ051610U03    I17 @T6G_MB_LIB.T6G(SCH_1):PAGE463
 U6017 AL34  GND14 PT5161LRS-PT5161LRS,SMLF,IC,AJ051610U03    I17 @T6G_MB_LIB.T6G(SCH_1):PAGE463
 U6017  AM1  GND15 PT5161LRS-PT5161LRS,SMLF,IC,AJ051610U03    I17 @T6G_MB_LIB.T6G(SCH_1):PAGE463
 U6017 AM35  GND16 PT5161LRS-PT5161LRS,SMLF,IC,AJ051610U03    I17 @T6G_MB_LIB.T6G(SCH_1):PAGE463
 U6017 AU13  GND17 PT5161LRS-PT5161LRS,SMLF,IC,AJ051610U03    I17 @T6G_MB_LIB.T6G(SCH_1):PAGE463
 U6017 AU22  GND18 PT5161LRS-PT5161LRS,SMLF,IC,AJ051610U03    I17 @T6G_MB_LIB.T6G(SCH_1):PAGE463
 U6017 AU32  GND19 PT5161LRS-PT5161LRS,SMLF,IC,AJ051610U03    I17 @T6G_MB_LIB.T6G(SCH_1):PAGE463
 U6017  AU4  GND20 PT5161LRS-PT5161LRS,SMLF,IC,AJ051610U03    I17 @T6G_MB_LIB.T6G(SCH_1):PAGE463
 U6017  AV2  GND21 PT5161LRS-PT5161LRS,SMLF,IC,AJ051610U03    I17 @T6G_MB_LIB.T6G(SCH_1):PAGE463
 U6017 AV34  GND22 PT5161LRS-PT5161LRS,SMLF,IC,AJ051610U03    I17 @T6G_MB_LIB.T6G(SCH_1):PAGE463
 U6017  AW1  GND23 PT5161LRS-PT5161LRS,SMLF,IC,AJ051610U03    I17 @T6G_MB_LIB.T6G(SCH_1):PAGE463
 U6017 AW35  GND24 PT5161LRS-PT5161LRS,SMLF,IC,AJ051610U03    I17 @T6G_MB_LIB.T6G(SCH_1):PAGE463
 U6017  B19  GND25 PT5161LRS-PT5161LRS,SMLF,IC,AJ051610U03    I17 @T6G_MB_LIB.T6G(SCH_1):PAGE463
 U6017 BD13  GND26 PT5161LRS-PT5161LRS,SMLF,IC,AJ051610U03    I17 @T6G_MB_LIB.T6G(SCH_1):PAGE463
 U6017 BD22  GND27 PT5161LRS-PT5161LRS,SMLF,IC,AJ051610U03    I17 @T6G_MB_LIB.T6G(SCH_1):PAGE463
 U6017 BD32  GND28 PT5161LRS-PT5161LRS,SMLF,IC,AJ051610U03    I17 @T6G_MB_LIB.T6G(SCH_1):PAGE463
 U6017  BD4  GND29 PT5161LRS-PT5161LRS,SMLF,IC,AJ051610U03    I17 @T6G_MB_LIB.T6G(SCH_1):PAGE463
 U6017  BE2  GND30 PT5161LRS-PT5161LRS,SMLF,IC,AJ051610U03    I17 @T6G_MB_LIB.T6G(SCH_1):PAGE463
 U6017 BE34  GND31 PT5161LRS-PT5161LRS,SMLF,IC,AJ051610U03    I17 @T6G_MB_LIB.T6G(SCH_1):PAGE463
 U6017  BF1  GND32 PT5161LRS-PT5161LRS,SMLF,IC,AJ051610U03    I17 @T6G_MB_LIB.T6G(SCH_1):PAGE463
 U6017 BF35  GND33 PT5161LRS-PT5161LRS,SMLF,IC,AJ051610U03    I17 @T6G_MB_LIB.T6G(SCH_1):PAGE463
 U6017 BL13  GND34 PT5161LRS-PT5161LRS,SMLF,IC,AJ051610U03    I17 @T6G_MB_LIB.T6G(SCH_1):PAGE463
 U6017 BL22  GND35 PT5161LRS-PT5161LRS,SMLF,IC,AJ051610U03    I17 @T6G_MB_LIB.T6G(SCH_1):PAGE463
 U6017 BL32  GND36 PT5161LRS-PT5161LRS,SMLF,IC,AJ051610U03    I17 @T6G_MB_LIB.T6G(SCH_1):PAGE463
 U6017  BL4  GND37 PT5161LRS-PT5161LRS,SMLF,IC,AJ051610U03    I17 @T6G_MB_LIB.T6G(SCH_1):PAGE463
 U6017  BM2  GND38 PT5161LRS-PT5161LRS,SMLF,IC,AJ051610U03    I17 @T6G_MB_LIB.T6G(SCH_1):PAGE463
 U6017 BM34  GND39 PT5161LRS-PT5161LRS,SMLF,IC,AJ051610U03    I17 @T6G_MB_LIB.T6G(SCH_1):PAGE463
 U6017  BN1  GND40 PT5161LRS-PT5161LRS,SMLF,IC,AJ051610U03    I17 @T6G_MB_LIB.T6G(SCH_1):PAGE463
 U6017 BN35  GND41 PT5161LRS-PT5161LRS,SMLF,IC,AJ051610U03    I17 @T6G_MB_LIB.T6G(SCH_1):PAGE463
 U6017 BV13  GND42 PT5161LRS-PT5161LRS,SMLF,IC,AJ051610U03    I17 @T6G_MB_LIB.T6G(SCH_1):PAGE463
 U6017 BV22  GND43 PT5161LRS-PT5161LRS,SMLF,IC,AJ051610U03    I17 @T6G_MB_LIB.T6G(SCH_1):PAGE463
 U6017 BV32  GND44 PT5161LRS-PT5161LRS,SMLF,IC,AJ051610U03    I17 @T6G_MB_LIB.T6G(SCH_1):PAGE463
 U6017  BV4  GND45 PT5161LRS-PT5161LRS,SMLF,IC,AJ051610U03    I17 @T6G_MB_LIB.T6G(SCH_1):PAGE463
 U6017  BW2  GND46 PT5161LRS-PT5161LRS,SMLF,IC,AJ051610U03    I17 @T6G_MB_LIB.T6G(SCH_1):PAGE463
 U6017 BW34  GND47 PT5161LRS-PT5161LRS,SMLF,IC,AJ051610U03    I17 @T6G_MB_LIB.T6G(SCH_1):PAGE463
 U6017  BY1  GND48 PT5161LRS-PT5161LRS,SMLF,IC,AJ051610U03    I17 @T6G_MB_LIB.T6G(SCH_1):PAGE463
 U6017 BY35  GND49 PT5161LRS-PT5161LRS,SMLF,IC,AJ051610U03    I17 @T6G_MB_LIB.T6G(SCH_1):PAGE463
 U6017 CE13  GND50 PT5161LRS-PT5161LRS,SMLF,IC,AJ051610U03    I17 @T6G_MB_LIB.T6G(SCH_1):PAGE463
 U6017 CE22  GND51 PT5161LRS-PT5161LRS,SMLF,IC,AJ051610U03    I17 @T6G_MB_LIB.T6G(SCH_1):PAGE463
 U6017 CE32  GND52 PT5161LRS-PT5161LRS,SMLF,IC,AJ051610U03    I17 @T6G_MB_LIB.T6G(SCH_1):PAGE463
 U6017  CE4  GND53 PT5161LRS-PT5161LRS,SMLF,IC,AJ051610U03    I17 @T6G_MB_LIB.T6G(SCH_1):PAGE463
 U6017  CF2  GND54 PT5161LRS-PT5161LRS,SMLF,IC,AJ051610U03    I17 @T6G_MB_LIB.T6G(SCH_1):PAGE463
 U6017 CF34  GND55 PT5161LRS-PT5161LRS,SMLF,IC,AJ051610U03    I17 @T6G_MB_LIB.T6G(SCH_1):PAGE463
 U6017  CG1  GND56 PT5161LRS-PT5161LRS,SMLF,IC,AJ051610U03    I17 @T6G_MB_LIB.T6G(SCH_1):PAGE463
 U6017 CG35  GND57 PT5161LRS-PT5161LRS,SMLF,IC,AJ051610U03    I17 @T6G_MB_LIB.T6G(SCH_1):PAGE463
 U6017 CM13  GND58 PT5161LRS-PT5161LRS,SMLF,IC,AJ051610U03    I17 @T6G_MB_LIB.T6G(SCH_1):PAGE463
 U6017 CM22  GND59 PT5161LRS-PT5161LRS,SMLF,IC,AJ051610U03    I17 @T6G_MB_LIB.T6G(SCH_1):PAGE463
 U6017 CM32  GND60 PT5161LRS-PT5161LRS,SMLF,IC,AJ051610U03    I17 @T6G_MB_LIB.T6G(SCH_1):PAGE463
 U6017  CM4  GND61 PT5161LRS-PT5161LRS,SMLF,IC,AJ051610U03    I17 @T6G_MB_LIB.T6G(SCH_1):PAGE463
 U6017  CN2  GND62 PT5161LRS-PT5161LRS,SMLF,IC,AJ051610U03    I17 @T6G_MB_LIB.T6G(SCH_1):PAGE463
 U6017 CN34  GND63 PT5161LRS-PT5161LRS,SMLF,IC,AJ051610U03    I17 @T6G_MB_LIB.T6G(SCH_1):PAGE463
 U6017  CP1  GND64 PT5161LRS-PT5161LRS,SMLF,IC,AJ051610U03    I17 @T6G_MB_LIB.T6G(SCH_1):PAGE463
 U6017 CP35  GND65 PT5161LRS-PT5161LRS,SMLF,IC,AJ051610U03    I17 @T6G_MB_LIB.T6G(SCH_1):PAGE463
 U6017 CW13  GND66 PT5161LRS-PT5161LRS,SMLF,IC,AJ051610U03    I17 @T6G_MB_LIB.T6G(SCH_1):PAGE463
 U6017 CW22  GND67 PT5161LRS-PT5161LRS,SMLF,IC,AJ051610U03    I17 @T6G_MB_LIB.T6G(SCH_1):PAGE463
 U6017 CW32  GND68 PT5161LRS-PT5161LRS,SMLF,IC,AJ051610U03    I17 @T6G_MB_LIB.T6G(SCH_1):PAGE463
 U6017  CW4  GND69 PT5161LRS-PT5161LRS,SMLF,IC,AJ051610U03    I17 @T6G_MB_LIB.T6G(SCH_1):PAGE463
 U6017  CY2  GND70 PT5161LRS-PT5161LRS,SMLF,IC,AJ051610U03    I17 @T6G_MB_LIB.T6G(SCH_1):PAGE463
 U6017 CY34  GND71 PT5161LRS-PT5161LRS,SMLF,IC,AJ051610U03    I17 @T6G_MB_LIB.T6G(SCH_1):PAGE463
 U6017  DA1  GND72 PT5161LRS-PT5161LRS,SMLF,IC,AJ051610U03    I17 @T6G_MB_LIB.T6G(SCH_1):PAGE463
 U6017 DA35  GND73 PT5161LRS-PT5161LRS,SMLF,IC,AJ051610U03    I17 @T6G_MB_LIB.T6G(SCH_1):PAGE463
 U6017 DF13  GND74 PT5161LRS-PT5161LRS,SMLF,IC,AJ051610U03    I17 @T6G_MB_LIB.T6G(SCH_1):PAGE463
 U6017 DF22  GND75 PT5161LRS-PT5161LRS,SMLF,IC,AJ051610U03    I17 @T6G_MB_LIB.T6G(SCH_1):PAGE463
 U6017 DF32  GND76 PT5161LRS-PT5161LRS,SMLF,IC,AJ051610U03    I17 @T6G_MB_LIB.T6G(SCH_1):PAGE463
 U6017  DF4  GND77 PT5161LRS-PT5161LRS,SMLF,IC,AJ051610U03    I17 @T6G_MB_LIB.T6G(SCH_1):PAGE463
 U6017  DG2  GND78 PT5161LRS-PT5161LRS,SMLF,IC,AJ051610U03    I17 @T6G_MB_LIB.T6G(SCH_1):PAGE463
 U6017 DG34  GND79 PT5161LRS-PT5161LRS,SMLF,IC,AJ051610U03    I17 @T6G_MB_LIB.T6G(SCH_1):PAGE463
 U6017  DH1  GND80 PT5161LRS-PT5161LRS,SMLF,IC,AJ051610U03    I17 @T6G_MB_LIB.T6G(SCH_1):PAGE463
 U6017 DH35  GND81 PT5161LRS-PT5161LRS,SMLF,IC,AJ051610U03    I17 @T6G_MB_LIB.T6G(SCH_1):PAGE463
 U6017 DN13  GND82 PT5161LRS-PT5161LRS,SMLF,IC,AJ051610U03    I17 @T6G_MB_LIB.T6G(SCH_1):PAGE463
 U6017 DN22  GND83 PT5161LRS-PT5161LRS,SMLF,IC,AJ051610U03    I17 @T6G_MB_LIB.T6G(SCH_1):PAGE463
 U6017 DN32  GND84 PT5161LRS-PT5161LRS,SMLF,IC,AJ051610U03    I17 @T6G_MB_LIB.T6G(SCH_1):PAGE463
 U6017  DN4  GND85 PT5161LRS-PT5161LRS,SMLF,IC,AJ051610U03    I17 @T6G_MB_LIB.T6G(SCH_1):PAGE463
 U6017  DP2  GND86 PT5161LRS-PT5161LRS,SMLF,IC,AJ051610U03    I17 @T6G_MB_LIB.T6G(SCH_1):PAGE463
 U6017 DP34  GND87 PT5161LRS-PT5161LRS,SMLF,IC,AJ051610U03    I17 @T6G_MB_LIB.T6G(SCH_1):PAGE463
 U6017  DR1  GND88 PT5161LRS-PT5161LRS,SMLF,IC,AJ051610U03    I17 @T6G_MB_LIB.T6G(SCH_1):PAGE463
 U6017 DR35  GND89 PT5161LRS-PT5161LRS,SMLF,IC,AJ051610U03    I17 @T6G_MB_LIB.T6G(SCH_1):PAGE463
 U6017 DY13  GND90 PT5161LRS-PT5161LRS,SMLF,IC,AJ051610U03    I17 @T6G_MB_LIB.T6G(SCH_1):PAGE463
 U6017 DY22  GND91 PT5161LRS-PT5161LRS,SMLF,IC,AJ051610U03    I17 @T6G_MB_LIB.T6G(SCH_1):PAGE463
 U6017 DY32  GND92 PT5161LRS-PT5161LRS,SMLF,IC,AJ051610U03    I17 @T6G_MB_LIB.T6G(SCH_1):PAGE463
 U6017  DY4  GND93 PT5161LRS-PT5161LRS,SMLF,IC,AJ051610U03    I17 @T6G_MB_LIB.T6G(SCH_1):PAGE463
 U6017  E14  GND94 PT5161LRS-PT5161LRS,SMLF,IC,AJ051610U03    I17 @T6G_MB_LIB.T6G(SCH_1):PAGE463
 U6017  E27  GND95 PT5161LRS-PT5161LRS,SMLF,IC,AJ051610U03    I17 @T6G_MB_LIB.T6G(SCH_1):PAGE463
 U6017  E33  GND96 PT5161LRS-PT5161LRS,SMLF,IC,AJ051610U03    I17 @T6G_MB_LIB.T6G(SCH_1):PAGE463
 U6017  EA2  GND97 PT5161LRS-PT5161LRS,SMLF,IC,AJ051610U03    I17 @T6G_MB_LIB.T6G(SCH_1):PAGE463
 U6017 EA34  GND98 PT5161LRS-PT5161LRS,SMLF,IC,AJ051610U03    I17 @T6G_MB_LIB.T6G(SCH_1):PAGE463
 U6017  EB1  GND99 PT5161LRS-PT5161LRS,SMLF,IC,AJ051610U03    I17 @T6G_MB_LIB.T6G(SCH_1):PAGE463
 U6017 EB35 GND100 PT5161LRS-PT5161LRS,SMLF,IC,AJ051610U03    I17 @T6G_MB_LIB.T6G(SCH_1):PAGE463
 U6017 EG13 GND101 PT5161LRS-PT5161LRS,SMLF,IC,AJ051610U03    I17 @T6G_MB_LIB.T6G(SCH_1):PAGE463
 U6017 EG22 GND102 PT5161LRS-PT5161LRS,SMLF,IC,AJ051610U03    I17 @T6G_MB_LIB.T6G(SCH_1):PAGE463
 U6017 EG32 GND103 PT5161LRS-PT5161LRS,SMLF,IC,AJ051610U03    I17 @T6G_MB_LIB.T6G(SCH_1):PAGE463
 U6017  EG4 GND104 PT5161LRS-PT5161LRS,SMLF,IC,AJ051610U03    I17 @T6G_MB_LIB.T6G(SCH_1):PAGE463
 U6017  EH2 GND105 PT5161LRS-PT5161LRS,SMLF,IC,AJ051610U03    I17 @T6G_MB_LIB.T6G(SCH_1):PAGE463
 U6017 EH34 GND106 PT5161LRS-PT5161LRS,SMLF,IC,AJ051610U03    I17 @T6G_MB_LIB.T6G(SCH_1):PAGE463
 U6017  EJ1 GND107 PT5161LRS-PT5161LRS,SMLF,IC,AJ051610U03    I17 @T6G_MB_LIB.T6G(SCH_1):PAGE463
 U6017 EJ35 GND108 PT5161LRS-PT5161LRS,SMLF,IC,AJ051610U03    I17 @T6G_MB_LIB.T6G(SCH_1):PAGE463
 U6017 EP13 GND109 PT5161LRS-PT5161LRS,SMLF,IC,AJ051610U03    I17 @T6G_MB_LIB.T6G(SCH_1):PAGE463
 U6017 EP22 GND110 PT5161LRS-PT5161LRS,SMLF,IC,AJ051610U03    I17 @T6G_MB_LIB.T6G(SCH_1):PAGE463
 U6017 EP32 GND111 PT5161LRS-PT5161LRS,SMLF,IC,AJ051610U03    I17 @T6G_MB_LIB.T6G(SCH_1):PAGE463
 U6017  EP4 GND112 PT5161LRS-PT5161LRS,SMLF,IC,AJ051610U03    I17 @T6G_MB_LIB.T6G(SCH_1):PAGE463
 U6017  ER2 GND113 PT5161LRS-PT5161LRS,SMLF,IC,AJ051610U03    I17 @T6G_MB_LIB.T6G(SCH_1):PAGE463
 U6017 ER34 GND114 PT5161LRS-PT5161LRS,SMLF,IC,AJ051610U03    I17 @T6G_MB_LIB.T6G(SCH_1):PAGE463
 U6017  ET1 GND115 PT5161LRS-PT5161LRS,SMLF,IC,AJ051610U03    I17 @T6G_MB_LIB.T6G(SCH_1):PAGE463
 U6017 ET35 GND116 PT5161LRS-PT5161LRS,SMLF,IC,AJ051610U03    I17 @T6G_MB_LIB.T6G(SCH_1):PAGE463
 U6017 FA15 GND117 PT5161LRS-PT5161LRS,SMLF,IC,AJ051610U03    I17 @T6G_MB_LIB.T6G(SCH_1):PAGE463
 U6017 FA32 GND118 PT5161LRS-PT5161LRS,SMLF,IC,AJ051610U03    I17 @T6G_MB_LIB.T6G(SCH_1):PAGE463
 U6017  FB2 GND119 PT5161LRS-PT5161LRS,SMLF,IC,AJ051610U03    I17 @T6G_MB_LIB.T6G(SCH_1):PAGE463
 U6017 FB34 GND120 PT5161LRS-PT5161LRS,SMLF,IC,AJ051610U03    I17 @T6G_MB_LIB.T6G(SCH_1):PAGE463
 U6017 FC19 GND121 PT5161LRS-PT5161LRS,SMLF,IC,AJ051610U03    I17 @T6G_MB_LIB.T6G(SCH_1):PAGE463
 U6017 FC23 GND122 PT5161LRS-PT5161LRS,SMLF,IC,AJ051610U03    I17 @T6G_MB_LIB.T6G(SCH_1):PAGE463
 U6017 FC25 GND123 PT5161LRS-PT5161LRS,SMLF,IC,AJ051610U03    I17 @T6G_MB_LIB.T6G(SCH_1):PAGE463
 U6017 FC28 GND124 PT5161LRS-PT5161LRS,SMLF,IC,AJ051610U03    I17 @T6G_MB_LIB.T6G(SCH_1):PAGE463
 U6017  FC3 GND125 PT5161LRS-PT5161LRS,SMLF,IC,AJ051610U03    I17 @T6G_MB_LIB.T6G(SCH_1):PAGE463
 U6017  FC6 GND126 PT5161LRS-PT5161LRS,SMLF,IC,AJ051610U03    I17 @T6G_MB_LIB.T6G(SCH_1):PAGE463
 U6017  FC9 GND127 PT5161LRS-PT5161LRS,SMLF,IC,AJ051610U03    I17 @T6G_MB_LIB.T6G(SCH_1):PAGE463
 U6017  FD1 GND128 PT5161LRS-PT5161LRS,SMLF,IC,AJ051610U03    I17 @T6G_MB_LIB.T6G(SCH_1):PAGE463
 U6017 FD35 GND129 PT5161LRS-PT5161LRS,SMLF,IC,AJ051610U03    I17 @T6G_MB_LIB.T6G(SCH_1):PAGE463
 U6017 FF14 GND130 PT5161LRS-PT5161LRS,SMLF,IC,AJ051610U03    I17 @T6G_MB_LIB.T6G(SCH_1):PAGE463
 U6017 FF21 GND131 PT5161LRS-PT5161LRS,SMLF,IC,AJ051610U03    I17 @T6G_MB_LIB.T6G(SCH_1):PAGE463
 U6017 FJ12 GND132 PT5161LRS-PT5161LRS,SMLF,IC,AJ051610U03    I17 @T6G_MB_LIB.T6G(SCH_1):PAGE463
 U6017 FJ19 GND133 PT5161LRS-PT5161LRS,SMLF,IC,AJ051610U03    I17 @T6G_MB_LIB.T6G(SCH_1):PAGE463
 U6017  H12 GND134 PT5161LRS-PT5161LRS,SMLF,IC,AJ051610U03    I17 @T6G_MB_LIB.T6G(SCH_1):PAGE463
 U6017  H16 GND135 PT5161LRS-PT5161LRS,SMLF,IC,AJ051610U03    I17 @T6G_MB_LIB.T6G(SCH_1):PAGE463
 U6017  H19 GND136 PT5161LRS-PT5161LRS,SMLF,IC,AJ051610U03    I17 @T6G_MB_LIB.T6G(SCH_1):PAGE463
 U6017  H31 GND137 PT5161LRS-PT5161LRS,SMLF,IC,AJ051610U03    I17 @T6G_MB_LIB.T6G(SCH_1):PAGE463
 U6017  J22 GND138 PT5161LRS-PT5161LRS,SMLF,IC,AJ051610U03    I17 @T6G_MB_LIB.T6G(SCH_1):PAGE463
 U6017   J4 GND139 PT5161LRS-PT5161LRS,SMLF,IC,AJ051610U03    I17 @T6G_MB_LIB.T6G(SCH_1):PAGE463
 U6017   K2 GND140 PT5161LRS-PT5161LRS,SMLF,IC,AJ051610U03    I17 @T6G_MB_LIB.T6G(SCH_1):PAGE463
 U6017  K34 GND141 PT5161LRS-PT5161LRS,SMLF,IC,AJ051610U03    I17 @T6G_MB_LIB.T6G(SCH_1):PAGE463
 U6017   L1 GND142 PT5161LRS-PT5161LRS,SMLF,IC,AJ051610U03    I17 @T6G_MB_LIB.T6G(SCH_1):PAGE463
 U6017  L35 GND143 PT5161LRS-PT5161LRS,SMLF,IC,AJ051610U03    I17 @T6G_MB_LIB.T6G(SCH_1):PAGE463
 U6017  T13 GND144 PT5161LRS-PT5161LRS,SMLF,IC,AJ051610U03    I17 @T6G_MB_LIB.T6G(SCH_1):PAGE463
 U6017  T22 GND145 PT5161LRS-PT5161LRS,SMLF,IC,AJ051610U03    I17 @T6G_MB_LIB.T6G(SCH_1):PAGE463
 U6017  T32 GND146 PT5161LRS-PT5161LRS,SMLF,IC,AJ051610U03    I17 @T6G_MB_LIB.T6G(SCH_1):PAGE463
 U6017   T4 GND147 PT5161LRS-PT5161LRS,SMLF,IC,AJ051610U03    I17 @T6G_MB_LIB.T6G(SCH_1):PAGE463
 U6017   U2 GND148 PT5161LRS-PT5161LRS,SMLF,IC,AJ051610U03    I17 @T6G_MB_LIB.T6G(SCH_1):PAGE463
 U6017  U34 GND149 PT5161LRS-PT5161LRS,SMLF,IC,AJ051610U03    I17 @T6G_MB_LIB.T6G(SCH_1):PAGE463
 U6017   V1 GND150 PT5161LRS-PT5161LRS,SMLF,IC,AJ051610U03    I17 @T6G_MB_LIB.T6G(SCH_1):PAGE463
 U6017  V35 GND151 PT5161LRS-PT5161LRS,SMLF,IC,AJ051610U03    I17 @T6G_MB_LIB.T6G(SCH_1):PAGE463
  C441    2      B Q_CAP_0201-1UF,4V,20%,X6S,CH-10KMEE00     I4 @T6G_MB_LIB.T6G(SCH_1):PAGE465
  C444    2      B Q_CAP_C0201-0.1UF,10V,10%,X7S,CH4102K6E00     I6 @T6G_MB_LIB.T6G(SCH_1):PAGE465
  C433    2      B Q_CAP_C0805-100UF,4V,20%,X6S,CH710KMEA01    I14 @T6G_MB_LIB.T6G(SCH_1):PAGE465
  C435    2      B Q_CAP_C0402-22UF,4V,20%,X6S,CH622KMEB02    I15 @T6G_MB_LIB.T6G(SCH_1):PAGE465
  C437    2      B Q_CAP_C0402-10UF,6.3V,20%,X6S,CH6101MEB01    I16 @T6G_MB_LIB.T6G(SCH_1):PAGE465
  C432    2      B Q_CAP_C0805-100UF,4V,20%,X6S,CH710KMEA01    I17 @T6G_MB_LIB.T6G(SCH_1):PAGE465
  C434    2      B Q_CAP_C0402-22UF,4V,20%,X6S,CH622KMEB02    I18 @T6G_MB_LIB.T6G(SCH_1):PAGE465
  C438    2      B Q_CAP_0402-4.7UF,6.3V,20%,X6S,CH5471MEB01    I19 @T6G_MB_LIB.T6G(SCH_1):PAGE465
  C440    2      B Q_CAP_0201-1UF,4V,20%,X6S,CH-10KMEE00    I20 @T6G_MB_LIB.T6G(SCH_1):PAGE465
  C436    2      B Q_CAP_C0402-10UF,6.3V,20%,X6S,CH6101MEB01    I21 @T6G_MB_LIB.T6G(SCH_1):PAGE465
  C439    2      B Q_CAP_0402-4.7UF,6.3V,20%,X6S,CH5471MEB01    I23 @T6G_MB_LIB.T6G(SCH_1):PAGE465
  C442    2      B Q_CAP_0201-1UF,4V,20%,X6S,CH-10KMEE00    I24 @T6G_MB_LIB.T6G(SCH_1):PAGE465
  C443    2      B Q_CAP_C0201-0.1UF,10V,10%,X7S,CH4102K6E00    I25 @T6G_MB_LIB.T6G(SCH_1):PAGE465
  C445    2      B Q_CAP_C0201-0.1UF,10V,10%,X7S,CH4102K6E00    I26 @T6G_MB_LIB.T6G(SCH_1):PAGE465
  C446    2      B Q_CAP_C0201-0.1UF,10V,10%,X7S,CH4102K6E00    I27 @T6G_MB_LIB.T6G(SCH_1):PAGE465
  C447    2      B Q_CAP_C0201-0.1UF,10V,10%,X7S,CH4102K6E00    I28 @T6G_MB_LIB.T6G(SCH_1):PAGE465
  C463    2      B Q_CAP_C0201-0.1UF,10V,10%,X7S,CH4102K6E00    I34 @T6G_MB_LIB.T6G(SCH_1):PAGE465
  C464    2      B Q_CAP_C0201-0.1UF,10V,10%,X7S,CH4102K6E00    I35 @T6G_MB_LIB.T6G(SCH_1):PAGE465
  C495    2      B Q_CAP_C0201-0.1UF,10V,10%,X7S,CH4102K6E00    I37 @T6G_MB_LIB.T6G(SCH_1):PAGE465
  C470    2      B Q_CAP_0201-1UF,4V,20%,X6S,CH-10KMEE00    I38 @T6G_MB_LIB.T6G(SCH_1):PAGE465
  C459    2      B Q_CAP_0201-1UF,4V,20%,X6S,CH-10KMEE00    I39 @T6G_MB_LIB.T6G(SCH_1):PAGE465
  C480    2      B Q_CAP_C0402-10UF,6.3V,20%,X6S,CH6101MEB01    I40 @T6G_MB_LIB.T6G(SCH_1):PAGE465
  C490    2      B Q_CAP_C0402-10UF,6.3V,20%,X6S,CH6101MEB01    I41 @T6G_MB_LIB.T6G(SCH_1):PAGE465
  C500    2      B Q_CAP_C0201-0.1UF,10V,10%,X7S,CH4102K6E00    I42 @T6G_MB_LIB.T6G(SCH_1):PAGE465
  C473    2      B Q_CAP_C0201-0.1UF,10V,10%,X7S,CH4102K6E00    I43 @T6G_MB_LIB.T6G(SCH_1):PAGE465
  C448    2      B Q_CAP_0201-1UF,4V,20%,X6S,CH-10KMEE00    I44 @T6G_MB_LIB.T6G(SCH_1):PAGE465
  C453    2      B Q_CAP_0201-1UF,4V,20%,X6S,CH-10KMEE00    I45 @T6G_MB_LIB.T6G(SCH_1):PAGE465
  C477    2      B Q_CAP_C0201-0.1UF,10V,10%,X7S,CH4102K6E00    I46 @T6G_MB_LIB.T6G(SCH_1):PAGE465
  C450    2      B Q_CAP_C0201-0.1UF,10V,10%,X7S,CH4102K6E00    I47 @T6G_MB_LIB.T6G(SCH_1):PAGE465
  C485    2      B Q_CAP_0201-1UF,4V,20%,X6S,CH-10KMEE00    I48 @T6G_MB_LIB.T6G(SCH_1):PAGE465
  C488    2      B Q_CAP_0201-1UF,4V,20%,X6S,CH-10KMEE00    I49 @T6G_MB_LIB.T6G(SCH_1):PAGE465
  C472    2      B Q_CAP_0402-4.7UF,6.3V,20%,X6S,CH5471MEB01    I50 @T6G_MB_LIB.T6G(SCH_1):PAGE465
  C469    2      B Q_CAP_0402-4.7UF,6.3V,20%,X6S,CH5471MEB01    I51 @T6G_MB_LIB.T6G(SCH_1):PAGE465
  C494    2      B Q_CAP_0402-4.7UF,6.3V,20%,X6S,CH5471MEB01    I52 @T6G_MB_LIB.T6G(SCH_1):PAGE465
  C491    2      B Q_CAP_0201-1UF,4V,20%,X6S,CH-10KMEE00    I53 @T6G_MB_LIB.T6G(SCH_1):PAGE465
  C492    2      B Q_CAP_0201-1UF,4V,20%,X6S,CH-10KMEE00    I54 @T6G_MB_LIB.T6G(SCH_1):PAGE465
  C481    2      B Q_CAP_C0201-0.1UF,10V,10%,X7S,CH4102K6E00    I56 @T6G_MB_LIB.T6G(SCH_1):PAGE465
  C457    2      B Q_CAP_C0201-0.1UF,10V,10%,X7S,CH4102K6E00    I57 @T6G_MB_LIB.T6G(SCH_1):PAGE465
  C497    2      B Q_CAP_0201-1UF,4V,20%,X6S,CH-10KMEE00    I60 @T6G_MB_LIB.T6G(SCH_1):PAGE465
  C455    2      B Q_CAP_0201-1UF,4V,20%,X6S,CH-10KMEE00    I61 @T6G_MB_LIB.T6G(SCH_1):PAGE465
  C466    2      B Q_CAP_C0805-100UF,4V,20%,X6S,CH710KMEA01    I64 @T6G_MB_LIB.T6G(SCH_1):PAGE465
  C471    2      B Q_CAP_C0805-100UF,4V,20%,X6S,CH710KMEA01    I65 @T6G_MB_LIB.T6G(SCH_1):PAGE465
  C474    2      B Q_CAP_C0805-100UF,4V,20%,X6S,CH710KMEA01    I67 @T6G_MB_LIB.T6G(SCH_1):PAGE465
  C478    2      B Q_CAP_C0402-22UF,4V,20%,X6S,CH622KMEB02    I68 @T6G_MB_LIB.T6G(SCH_1):PAGE465
  C475    2      B Q_CAP_C0805-100UF,4V,20%,X6S,CH710KMEA01    I69 @T6G_MB_LIB.T6G(SCH_1):PAGE465
  C501    2      B Q_CAP_C0402-22UF,4V,20%,X6S,CH622KMEB02    I70 @T6G_MB_LIB.T6G(SCH_1):PAGE465
  C476    2      B Q_CAP_C0402-22UF,4V,20%,X6S,CH622KMEB02    I71 @T6G_MB_LIB.T6G(SCH_1):PAGE465
  C489    2      B Q_CAP_C0402-10UF,6.3V,20%,X6S,CH6101MEB01    I72 @T6G_MB_LIB.T6G(SCH_1):PAGE465
  C484    2      B Q_CAP_0402-4.7UF,6.3V,20%,X6S,CH5471MEB01    I73 @T6G_MB_LIB.T6G(SCH_1):PAGE465
  C454    2      B Q_CAP_0201-1UF,4V,20%,X6S,CH-10KMEE00    I74 @T6G_MB_LIB.T6G(SCH_1):PAGE465
  C487    2      B Q_CAP_C0402-22UF,4V,20%,X6S,CH622KMEB02    I75 @T6G_MB_LIB.T6G(SCH_1):PAGE465
  C499    2      B Q_CAP_C0402-10UF,6.3V,20%,X6S,CH6101MEB01    I76 @T6G_MB_LIB.T6G(SCH_1):PAGE465
  C482    2      B Q_CAP_C0402-10UF,6.3V,20%,X6S,CH6101MEB01    I77 @T6G_MB_LIB.T6G(SCH_1):PAGE465
  C449    2      B Q_CAP_C0201-0.1UF,10V,10%,X7S,CH4102K6E00    I78 @T6G_MB_LIB.T6G(SCH_1):PAGE465
  C451    2      B Q_CAP_C0201-0.1UF,10V,10%,X7S,CH4102K6E00    I79 @T6G_MB_LIB.T6G(SCH_1):PAGE465
  C493    2      B Q_CAP_C0201-0.1UF,10V,10%,X7S,CH4102K6E00    I80 @T6G_MB_LIB.T6G(SCH_1):PAGE465
  C458    2      B Q_CAP_C0201-0.1UF,10V,10%,X7S,CH4102K6E00    I82 @T6G_MB_LIB.T6G(SCH_1):PAGE465
  C462    2      B Q_CAP_C0201-0.1UF,10V,10%,X7S,CH4102K6E00    I83 @T6G_MB_LIB.T6G(SCH_1):PAGE465
  C452    2      B Q_CAP_0201-1UF,4V,20%,X6S,CH-10KMEE00    I84 @T6G_MB_LIB.T6G(SCH_1):PAGE465
  C486    2      B Q_CAP_C0402-22UF,4V,20%,X6S,CH622KMEB02    I85 @T6G_MB_LIB.T6G(SCH_1):PAGE465
  C483    2      B Q_CAP_0402-4.7UF,6.3V,20%,X6S,CH5471MEB01    I86 @T6G_MB_LIB.T6G(SCH_1):PAGE465
  C479    2      B Q_CAP_C0805-100UF,4V,20%,X6S,CH710KMEA01    I87 @T6G_MB_LIB.T6G(SCH_1):PAGE465
 C1713    2      B Q_CAP_0402-0.1UF,25V,10%,X7R,CH4104K1B00    I61 @T6G_MB_LIB.T6G(SCH_1):PAGE246
  U181   12    VSS PCA9539RPW-PCA9539RPW,SMLF,IC,AL009539K07    I83 @T6G_MB_LIB.T6G(SCH_1):PAGE246
 R4154    2      B Q_RES_0402LF-100K,1%,1/16W,EMPTY,CS41002FB09     I2 @T6G_MB_LIB.T6G(SCH_1):PAGE332
  Q134    1     S1 MOSFET_NCH_DUAL-PJT138K,SMLF,IC,BAM138K0003     I6 @T6G_MB_LIB.T6G(SCH_1):PAGE332
  Q134    4     S2 MOSFET_NCH_DUAL-PJT138K,SMLF,IC,BAM138K0003    I10 @T6G_MB_LIB.T6G(SCH_1):PAGE332
 R4122    2      B Q_RES_0402LF-100K,1%,1/16W,EMPTY,CS41002FB09    I13 @T6G_MB_LIB.T6G(SCH_1):PAGE332
 R4120    2      B Q_RES_0402LF-100K,1%,1/16W,EMPTY,CS41002FB09    I22 @T6G_MB_LIB.T6G(SCH_1):PAGE332
  Q132    1     S1 MOSFET_NCH_DUAL-PJT138K,SMLF,IC,BAM138K0003    I25 @T6G_MB_LIB.T6G(SCH_1):PAGE332
  Q131    1     S1 MOSFET_NCH_DUAL-PJT138K,SMLF,IC,BAM138K0003    I30 @T6G_MB_LIB.T6G(SCH_1):PAGE332
  Q132    4     S2 MOSFET_NCH_DUAL-PJT138K,SMLF,IC,BAM138K0003    I32 @T6G_MB_LIB.T6G(SCH_1):PAGE332
  Q128    1     S1 MOSFET_NCH_DUAL-PJT138K,SMLF,IC,BAM138K0003    I37 @T6G_MB_LIB.T6G(SCH_1):PAGE332
  Q131    4     S2 MOSFET_NCH_DUAL-PJT138K,SMLF,IC,BAM138K0003    I40 @T6G_MB_LIB.T6G(SCH_1):PAGE332
  Q128    4     S2 MOSFET_NCH_DUAL-PJT138K,SMLF,IC,BAM138K0003    I42 @T6G_MB_LIB.T6G(SCH_1):PAGE332
   C15    2      B Q_CAP_0402-0.1UF,25V,10%,X7R,CH4104K1B00    I50 @T6G_MB_LIB.T6G(SCH_1):PAGE332
 R4559    2      B Q_RES_0402LF-100K,1%,1/16W,CHIP,CS41002FB09    I54 @T6G_MB_LIB.T6G(SCH_1):PAGE332
  Q146    1     S1 MOSFET_NCH_DUAL-PJT138K,SMLF,IC,BAM138K0003    I57 @T6G_MB_LIB.T6G(SCH_1):PAGE332
   C18    2      B Q_CAP_0402-0.1UF,25V,10%,X7R,CH4104K1B00    I61 @T6G_MB_LIB.T6G(SCH_1):PAGE332
   C13    2      B Q_CAP_0402-0.1UF,25V,10%,X7R,CH4104K1B00    I64 @T6G_MB_LIB.T6G(SCH_1):PAGE332
   C14    2      B Q_CAP_0402-0.1UF,25V,10%,X7R,CH4104K1B00    I73 @T6G_MB_LIB.T6G(SCH_1):PAGE332
   C12    2      B Q_CAP_0402-0.1UF,25V,10%,X7R,CH4104K1B00    I75 @T6G_MB_LIB.T6G(SCH_1):PAGE332
 R4134    2      B Q_RES_0402LF-100K,1%,1/16W,EMPTY,CS41002FB09    I81 @T6G_MB_LIB.T6G(SCH_1):PAGE332
  Q129    1     S1 MOSFET_NCH_DUAL-PJT138K,SMLF,IC,BAM138K0003    I86 @T6G_MB_LIB.T6G(SCH_1):PAGE332
 R4136    2      B Q_RES_0402LF-100K,1%,1/16W,EMPTY,CS41002FB09    I92 @T6G_MB_LIB.T6G(SCH_1):PAGE332
 R4132    2      B Q_RES_0402LF-100K,1%,1/16W,EMPTY,CS41002FB09    I96 @T6G_MB_LIB.T6G(SCH_1):PAGE332
  Q133    1     S1 MOSFET_NCH_DUAL-PJT138K,SMLF,IC,BAM138K0003    I98 @T6G_MB_LIB.T6G(SCH_1):PAGE332
  Q130    1     S1 MOSFET_NCH_DUAL-PJT138K,SMLF,IC,BAM138K0003   I102 @T6G_MB_LIB.T6G(SCH_1):PAGE332
  Q129    4     S2 MOSFET_NCH_DUAL-PJT138K,SMLF,IC,BAM138K0003   I113 @T6G_MB_LIB.T6G(SCH_1):PAGE332
   C17    2      B Q_CAP_0402-0.1UF,25V,10%,X7R,CH4104K1B00   I118 @T6G_MB_LIB.T6G(SCH_1):PAGE332
  Q133    4     S2 MOSFET_NCH_DUAL-PJT138K,SMLF,IC,BAM138K0003   I120 @T6G_MB_LIB.T6G(SCH_1):PAGE332
  Q130    4     S2 MOSFET_NCH_DUAL-PJT138K,SMLF,IC,BAM138K0003   I123 @T6G_MB_LIB.T6G(SCH_1):PAGE332
   C19    2      B Q_CAP_0402-0.1UF,25V,10%,X7R,CH4104K1B00   I127 @T6G_MB_LIB.T6G(SCH_1):PAGE332
   C16    2      B Q_CAP_0402-0.1UF,25V,10%,X7R,CH4104K1B00   I130 @T6G_MB_LIB.T6G(SCH_1):PAGE332
  Q146    4     S2 MOSFET_NCH_DUAL-PJT138K,SMLF,IC,BAM138K0003   I134 @T6G_MB_LIB.T6G(SCH_1):PAGE332
 R4124    2      B Q_RES_0402LF-100K,1%,1/16W,EMPTY,CS41002FB09   I135 @T6G_MB_LIB.T6G(SCH_1):PAGE332
 R9007    2      B Q_RES_0402LF-100K,1%,1/16W,EMPTY,CS41002FB09     I2 @T6G_MB_LIB.T6G(SCH_1):PAGE330
 Q9001    1     S1 MOSFET_NCH_DUAL-PJT138K,SMLF,IC,BAM138K0003     I3 @T6G_MB_LIB.T6G(SCH_1):PAGE330
 R8001    2      B Q_RES_0402LF-100K,1%,1/16W,EMPTY,CS41002FB09    I12 @T6G_MB_LIB.T6G(SCH_1):PAGE330
 R9003    2      B Q_RES_0402LF-100K,1%,1/16W,EMPTY,CS41002FB09    I20 @T6G_MB_LIB.T6G(SCH_1):PAGE330
 Q9001    4     S2 MOSFET_NCH_DUAL-PJT138K,SMLF,IC,BAM138K0003    I22 @T6G_MB_LIB.T6G(SCH_1):PAGE330
 Q8000    1     S1 MOSFET_NCH_DUAL-PJT138K,SMLF,IC,BAM138K0003    I29 @T6G_MB_LIB.T6G(SCH_1):PAGE330
 Q9000    4     S2 MOSFET_NCH_DUAL-PJT138K,SMLF,IC,BAM138K0003    I31 @T6G_MB_LIB.T6G(SCH_1):PAGE330
 C8000    2      B Q_CAP_0402-1000PF,50V,5%,EMPTY,TMP_QCH21006JB10    I36 @T6G_MB_LIB.T6G(SCH_1):PAGE330
 C9001    2      B Q_CAP_0402-1000PF,50V,5%,EMPTY,TMP_QCH21006JB10    I42 @T6G_MB_LIB.T6G(SCH_1):PAGE330
 C9000    2      B Q_CAP_0402-1000PF,50V,5%,EMPTY,TMP_QCH21006JB10    I45 @T6G_MB_LIB.T6G(SCH_1):PAGE330
 R9015    2      B Q_RES_0402LF-100K,1%,1/16W,EMPTY,CS41002FB09    I50 @T6G_MB_LIB.T6G(SCH_1):PAGE330
 Q9002    1     S1 MOSFET_NCH_DUAL-PJT138K,SMLF,IC,BAM138K0003    I52 @T6G_MB_LIB.T6G(SCH_1):PAGE330
 R3441    2      B Q_RES_0402LF-0,5%,1/16W,CHIP,CS00002JB13    I64 @T6G_MB_LIB.T6G(SCH_1):PAGE330
 R3440    2      B Q_RES_0402LF-0,5%,1/16W,EMPTY,CS00002JB13    I65 @T6G_MB_LIB.T6G(SCH_1):PAGE330
 R3443    2      B Q_RES_0402LF-0,5%,1/16W,CHIP,CS00002JB13    I66 @T6G_MB_LIB.T6G(SCH_1):PAGE330
 R3442    2      B Q_RES_0402LF-0,5%,1/16W,CHIP,CS00002JB13    I67 @T6G_MB_LIB.T6G(SCH_1):PAGE330
 R2656    2      B Q_RES_0402LF-100,1%,1/16W,EMPTY,CS11002FB07    I69 @T6G_MB_LIB.T6G(SCH_1):PAGE330
 C9002    2      B Q_CAP_0402-1000PF,50V,5%,EMPTY,TMP_QCH21006JB10    I71 @T6G_MB_LIB.T6G(SCH_1):PAGE330
 Q9002    4     S2 MOSFET_NCH_DUAL-PJT138K,SMLF,IC,BAM138K0003    I75 @T6G_MB_LIB.T6G(SCH_1):PAGE330
 C6084    2      B Q_CAP_0402-0.1UF,25V,10%,EMPTY,CH4104K1B00   I107 @T6G_MB_LIB.T6G(SCH_1):PAGE371
 C9003    2      B Q_CAP_C0402-1UF,25V,10%,EMPTY,CH5104KEB02   I110 @T6G_MB_LIB.T6G(SCH_1):PAGE371
 C1561    2      B Q_CAP_0402-0.1UF,25V,10%,EMPTY,CH4104K1B00    I96 @T6G_MB_LIB.T6G(SCH_1):PAGE372
 C9004    2      B Q_CAP_C0402-1UF,25V,10%,EMPTY,CH5104KEB02    I99 @T6G_MB_LIB.T6G(SCH_1):PAGE372
  R979    2      B Q_RES_0201LF-10K,1%,1/20W,CHIP,CS31001FE17    I27 @T6G_MB_LIB.T6G(SCH_1):PAGE385
  R980    2      B Q_RES_0201LF-10K,1%,1/20W,CHIP,CS31001FE17    I28 @T6G_MB_LIB.T6G(SCH_1):PAGE385
  R982    2      B Q_RES_0201LF-4.7K,5%,1/20W,CHIP,CS24701JE04    I29 @T6G_MB_LIB.T6G(SCH_1):PAGE385
  R623    2      B Q_RES_0201LF-51.1,1%,1/20W,EMPTY,CS05111FE00    I37 @T6G_MB_LIB.T6G(SCH_1):PAGE385
  R624    2      B Q_RES_0201LF-51.1,1%,1/20W,EMPTY,CS05111FE00    I38 @T6G_MB_LIB.T6G(SCH_1):PAGE385
 U6010  E30 T_SENSE PT5161LRS-PT5161LRS,SMLF,IC,AJ051610U03    I53 @T6G_MB_LIB.T6G(SCH_1):PAGE385
  R984    2      B Q_RES_0201LF-4.7K,5%,1/20W,CHIP,CS24701JE04    I57 @T6G_MB_LIB.T6G(SCH_1):PAGE385
  R995    2      B Q_RES_0201LF-4.7K,5%,1/20W,CHIP,CS24701JE04    I58 @T6G_MB_LIB.T6G(SCH_1):PAGE385
  R997    2      B Q_RES_0201LF-4.7K,5%,1/20W,CHIP,CS24701JE04    I60 @T6G_MB_LIB.T6G(SCH_1):PAGE385
 R1001    2      B Q_RES_0201LF-4.7K,5%,1/20W,EMPTY,CS24701JE04    I71 @T6G_MB_LIB.T6G(SCH_1):PAGE385
  R965    2      B Q_RES_0201LF-1K,1%,1/20W,EMPTY,CS21001FE07    I86 @T6G_MB_LIB.T6G(SCH_1):PAGE385
  R967    2      B Q_RES_0201LF-20K,1%,1/20W,CHIP,CS32001FE00    I87 @T6G_MB_LIB.T6G(SCH_1):PAGE385
  R969    2      B Q_RES_0201LF-1K,1%,1/20W,CHIP,CS21001FE07    I90 @T6G_MB_LIB.T6G(SCH_1):PAGE385
  R971    2      B Q_RES_0201LF-10K,1%,1/20W,CHIP,CS31001FE17    I96 @T6G_MB_LIB.T6G(SCH_1):PAGE385
  R970    2      B Q_RES_0201LF-10K,1%,1/20W,CHIP,CS31001FE17    I97 @T6G_MB_LIB.T6G(SCH_1):PAGE385
 R6821    2      B Q_RES_0201LF-0,5%,1/20W,CHIP,CS00001JE10    I13 @T6G_MB_LIB.T6G(SCH_1):PAGE386
 R6820    2      B Q_RES_0201LF-0,5%,1/20W,CHIP,CS00001JE10    I15 @T6G_MB_LIB.T6G(SCH_1):PAGE386
 U6010 AC13   GND1 PT5161LRS-PT5161LRS,SMLF,IC,AJ051610U03    I17 @T6G_MB_LIB.T6G(SCH_1):PAGE386
 U6010 AC22   GND2 PT5161LRS-PT5161LRS,SMLF,IC,AJ051610U03    I17 @T6G_MB_LIB.T6G(SCH_1):PAGE386
 U6010 AC32   GND3 PT5161LRS-PT5161LRS,SMLF,IC,AJ051610U03    I17 @T6G_MB_LIB.T6G(SCH_1):PAGE386
 U6010  AC4   GND4 PT5161LRS-PT5161LRS,SMLF,IC,AJ051610U03    I17 @T6G_MB_LIB.T6G(SCH_1):PAGE386
 U6010  AD2   GND5 PT5161LRS-PT5161LRS,SMLF,IC,AJ051610U03    I17 @T6G_MB_LIB.T6G(SCH_1):PAGE386
 U6010 AD34   GND6 PT5161LRS-PT5161LRS,SMLF,IC,AJ051610U03    I17 @T6G_MB_LIB.T6G(SCH_1):PAGE386
 U6010  AE1   GND7 PT5161LRS-PT5161LRS,SMLF,IC,AJ051610U03    I17 @T6G_MB_LIB.T6G(SCH_1):PAGE386
 U6010 AE35   GND8 PT5161LRS-PT5161LRS,SMLF,IC,AJ051610U03    I17 @T6G_MB_LIB.T6G(SCH_1):PAGE386
 U6010 AK13   GND9 PT5161LRS-PT5161LRS,SMLF,IC,AJ051610U03    I17 @T6G_MB_LIB.T6G(SCH_1):PAGE386
 U6010 AK22  GND10 PT5161LRS-PT5161LRS,SMLF,IC,AJ051610U03    I17 @T6G_MB_LIB.T6G(SCH_1):PAGE386
 U6010 AK32  GND11 PT5161LRS-PT5161LRS,SMLF,IC,AJ051610U03    I17 @T6G_MB_LIB.T6G(SCH_1):PAGE386
 U6010  AK4  GND12 PT5161LRS-PT5161LRS,SMLF,IC,AJ051610U03    I17 @T6G_MB_LIB.T6G(SCH_1):PAGE386
 U6010  AL2  GND13 PT5161LRS-PT5161LRS,SMLF,IC,AJ051610U03    I17 @T6G_MB_LIB.T6G(SCH_1):PAGE386
 U6010 AL34  GND14 PT5161LRS-PT5161LRS,SMLF,IC,AJ051610U03    I17 @T6G_MB_LIB.T6G(SCH_1):PAGE386
 U6010  AM1  GND15 PT5161LRS-PT5161LRS,SMLF,IC,AJ051610U03    I17 @T6G_MB_LIB.T6G(SCH_1):PAGE386
 U6010 AM35  GND16 PT5161LRS-PT5161LRS,SMLF,IC,AJ051610U03    I17 @T6G_MB_LIB.T6G(SCH_1):PAGE386
 U6010 AU13  GND17 PT5161LRS-PT5161LRS,SMLF,IC,AJ051610U03    I17 @T6G_MB_LIB.T6G(SCH_1):PAGE386
 U6010 AU22  GND18 PT5161LRS-PT5161LRS,SMLF,IC,AJ051610U03    I17 @T6G_MB_LIB.T6G(SCH_1):PAGE386
 U6010 AU32  GND19 PT5161LRS-PT5161LRS,SMLF,IC,AJ051610U03    I17 @T6G_MB_LIB.T6G(SCH_1):PAGE386
 U6010  AU4  GND20 PT5161LRS-PT5161LRS,SMLF,IC,AJ051610U03    I17 @T6G_MB_LIB.T6G(SCH_1):PAGE386
 U6010  AV2  GND21 PT5161LRS-PT5161LRS,SMLF,IC,AJ051610U03    I17 @T6G_MB_LIB.T6G(SCH_1):PAGE386
 U6010 AV34  GND22 PT5161LRS-PT5161LRS,SMLF,IC,AJ051610U03    I17 @T6G_MB_LIB.T6G(SCH_1):PAGE386
 U6010  AW1  GND23 PT5161LRS-PT5161LRS,SMLF,IC,AJ051610U03    I17 @T6G_MB_LIB.T6G(SCH_1):PAGE386
 U6010 AW35  GND24 PT5161LRS-PT5161LRS,SMLF,IC,AJ051610U03    I17 @T6G_MB_LIB.T6G(SCH_1):PAGE386
 U6010  B19  GND25 PT5161LRS-PT5161LRS,SMLF,IC,AJ051610U03    I17 @T6G_MB_LIB.T6G(SCH_1):PAGE386
 U6010 BD13  GND26 PT5161LRS-PT5161LRS,SMLF,IC,AJ051610U03    I17 @T6G_MB_LIB.T6G(SCH_1):PAGE386
 U6010 BD22  GND27 PT5161LRS-PT5161LRS,SMLF,IC,AJ051610U03    I17 @T6G_MB_LIB.T6G(SCH_1):PAGE386
 U6010 BD32  GND28 PT5161LRS-PT5161LRS,SMLF,IC,AJ051610U03    I17 @T6G_MB_LIB.T6G(SCH_1):PAGE386
 U6010  BD4  GND29 PT5161LRS-PT5161LRS,SMLF,IC,AJ051610U03    I17 @T6G_MB_LIB.T6G(SCH_1):PAGE386
 U6010  BE2  GND30 PT5161LRS-PT5161LRS,SMLF,IC,AJ051610U03    I17 @T6G_MB_LIB.T6G(SCH_1):PAGE386
 U6010 BE34  GND31 PT5161LRS-PT5161LRS,SMLF,IC,AJ051610U03    I17 @T6G_MB_LIB.T6G(SCH_1):PAGE386
 U6010  BF1  GND32 PT5161LRS-PT5161LRS,SMLF,IC,AJ051610U03    I17 @T6G_MB_LIB.T6G(SCH_1):PAGE386
 U6010 BF35  GND33 PT5161LRS-PT5161LRS,SMLF,IC,AJ051610U03    I17 @T6G_MB_LIB.T6G(SCH_1):PAGE386
 U6010 BL13  GND34 PT5161LRS-PT5161LRS,SMLF,IC,AJ051610U03    I17 @T6G_MB_LIB.T6G(SCH_1):PAGE386
 U6010 BL22  GND35 PT5161LRS-PT5161LRS,SMLF,IC,AJ051610U03    I17 @T6G_MB_LIB.T6G(SCH_1):PAGE386
 U6010 BL32  GND36 PT5161LRS-PT5161LRS,SMLF,IC,AJ051610U03    I17 @T6G_MB_LIB.T6G(SCH_1):PAGE386
 U6010  BL4  GND37 PT5161LRS-PT5161LRS,SMLF,IC,AJ051610U03    I17 @T6G_MB_LIB.T6G(SCH_1):PAGE386
 U6010  BM2  GND38 PT5161LRS-PT5161LRS,SMLF,IC,AJ051610U03    I17 @T6G_MB_LIB.T6G(SCH_1):PAGE386
 U6010 BM34  GND39 PT5161LRS-PT5161LRS,SMLF,IC,AJ051610U03    I17 @T6G_MB_LIB.T6G(SCH_1):PAGE386
 U6010  BN1  GND40 PT5161LRS-PT5161LRS,SMLF,IC,AJ051610U03    I17 @T6G_MB_LIB.T6G(SCH_1):PAGE386
 U6010 BN35  GND41 PT5161LRS-PT5161LRS,SMLF,IC,AJ051610U03    I17 @T6G_MB_LIB.T6G(SCH_1):PAGE386
 U6010 BV13  GND42 PT5161LRS-PT5161LRS,SMLF,IC,AJ051610U03    I17 @T6G_MB_LIB.T6G(SCH_1):PAGE386
 U6010 BV22  GND43 PT5161LRS-PT5161LRS,SMLF,IC,AJ051610U03    I17 @T6G_MB_LIB.T6G(SCH_1):PAGE386
 U6010 BV32  GND44 PT5161LRS-PT5161LRS,SMLF,IC,AJ051610U03    I17 @T6G_MB_LIB.T6G(SCH_1):PAGE386
 U6010  BV4  GND45 PT5161LRS-PT5161LRS,SMLF,IC,AJ051610U03    I17 @T6G_MB_LIB.T6G(SCH_1):PAGE386
 U6010  BW2  GND46 PT5161LRS-PT5161LRS,SMLF,IC,AJ051610U03    I17 @T6G_MB_LIB.T6G(SCH_1):PAGE386
 U6010 BW34  GND47 PT5161LRS-PT5161LRS,SMLF,IC,AJ051610U03    I17 @T6G_MB_LIB.T6G(SCH_1):PAGE386
 U6010  BY1  GND48 PT5161LRS-PT5161LRS,SMLF,IC,AJ051610U03    I17 @T6G_MB_LIB.T6G(SCH_1):PAGE386
 U6010 BY35  GND49 PT5161LRS-PT5161LRS,SMLF,IC,AJ051610U03    I17 @T6G_MB_LIB.T6G(SCH_1):PAGE386
 U6010 CE13  GND50 PT5161LRS-PT5161LRS,SMLF,IC,AJ051610U03    I17 @T6G_MB_LIB.T6G(SCH_1):PAGE386
 U6010 CE22  GND51 PT5161LRS-PT5161LRS,SMLF,IC,AJ051610U03    I17 @T6G_MB_LIB.T6G(SCH_1):PAGE386
 U6010 CE32  GND52 PT5161LRS-PT5161LRS,SMLF,IC,AJ051610U03    I17 @T6G_MB_LIB.T6G(SCH_1):PAGE386
 U6010  CE4  GND53 PT5161LRS-PT5161LRS,SMLF,IC,AJ051610U03    I17 @T6G_MB_LIB.T6G(SCH_1):PAGE386
 U6010  CF2  GND54 PT5161LRS-PT5161LRS,SMLF,IC,AJ051610U03    I17 @T6G_MB_LIB.T6G(SCH_1):PAGE386
 U6010 CF34  GND55 PT5161LRS-PT5161LRS,SMLF,IC,AJ051610U03    I17 @T6G_MB_LIB.T6G(SCH_1):PAGE386
 U6010  CG1  GND56 PT5161LRS-PT5161LRS,SMLF,IC,AJ051610U03    I17 @T6G_MB_LIB.T6G(SCH_1):PAGE386
 U6010 CG35  GND57 PT5161LRS-PT5161LRS,SMLF,IC,AJ051610U03    I17 @T6G_MB_LIB.T6G(SCH_1):PAGE386
 U6010 CM13  GND58 PT5161LRS-PT5161LRS,SMLF,IC,AJ051610U03    I17 @T6G_MB_LIB.T6G(SCH_1):PAGE386
 U6010 CM22  GND59 PT5161LRS-PT5161LRS,SMLF,IC,AJ051610U03    I17 @T6G_MB_LIB.T6G(SCH_1):PAGE386
 U6010 CM32  GND60 PT5161LRS-PT5161LRS,SMLF,IC,AJ051610U03    I17 @T6G_MB_LIB.T6G(SCH_1):PAGE386
 U6010  CM4  GND61 PT5161LRS-PT5161LRS,SMLF,IC,AJ051610U03    I17 @T6G_MB_LIB.T6G(SCH_1):PAGE386
 U6010  CN2  GND62 PT5161LRS-PT5161LRS,SMLF,IC,AJ051610U03    I17 @T6G_MB_LIB.T6G(SCH_1):PAGE386
 U6010 CN34  GND63 PT5161LRS-PT5161LRS,SMLF,IC,AJ051610U03    I17 @T6G_MB_LIB.T6G(SCH_1):PAGE386
 U6010  CP1  GND64 PT5161LRS-PT5161LRS,SMLF,IC,AJ051610U03    I17 @T6G_MB_LIB.T6G(SCH_1):PAGE386
 U6010 CP35  GND65 PT5161LRS-PT5161LRS,SMLF,IC,AJ051610U03    I17 @T6G_MB_LIB.T6G(SCH_1):PAGE386
 U6010 CW13  GND66 PT5161LRS-PT5161LRS,SMLF,IC,AJ051610U03    I17 @T6G_MB_LIB.T6G(SCH_1):PAGE386
 U6010 CW22  GND67 PT5161LRS-PT5161LRS,SMLF,IC,AJ051610U03    I17 @T6G_MB_LIB.T6G(SCH_1):PAGE386
 U6010 CW32  GND68 PT5161LRS-PT5161LRS,SMLF,IC,AJ051610U03    I17 @T6G_MB_LIB.T6G(SCH_1):PAGE386
 U6010  CW4  GND69 PT5161LRS-PT5161LRS,SMLF,IC,AJ051610U03    I17 @T6G_MB_LIB.T6G(SCH_1):PAGE386
 U6010  CY2  GND70 PT5161LRS-PT5161LRS,SMLF,IC,AJ051610U03    I17 @T6G_MB_LIB.T6G(SCH_1):PAGE386
 U6010 CY34  GND71 PT5161LRS-PT5161LRS,SMLF,IC,AJ051610U03    I17 @T6G_MB_LIB.T6G(SCH_1):PAGE386
 U6010  DA1  GND72 PT5161LRS-PT5161LRS,SMLF,IC,AJ051610U03    I17 @T6G_MB_LIB.T6G(SCH_1):PAGE386
 U6010 DA35  GND73 PT5161LRS-PT5161LRS,SMLF,IC,AJ051610U03    I17 @T6G_MB_LIB.T6G(SCH_1):PAGE386
 U6010 DF13  GND74 PT5161LRS-PT5161LRS,SMLF,IC,AJ051610U03    I17 @T6G_MB_LIB.T6G(SCH_1):PAGE386
 U6010 DF22  GND75 PT5161LRS-PT5161LRS,SMLF,IC,AJ051610U03    I17 @T6G_MB_LIB.T6G(SCH_1):PAGE386
 U6010 DF32  GND76 PT5161LRS-PT5161LRS,SMLF,IC,AJ051610U03    I17 @T6G_MB_LIB.T6G(SCH_1):PAGE386
 U6010  DF4  GND77 PT5161LRS-PT5161LRS,SMLF,IC,AJ051610U03    I17 @T6G_MB_LIB.T6G(SCH_1):PAGE386
 U6010  DG2  GND78 PT5161LRS-PT5161LRS,SMLF,IC,AJ051610U03    I17 @T6G_MB_LIB.T6G(SCH_1):PAGE386
 U6010 DG34  GND79 PT5161LRS-PT5161LRS,SMLF,IC,AJ051610U03    I17 @T6G_MB_LIB.T6G(SCH_1):PAGE386
 U6010  DH1  GND80 PT5161LRS-PT5161LRS,SMLF,IC,AJ051610U03    I17 @T6G_MB_LIB.T6G(SCH_1):PAGE386
 U6010 DH35  GND81 PT5161LRS-PT5161LRS,SMLF,IC,AJ051610U03    I17 @T6G_MB_LIB.T6G(SCH_1):PAGE386
 U6010 DN13  GND82 PT5161LRS-PT5161LRS,SMLF,IC,AJ051610U03    I17 @T6G_MB_LIB.T6G(SCH_1):PAGE386
 U6010 DN22  GND83 PT5161LRS-PT5161LRS,SMLF,IC,AJ051610U03    I17 @T6G_MB_LIB.T6G(SCH_1):PAGE386
 U6010 DN32  GND84 PT5161LRS-PT5161LRS,SMLF,IC,AJ051610U03    I17 @T6G_MB_LIB.T6G(SCH_1):PAGE386
 U6010  DN4  GND85 PT5161LRS-PT5161LRS,SMLF,IC,AJ051610U03    I17 @T6G_MB_LIB.T6G(SCH_1):PAGE386
 U6010  DP2  GND86 PT5161LRS-PT5161LRS,SMLF,IC,AJ051610U03    I17 @T6G_MB_LIB.T6G(SCH_1):PAGE386
 U6010 DP34  GND87 PT5161LRS-PT5161LRS,SMLF,IC,AJ051610U03    I17 @T6G_MB_LIB.T6G(SCH_1):PAGE386
 U6010  DR1  GND88 PT5161LRS-PT5161LRS,SMLF,IC,AJ051610U03    I17 @T6G_MB_LIB.T6G(SCH_1):PAGE386
 U6010 DR35  GND89 PT5161LRS-PT5161LRS,SMLF,IC,AJ051610U03    I17 @T6G_MB_LIB.T6G(SCH_1):PAGE386
 U6010 DY13  GND90 PT5161LRS-PT5161LRS,SMLF,IC,AJ051610U03    I17 @T6G_MB_LIB.T6G(SCH_1):PAGE386
 U6010 DY22  GND91 PT5161LRS-PT5161LRS,SMLF,IC,AJ051610U03    I17 @T6G_MB_LIB.T6G(SCH_1):PAGE386
 U6010 DY32  GND92 PT5161LRS-PT5161LRS,SMLF,IC,AJ051610U03    I17 @T6G_MB_LIB.T6G(SCH_1):PAGE386
 U6010  DY4  GND93 PT5161LRS-PT5161LRS,SMLF,IC,AJ051610U03    I17 @T6G_MB_LIB.T6G(SCH_1):PAGE386
 U6010  E14  GND94 PT5161LRS-PT5161LRS,SMLF,IC,AJ051610U03    I17 @T6G_MB_LIB.T6G(SCH_1):PAGE386
 U6010  E27  GND95 PT5161LRS-PT5161LRS,SMLF,IC,AJ051610U03    I17 @T6G_MB_LIB.T6G(SCH_1):PAGE386
 U6010  E33  GND96 PT5161LRS-PT5161LRS,SMLF,IC,AJ051610U03    I17 @T6G_MB_LIB.T6G(SCH_1):PAGE386
 U6010  EA2  GND97 PT5161LRS-PT5161LRS,SMLF,IC,AJ051610U03    I17 @T6G_MB_LIB.T6G(SCH_1):PAGE386
 U6010 EA34  GND98 PT5161LRS-PT5161LRS,SMLF,IC,AJ051610U03    I17 @T6G_MB_LIB.T6G(SCH_1):PAGE386
 U6010  EB1  GND99 PT5161LRS-PT5161LRS,SMLF,IC,AJ051610U03    I17 @T6G_MB_LIB.T6G(SCH_1):PAGE386
 U6010 EB35 GND100 PT5161LRS-PT5161LRS,SMLF,IC,AJ051610U03    I17 @T6G_MB_LIB.T6G(SCH_1):PAGE386
 U6010 EG13 GND101 PT5161LRS-PT5161LRS,SMLF,IC,AJ051610U03    I17 @T6G_MB_LIB.T6G(SCH_1):PAGE386
 U6010 EG22 GND102 PT5161LRS-PT5161LRS,SMLF,IC,AJ051610U03    I17 @T6G_MB_LIB.T6G(SCH_1):PAGE386
 U6010 EG32 GND103 PT5161LRS-PT5161LRS,SMLF,IC,AJ051610U03    I17 @T6G_MB_LIB.T6G(SCH_1):PAGE386
 U6010  EG4 GND104 PT5161LRS-PT5161LRS,SMLF,IC,AJ051610U03    I17 @T6G_MB_LIB.T6G(SCH_1):PAGE386
 U6010  EH2 GND105 PT5161LRS-PT5161LRS,SMLF,IC,AJ051610U03    I17 @T6G_MB_LIB.T6G(SCH_1):PAGE386
 U6010 EH34 GND106 PT5161LRS-PT5161LRS,SMLF,IC,AJ051610U03    I17 @T6G_MB_LIB.T6G(SCH_1):PAGE386
 U6010  EJ1 GND107 PT5161LRS-PT5161LRS,SMLF,IC,AJ051610U03    I17 @T6G_MB_LIB.T6G(SCH_1):PAGE386
 U6010 EJ35 GND108 PT5161LRS-PT5161LRS,SMLF,IC,AJ051610U03    I17 @T6G_MB_LIB.T6G(SCH_1):PAGE386
 U6010 EP13 GND109 PT5161LRS-PT5161LRS,SMLF,IC,AJ051610U03    I17 @T6G_MB_LIB.T6G(SCH_1):PAGE386
 U6010 EP22 GND110 PT5161LRS-PT5161LRS,SMLF,IC,AJ051610U03    I17 @T6G_MB_LIB.T6G(SCH_1):PAGE386
 U6010 EP32 GND111 PT5161LRS-PT5161LRS,SMLF,IC,AJ051610U03    I17 @T6G_MB_LIB.T6G(SCH_1):PAGE386
 U6010  EP4 GND112 PT5161LRS-PT5161LRS,SMLF,IC,AJ051610U03    I17 @T6G_MB_LIB.T6G(SCH_1):PAGE386
 U6010  ER2 GND113 PT5161LRS-PT5161LRS,SMLF,IC,AJ051610U03    I17 @T6G_MB_LIB.T6G(SCH_1):PAGE386
 U6010 ER34 GND114 PT5161LRS-PT5161LRS,SMLF,IC,AJ051610U03    I17 @T6G_MB_LIB.T6G(SCH_1):PAGE386
 U6010  ET1 GND115 PT5161LRS-PT5161LRS,SMLF,IC,AJ051610U03    I17 @T6G_MB_LIB.T6G(SCH_1):PAGE386
 U6010 ET35 GND116 PT5161LRS-PT5161LRS,SMLF,IC,AJ051610U03    I17 @T6G_MB_LIB.T6G(SCH_1):PAGE386
 U6010 FA15 GND117 PT5161LRS-PT5161LRS,SMLF,IC,AJ051610U03    I17 @T6G_MB_LIB.T6G(SCH_1):PAGE386
 U6010 FA32 GND118 PT5161LRS-PT5161LRS,SMLF,IC,AJ051610U03    I17 @T6G_MB_LIB.T6G(SCH_1):PAGE386
 U6010  FB2 GND119 PT5161LRS-PT5161LRS,SMLF,IC,AJ051610U03    I17 @T6G_MB_LIB.T6G(SCH_1):PAGE386
 U6010 FB34 GND120 PT5161LRS-PT5161LRS,SMLF,IC,AJ051610U03    I17 @T6G_MB_LIB.T6G(SCH_1):PAGE386
 U6010 FC19 GND121 PT5161LRS-PT5161LRS,SMLF,IC,AJ051610U03    I17 @T6G_MB_LIB.T6G(SCH_1):PAGE386
 U6010 FC23 GND122 PT5161LRS-PT5161LRS,SMLF,IC,AJ051610U03    I17 @T6G_MB_LIB.T6G(SCH_1):PAGE386
 U6010 FC25 GND123 PT5161LRS-PT5161LRS,SMLF,IC,AJ051610U03    I17 @T6G_MB_LIB.T6G(SCH_1):PAGE386
 U6010 FC28 GND124 PT5161LRS-PT5161LRS,SMLF,IC,AJ051610U03    I17 @T6G_MB_LIB.T6G(SCH_1):PAGE386
 U6010  FC3 GND125 PT5161LRS-PT5161LRS,SMLF,IC,AJ051610U03    I17 @T6G_MB_LIB.T6G(SCH_1):PAGE386
 U6010  FC6 GND126 PT5161LRS-PT5161LRS,SMLF,IC,AJ051610U03    I17 @T6G_MB_LIB.T6G(SCH_1):PAGE386
 U6010  FC9 GND127 PT5161LRS-PT5161LRS,SMLF,IC,AJ051610U03    I17 @T6G_MB_LIB.T6G(SCH_1):PAGE386
 U6010  FD1 GND128 PT5161LRS-PT5161LRS,SMLF,IC,AJ051610U03    I17 @T6G_MB_LIB.T6G(SCH_1):PAGE386
 U6010 FD35 GND129 PT5161LRS-PT5161LRS,SMLF,IC,AJ051610U03    I17 @T6G_MB_LIB.T6G(SCH_1):PAGE386
 U6010 FF14 GND130 PT5161LRS-PT5161LRS,SMLF,IC,AJ051610U03    I17 @T6G_MB_LIB.T6G(SCH_1):PAGE386
 U6010 FF21 GND131 PT5161LRS-PT5161LRS,SMLF,IC,AJ051610U03    I17 @T6G_MB_LIB.T6G(SCH_1):PAGE386
 U6010 FJ12 GND132 PT5161LRS-PT5161LRS,SMLF,IC,AJ051610U03    I17 @T6G_MB_LIB.T6G(SCH_1):PAGE386
 U6010 FJ19 GND133 PT5161LRS-PT5161LRS,SMLF,IC,AJ051610U03    I17 @T6G_MB_LIB.T6G(SCH_1):PAGE386
 U6010  H12 GND134 PT5161LRS-PT5161LRS,SMLF,IC,AJ051610U03    I17 @T6G_MB_LIB.T6G(SCH_1):PAGE386
 U6010  H16 GND135 PT5161LRS-PT5161LRS,SMLF,IC,AJ051610U03    I17 @T6G_MB_LIB.T6G(SCH_1):PAGE386
 U6010  H19 GND136 PT5161LRS-PT5161LRS,SMLF,IC,AJ051610U03    I17 @T6G_MB_LIB.T6G(SCH_1):PAGE386
 U6010  H31 GND137 PT5161LRS-PT5161LRS,SMLF,IC,AJ051610U03    I17 @T6G_MB_LIB.T6G(SCH_1):PAGE386
 U6010  J22 GND138 PT5161LRS-PT5161LRS,SMLF,IC,AJ051610U03    I17 @T6G_MB_LIB.T6G(SCH_1):PAGE386
 U6010   J4 GND139 PT5161LRS-PT5161LRS,SMLF,IC,AJ051610U03    I17 @T6G_MB_LIB.T6G(SCH_1):PAGE386
 U6010   K2 GND140 PT5161LRS-PT5161LRS,SMLF,IC,AJ051610U03    I17 @T6G_MB_LIB.T6G(SCH_1):PAGE386
 U6010  K34 GND141 PT5161LRS-PT5161LRS,SMLF,IC,AJ051610U03    I17 @T6G_MB_LIB.T6G(SCH_1):PAGE386
 U6010   L1 GND142 PT5161LRS-PT5161LRS,SMLF,IC,AJ051610U03    I17 @T6G_MB_LIB.T6G(SCH_1):PAGE386
 U6010  L35 GND143 PT5161LRS-PT5161LRS,SMLF,IC,AJ051610U03    I17 @T6G_MB_LIB.T6G(SCH_1):PAGE386
 U6010  T13 GND144 PT5161LRS-PT5161LRS,SMLF,IC,AJ051610U03    I17 @T6G_MB_LIB.T6G(SCH_1):PAGE386
 U6010  T22 GND145 PT5161LRS-PT5161LRS,SMLF,IC,AJ051610U03    I17 @T6G_MB_LIB.T6G(SCH_1):PAGE386
 U6010  T32 GND146 PT5161LRS-PT5161LRS,SMLF,IC,AJ051610U03    I17 @T6G_MB_LIB.T6G(SCH_1):PAGE386
 U6010   T4 GND147 PT5161LRS-PT5161LRS,SMLF,IC,AJ051610U03    I17 @T6G_MB_LIB.T6G(SCH_1):PAGE386
 U6010   U2 GND148 PT5161LRS-PT5161LRS,SMLF,IC,AJ051610U03    I17 @T6G_MB_LIB.T6G(SCH_1):PAGE386
 U6010  U34 GND149 PT5161LRS-PT5161LRS,SMLF,IC,AJ051610U03    I17 @T6G_MB_LIB.T6G(SCH_1):PAGE386
 U6010   V1 GND150 PT5161LRS-PT5161LRS,SMLF,IC,AJ051610U03    I17 @T6G_MB_LIB.T6G(SCH_1):PAGE386
 U6010  V35 GND151 PT5161LRS-PT5161LRS,SMLF,IC,AJ051610U03    I17 @T6G_MB_LIB.T6G(SCH_1):PAGE386
 C7510    2      B Q_CAP_C0201-0.1UF,10V,10%,X7S,CH4102K6E00    I21 @T6G_MB_LIB.T6G(SCH_1):PAGE387
 R6822    2      B Q_RES_0201LF-1K,1%,1/20W,CHIP,CS21001FE07    I24 @T6G_MB_LIB.T6G(SCH_1):PAGE387
  C513    2      B Q_CAP_0201-1UF,4V,20%,X6S,CH-10KMEE00     I8 @T6G_MB_LIB.T6G(SCH_1):PAGE388
  C516    2      B Q_CAP_C0201-0.1UF,10V,10%,X7S,CH4102K6E00     I9 @T6G_MB_LIB.T6G(SCH_1):PAGE388
  C503    2      B Q_CAP_C0805-100UF,4V,20%,X6S,CH710KMEA01    I13 @T6G_MB_LIB.T6G(SCH_1):PAGE388
  C505    2      B Q_CAP_C0402-22UF,4V,20%,X6S,CH622KMEB02    I14 @T6G_MB_LIB.T6G(SCH_1):PAGE388
  C502    2      B Q_CAP_C0805-100UF,4V,20%,X6S,CH710KMEA01    I16 @T6G_MB_LIB.T6G(SCH_1):PAGE388
  C507    2      B Q_CAP_C0402-10UF,6.3V,20%,X6S,CH6101MEB01    I17 @T6G_MB_LIB.T6G(SCH_1):PAGE388
  C510    2      B Q_CAP_0402-4.7UF,6.3V,20%,X6S,CH5471MEB01    I18 @T6G_MB_LIB.T6G(SCH_1):PAGE388
  C512    2      B Q_CAP_0201-1UF,4V,20%,X6S,CH-10KMEE00    I19 @T6G_MB_LIB.T6G(SCH_1):PAGE388
  C514    2      B Q_CAP_0201-1UF,4V,20%,X6S,CH-10KMEE00    I22 @T6G_MB_LIB.T6G(SCH_1):PAGE388
  C515    2      B Q_CAP_C0201-0.1UF,10V,10%,X7S,CH4102K6E00    I23 @T6G_MB_LIB.T6G(SCH_1):PAGE388
  C504    2      B Q_CAP_C0402-22UF,4V,20%,X6S,CH622KMEB02    I24 @T6G_MB_LIB.T6G(SCH_1):PAGE388
  C506    2      B Q_CAP_C0402-10UF,6.3V,20%,X6S,CH6101MEB01    I25 @T6G_MB_LIB.T6G(SCH_1):PAGE388
  C511    2      B Q_CAP_0402-4.7UF,6.3V,20%,X6S,CH5471MEB01    I26 @T6G_MB_LIB.T6G(SCH_1):PAGE388
  C517    2      B Q_CAP_C0201-0.1UF,10V,10%,X7S,CH4102K6E00    I27 @T6G_MB_LIB.T6G(SCH_1):PAGE388
  C519    2      B Q_CAP_C0201-0.1UF,10V,10%,X7S,CH4102K6E00    I28 @T6G_MB_LIB.T6G(SCH_1):PAGE388
  C520    2      B Q_CAP_C0201-0.1UF,10V,10%,X7S,CH4102K6E00    I29 @T6G_MB_LIB.T6G(SCH_1):PAGE388
  C538    2      B Q_CAP_C0201-0.1UF,10V,10%,X7S,CH4102K6E00    I32 @T6G_MB_LIB.T6G(SCH_1):PAGE388
  C544    2      B Q_CAP_C0201-0.1UF,10V,10%,X7S,CH4102K6E00    I36 @T6G_MB_LIB.T6G(SCH_1):PAGE388
  C576    2      B Q_CAP_C0201-0.1UF,10V,10%,X7S,CH4102K6E00    I38 @T6G_MB_LIB.T6G(SCH_1):PAGE388
  C580    2      B Q_CAP_C0201-0.1UF,10V,10%,X7S,CH4102K6E00    I39 @T6G_MB_LIB.T6G(SCH_1):PAGE388
  C555    2      B Q_CAP_0201-1UF,4V,20%,X6S,CH-10KMEE00    I40 @T6G_MB_LIB.T6G(SCH_1):PAGE388
  C561    2      B Q_CAP_C0402-10UF,6.3V,20%,X6S,CH6101MEB01    I41 @T6G_MB_LIB.T6G(SCH_1):PAGE388
  C539    2      B Q_CAP_0201-1UF,4V,20%,X6S,CH-10KMEE00    I42 @T6G_MB_LIB.T6G(SCH_1):PAGE388
  C562    2      B Q_CAP_0201-1UF,4V,20%,X6S,CH-10KMEE00    I43 @T6G_MB_LIB.T6G(SCH_1):PAGE388
  C579    2      B Q_CAP_C0402-10UF,6.3V,20%,X6S,CH6101MEB01    I44 @T6G_MB_LIB.T6G(SCH_1):PAGE388
  C554    2      B Q_CAP_0402-4.7UF,6.3V,20%,X6S,CH5471MEB01    I45 @T6G_MB_LIB.T6G(SCH_1):PAGE388
  C571    2      B Q_CAP_0402-4.7UF,6.3V,20%,X6S,CH5471MEB01    I46 @T6G_MB_LIB.T6G(SCH_1):PAGE388
  C541    2      B Q_CAP_C0201-0.1UF,10V,10%,X7S,CH4102K6E00    I48 @T6G_MB_LIB.T6G(SCH_1):PAGE388
  C582    2      B Q_CAP_C0201-0.1UF,10V,10%,X7S,CH4102K6E00    I49 @T6G_MB_LIB.T6G(SCH_1):PAGE388
  C523    2      B Q_CAP_C0201-0.1UF,10V,10%,X7S,CH4102K6E00    I50 @T6G_MB_LIB.T6G(SCH_1):PAGE388
  C585    2      B Q_CAP_C0201-0.1UF,10V,10%,X7S,CH4102K6E00    I51 @T6G_MB_LIB.T6G(SCH_1):PAGE388
  C570    2      B Q_CAP_0201-1UF,4V,20%,X6S,CH-10KMEE00    I52 @T6G_MB_LIB.T6G(SCH_1):PAGE388
  C573    2      B Q_CAP_0201-1UF,4V,20%,X6S,CH-10KMEE00    I53 @T6G_MB_LIB.T6G(SCH_1):PAGE388
  C557    2      B Q_CAP_0402-4.7UF,6.3V,20%,X6S,CH5471MEB01    I54 @T6G_MB_LIB.T6G(SCH_1):PAGE388
  C572    2      B Q_CAP_0402-4.7UF,6.3V,20%,X6S,CH5471MEB01    I55 @T6G_MB_LIB.T6G(SCH_1):PAGE388
  C577    2      B Q_CAP_0201-1UF,4V,20%,X6S,CH-10KMEE00    I56 @T6G_MB_LIB.T6G(SCH_1):PAGE388
  C581    2      B Q_CAP_0201-1UF,4V,20%,X6S,CH-10KMEE00    I57 @T6G_MB_LIB.T6G(SCH_1):PAGE388
  C525    2      B Q_CAP_0201-1UF,4V,20%,X6S,CH-10KMEE00    I58 @T6G_MB_LIB.T6G(SCH_1):PAGE388
  C529    2      B Q_CAP_0201-1UF,4V,20%,X6S,CH-10KMEE00    I59 @T6G_MB_LIB.T6G(SCH_1):PAGE388
  C558    2      B Q_CAP_C0201-0.1UF,10V,10%,X7S,CH4102K6E00    I60 @T6G_MB_LIB.T6G(SCH_1):PAGE388
  C543    2      B Q_CAP_C0201-0.1UF,10V,10%,X7S,CH4102K6E00    I62 @T6G_MB_LIB.T6G(SCH_1):PAGE388
  C521    2      B Q_CAP_0201-1UF,4V,20%,X6S,CH-10KMEE00    I65 @T6G_MB_LIB.T6G(SCH_1):PAGE388
  C526    2      B Q_CAP_0201-1UF,4V,20%,X6S,CH-10KMEE00    I66 @T6G_MB_LIB.T6G(SCH_1):PAGE388
  C550    2      B Q_CAP_C0805-100UF,4V,20%,X6S,CH710KMEA01    I67 @T6G_MB_LIB.T6G(SCH_1):PAGE388
  C556    2      B Q_CAP_C0805-100UF,4V,20%,X6S,CH710KMEA01    I69 @T6G_MB_LIB.T6G(SCH_1):PAGE388
  C560    2      B Q_CAP_C0805-100UF,4V,20%,X6S,CH710KMEA01    I70 @T6G_MB_LIB.T6G(SCH_1):PAGE388
  C564    2      B Q_CAP_C0805-100UF,4V,20%,X6S,CH710KMEA01    I71 @T6G_MB_LIB.T6G(SCH_1):PAGE388
  C559    2      B Q_CAP_C0805-100UF,4V,20%,X6S,CH710KMEA01    I72 @T6G_MB_LIB.T6G(SCH_1):PAGE388
  C574    2      B Q_CAP_C0402-10UF,6.3V,20%,X6S,CH6101MEB01    I73 @T6G_MB_LIB.T6G(SCH_1):PAGE388
  C563    2      B Q_CAP_C0402-22UF,4V,20%,X6S,CH622KMEB02    I74 @T6G_MB_LIB.T6G(SCH_1):PAGE388
  C586    2      B Q_CAP_C0402-22UF,4V,20%,X6S,CH622KMEB02    I75 @T6G_MB_LIB.T6G(SCH_1):PAGE388
  C565    2      B Q_CAP_C0402-22UF,4V,20%,X6S,CH622KMEB02    I76 @T6G_MB_LIB.T6G(SCH_1):PAGE388
  C575    2      B Q_CAP_C0402-22UF,4V,20%,X6S,CH622KMEB02    I77 @T6G_MB_LIB.T6G(SCH_1):PAGE388
  C568    2      B Q_CAP_C0402-22UF,4V,20%,X6S,CH622KMEB02    I78 @T6G_MB_LIB.T6G(SCH_1):PAGE388
  C569    2      B Q_CAP_0402-4.7UF,6.3V,20%,X6S,CH5471MEB01    I79 @T6G_MB_LIB.T6G(SCH_1):PAGE388
  C528    2      B Q_CAP_0201-1UF,4V,20%,X6S,CH-10KMEE00    I80 @T6G_MB_LIB.T6G(SCH_1):PAGE388
  C522    2      B Q_CAP_C0201-0.1UF,10V,10%,X7S,CH4102K6E00    I81 @T6G_MB_LIB.T6G(SCH_1):PAGE388
  C584    2      B Q_CAP_C0402-10UF,6.3V,20%,X6S,CH6101MEB01    I82 @T6G_MB_LIB.T6G(SCH_1):PAGE388
  C567    2      B Q_CAP_C0402-10UF,6.3V,20%,X6S,CH6101MEB01    I83 @T6G_MB_LIB.T6G(SCH_1):PAGE388
  C524    2      B Q_CAP_C0201-0.1UF,10V,10%,X7S,CH4102K6E00    I84 @T6G_MB_LIB.T6G(SCH_1):PAGE388
  C578    2      B Q_CAP_C0201-0.1UF,10V,10%,X7S,CH4102K6E00    I85 @T6G_MB_LIB.T6G(SCH_1):PAGE388
  C540    2      B Q_CAP_C0201-0.1UF,10V,10%,X7S,CH4102K6E00    I87 @T6G_MB_LIB.T6G(SCH_1):PAGE388
 R1028    2      B Q_RES_0201LF-10K,1%,1/20W,CHIP,CS31001FE17     I7 @T6G_MB_LIB.T6G(SCH_1):PAGE408
 R1029    2      B Q_RES_0201LF-10K,1%,1/20W,CHIP,CS31001FE17     I8 @T6G_MB_LIB.T6G(SCH_1):PAGE408
 R1031    2      B Q_RES_0201LF-4.7K,5%,1/20W,CHIP,CS24701JE04     I9 @T6G_MB_LIB.T6G(SCH_1):PAGE408
 R1033    2      B Q_RES_0201LF-4.7K,5%,1/20W,CHIP,CS24701JE04    I36 @T6G_MB_LIB.T6G(SCH_1):PAGE408
 R1035    2      B Q_RES_0201LF-4.7K,5%,1/20W,CHIP,CS24701JE04    I37 @T6G_MB_LIB.T6G(SCH_1):PAGE408
 R1037    2      B Q_RES_0201LF-4.7K,5%,1/20W,CHIP,CS24701JE04    I39 @T6G_MB_LIB.T6G(SCH_1):PAGE408
 R1006    2      B Q_RES_0201LF-4.7K,5%,1/20W,EMPTY,CS24701JE04    I50 @T6G_MB_LIB.T6G(SCH_1):PAGE408
 R1014    2      B Q_RES_0201LF-1K,1%,1/20W,EMPTY,CS21001FE07    I64 @T6G_MB_LIB.T6G(SCH_1):PAGE408
 R1016    2      B Q_RES_0201LF-20K,1%,1/20W,CHIP,CS32001FE00    I65 @T6G_MB_LIB.T6G(SCH_1):PAGE408
 R1018    2      B Q_RES_0201LF-1K,1%,1/20W,CHIP,CS21001FE07    I68 @T6G_MB_LIB.T6G(SCH_1):PAGE408
 R1019    2      B Q_RES_0201LF-10K,1%,1/20W,CHIP,CS31001FE17    I73 @T6G_MB_LIB.T6G(SCH_1):PAGE408
 R1020    2      B Q_RES_0201LF-10K,1%,1/20W,CHIP,CS31001FE17    I74 @T6G_MB_LIB.T6G(SCH_1):PAGE408
 U6011  E30 T_SENSE PT5161LRS-PT5161LRS,SMLF,IC,AJ051610U03    I83 @T6G_MB_LIB.T6G(SCH_1):PAGE408
 R1042    2      B Q_RES_0201LF-0,5%,1/20W,CHIP,CS00001JE10    I13 @T6G_MB_LIB.T6G(SCH_1):PAGE409
 R1043    2      B Q_RES_0201LF-0,5%,1/20W,CHIP,CS00001JE10    I15 @T6G_MB_LIB.T6G(SCH_1):PAGE409
 U6011 AC13   GND1 PT5161LRS-PT5161LRS,SMLF,IC,AJ051610U03    I17 @T6G_MB_LIB.T6G(SCH_1):PAGE409
 U6011 AC22   GND2 PT5161LRS-PT5161LRS,SMLF,IC,AJ051610U03    I17 @T6G_MB_LIB.T6G(SCH_1):PAGE409
 U6011 AC32   GND3 PT5161LRS-PT5161LRS,SMLF,IC,AJ051610U03    I17 @T6G_MB_LIB.T6G(SCH_1):PAGE409
 U6011  AC4   GND4 PT5161LRS-PT5161LRS,SMLF,IC,AJ051610U03    I17 @T6G_MB_LIB.T6G(SCH_1):PAGE409
 U6011  AD2   GND5 PT5161LRS-PT5161LRS,SMLF,IC,AJ051610U03    I17 @T6G_MB_LIB.T6G(SCH_1):PAGE409
 U6011 AD34   GND6 PT5161LRS-PT5161LRS,SMLF,IC,AJ051610U03    I17 @T6G_MB_LIB.T6G(SCH_1):PAGE409
 U6011  AE1   GND7 PT5161LRS-PT5161LRS,SMLF,IC,AJ051610U03    I17 @T6G_MB_LIB.T6G(SCH_1):PAGE409
 U6011 AE35   GND8 PT5161LRS-PT5161LRS,SMLF,IC,AJ051610U03    I17 @T6G_MB_LIB.T6G(SCH_1):PAGE409
 U6011 AK13   GND9 PT5161LRS-PT5161LRS,SMLF,IC,AJ051610U03    I17 @T6G_MB_LIB.T6G(SCH_1):PAGE409
 U6011 AK22  GND10 PT5161LRS-PT5161LRS,SMLF,IC,AJ051610U03    I17 @T6G_MB_LIB.T6G(SCH_1):PAGE409
 U6011 AK32  GND11 PT5161LRS-PT5161LRS,SMLF,IC,AJ051610U03    I17 @T6G_MB_LIB.T6G(SCH_1):PAGE409
 U6011  AK4  GND12 PT5161LRS-PT5161LRS,SMLF,IC,AJ051610U03    I17 @T6G_MB_LIB.T6G(SCH_1):PAGE409
 U6011  AL2  GND13 PT5161LRS-PT5161LRS,SMLF,IC,AJ051610U03    I17 @T6G_MB_LIB.T6G(SCH_1):PAGE409
 U6011 AL34  GND14 PT5161LRS-PT5161LRS,SMLF,IC,AJ051610U03    I17 @T6G_MB_LIB.T6G(SCH_1):PAGE409
 U6011  AM1  GND15 PT5161LRS-PT5161LRS,SMLF,IC,AJ051610U03    I17 @T6G_MB_LIB.T6G(SCH_1):PAGE409
 U6011 AM35  GND16 PT5161LRS-PT5161LRS,SMLF,IC,AJ051610U03    I17 @T6G_MB_LIB.T6G(SCH_1):PAGE409
 U6011 AU13  GND17 PT5161LRS-PT5161LRS,SMLF,IC,AJ051610U03    I17 @T6G_MB_LIB.T6G(SCH_1):PAGE409
 U6011 AU22  GND18 PT5161LRS-PT5161LRS,SMLF,IC,AJ051610U03    I17 @T6G_MB_LIB.T6G(SCH_1):PAGE409
 U6011 AU32  GND19 PT5161LRS-PT5161LRS,SMLF,IC,AJ051610U03    I17 @T6G_MB_LIB.T6G(SCH_1):PAGE409
 U6011  AU4  GND20 PT5161LRS-PT5161LRS,SMLF,IC,AJ051610U03    I17 @T6G_MB_LIB.T6G(SCH_1):PAGE409
 U6011  AV2  GND21 PT5161LRS-PT5161LRS,SMLF,IC,AJ051610U03    I17 @T6G_MB_LIB.T6G(SCH_1):PAGE409
 U6011 AV34  GND22 PT5161LRS-PT5161LRS,SMLF,IC,AJ051610U03    I17 @T6G_MB_LIB.T6G(SCH_1):PAGE409
 U6011  AW1  GND23 PT5161LRS-PT5161LRS,SMLF,IC,AJ051610U03    I17 @T6G_MB_LIB.T6G(SCH_1):PAGE409
 U6011 AW35  GND24 PT5161LRS-PT5161LRS,SMLF,IC,AJ051610U03    I17 @T6G_MB_LIB.T6G(SCH_1):PAGE409
 U6011  B19  GND25 PT5161LRS-PT5161LRS,SMLF,IC,AJ051610U03    I17 @T6G_MB_LIB.T6G(SCH_1):PAGE409
 U6011 BD13  GND26 PT5161LRS-PT5161LRS,SMLF,IC,AJ051610U03    I17 @T6G_MB_LIB.T6G(SCH_1):PAGE409
 U6011 BD22  GND27 PT5161LRS-PT5161LRS,SMLF,IC,AJ051610U03    I17 @T6G_MB_LIB.T6G(SCH_1):PAGE409
 U6011 BD32  GND28 PT5161LRS-PT5161LRS,SMLF,IC,AJ051610U03    I17 @T6G_MB_LIB.T6G(SCH_1):PAGE409
 U6011  BD4  GND29 PT5161LRS-PT5161LRS,SMLF,IC,AJ051610U03    I17 @T6G_MB_LIB.T6G(SCH_1):PAGE409
 U6011  BE2  GND30 PT5161LRS-PT5161LRS,SMLF,IC,AJ051610U03    I17 @T6G_MB_LIB.T6G(SCH_1):PAGE409
 U6011 BE34  GND31 PT5161LRS-PT5161LRS,SMLF,IC,AJ051610U03    I17 @T6G_MB_LIB.T6G(SCH_1):PAGE409
 U6011  BF1  GND32 PT5161LRS-PT5161LRS,SMLF,IC,AJ051610U03    I17 @T6G_MB_LIB.T6G(SCH_1):PAGE409
 U6011 BF35  GND33 PT5161LRS-PT5161LRS,SMLF,IC,AJ051610U03    I17 @T6G_MB_LIB.T6G(SCH_1):PAGE409
 U6011 BL13  GND34 PT5161LRS-PT5161LRS,SMLF,IC,AJ051610U03    I17 @T6G_MB_LIB.T6G(SCH_1):PAGE409
 U6011 BL22  GND35 PT5161LRS-PT5161LRS,SMLF,IC,AJ051610U03    I17 @T6G_MB_LIB.T6G(SCH_1):PAGE409
 U6011 BL32  GND36 PT5161LRS-PT5161LRS,SMLF,IC,AJ051610U03    I17 @T6G_MB_LIB.T6G(SCH_1):PAGE409
 U6011  BL4  GND37 PT5161LRS-PT5161LRS,SMLF,IC,AJ051610U03    I17 @T6G_MB_LIB.T6G(SCH_1):PAGE409
 U6011  BM2  GND38 PT5161LRS-PT5161LRS,SMLF,IC,AJ051610U03    I17 @T6G_MB_LIB.T6G(SCH_1):PAGE409
 U6011 BM34  GND39 PT5161LRS-PT5161LRS,SMLF,IC,AJ051610U03    I17 @T6G_MB_LIB.T6G(SCH_1):PAGE409
 U6011  BN1  GND40 PT5161LRS-PT5161LRS,SMLF,IC,AJ051610U03    I17 @T6G_MB_LIB.T6G(SCH_1):PAGE409
 U6011 BN35  GND41 PT5161LRS-PT5161LRS,SMLF,IC,AJ051610U03    I17 @T6G_MB_LIB.T6G(SCH_1):PAGE409
 U6011 BV13  GND42 PT5161LRS-PT5161LRS,SMLF,IC,AJ051610U03    I17 @T6G_MB_LIB.T6G(SCH_1):PAGE409
 U6011 BV22  GND43 PT5161LRS-PT5161LRS,SMLF,IC,AJ051610U03    I17 @T6G_MB_LIB.T6G(SCH_1):PAGE409
 U6011 BV32  GND44 PT5161LRS-PT5161LRS,SMLF,IC,AJ051610U03    I17 @T6G_MB_LIB.T6G(SCH_1):PAGE409
 U6011  BV4  GND45 PT5161LRS-PT5161LRS,SMLF,IC,AJ051610U03    I17 @T6G_MB_LIB.T6G(SCH_1):PAGE409
 U6011  BW2  GND46 PT5161LRS-PT5161LRS,SMLF,IC,AJ051610U03    I17 @T6G_MB_LIB.T6G(SCH_1):PAGE409
 U6011 BW34  GND47 PT5161LRS-PT5161LRS,SMLF,IC,AJ051610U03    I17 @T6G_MB_LIB.T6G(SCH_1):PAGE409
 U6011  BY1  GND48 PT5161LRS-PT5161LRS,SMLF,IC,AJ051610U03    I17 @T6G_MB_LIB.T6G(SCH_1):PAGE409
 U6011 BY35  GND49 PT5161LRS-PT5161LRS,SMLF,IC,AJ051610U03    I17 @T6G_MB_LIB.T6G(SCH_1):PAGE409
 U6011 CE13  GND50 PT5161LRS-PT5161LRS,SMLF,IC,AJ051610U03    I17 @T6G_MB_LIB.T6G(SCH_1):PAGE409
 U6011 CE22  GND51 PT5161LRS-PT5161LRS,SMLF,IC,AJ051610U03    I17 @T6G_MB_LIB.T6G(SCH_1):PAGE409
 U6011 CE32  GND52 PT5161LRS-PT5161LRS,SMLF,IC,AJ051610U03    I17 @T6G_MB_LIB.T6G(SCH_1):PAGE409
 U6011  CE4  GND53 PT5161LRS-PT5161LRS,SMLF,IC,AJ051610U03    I17 @T6G_MB_LIB.T6G(SCH_1):PAGE409
 U6011  CF2  GND54 PT5161LRS-PT5161LRS,SMLF,IC,AJ051610U03    I17 @T6G_MB_LIB.T6G(SCH_1):PAGE409
 U6011 CF34  GND55 PT5161LRS-PT5161LRS,SMLF,IC,AJ051610U03    I17 @T6G_MB_LIB.T6G(SCH_1):PAGE409
 U6011  CG1  GND56 PT5161LRS-PT5161LRS,SMLF,IC,AJ051610U03    I17 @T6G_MB_LIB.T6G(SCH_1):PAGE409
 U6011 CG35  GND57 PT5161LRS-PT5161LRS,SMLF,IC,AJ051610U03    I17 @T6G_MB_LIB.T6G(SCH_1):PAGE409
 U6011 CM13  GND58 PT5161LRS-PT5161LRS,SMLF,IC,AJ051610U03    I17 @T6G_MB_LIB.T6G(SCH_1):PAGE409
 U6011 CM22  GND59 PT5161LRS-PT5161LRS,SMLF,IC,AJ051610U03    I17 @T6G_MB_LIB.T6G(SCH_1):PAGE409
 U6011 CM32  GND60 PT5161LRS-PT5161LRS,SMLF,IC,AJ051610U03    I17 @T6G_MB_LIB.T6G(SCH_1):PAGE409
 U6011  CM4  GND61 PT5161LRS-PT5161LRS,SMLF,IC,AJ051610U03    I17 @T6G_MB_LIB.T6G(SCH_1):PAGE409
 U6011  CN2  GND62 PT5161LRS-PT5161LRS,SMLF,IC,AJ051610U03    I17 @T6G_MB_LIB.T6G(SCH_1):PAGE409
 U6011 CN34  GND63 PT5161LRS-PT5161LRS,SMLF,IC,AJ051610U03    I17 @T6G_MB_LIB.T6G(SCH_1):PAGE409
 U6011  CP1  GND64 PT5161LRS-PT5161LRS,SMLF,IC,AJ051610U03    I17 @T6G_MB_LIB.T6G(SCH_1):PAGE409
 U6011 CP35  GND65 PT5161LRS-PT5161LRS,SMLF,IC,AJ051610U03    I17 @T6G_MB_LIB.T6G(SCH_1):PAGE409
 U6011 CW13  GND66 PT5161LRS-PT5161LRS,SMLF,IC,AJ051610U03    I17 @T6G_MB_LIB.T6G(SCH_1):PAGE409
 U6011 CW22  GND67 PT5161LRS-PT5161LRS,SMLF,IC,AJ051610U03    I17 @T6G_MB_LIB.T6G(SCH_1):PAGE409
 U6011 CW32  GND68 PT5161LRS-PT5161LRS,SMLF,IC,AJ051610U03    I17 @T6G_MB_LIB.T6G(SCH_1):PAGE409
 U6011  CW4  GND69 PT5161LRS-PT5161LRS,SMLF,IC,AJ051610U03    I17 @T6G_MB_LIB.T6G(SCH_1):PAGE409
 U6011  CY2  GND70 PT5161LRS-PT5161LRS,SMLF,IC,AJ051610U03    I17 @T6G_MB_LIB.T6G(SCH_1):PAGE409
 U6011 CY34  GND71 PT5161LRS-PT5161LRS,SMLF,IC,AJ051610U03    I17 @T6G_MB_LIB.T6G(SCH_1):PAGE409
 U6011  DA1  GND72 PT5161LRS-PT5161LRS,SMLF,IC,AJ051610U03    I17 @T6G_MB_LIB.T6G(SCH_1):PAGE409
 U6011 DA35  GND73 PT5161LRS-PT5161LRS,SMLF,IC,AJ051610U03    I17 @T6G_MB_LIB.T6G(SCH_1):PAGE409
 U6011 DF13  GND74 PT5161LRS-PT5161LRS,SMLF,IC,AJ051610U03    I17 @T6G_MB_LIB.T6G(SCH_1):PAGE409
 U6011 DF22  GND75 PT5161LRS-PT5161LRS,SMLF,IC,AJ051610U03    I17 @T6G_MB_LIB.T6G(SCH_1):PAGE409
 U6011 DF32  GND76 PT5161LRS-PT5161LRS,SMLF,IC,AJ051610U03    I17 @T6G_MB_LIB.T6G(SCH_1):PAGE409
 U6011  DF4  GND77 PT5161LRS-PT5161LRS,SMLF,IC,AJ051610U03    I17 @T6G_MB_LIB.T6G(SCH_1):PAGE409
 U6011  DG2  GND78 PT5161LRS-PT5161LRS,SMLF,IC,AJ051610U03    I17 @T6G_MB_LIB.T6G(SCH_1):PAGE409
 U6011 DG34  GND79 PT5161LRS-PT5161LRS,SMLF,IC,AJ051610U03    I17 @T6G_MB_LIB.T6G(SCH_1):PAGE409
 U6011  DH1  GND80 PT5161LRS-PT5161LRS,SMLF,IC,AJ051610U03    I17 @T6G_MB_LIB.T6G(SCH_1):PAGE409
 U6011 DH35  GND81 PT5161LRS-PT5161LRS,SMLF,IC,AJ051610U03    I17 @T6G_MB_LIB.T6G(SCH_1):PAGE409
 U6011 DN13  GND82 PT5161LRS-PT5161LRS,SMLF,IC,AJ051610U03    I17 @T6G_MB_LIB.T6G(SCH_1):PAGE409
 U6011 DN22  GND83 PT5161LRS-PT5161LRS,SMLF,IC,AJ051610U03    I17 @T6G_MB_LIB.T6G(SCH_1):PAGE409
 U6011 DN32  GND84 PT5161LRS-PT5161LRS,SMLF,IC,AJ051610U03    I17 @T6G_MB_LIB.T6G(SCH_1):PAGE409
 U6011  DN4  GND85 PT5161LRS-PT5161LRS,SMLF,IC,AJ051610U03    I17 @T6G_MB_LIB.T6G(SCH_1):PAGE409
 U6011  DP2  GND86 PT5161LRS-PT5161LRS,SMLF,IC,AJ051610U03    I17 @T6G_MB_LIB.T6G(SCH_1):PAGE409
 U6011 DP34  GND87 PT5161LRS-PT5161LRS,SMLF,IC,AJ051610U03    I17 @T6G_MB_LIB.T6G(SCH_1):PAGE409
 U6011  DR1  GND88 PT5161LRS-PT5161LRS,SMLF,IC,AJ051610U03    I17 @T6G_MB_LIB.T6G(SCH_1):PAGE409
 U6011 DR35  GND89 PT5161LRS-PT5161LRS,SMLF,IC,AJ051610U03    I17 @T6G_MB_LIB.T6G(SCH_1):PAGE409
 U6011 DY13  GND90 PT5161LRS-PT5161LRS,SMLF,IC,AJ051610U03    I17 @T6G_MB_LIB.T6G(SCH_1):PAGE409
 U6011 DY22  GND91 PT5161LRS-PT5161LRS,SMLF,IC,AJ051610U03    I17 @T6G_MB_LIB.T6G(SCH_1):PAGE409
 U6011 DY32  GND92 PT5161LRS-PT5161LRS,SMLF,IC,AJ051610U03    I17 @T6G_MB_LIB.T6G(SCH_1):PAGE409
 U6011  DY4  GND93 PT5161LRS-PT5161LRS,SMLF,IC,AJ051610U03    I17 @T6G_MB_LIB.T6G(SCH_1):PAGE409
 U6011  E14  GND94 PT5161LRS-PT5161LRS,SMLF,IC,AJ051610U03    I17 @T6G_MB_LIB.T6G(SCH_1):PAGE409
 U6011  E27  GND95 PT5161LRS-PT5161LRS,SMLF,IC,AJ051610U03    I17 @T6G_MB_LIB.T6G(SCH_1):PAGE409
 U6011  E33  GND96 PT5161LRS-PT5161LRS,SMLF,IC,AJ051610U03    I17 @T6G_MB_LIB.T6G(SCH_1):PAGE409
 U6011  EA2  GND97 PT5161LRS-PT5161LRS,SMLF,IC,AJ051610U03    I17 @T6G_MB_LIB.T6G(SCH_1):PAGE409
 U6011 EA34  GND98 PT5161LRS-PT5161LRS,SMLF,IC,AJ051610U03    I17 @T6G_MB_LIB.T6G(SCH_1):PAGE409
 U6011  EB1  GND99 PT5161LRS-PT5161LRS,SMLF,IC,AJ051610U03    I17 @T6G_MB_LIB.T6G(SCH_1):PAGE409
 U6011 EB35 GND100 PT5161LRS-PT5161LRS,SMLF,IC,AJ051610U03    I17 @T6G_MB_LIB.T6G(SCH_1):PAGE409
 U6011 EG13 GND101 PT5161LRS-PT5161LRS,SMLF,IC,AJ051610U03    I17 @T6G_MB_LIB.T6G(SCH_1):PAGE409
 U6011 EG22 GND102 PT5161LRS-PT5161LRS,SMLF,IC,AJ051610U03    I17 @T6G_MB_LIB.T6G(SCH_1):PAGE409
 U6011 EG32 GND103 PT5161LRS-PT5161LRS,SMLF,IC,AJ051610U03    I17 @T6G_MB_LIB.T6G(SCH_1):PAGE409
 U6011  EG4 GND104 PT5161LRS-PT5161LRS,SMLF,IC,AJ051610U03    I17 @T6G_MB_LIB.T6G(SCH_1):PAGE409
 U6011  EH2 GND105 PT5161LRS-PT5161LRS,SMLF,IC,AJ051610U03    I17 @T6G_MB_LIB.T6G(SCH_1):PAGE409
 U6011 EH34 GND106 PT5161LRS-PT5161LRS,SMLF,IC,AJ051610U03    I17 @T6G_MB_LIB.T6G(SCH_1):PAGE409
 U6011  EJ1 GND107 PT5161LRS-PT5161LRS,SMLF,IC,AJ051610U03    I17 @T6G_MB_LIB.T6G(SCH_1):PAGE409
 U6011 EJ35 GND108 PT5161LRS-PT5161LRS,SMLF,IC,AJ051610U03    I17 @T6G_MB_LIB.T6G(SCH_1):PAGE409
 U6011 EP13 GND109 PT5161LRS-PT5161LRS,SMLF,IC,AJ051610U03    I17 @T6G_MB_LIB.T6G(SCH_1):PAGE409
 U6011 EP22 GND110 PT5161LRS-PT5161LRS,SMLF,IC,AJ051610U03    I17 @T6G_MB_LIB.T6G(SCH_1):PAGE409
 U6011 EP32 GND111 PT5161LRS-PT5161LRS,SMLF,IC,AJ051610U03    I17 @T6G_MB_LIB.T6G(SCH_1):PAGE409
 U6011  EP4 GND112 PT5161LRS-PT5161LRS,SMLF,IC,AJ051610U03    I17 @T6G_MB_LIB.T6G(SCH_1):PAGE409
 U6011  ER2 GND113 PT5161LRS-PT5161LRS,SMLF,IC,AJ051610U03    I17 @T6G_MB_LIB.T6G(SCH_1):PAGE409
 U6011 ER34 GND114 PT5161LRS-PT5161LRS,SMLF,IC,AJ051610U03    I17 @T6G_MB_LIB.T6G(SCH_1):PAGE409
 U6011  ET1 GND115 PT5161LRS-PT5161LRS,SMLF,IC,AJ051610U03    I17 @T6G_MB_LIB.T6G(SCH_1):PAGE409
 U6011 ET35 GND116 PT5161LRS-PT5161LRS,SMLF,IC,AJ051610U03    I17 @T6G_MB_LIB.T6G(SCH_1):PAGE409
 U6011 FA15 GND117 PT5161LRS-PT5161LRS,SMLF,IC,AJ051610U03    I17 @T6G_MB_LIB.T6G(SCH_1):PAGE409
 U6011 FA32 GND118 PT5161LRS-PT5161LRS,SMLF,IC,AJ051610U03    I17 @T6G_MB_LIB.T6G(SCH_1):PAGE409
 U6011  FB2 GND119 PT5161LRS-PT5161LRS,SMLF,IC,AJ051610U03    I17 @T6G_MB_LIB.T6G(SCH_1):PAGE409
 U6011 FB34 GND120 PT5161LRS-PT5161LRS,SMLF,IC,AJ051610U03    I17 @T6G_MB_LIB.T6G(SCH_1):PAGE409
 U6011 FC19 GND121 PT5161LRS-PT5161LRS,SMLF,IC,AJ051610U03    I17 @T6G_MB_LIB.T6G(SCH_1):PAGE409
 U6011 FC23 GND122 PT5161LRS-PT5161LRS,SMLF,IC,AJ051610U03    I17 @T6G_MB_LIB.T6G(SCH_1):PAGE409
 U6011 FC25 GND123 PT5161LRS-PT5161LRS,SMLF,IC,AJ051610U03    I17 @T6G_MB_LIB.T6G(SCH_1):PAGE409
 U6011 FC28 GND124 PT5161LRS-PT5161LRS,SMLF,IC,AJ051610U03    I17 @T6G_MB_LIB.T6G(SCH_1):PAGE409
 U6011  FC3 GND125 PT5161LRS-PT5161LRS,SMLF,IC,AJ051610U03    I17 @T6G_MB_LIB.T6G(SCH_1):PAGE409
 U6011  FC6 GND126 PT5161LRS-PT5161LRS,SMLF,IC,AJ051610U03    I17 @T6G_MB_LIB.T6G(SCH_1):PAGE409
 U6011  FC9 GND127 PT5161LRS-PT5161LRS,SMLF,IC,AJ051610U03    I17 @T6G_MB_LIB.T6G(SCH_1):PAGE409
 U6011  FD1 GND128 PT5161LRS-PT5161LRS,SMLF,IC,AJ051610U03    I17 @T6G_MB_LIB.T6G(SCH_1):PAGE409
 U6011 FD35 GND129 PT5161LRS-PT5161LRS,SMLF,IC,AJ051610U03    I17 @T6G_MB_LIB.T6G(SCH_1):PAGE409
 U6011 FF14 GND130 PT5161LRS-PT5161LRS,SMLF,IC,AJ051610U03    I17 @T6G_MB_LIB.T6G(SCH_1):PAGE409
 U6011 FF21 GND131 PT5161LRS-PT5161LRS,SMLF,IC,AJ051610U03    I17 @T6G_MB_LIB.T6G(SCH_1):PAGE409
 U6011 FJ12 GND132 PT5161LRS-PT5161LRS,SMLF,IC,AJ051610U03    I17 @T6G_MB_LIB.T6G(SCH_1):PAGE409
 U6011 FJ19 GND133 PT5161LRS-PT5161LRS,SMLF,IC,AJ051610U03    I17 @T6G_MB_LIB.T6G(SCH_1):PAGE409
 U6011  H12 GND134 PT5161LRS-PT5161LRS,SMLF,IC,AJ051610U03    I17 @T6G_MB_LIB.T6G(SCH_1):PAGE409
 U6011  H16 GND135 PT5161LRS-PT5161LRS,SMLF,IC,AJ051610U03    I17 @T6G_MB_LIB.T6G(SCH_1):PAGE409
 U6011  H19 GND136 PT5161LRS-PT5161LRS,SMLF,IC,AJ051610U03    I17 @T6G_MB_LIB.T6G(SCH_1):PAGE409
 U6011  H31 GND137 PT5161LRS-PT5161LRS,SMLF,IC,AJ051610U03    I17 @T6G_MB_LIB.T6G(SCH_1):PAGE409
 U6011  J22 GND138 PT5161LRS-PT5161LRS,SMLF,IC,AJ051610U03    I17 @T6G_MB_LIB.T6G(SCH_1):PAGE409
 U6011   J4 GND139 PT5161LRS-PT5161LRS,SMLF,IC,AJ051610U03    I17 @T6G_MB_LIB.T6G(SCH_1):PAGE409
 U6011   K2 GND140 PT5161LRS-PT5161LRS,SMLF,IC,AJ051610U03    I17 @T6G_MB_LIB.T6G(SCH_1):PAGE409
 U6011  K34 GND141 PT5161LRS-PT5161LRS,SMLF,IC,AJ051610U03    I17 @T6G_MB_LIB.T6G(SCH_1):PAGE409
 U6011   L1 GND142 PT5161LRS-PT5161LRS,SMLF,IC,AJ051610U03    I17 @T6G_MB_LIB.T6G(SCH_1):PAGE409
 U6011  L35 GND143 PT5161LRS-PT5161LRS,SMLF,IC,AJ051610U03    I17 @T6G_MB_LIB.T6G(SCH_1):PAGE409
 U6011  T13 GND144 PT5161LRS-PT5161LRS,SMLF,IC,AJ051610U03    I17 @T6G_MB_LIB.T6G(SCH_1):PAGE409
 U6011  T22 GND145 PT5161LRS-PT5161LRS,SMLF,IC,AJ051610U03    I17 @T6G_MB_LIB.T6G(SCH_1):PAGE409
 U6011  T32 GND146 PT5161LRS-PT5161LRS,SMLF,IC,AJ051610U03    I17 @T6G_MB_LIB.T6G(SCH_1):PAGE409
 U6011   T4 GND147 PT5161LRS-PT5161LRS,SMLF,IC,AJ051610U03    I17 @T6G_MB_LIB.T6G(SCH_1):PAGE409
 U6011   U2 GND148 PT5161LRS-PT5161LRS,SMLF,IC,AJ051610U03    I17 @T6G_MB_LIB.T6G(SCH_1):PAGE409
 U6011  U34 GND149 PT5161LRS-PT5161LRS,SMLF,IC,AJ051610U03    I17 @T6G_MB_LIB.T6G(SCH_1):PAGE409
 U6011   V1 GND150 PT5161LRS-PT5161LRS,SMLF,IC,AJ051610U03    I17 @T6G_MB_LIB.T6G(SCH_1):PAGE409
 U6011  V35 GND151 PT5161LRS-PT5161LRS,SMLF,IC,AJ051610U03    I17 @T6G_MB_LIB.T6G(SCH_1):PAGE409
 R1044    2      B Q_RES_0201LF-1K,1%,1/20W,CHIP,CS21001FE07    I20 @T6G_MB_LIB.T6G(SCH_1):PAGE410
  C664    2      B Q_CAP_C0201-0.1UF,10V,10%,X7S,CH4102K6E00    I24 @T6G_MB_LIB.T6G(SCH_1):PAGE410
  C598    2      B Q_CAP_0201-1UF,4V,20%,X6S,CH-10KMEE00     I5 @T6G_MB_LIB.T6G(SCH_1):PAGE411
  C601    2      B Q_CAP_C0201-0.1UF,10V,10%,X7S,CH4102K6E00     I7 @T6G_MB_LIB.T6G(SCH_1):PAGE411
  C588    2      B Q_CAP_C0805-100UF,4V,20%,X6S,CH710KMEA01    I12 @T6G_MB_LIB.T6G(SCH_1):PAGE411
  C590    2      B Q_CAP_C0402-22UF,4V,20%,X6S,CH622KMEB02    I15 @T6G_MB_LIB.T6G(SCH_1):PAGE411
  C595    2      B Q_CAP_C0402-10UF,6.3V,20%,X6S,CH6101MEB01    I16 @T6G_MB_LIB.T6G(SCH_1):PAGE411
  C587    2      B Q_CAP_C0805-100UF,4V,20%,X6S,CH710KMEA01    I17 @T6G_MB_LIB.T6G(SCH_1):PAGE411
  C589    2      B Q_CAP_C0402-22UF,4V,20%,X6S,CH622KMEB02    I18 @T6G_MB_LIB.T6G(SCH_1):PAGE411
  C594    2      B Q_CAP_0402-4.7UF,6.3V,20%,X6S,CH5471MEB01    I19 @T6G_MB_LIB.T6G(SCH_1):PAGE411
  C597    2      B Q_CAP_0201-1UF,4V,20%,X6S,CH-10KMEE00    I20 @T6G_MB_LIB.T6G(SCH_1):PAGE411
  C599    2      B Q_CAP_0201-1UF,4V,20%,X6S,CH-10KMEE00    I21 @T6G_MB_LIB.T6G(SCH_1):PAGE411
  C591    2      B Q_CAP_C0402-10UF,6.3V,20%,X6S,CH6101MEB01    I22 @T6G_MB_LIB.T6G(SCH_1):PAGE411
  C596    2      B Q_CAP_0402-4.7UF,6.3V,20%,X6S,CH5471MEB01    I24 @T6G_MB_LIB.T6G(SCH_1):PAGE411
  C600    2      B Q_CAP_C0201-0.1UF,10V,10%,X7S,CH4102K6E00    I25 @T6G_MB_LIB.T6G(SCH_1):PAGE411
  C602    2      B Q_CAP_C0201-0.1UF,10V,10%,X7S,CH4102K6E00    I26 @T6G_MB_LIB.T6G(SCH_1):PAGE411
  C603    2      B Q_CAP_C0201-0.1UF,10V,10%,X7S,CH4102K6E00    I27 @T6G_MB_LIB.T6G(SCH_1):PAGE411
  C606    2      B Q_CAP_C0201-0.1UF,10V,10%,X7S,CH4102K6E00    I28 @T6G_MB_LIB.T6G(SCH_1):PAGE411
  C617    2      B Q_CAP_C0201-0.1UF,10V,10%,X7S,CH4102K6E00    I32 @T6G_MB_LIB.T6G(SCH_1):PAGE411
  C623    2      B Q_CAP_C0201-0.1UF,10V,10%,X7S,CH4102K6E00    I34 @T6G_MB_LIB.T6G(SCH_1):PAGE411
  C662    2      B Q_CAP_C0201-0.1UF,10V,10%,X7S,CH4102K6E00    I37 @T6G_MB_LIB.T6G(SCH_1):PAGE411
  C609    2      B Q_CAP_0201-1UF,4V,20%,X6S,CH-10KMEE00    I38 @T6G_MB_LIB.T6G(SCH_1):PAGE411
  C618    2      B Q_CAP_0201-1UF,4V,20%,X6S,CH-10KMEE00    I39 @T6G_MB_LIB.T6G(SCH_1):PAGE411
  C626    2      B Q_CAP_C0402-10UF,6.3V,20%,X6S,CH6101MEB01    I40 @T6G_MB_LIB.T6G(SCH_1):PAGE411
  C645    2      B Q_CAP_C0402-10UF,6.3V,20%,X6S,CH6101MEB01    I41 @T6G_MB_LIB.T6G(SCH_1):PAGE411
  C616    2      B Q_CAP_C0201-0.1UF,10V,10%,X7S,CH4102K6E00    I42 @T6G_MB_LIB.T6G(SCH_1):PAGE411
  C657    2      B Q_CAP_C0201-0.1UF,10V,10%,X7S,CH4102K6E00    I43 @T6G_MB_LIB.T6G(SCH_1):PAGE411
  C607    2      B Q_CAP_0201-1UF,4V,20%,X6S,CH-10KMEE00    I44 @T6G_MB_LIB.T6G(SCH_1):PAGE411
  C643    2      B Q_CAP_0201-1UF,4V,20%,X6S,CH-10KMEE00    I45 @T6G_MB_LIB.T6G(SCH_1):PAGE411
  C635    2      B Q_CAP_C0201-0.1UF,10V,10%,X7S,CH4102K6E00    I46 @T6G_MB_LIB.T6G(SCH_1):PAGE411
  C627    2      B Q_CAP_C0201-0.1UF,10V,10%,X7S,CH4102K6E00    I47 @T6G_MB_LIB.T6G(SCH_1):PAGE411
  C647    2      B Q_CAP_0201-1UF,4V,20%,X6S,CH-10KMEE00    I48 @T6G_MB_LIB.T6G(SCH_1):PAGE411
  C654    2      B Q_CAP_0201-1UF,4V,20%,X6S,CH-10KMEE00    I49 @T6G_MB_LIB.T6G(SCH_1):PAGE411
  C644    2      B Q_CAP_0402-4.7UF,6.3V,20%,X6S,CH5471MEB01    I50 @T6G_MB_LIB.T6G(SCH_1):PAGE411
  C638    2      B Q_CAP_0402-4.7UF,6.3V,20%,X6S,CH5471MEB01    I51 @T6G_MB_LIB.T6G(SCH_1):PAGE411
  C649    2      B Q_CAP_0402-4.7UF,6.3V,20%,X6S,CH5471MEB01    I52 @T6G_MB_LIB.T6G(SCH_1):PAGE411
  C653    2      B Q_CAP_0201-1UF,4V,20%,X6S,CH-10KMEE00    I53 @T6G_MB_LIB.T6G(SCH_1):PAGE411
  C631    2      B Q_CAP_C0201-0.1UF,10V,10%,X7S,CH4102K6E00    I55 @T6G_MB_LIB.T6G(SCH_1):PAGE411
  C650    2      B Q_CAP_C0201-0.1UF,10V,10%,X7S,CH4102K6E00    I58 @T6G_MB_LIB.T6G(SCH_1):PAGE411
  C620    2      B Q_CAP_0201-1UF,4V,20%,X6S,CH-10KMEE00    I59 @T6G_MB_LIB.T6G(SCH_1):PAGE411
  C613    2      B Q_CAP_0201-1UF,4V,20%,X6S,CH-10KMEE00    I61 @T6G_MB_LIB.T6G(SCH_1):PAGE411
  C625    2      B Q_CAP_C0805-100UF,4V,20%,X6S,CH710KMEA01    I64 @T6G_MB_LIB.T6G(SCH_1):PAGE411
  C628    2      B Q_CAP_C0805-100UF,4V,20%,X6S,CH710KMEA01    I65 @T6G_MB_LIB.T6G(SCH_1):PAGE411
  C632    2      B Q_CAP_C0805-100UF,4V,20%,X6S,CH710KMEA01    I67 @T6G_MB_LIB.T6G(SCH_1):PAGE411
  C636    2      B Q_CAP_C0402-22UF,4V,20%,X6S,CH622KMEB02    I68 @T6G_MB_LIB.T6G(SCH_1):PAGE411
  C633    2      B Q_CAP_C0805-100UF,4V,20%,X6S,CH710KMEA01    I69 @T6G_MB_LIB.T6G(SCH_1):PAGE411
  C637    2      B Q_CAP_C0805-100UF,4V,20%,X6S,CH710KMEA01    I70 @T6G_MB_LIB.T6G(SCH_1):PAGE411
  C634    2      B Q_CAP_C0402-22UF,4V,20%,X6S,CH622KMEB02    I71 @T6G_MB_LIB.T6G(SCH_1):PAGE411
  C663    2      B Q_CAP_C0402-22UF,4V,20%,X6S,CH622KMEB02    I72 @T6G_MB_LIB.T6G(SCH_1):PAGE411
  C630    2      B Q_CAP_C0402-22UF,4V,20%,X6S,CH622KMEB02    I73 @T6G_MB_LIB.T6G(SCH_1):PAGE411
  C646    2      B Q_CAP_C0402-10UF,6.3V,20%,X6S,CH6101MEB01    I74 @T6G_MB_LIB.T6G(SCH_1):PAGE411
  C651    2      B Q_CAP_0402-4.7UF,6.3V,20%,X6S,CH5471MEB01    I75 @T6G_MB_LIB.T6G(SCH_1):PAGE411
  C655    2      B Q_CAP_0201-1UF,4V,20%,X6S,CH-10KMEE00    I76 @T6G_MB_LIB.T6G(SCH_1):PAGE411
  C656    2      B Q_CAP_C0402-22UF,4V,20%,X6S,CH622KMEB02    I77 @T6G_MB_LIB.T6G(SCH_1):PAGE411
  C661    2      B Q_CAP_C0402-10UF,6.3V,20%,X6S,CH6101MEB01    I78 @T6G_MB_LIB.T6G(SCH_1):PAGE411
  C648    2      B Q_CAP_C0402-10UF,6.3V,20%,X6S,CH6101MEB01    I79 @T6G_MB_LIB.T6G(SCH_1):PAGE411
  C608    2      B Q_CAP_C0201-0.1UF,10V,10%,X7S,CH4102K6E00    I81 @T6G_MB_LIB.T6G(SCH_1):PAGE411
  C610    2      B Q_CAP_C0201-0.1UF,10V,10%,X7S,CH4102K6E00    I82 @T6G_MB_LIB.T6G(SCH_1):PAGE411
  C615    2      B Q_CAP_C0201-0.1UF,10V,10%,X7S,CH4102K6E00    I83 @T6G_MB_LIB.T6G(SCH_1):PAGE411
  C619    2      B Q_CAP_C0201-0.1UF,10V,10%,X7S,CH4102K6E00    I84 @T6G_MB_LIB.T6G(SCH_1):PAGE411
  C614    2      B Q_CAP_C0201-0.1UF,10V,10%,X7S,CH4102K6E00    I85 @T6G_MB_LIB.T6G(SCH_1):PAGE411
  C622    2      B Q_CAP_0201-1UF,4V,20%,X6S,CH-10KMEE00    I86 @T6G_MB_LIB.T6G(SCH_1):PAGE411
  C652    2      B Q_CAP_0402-4.7UF,6.3V,20%,X6S,CH5471MEB01    I87 @T6G_MB_LIB.T6G(SCH_1):PAGE411
 R1072    2      B Q_RES_0201LF-10K,1%,1/20W,CHIP,CS31001FE17     I8 @T6G_MB_LIB.T6G(SCH_1):PAGE419
  R631    2      B Q_RES_0201LF-51.1,1%,1/20W,EMPTY,CS05111FE00    I17 @T6G_MB_LIB.T6G(SCH_1):PAGE419
  R634    2      B Q_RES_0201LF-51.1,1%,1/20W,EMPTY,CS05111FE00    I18 @T6G_MB_LIB.T6G(SCH_1):PAGE419
 R1076    2      B Q_RES_0201LF-4.7K,5%,1/20W,CHIP,CS24701JE04    I36 @T6G_MB_LIB.T6G(SCH_1):PAGE419
 R1078    2      B Q_RES_0201LF-4.7K,5%,1/20W,CHIP,CS24701JE04    I37 @T6G_MB_LIB.T6G(SCH_1):PAGE419
 R1079    2      B Q_RES_0201LF-4.7K,5%,1/20W,CHIP,CS24701JE04    I39 @T6G_MB_LIB.T6G(SCH_1):PAGE419
 R1048    2      B Q_RES_0201LF-4.7K,5%,1/20W,EMPTY,CS24701JE04    I50 @T6G_MB_LIB.T6G(SCH_1):PAGE419
 R1056    2      B Q_RES_0201LF-1K,1%,1/20W,EMPTY,CS21001FE07    I65 @T6G_MB_LIB.T6G(SCH_1):PAGE419
 R1058    2      B Q_RES_0201LF-20K,1%,1/20W,CHIP,CS32001FE00    I66 @T6G_MB_LIB.T6G(SCH_1):PAGE419
 R1060    2      B Q_RES_0201LF-1K,1%,1/20W,CHIP,CS21001FE07    I69 @T6G_MB_LIB.T6G(SCH_1):PAGE419
 R1062    2      B Q_RES_0201LF-10K,1%,1/20W,CHIP,CS31001FE17    I76 @T6G_MB_LIB.T6G(SCH_1):PAGE419
 R1061    2      B Q_RES_0201LF-10K,1%,1/20W,CHIP,CS31001FE17    I77 @T6G_MB_LIB.T6G(SCH_1):PAGE419
 U6012  E30 T_SENSE PT5161LRS-PT5161LRS,SMLF,IC,AJ051610U03    I83 @T6G_MB_LIB.T6G(SCH_1):PAGE419
 R1083    2      B Q_RES_0201LF-0,5%,1/20W,CHIP,CS00001JE10    I13 @T6G_MB_LIB.T6G(SCH_1):PAGE420
 R1084    2      B Q_RES_0201LF-0,5%,1/20W,CHIP,CS00001JE10    I14 @T6G_MB_LIB.T6G(SCH_1):PAGE420
 U6012 AC13   GND1 PT5161LRS-PT5161LRS,SMLF,IC,AJ051610U03    I17 @T6G_MB_LIB.T6G(SCH_1):PAGE420
 U6012 AC22   GND2 PT5161LRS-PT5161LRS,SMLF,IC,AJ051610U03    I17 @T6G_MB_LIB.T6G(SCH_1):PAGE420
 U6012 AC32   GND3 PT5161LRS-PT5161LRS,SMLF,IC,AJ051610U03    I17 @T6G_MB_LIB.T6G(SCH_1):PAGE420
 U6012  AC4   GND4 PT5161LRS-PT5161LRS,SMLF,IC,AJ051610U03    I17 @T6G_MB_LIB.T6G(SCH_1):PAGE420
 U6012  AD2   GND5 PT5161LRS-PT5161LRS,SMLF,IC,AJ051610U03    I17 @T6G_MB_LIB.T6G(SCH_1):PAGE420
 U6012 AD34   GND6 PT5161LRS-PT5161LRS,SMLF,IC,AJ051610U03    I17 @T6G_MB_LIB.T6G(SCH_1):PAGE420
 U6012  AE1   GND7 PT5161LRS-PT5161LRS,SMLF,IC,AJ051610U03    I17 @T6G_MB_LIB.T6G(SCH_1):PAGE420
 U6012 AE35   GND8 PT5161LRS-PT5161LRS,SMLF,IC,AJ051610U03    I17 @T6G_MB_LIB.T6G(SCH_1):PAGE420
 U6012 AK13   GND9 PT5161LRS-PT5161LRS,SMLF,IC,AJ051610U03    I17 @T6G_MB_LIB.T6G(SCH_1):PAGE420
 U6012 AK22  GND10 PT5161LRS-PT5161LRS,SMLF,IC,AJ051610U03    I17 @T6G_MB_LIB.T6G(SCH_1):PAGE420
 U6012 AK32  GND11 PT5161LRS-PT5161LRS,SMLF,IC,AJ051610U03    I17 @T6G_MB_LIB.T6G(SCH_1):PAGE420
 U6012  AK4  GND12 PT5161LRS-PT5161LRS,SMLF,IC,AJ051610U03    I17 @T6G_MB_LIB.T6G(SCH_1):PAGE420
 U6012  AL2  GND13 PT5161LRS-PT5161LRS,SMLF,IC,AJ051610U03    I17 @T6G_MB_LIB.T6G(SCH_1):PAGE420
 U6012 AL34  GND14 PT5161LRS-PT5161LRS,SMLF,IC,AJ051610U03    I17 @T6G_MB_LIB.T6G(SCH_1):PAGE420
 U6012  AM1  GND15 PT5161LRS-PT5161LRS,SMLF,IC,AJ051610U03    I17 @T6G_MB_LIB.T6G(SCH_1):PAGE420
 U6012 AM35  GND16 PT5161LRS-PT5161LRS,SMLF,IC,AJ051610U03    I17 @T6G_MB_LIB.T6G(SCH_1):PAGE420
 U6012 AU13  GND17 PT5161LRS-PT5161LRS,SMLF,IC,AJ051610U03    I17 @T6G_MB_LIB.T6G(SCH_1):PAGE420
 U6012 AU22  GND18 PT5161LRS-PT5161LRS,SMLF,IC,AJ051610U03    I17 @T6G_MB_LIB.T6G(SCH_1):PAGE420
 U6012 AU32  GND19 PT5161LRS-PT5161LRS,SMLF,IC,AJ051610U03    I17 @T6G_MB_LIB.T6G(SCH_1):PAGE420
 U6012  AU4  GND20 PT5161LRS-PT5161LRS,SMLF,IC,AJ051610U03    I17 @T6G_MB_LIB.T6G(SCH_1):PAGE420
 U6012  AV2  GND21 PT5161LRS-PT5161LRS,SMLF,IC,AJ051610U03    I17 @T6G_MB_LIB.T6G(SCH_1):PAGE420
 U6012 AV34  GND22 PT5161LRS-PT5161LRS,SMLF,IC,AJ051610U03    I17 @T6G_MB_LIB.T6G(SCH_1):PAGE420
 U6012  AW1  GND23 PT5161LRS-PT5161LRS,SMLF,IC,AJ051610U03    I17 @T6G_MB_LIB.T6G(SCH_1):PAGE420
 U6012 AW35  GND24 PT5161LRS-PT5161LRS,SMLF,IC,AJ051610U03    I17 @T6G_MB_LIB.T6G(SCH_1):PAGE420
 U6012  B19  GND25 PT5161LRS-PT5161LRS,SMLF,IC,AJ051610U03    I17 @T6G_MB_LIB.T6G(SCH_1):PAGE420
 U6012 BD13  GND26 PT5161LRS-PT5161LRS,SMLF,IC,AJ051610U03    I17 @T6G_MB_LIB.T6G(SCH_1):PAGE420
 U6012 BD22  GND27 PT5161LRS-PT5161LRS,SMLF,IC,AJ051610U03    I17 @T6G_MB_LIB.T6G(SCH_1):PAGE420
 U6012 BD32  GND28 PT5161LRS-PT5161LRS,SMLF,IC,AJ051610U03    I17 @T6G_MB_LIB.T6G(SCH_1):PAGE420
 U6012  BD4  GND29 PT5161LRS-PT5161LRS,SMLF,IC,AJ051610U03    I17 @T6G_MB_LIB.T6G(SCH_1):PAGE420
 U6012  BE2  GND30 PT5161LRS-PT5161LRS,SMLF,IC,AJ051610U03    I17 @T6G_MB_LIB.T6G(SCH_1):PAGE420
 U6012 BE34  GND31 PT5161LRS-PT5161LRS,SMLF,IC,AJ051610U03    I17 @T6G_MB_LIB.T6G(SCH_1):PAGE420
 U6012  BF1  GND32 PT5161LRS-PT5161LRS,SMLF,IC,AJ051610U03    I17 @T6G_MB_LIB.T6G(SCH_1):PAGE420
 U6012 BF35  GND33 PT5161LRS-PT5161LRS,SMLF,IC,AJ051610U03    I17 @T6G_MB_LIB.T6G(SCH_1):PAGE420
 U6012 BL13  GND34 PT5161LRS-PT5161LRS,SMLF,IC,AJ051610U03    I17 @T6G_MB_LIB.T6G(SCH_1):PAGE420
 U6012 BL22  GND35 PT5161LRS-PT5161LRS,SMLF,IC,AJ051610U03    I17 @T6G_MB_LIB.T6G(SCH_1):PAGE420
 U6012 BL32  GND36 PT5161LRS-PT5161LRS,SMLF,IC,AJ051610U03    I17 @T6G_MB_LIB.T6G(SCH_1):PAGE420
 U6012  BL4  GND37 PT5161LRS-PT5161LRS,SMLF,IC,AJ051610U03    I17 @T6G_MB_LIB.T6G(SCH_1):PAGE420
 U6012  BM2  GND38 PT5161LRS-PT5161LRS,SMLF,IC,AJ051610U03    I17 @T6G_MB_LIB.T6G(SCH_1):PAGE420
 U6012 BM34  GND39 PT5161LRS-PT5161LRS,SMLF,IC,AJ051610U03    I17 @T6G_MB_LIB.T6G(SCH_1):PAGE420
 U6012  BN1  GND40 PT5161LRS-PT5161LRS,SMLF,IC,AJ051610U03    I17 @T6G_MB_LIB.T6G(SCH_1):PAGE420
 U6012 BN35  GND41 PT5161LRS-PT5161LRS,SMLF,IC,AJ051610U03    I17 @T6G_MB_LIB.T6G(SCH_1):PAGE420
 U6012 BV13  GND42 PT5161LRS-PT5161LRS,SMLF,IC,AJ051610U03    I17 @T6G_MB_LIB.T6G(SCH_1):PAGE420
 U6012 BV22  GND43 PT5161LRS-PT5161LRS,SMLF,IC,AJ051610U03    I17 @T6G_MB_LIB.T6G(SCH_1):PAGE420
 U6012 BV32  GND44 PT5161LRS-PT5161LRS,SMLF,IC,AJ051610U03    I17 @T6G_MB_LIB.T6G(SCH_1):PAGE420
 U6012  BV4  GND45 PT5161LRS-PT5161LRS,SMLF,IC,AJ051610U03    I17 @T6G_MB_LIB.T6G(SCH_1):PAGE420
 U6012  BW2  GND46 PT5161LRS-PT5161LRS,SMLF,IC,AJ051610U03    I17 @T6G_MB_LIB.T6G(SCH_1):PAGE420
 U6012 BW34  GND47 PT5161LRS-PT5161LRS,SMLF,IC,AJ051610U03    I17 @T6G_MB_LIB.T6G(SCH_1):PAGE420
 U6012  BY1  GND48 PT5161LRS-PT5161LRS,SMLF,IC,AJ051610U03    I17 @T6G_MB_LIB.T6G(SCH_1):PAGE420
 U6012 BY35  GND49 PT5161LRS-PT5161LRS,SMLF,IC,AJ051610U03    I17 @T6G_MB_LIB.T6G(SCH_1):PAGE420
 U6012 CE13  GND50 PT5161LRS-PT5161LRS,SMLF,IC,AJ051610U03    I17 @T6G_MB_LIB.T6G(SCH_1):PAGE420
 U6012 CE22  GND51 PT5161LRS-PT5161LRS,SMLF,IC,AJ051610U03    I17 @T6G_MB_LIB.T6G(SCH_1):PAGE420
 U6012 CE32  GND52 PT5161LRS-PT5161LRS,SMLF,IC,AJ051610U03    I17 @T6G_MB_LIB.T6G(SCH_1):PAGE420
 U6012  CE4  GND53 PT5161LRS-PT5161LRS,SMLF,IC,AJ051610U03    I17 @T6G_MB_LIB.T6G(SCH_1):PAGE420
 U6012  CF2  GND54 PT5161LRS-PT5161LRS,SMLF,IC,AJ051610U03    I17 @T6G_MB_LIB.T6G(SCH_1):PAGE420
 U6012 CF34  GND55 PT5161LRS-PT5161LRS,SMLF,IC,AJ051610U03    I17 @T6G_MB_LIB.T6G(SCH_1):PAGE420
 U6012  CG1  GND56 PT5161LRS-PT5161LRS,SMLF,IC,AJ051610U03    I17 @T6G_MB_LIB.T6G(SCH_1):PAGE420
 U6012 CG35  GND57 PT5161LRS-PT5161LRS,SMLF,IC,AJ051610U03    I17 @T6G_MB_LIB.T6G(SCH_1):PAGE420
 U6012 CM13  GND58 PT5161LRS-PT5161LRS,SMLF,IC,AJ051610U03    I17 @T6G_MB_LIB.T6G(SCH_1):PAGE420
 U6012 CM22  GND59 PT5161LRS-PT5161LRS,SMLF,IC,AJ051610U03    I17 @T6G_MB_LIB.T6G(SCH_1):PAGE420
 U6012 CM32  GND60 PT5161LRS-PT5161LRS,SMLF,IC,AJ051610U03    I17 @T6G_MB_LIB.T6G(SCH_1):PAGE420
 U6012  CM4  GND61 PT5161LRS-PT5161LRS,SMLF,IC,AJ051610U03    I17 @T6G_MB_LIB.T6G(SCH_1):PAGE420
 U6012  CN2  GND62 PT5161LRS-PT5161LRS,SMLF,IC,AJ051610U03    I17 @T6G_MB_LIB.T6G(SCH_1):PAGE420
 U6012 CN34  GND63 PT5161LRS-PT5161LRS,SMLF,IC,AJ051610U03    I17 @T6G_MB_LIB.T6G(SCH_1):PAGE420
 U6012  CP1  GND64 PT5161LRS-PT5161LRS,SMLF,IC,AJ051610U03    I17 @T6G_MB_LIB.T6G(SCH_1):PAGE420
 U6012 CP35  GND65 PT5161LRS-PT5161LRS,SMLF,IC,AJ051610U03    I17 @T6G_MB_LIB.T6G(SCH_1):PAGE420
 U6012 CW13  GND66 PT5161LRS-PT5161LRS,SMLF,IC,AJ051610U03    I17 @T6G_MB_LIB.T6G(SCH_1):PAGE420
 U6012 CW22  GND67 PT5161LRS-PT5161LRS,SMLF,IC,AJ051610U03    I17 @T6G_MB_LIB.T6G(SCH_1):PAGE420
 U6012 CW32  GND68 PT5161LRS-PT5161LRS,SMLF,IC,AJ051610U03    I17 @T6G_MB_LIB.T6G(SCH_1):PAGE420
 U6012  CW4  GND69 PT5161LRS-PT5161LRS,SMLF,IC,AJ051610U03    I17 @T6G_MB_LIB.T6G(SCH_1):PAGE420
 U6012  CY2  GND70 PT5161LRS-PT5161LRS,SMLF,IC,AJ051610U03    I17 @T6G_MB_LIB.T6G(SCH_1):PAGE420
 U6012 CY34  GND71 PT5161LRS-PT5161LRS,SMLF,IC,AJ051610U03    I17 @T6G_MB_LIB.T6G(SCH_1):PAGE420
 U6012  DA1  GND72 PT5161LRS-PT5161LRS,SMLF,IC,AJ051610U03    I17 @T6G_MB_LIB.T6G(SCH_1):PAGE420
 U6012 DA35  GND73 PT5161LRS-PT5161LRS,SMLF,IC,AJ051610U03    I17 @T6G_MB_LIB.T6G(SCH_1):PAGE420
 U6012 DF13  GND74 PT5161LRS-PT5161LRS,SMLF,IC,AJ051610U03    I17 @T6G_MB_LIB.T6G(SCH_1):PAGE420
 U6012 DF22  GND75 PT5161LRS-PT5161LRS,SMLF,IC,AJ051610U03    I17 @T6G_MB_LIB.T6G(SCH_1):PAGE420
 U6012 DF32  GND76 PT5161LRS-PT5161LRS,SMLF,IC,AJ051610U03    I17 @T6G_MB_LIB.T6G(SCH_1):PAGE420
 U6012  DF4  GND77 PT5161LRS-PT5161LRS,SMLF,IC,AJ051610U03    I17 @T6G_MB_LIB.T6G(SCH_1):PAGE420
 U6012  DG2  GND78 PT5161LRS-PT5161LRS,SMLF,IC,AJ051610U03    I17 @T6G_MB_LIB.T6G(SCH_1):PAGE420
 U6012 DG34  GND79 PT5161LRS-PT5161LRS,SMLF,IC,AJ051610U03    I17 @T6G_MB_LIB.T6G(SCH_1):PAGE420
 U6012  DH1  GND80 PT5161LRS-PT5161LRS,SMLF,IC,AJ051610U03    I17 @T6G_MB_LIB.T6G(SCH_1):PAGE420
 U6012 DH35  GND81 PT5161LRS-PT5161LRS,SMLF,IC,AJ051610U03    I17 @T6G_MB_LIB.T6G(SCH_1):PAGE420
 U6012 DN13  GND82 PT5161LRS-PT5161LRS,SMLF,IC,AJ051610U03    I17 @T6G_MB_LIB.T6G(SCH_1):PAGE420
 U6012 DN22  GND83 PT5161LRS-PT5161LRS,SMLF,IC,AJ051610U03    I17 @T6G_MB_LIB.T6G(SCH_1):PAGE420
 U6012 DN32  GND84 PT5161LRS-PT5161LRS,SMLF,IC,AJ051610U03    I17 @T6G_MB_LIB.T6G(SCH_1):PAGE420
 U6012  DN4  GND85 PT5161LRS-PT5161LRS,SMLF,IC,AJ051610U03    I17 @T6G_MB_LIB.T6G(SCH_1):PAGE420
 U6012  DP2  GND86 PT5161LRS-PT5161LRS,SMLF,IC,AJ051610U03    I17 @T6G_MB_LIB.T6G(SCH_1):PAGE420
 U6012 DP34  GND87 PT5161LRS-PT5161LRS,SMLF,IC,AJ051610U03    I17 @T6G_MB_LIB.T6G(SCH_1):PAGE420
 U6012  DR1  GND88 PT5161LRS-PT5161LRS,SMLF,IC,AJ051610U03    I17 @T6G_MB_LIB.T6G(SCH_1):PAGE420
 U6012 DR35  GND89 PT5161LRS-PT5161LRS,SMLF,IC,AJ051610U03    I17 @T6G_MB_LIB.T6G(SCH_1):PAGE420
 U6012 DY13  GND90 PT5161LRS-PT5161LRS,SMLF,IC,AJ051610U03    I17 @T6G_MB_LIB.T6G(SCH_1):PAGE420
 U6012 DY22  GND91 PT5161LRS-PT5161LRS,SMLF,IC,AJ051610U03    I17 @T6G_MB_LIB.T6G(SCH_1):PAGE420
 U6012 DY32  GND92 PT5161LRS-PT5161LRS,SMLF,IC,AJ051610U03    I17 @T6G_MB_LIB.T6G(SCH_1):PAGE420
 U6012  DY4  GND93 PT5161LRS-PT5161LRS,SMLF,IC,AJ051610U03    I17 @T6G_MB_LIB.T6G(SCH_1):PAGE420
 U6012  E14  GND94 PT5161LRS-PT5161LRS,SMLF,IC,AJ051610U03    I17 @T6G_MB_LIB.T6G(SCH_1):PAGE420
 U6012  E27  GND95 PT5161LRS-PT5161LRS,SMLF,IC,AJ051610U03    I17 @T6G_MB_LIB.T6G(SCH_1):PAGE420
 U6012  E33  GND96 PT5161LRS-PT5161LRS,SMLF,IC,AJ051610U03    I17 @T6G_MB_LIB.T6G(SCH_1):PAGE420
 U6012  EA2  GND97 PT5161LRS-PT5161LRS,SMLF,IC,AJ051610U03    I17 @T6G_MB_LIB.T6G(SCH_1):PAGE420
 U6012 EA34  GND98 PT5161LRS-PT5161LRS,SMLF,IC,AJ051610U03    I17 @T6G_MB_LIB.T6G(SCH_1):PAGE420
 U6012  EB1  GND99 PT5161LRS-PT5161LRS,SMLF,IC,AJ051610U03    I17 @T6G_MB_LIB.T6G(SCH_1):PAGE420
 U6012 EB35 GND100 PT5161LRS-PT5161LRS,SMLF,IC,AJ051610U03    I17 @T6G_MB_LIB.T6G(SCH_1):PAGE420
 U6012 EG13 GND101 PT5161LRS-PT5161LRS,SMLF,IC,AJ051610U03    I17 @T6G_MB_LIB.T6G(SCH_1):PAGE420
 U6012 EG22 GND102 PT5161LRS-PT5161LRS,SMLF,IC,AJ051610U03    I17 @T6G_MB_LIB.T6G(SCH_1):PAGE420
 U6012 EG32 GND103 PT5161LRS-PT5161LRS,SMLF,IC,AJ051610U03    I17 @T6G_MB_LIB.T6G(SCH_1):PAGE420
 U6012  EG4 GND104 PT5161LRS-PT5161LRS,SMLF,IC,AJ051610U03    I17 @T6G_MB_LIB.T6G(SCH_1):PAGE420
 U6012  EH2 GND105 PT5161LRS-PT5161LRS,SMLF,IC,AJ051610U03    I17 @T6G_MB_LIB.T6G(SCH_1):PAGE420
 U6012 EH34 GND106 PT5161LRS-PT5161LRS,SMLF,IC,AJ051610U03    I17 @T6G_MB_LIB.T6G(SCH_1):PAGE420
 U6012  EJ1 GND107 PT5161LRS-PT5161LRS,SMLF,IC,AJ051610U03    I17 @T6G_MB_LIB.T6G(SCH_1):PAGE420
 U6012 EJ35 GND108 PT5161LRS-PT5161LRS,SMLF,IC,AJ051610U03    I17 @T6G_MB_LIB.T6G(SCH_1):PAGE420
 U6012 EP13 GND109 PT5161LRS-PT5161LRS,SMLF,IC,AJ051610U03    I17 @T6G_MB_LIB.T6G(SCH_1):PAGE420
 U6012 EP22 GND110 PT5161LRS-PT5161LRS,SMLF,IC,AJ051610U03    I17 @T6G_MB_LIB.T6G(SCH_1):PAGE420
 U6012 EP32 GND111 PT5161LRS-PT5161LRS,SMLF,IC,AJ051610U03    I17 @T6G_MB_LIB.T6G(SCH_1):PAGE420
 U6012  EP4 GND112 PT5161LRS-PT5161LRS,SMLF,IC,AJ051610U03    I17 @T6G_MB_LIB.T6G(SCH_1):PAGE420
 U6012  ER2 GND113 PT5161LRS-PT5161LRS,SMLF,IC,AJ051610U03    I17 @T6G_MB_LIB.T6G(SCH_1):PAGE420
 U6012 ER34 GND114 PT5161LRS-PT5161LRS,SMLF,IC,AJ051610U03    I17 @T6G_MB_LIB.T6G(SCH_1):PAGE420
 U6012  ET1 GND115 PT5161LRS-PT5161LRS,SMLF,IC,AJ051610U03    I17 @T6G_MB_LIB.T6G(SCH_1):PAGE420
 U6012 ET35 GND116 PT5161LRS-PT5161LRS,SMLF,IC,AJ051610U03    I17 @T6G_MB_LIB.T6G(SCH_1):PAGE420
 U6012 FA15 GND117 PT5161LRS-PT5161LRS,SMLF,IC,AJ051610U03    I17 @T6G_MB_LIB.T6G(SCH_1):PAGE420
 U6012 FA32 GND118 PT5161LRS-PT5161LRS,SMLF,IC,AJ051610U03    I17 @T6G_MB_LIB.T6G(SCH_1):PAGE420
 U6012  FB2 GND119 PT5161LRS-PT5161LRS,SMLF,IC,AJ051610U03    I17 @T6G_MB_LIB.T6G(SCH_1):PAGE420
 U6012 FB34 GND120 PT5161LRS-PT5161LRS,SMLF,IC,AJ051610U03    I17 @T6G_MB_LIB.T6G(SCH_1):PAGE420
 U6012 FC19 GND121 PT5161LRS-PT5161LRS,SMLF,IC,AJ051610U03    I17 @T6G_MB_LIB.T6G(SCH_1):PAGE420
 U6012 FC23 GND122 PT5161LRS-PT5161LRS,SMLF,IC,AJ051610U03    I17 @T6G_MB_LIB.T6G(SCH_1):PAGE420
 U6012 FC25 GND123 PT5161LRS-PT5161LRS,SMLF,IC,AJ051610U03    I17 @T6G_MB_LIB.T6G(SCH_1):PAGE420
 U6012 FC28 GND124 PT5161LRS-PT5161LRS,SMLF,IC,AJ051610U03    I17 @T6G_MB_LIB.T6G(SCH_1):PAGE420
 U6012  FC3 GND125 PT5161LRS-PT5161LRS,SMLF,IC,AJ051610U03    I17 @T6G_MB_LIB.T6G(SCH_1):PAGE420
 U6012  FC6 GND126 PT5161LRS-PT5161LRS,SMLF,IC,AJ051610U03    I17 @T6G_MB_LIB.T6G(SCH_1):PAGE420
 U6012  FC9 GND127 PT5161LRS-PT5161LRS,SMLF,IC,AJ051610U03    I17 @T6G_MB_LIB.T6G(SCH_1):PAGE420
 U6012  FD1 GND128 PT5161LRS-PT5161LRS,SMLF,IC,AJ051610U03    I17 @T6G_MB_LIB.T6G(SCH_1):PAGE420
 U6012 FD35 GND129 PT5161LRS-PT5161LRS,SMLF,IC,AJ051610U03    I17 @T6G_MB_LIB.T6G(SCH_1):PAGE420
 U6012 FF14 GND130 PT5161LRS-PT5161LRS,SMLF,IC,AJ051610U03    I17 @T6G_MB_LIB.T6G(SCH_1):PAGE420
 U6012 FF21 GND131 PT5161LRS-PT5161LRS,SMLF,IC,AJ051610U03    I17 @T6G_MB_LIB.T6G(SCH_1):PAGE420
 U6012 FJ12 GND132 PT5161LRS-PT5161LRS,SMLF,IC,AJ051610U03    I17 @T6G_MB_LIB.T6G(SCH_1):PAGE420
 U6012 FJ19 GND133 PT5161LRS-PT5161LRS,SMLF,IC,AJ051610U03    I17 @T6G_MB_LIB.T6G(SCH_1):PAGE420
 U6012  H12 GND134 PT5161LRS-PT5161LRS,SMLF,IC,AJ051610U03    I17 @T6G_MB_LIB.T6G(SCH_1):PAGE420
 U6012  H16 GND135 PT5161LRS-PT5161LRS,SMLF,IC,AJ051610U03    I17 @T6G_MB_LIB.T6G(SCH_1):PAGE420
 U6012  H19 GND136 PT5161LRS-PT5161LRS,SMLF,IC,AJ051610U03    I17 @T6G_MB_LIB.T6G(SCH_1):PAGE420
 U6012  H31 GND137 PT5161LRS-PT5161LRS,SMLF,IC,AJ051610U03    I17 @T6G_MB_LIB.T6G(SCH_1):PAGE420
 U6012  J22 GND138 PT5161LRS-PT5161LRS,SMLF,IC,AJ051610U03    I17 @T6G_MB_LIB.T6G(SCH_1):PAGE420
 U6012   J4 GND139 PT5161LRS-PT5161LRS,SMLF,IC,AJ051610U03    I17 @T6G_MB_LIB.T6G(SCH_1):PAGE420
 U6012   K2 GND140 PT5161LRS-PT5161LRS,SMLF,IC,AJ051610U03    I17 @T6G_MB_LIB.T6G(SCH_1):PAGE420
 U6012  K34 GND141 PT5161LRS-PT5161LRS,SMLF,IC,AJ051610U03    I17 @T6G_MB_LIB.T6G(SCH_1):PAGE420
 U6012   L1 GND142 PT5161LRS-PT5161LRS,SMLF,IC,AJ051610U03    I17 @T6G_MB_LIB.T6G(SCH_1):PAGE420
 U6012  L35 GND143 PT5161LRS-PT5161LRS,SMLF,IC,AJ051610U03    I17 @T6G_MB_LIB.T6G(SCH_1):PAGE420
 U6012  T13 GND144 PT5161LRS-PT5161LRS,SMLF,IC,AJ051610U03    I17 @T6G_MB_LIB.T6G(SCH_1):PAGE420
 U6012  T22 GND145 PT5161LRS-PT5161LRS,SMLF,IC,AJ051610U03    I17 @T6G_MB_LIB.T6G(SCH_1):PAGE420
 U6012  T32 GND146 PT5161LRS-PT5161LRS,SMLF,IC,AJ051610U03    I17 @T6G_MB_LIB.T6G(SCH_1):PAGE420
 U6012   T4 GND147 PT5161LRS-PT5161LRS,SMLF,IC,AJ051610U03    I17 @T6G_MB_LIB.T6G(SCH_1):PAGE420
 U6012   U2 GND148 PT5161LRS-PT5161LRS,SMLF,IC,AJ051610U03    I17 @T6G_MB_LIB.T6G(SCH_1):PAGE420
 U6012  U34 GND149 PT5161LRS-PT5161LRS,SMLF,IC,AJ051610U03    I17 @T6G_MB_LIB.T6G(SCH_1):PAGE420
 U6012   V1 GND150 PT5161LRS-PT5161LRS,SMLF,IC,AJ051610U03    I17 @T6G_MB_LIB.T6G(SCH_1):PAGE420
 U6012  V35 GND151 PT5161LRS-PT5161LRS,SMLF,IC,AJ051610U03    I17 @T6G_MB_LIB.T6G(SCH_1):PAGE420
 R1085    2      B Q_RES_0201LF-1K,1%,1/20W,CHIP,CS21001FE07    I18 @T6G_MB_LIB.T6G(SCH_1):PAGE421
  C989    2      B Q_CAP_C0201-0.1UF,10V,10%,X7S,CH4102K6E00    I23 @T6G_MB_LIB.T6G(SCH_1):PAGE421
  C666    2      B Q_CAP_C0805-100UF,4V,20%,X6S,CH710KMEA01     I6 @T6G_MB_LIB.T6G(SCH_1):PAGE422
  C668    2      B Q_CAP_C0402-22UF,4V,20%,X6S,CH622KMEB02     I7 @T6G_MB_LIB.T6G(SCH_1):PAGE422
  C676    2      B Q_CAP_0201-1UF,4V,20%,X6S,CH-10KMEE00     I9 @T6G_MB_LIB.T6G(SCH_1):PAGE422
  C775    2      B Q_CAP_C0201-0.1UF,10V,10%,X7S,CH4102K6E00    I10 @T6G_MB_LIB.T6G(SCH_1):PAGE422
  C671    2      B Q_CAP_C0402-10UF,6.3V,20%,X6S,CH6101MEB01    I12 @T6G_MB_LIB.T6G(SCH_1):PAGE422
  C670    2      B Q_CAP_0402-4.7UF,6.3V,20%,X6S,CH5471MEB01    I13 @T6G_MB_LIB.T6G(SCH_1):PAGE422
  C673    2      B Q_CAP_0201-1UF,4V,20%,X6S,CH-10KMEE00    I15 @T6G_MB_LIB.T6G(SCH_1):PAGE422
  C677    2      B Q_CAP_0201-1UF,4V,20%,X6S,CH-10KMEE00    I16 @T6G_MB_LIB.T6G(SCH_1):PAGE422
  C774    2      B Q_CAP_C0201-0.1UF,10V,10%,X7S,CH4102K6E00    I17 @T6G_MB_LIB.T6G(SCH_1):PAGE422
  C776    2      B Q_CAP_C0201-0.1UF,10V,10%,X7S,CH4102K6E00    I18 @T6G_MB_LIB.T6G(SCH_1):PAGE422
  C777    2      B Q_CAP_C0201-0.1UF,10V,10%,X7S,CH4102K6E00    I19 @T6G_MB_LIB.T6G(SCH_1):PAGE422
  C778    2      B Q_CAP_C0201-0.1UF,10V,10%,X7S,CH4102K6E00    I20 @T6G_MB_LIB.T6G(SCH_1):PAGE422
  C665    2      B Q_CAP_C0805-100UF,4V,20%,X6S,CH710KMEA01    I25 @T6G_MB_LIB.T6G(SCH_1):PAGE422
  C669    2      B Q_CAP_C0402-10UF,6.3V,20%,X6S,CH6101MEB01    I26 @T6G_MB_LIB.T6G(SCH_1):PAGE422
  C667    2      B Q_CAP_C0402-22UF,4V,20%,X6S,CH622KMEB02    I27 @T6G_MB_LIB.T6G(SCH_1):PAGE422
  C672    2      B Q_CAP_0402-4.7UF,6.3V,20%,X6S,CH5471MEB01    I29 @T6G_MB_LIB.T6G(SCH_1):PAGE422
  C982    2      B Q_CAP_C0201-0.1UF,10V,10%,X7S,CH4102K6E00    I34 @T6G_MB_LIB.T6G(SCH_1):PAGE422
  C984    2      B Q_CAP_C0201-0.1UF,10V,10%,X7S,CH4102K6E00    I35 @T6G_MB_LIB.T6G(SCH_1):PAGE422
  C791    2      B Q_CAP_C0201-0.1UF,10V,10%,X7S,CH4102K6E00    I36 @T6G_MB_LIB.T6G(SCH_1):PAGE422
  C794    2      B Q_CAP_C0201-0.1UF,10V,10%,X7S,CH4102K6E00    I39 @T6G_MB_LIB.T6G(SCH_1):PAGE422
  C790    2      B Q_CAP_C0201-0.1UF,10V,10%,X7S,CH4102K6E00    I40 @T6G_MB_LIB.T6G(SCH_1):PAGE422
  C987    2      B Q_CAP_C0201-0.1UF,10V,10%,X7S,CH4102K6E00    I41 @T6G_MB_LIB.T6G(SCH_1):PAGE422
  C800    2      B Q_CAP_C0201-0.1UF,10V,10%,X7S,CH4102K6E00    I42 @T6G_MB_LIB.T6G(SCH_1):PAGE422
  C784    2      B Q_CAP_C0201-0.1UF,10V,10%,X7S,CH4102K6E00    I43 @T6G_MB_LIB.T6G(SCH_1):PAGE422
  C797    2      B Q_CAP_0201-1UF,4V,20%,X6S,CH-10KMEE00    I44 @T6G_MB_LIB.T6G(SCH_1):PAGE422
  C781    2      B Q_CAP_0201-1UF,4V,20%,X6S,CH-10KMEE00    I45 @T6G_MB_LIB.T6G(SCH_1):PAGE422
  C788    2      B Q_CAP_0201-1UF,4V,20%,X6S,CH-10KMEE00    I46 @T6G_MB_LIB.T6G(SCH_1):PAGE422
  C796    2      B Q_CAP_C0402-10UF,6.3V,20%,X6S,CH6101MEB01    I47 @T6G_MB_LIB.T6G(SCH_1):PAGE422
  C795    2      B Q_CAP_C0805-100UF,4V,20%,X6S,CH710KMEA01    I48 @T6G_MB_LIB.T6G(SCH_1):PAGE422
  C981    2      B Q_CAP_0402-4.7UF,6.3V,20%,X6S,CH5471MEB01    I49 @T6G_MB_LIB.T6G(SCH_1):PAGE422
  C798    2      B Q_CAP_C0805-100UF,4V,20%,X6S,CH710KMEA01    I50 @T6G_MB_LIB.T6G(SCH_1):PAGE422
  C802    2      B Q_CAP_C0805-100UF,4V,20%,X6S,CH710KMEA01    I51 @T6G_MB_LIB.T6G(SCH_1):PAGE422
  C792    2      B Q_CAP_0201-1UF,4V,20%,X6S,CH-10KMEE00    I52 @T6G_MB_LIB.T6G(SCH_1):PAGE422
  C975    2      B Q_CAP_0201-1UF,4V,20%,X6S,CH-10KMEE00    I54 @T6G_MB_LIB.T6G(SCH_1):PAGE422
  C979    2      B Q_CAP_0201-1UF,4V,20%,X6S,CH-10KMEE00    I55 @T6G_MB_LIB.T6G(SCH_1):PAGE422
  C967    2      B Q_CAP_0402-4.7UF,6.3V,20%,X6S,CH5471MEB01    I56 @T6G_MB_LIB.T6G(SCH_1):PAGE422
  C970    2      B Q_CAP_0402-4.7UF,6.3V,20%,X6S,CH5471MEB01    I57 @T6G_MB_LIB.T6G(SCH_1):PAGE422
  C966    2      B Q_CAP_C0805-100UF,4V,20%,X6S,CH710KMEA01    I58 @T6G_MB_LIB.T6G(SCH_1):PAGE422
  C969    2      B Q_CAP_C0402-22UF,4V,20%,X6S,CH622KMEB02    I59 @T6G_MB_LIB.T6G(SCH_1):PAGE422
  C977    2      B Q_CAP_0402-4.7UF,6.3V,20%,X6S,CH5471MEB01    I60 @T6G_MB_LIB.T6G(SCH_1):PAGE422
  C978    2      B Q_CAP_0201-1UF,4V,20%,X6S,CH-10KMEE00    I61 @T6G_MB_LIB.T6G(SCH_1):PAGE422
  C783    2      B Q_CAP_0201-1UF,4V,20%,X6S,CH-10KMEE00    I62 @T6G_MB_LIB.T6G(SCH_1):PAGE422
  C988    2      B Q_CAP_C0402-22UF,4V,20%,X6S,CH622KMEB02    I63 @T6G_MB_LIB.T6G(SCH_1):PAGE422
  C974    2      B Q_CAP_C0402-22UF,4V,20%,X6S,CH622KMEB02    I64 @T6G_MB_LIB.T6G(SCH_1):PAGE422
  C799    2      B Q_CAP_C0402-22UF,4V,20%,X6S,CH622KMEB02    I65 @T6G_MB_LIB.T6G(SCH_1):PAGE422
  C983    2      B Q_CAP_0201-1UF,4V,20%,X6S,CH-10KMEE00    I66 @T6G_MB_LIB.T6G(SCH_1):PAGE422
  C804    2      B Q_CAP_C0201-0.1UF,10V,10%,X7S,CH4102K6E00    I68 @T6G_MB_LIB.T6G(SCH_1):PAGE422
  C968    2      B Q_CAP_C0201-0.1UF,10V,10%,X7S,CH4102K6E00    I69 @T6G_MB_LIB.T6G(SCH_1):PAGE422
  C786    2      B Q_CAP_0201-1UF,4V,20%,X6S,CH-10KMEE00    I72 @T6G_MB_LIB.T6G(SCH_1):PAGE422
  C779    2      B Q_CAP_0201-1UF,4V,20%,X6S,CH-10KMEE00    I73 @T6G_MB_LIB.T6G(SCH_1):PAGE422
  C986    2      B Q_CAP_C0402-10UF,6.3V,20%,X6S,CH6101MEB01    I74 @T6G_MB_LIB.T6G(SCH_1):PAGE422
  C973    2      B Q_CAP_C0402-10UF,6.3V,20%,X6S,CH6101MEB01    I75 @T6G_MB_LIB.T6G(SCH_1):PAGE422
  C801    2      B Q_CAP_C0805-100UF,4V,20%,X6S,CH710KMEA01    I77 @T6G_MB_LIB.T6G(SCH_1):PAGE422
  C805    2      B Q_CAP_C0402-22UF,4V,20%,X6S,CH622KMEB02    I78 @T6G_MB_LIB.T6G(SCH_1):PAGE422
  C971    2      B Q_CAP_C0402-10UF,6.3V,20%,X6S,CH6101MEB01    I79 @T6G_MB_LIB.T6G(SCH_1):PAGE422
  C976    2      B Q_CAP_0402-4.7UF,6.3V,20%,X6S,CH5471MEB01    I80 @T6G_MB_LIB.T6G(SCH_1):PAGE422
  C980    2      B Q_CAP_0201-1UF,4V,20%,X6S,CH-10KMEE00    I81 @T6G_MB_LIB.T6G(SCH_1):PAGE422
  C780    2      B Q_CAP_C0201-0.1UF,10V,10%,X7S,CH4102K6E00    I82 @T6G_MB_LIB.T6G(SCH_1):PAGE422
  C782    2      B Q_CAP_C0201-0.1UF,10V,10%,X7S,CH4102K6E00    I83 @T6G_MB_LIB.T6G(SCH_1):PAGE422
  C785    2      B Q_CAP_C0201-0.1UF,10V,10%,X7S,CH4102K6E00    I84 @T6G_MB_LIB.T6G(SCH_1):PAGE422
  C789    2      B Q_CAP_C0201-0.1UF,10V,10%,X7S,CH4102K6E00    I86 @T6G_MB_LIB.T6G(SCH_1):PAGE422
  C803    2      B Q_CAP_C0402-10UF,6.3V,20%,X6S,CH6101MEB01    I87 @T6G_MB_LIB.T6G(SCH_1):PAGE422
  R635    2      B Q_RES_0201LF-51.1,1%,1/20W,EMPTY,CS05111FE00    I18 @T6G_MB_LIB.T6G(SCH_1):PAGE430
  R636    2      B Q_RES_0201LF-51.1,1%,1/20W,EMPTY,CS05111FE00    I19 @T6G_MB_LIB.T6G(SCH_1):PAGE430
 R1118    2      B Q_RES_0201LF-4.7K,5%,1/20W,CHIP,CS24701JE04    I36 @T6G_MB_LIB.T6G(SCH_1):PAGE430
 R1120    2      B Q_RES_0201LF-4.7K,5%,1/20W,CHIP,CS24701JE04    I37 @T6G_MB_LIB.T6G(SCH_1):PAGE430
 R1121    2      B Q_RES_0201LF-4.7K,5%,1/20W,CHIP,CS24701JE04    I39 @T6G_MB_LIB.T6G(SCH_1):PAGE430
 R1091    2      B Q_RES_0201LF-4.7K,5%,1/20W,EMPTY,CS24701JE04    I50 @T6G_MB_LIB.T6G(SCH_1):PAGE430
 R1098    2      B Q_RES_0201LF-1K,1%,1/20W,EMPTY,CS21001FE07    I65 @T6G_MB_LIB.T6G(SCH_1):PAGE430
 R1100    2      B Q_RES_0201LF-20K,1%,1/20W,CHIP,CS32001FE00    I66 @T6G_MB_LIB.T6G(SCH_1):PAGE430
 R1102    2      B Q_RES_0201LF-1K,1%,1/20W,CHIP,CS21001FE07    I69 @T6G_MB_LIB.T6G(SCH_1):PAGE430
 R1103    2      B Q_RES_0201LF-10K,1%,1/20W,CHIP,CS31001FE17    I74 @T6G_MB_LIB.T6G(SCH_1):PAGE430
 R1104    2      B Q_RES_0201LF-10K,1%,1/20W,CHIP,CS31001FE17    I75 @T6G_MB_LIB.T6G(SCH_1):PAGE430
 U6013  E30 T_SENSE PT5161LRS-PT5161LRS,SMLF,IC,AJ051610U03    I83 @T6G_MB_LIB.T6G(SCH_1):PAGE430
 R1125    2      B Q_RES_0201LF-0,5%,1/20W,CHIP,CS00001JE10    I13 @T6G_MB_LIB.T6G(SCH_1):PAGE431
 R1126    2      B Q_RES_0201LF-0,5%,1/20W,CHIP,CS00001JE10    I14 @T6G_MB_LIB.T6G(SCH_1):PAGE431
 U6013 AC13   GND1 PT5161LRS-PT5161LRS,SMLF,IC,AJ051610U03    I17 @T6G_MB_LIB.T6G(SCH_1):PAGE431
 U6013 AC22   GND2 PT5161LRS-PT5161LRS,SMLF,IC,AJ051610U03    I17 @T6G_MB_LIB.T6G(SCH_1):PAGE431
 U6013 AC32   GND3 PT5161LRS-PT5161LRS,SMLF,IC,AJ051610U03    I17 @T6G_MB_LIB.T6G(SCH_1):PAGE431
 U6013  AC4   GND4 PT5161LRS-PT5161LRS,SMLF,IC,AJ051610U03    I17 @T6G_MB_LIB.T6G(SCH_1):PAGE431
 U6013  AD2   GND5 PT5161LRS-PT5161LRS,SMLF,IC,AJ051610U03    I17 @T6G_MB_LIB.T6G(SCH_1):PAGE431
 U6013 AD34   GND6 PT5161LRS-PT5161LRS,SMLF,IC,AJ051610U03    I17 @T6G_MB_LIB.T6G(SCH_1):PAGE431
 U6013  AE1   GND7 PT5161LRS-PT5161LRS,SMLF,IC,AJ051610U03    I17 @T6G_MB_LIB.T6G(SCH_1):PAGE431
 U6013 AE35   GND8 PT5161LRS-PT5161LRS,SMLF,IC,AJ051610U03    I17 @T6G_MB_LIB.T6G(SCH_1):PAGE431
 U6013 AK13   GND9 PT5161LRS-PT5161LRS,SMLF,IC,AJ051610U03    I17 @T6G_MB_LIB.T6G(SCH_1):PAGE431
 U6013 AK22  GND10 PT5161LRS-PT5161LRS,SMLF,IC,AJ051610U03    I17 @T6G_MB_LIB.T6G(SCH_1):PAGE431
 U6013 AK32  GND11 PT5161LRS-PT5161LRS,SMLF,IC,AJ051610U03    I17 @T6G_MB_LIB.T6G(SCH_1):PAGE431
 U6013  AK4  GND12 PT5161LRS-PT5161LRS,SMLF,IC,AJ051610U03    I17 @T6G_MB_LIB.T6G(SCH_1):PAGE431
 U6013  AL2  GND13 PT5161LRS-PT5161LRS,SMLF,IC,AJ051610U03    I17 @T6G_MB_LIB.T6G(SCH_1):PAGE431
 U6013 AL34  GND14 PT5161LRS-PT5161LRS,SMLF,IC,AJ051610U03    I17 @T6G_MB_LIB.T6G(SCH_1):PAGE431
 U6013  AM1  GND15 PT5161LRS-PT5161LRS,SMLF,IC,AJ051610U03    I17 @T6G_MB_LIB.T6G(SCH_1):PAGE431
 U6013 AM35  GND16 PT5161LRS-PT5161LRS,SMLF,IC,AJ051610U03    I17 @T6G_MB_LIB.T6G(SCH_1):PAGE431
 U6013 AU13  GND17 PT5161LRS-PT5161LRS,SMLF,IC,AJ051610U03    I17 @T6G_MB_LIB.T6G(SCH_1):PAGE431
 U6013 AU22  GND18 PT5161LRS-PT5161LRS,SMLF,IC,AJ051610U03    I17 @T6G_MB_LIB.T6G(SCH_1):PAGE431
 U6013 AU32  GND19 PT5161LRS-PT5161LRS,SMLF,IC,AJ051610U03    I17 @T6G_MB_LIB.T6G(SCH_1):PAGE431
 U6013  AU4  GND20 PT5161LRS-PT5161LRS,SMLF,IC,AJ051610U03    I17 @T6G_MB_LIB.T6G(SCH_1):PAGE431
 U6013  AV2  GND21 PT5161LRS-PT5161LRS,SMLF,IC,AJ051610U03    I17 @T6G_MB_LIB.T6G(SCH_1):PAGE431
 U6013 AV34  GND22 PT5161LRS-PT5161LRS,SMLF,IC,AJ051610U03    I17 @T6G_MB_LIB.T6G(SCH_1):PAGE431
 U6013  AW1  GND23 PT5161LRS-PT5161LRS,SMLF,IC,AJ051610U03    I17 @T6G_MB_LIB.T6G(SCH_1):PAGE431
 U6013 AW35  GND24 PT5161LRS-PT5161LRS,SMLF,IC,AJ051610U03    I17 @T6G_MB_LIB.T6G(SCH_1):PAGE431
 U6013  B19  GND25 PT5161LRS-PT5161LRS,SMLF,IC,AJ051610U03    I17 @T6G_MB_LIB.T6G(SCH_1):PAGE431
 U6013 BD13  GND26 PT5161LRS-PT5161LRS,SMLF,IC,AJ051610U03    I17 @T6G_MB_LIB.T6G(SCH_1):PAGE431
 U6013 BD22  GND27 PT5161LRS-PT5161LRS,SMLF,IC,AJ051610U03    I17 @T6G_MB_LIB.T6G(SCH_1):PAGE431
 U6013 BD32  GND28 PT5161LRS-PT5161LRS,SMLF,IC,AJ051610U03    I17 @T6G_MB_LIB.T6G(SCH_1):PAGE431
 U6013  BD4  GND29 PT5161LRS-PT5161LRS,SMLF,IC,AJ051610U03    I17 @T6G_MB_LIB.T6G(SCH_1):PAGE431
 U6013  BE2  GND30 PT5161LRS-PT5161LRS,SMLF,IC,AJ051610U03    I17 @T6G_MB_LIB.T6G(SCH_1):PAGE431
 U6013 BE34  GND31 PT5161LRS-PT5161LRS,SMLF,IC,AJ051610U03    I17 @T6G_MB_LIB.T6G(SCH_1):PAGE431
 U6013  BF1  GND32 PT5161LRS-PT5161LRS,SMLF,IC,AJ051610U03    I17 @T6G_MB_LIB.T6G(SCH_1):PAGE431
 U6013 BF35  GND33 PT5161LRS-PT5161LRS,SMLF,IC,AJ051610U03    I17 @T6G_MB_LIB.T6G(SCH_1):PAGE431
 U6013 BL13  GND34 PT5161LRS-PT5161LRS,SMLF,IC,AJ051610U03    I17 @T6G_MB_LIB.T6G(SCH_1):PAGE431
 U6013 BL22  GND35 PT5161LRS-PT5161LRS,SMLF,IC,AJ051610U03    I17 @T6G_MB_LIB.T6G(SCH_1):PAGE431
 U6013 BL32  GND36 PT5161LRS-PT5161LRS,SMLF,IC,AJ051610U03    I17 @T6G_MB_LIB.T6G(SCH_1):PAGE431
 U6013  BL4  GND37 PT5161LRS-PT5161LRS,SMLF,IC,AJ051610U03    I17 @T6G_MB_LIB.T6G(SCH_1):PAGE431
 U6013  BM2  GND38 PT5161LRS-PT5161LRS,SMLF,IC,AJ051610U03    I17 @T6G_MB_LIB.T6G(SCH_1):PAGE431
 U6013 BM34  GND39 PT5161LRS-PT5161LRS,SMLF,IC,AJ051610U03    I17 @T6G_MB_LIB.T6G(SCH_1):PAGE431
 U6013  BN1  GND40 PT5161LRS-PT5161LRS,SMLF,IC,AJ051610U03    I17 @T6G_MB_LIB.T6G(SCH_1):PAGE431
 U6013 BN35  GND41 PT5161LRS-PT5161LRS,SMLF,IC,AJ051610U03    I17 @T6G_MB_LIB.T6G(SCH_1):PAGE431
 U6013 BV13  GND42 PT5161LRS-PT5161LRS,SMLF,IC,AJ051610U03    I17 @T6G_MB_LIB.T6G(SCH_1):PAGE431
 U6013 BV22  GND43 PT5161LRS-PT5161LRS,SMLF,IC,AJ051610U03    I17 @T6G_MB_LIB.T6G(SCH_1):PAGE431
 U6013 BV32  GND44 PT5161LRS-PT5161LRS,SMLF,IC,AJ051610U03    I17 @T6G_MB_LIB.T6G(SCH_1):PAGE431
 U6013  BV4  GND45 PT5161LRS-PT5161LRS,SMLF,IC,AJ051610U03    I17 @T6G_MB_LIB.T6G(SCH_1):PAGE431
 U6013  BW2  GND46 PT5161LRS-PT5161LRS,SMLF,IC,AJ051610U03    I17 @T6G_MB_LIB.T6G(SCH_1):PAGE431
 U6013 BW34  GND47 PT5161LRS-PT5161LRS,SMLF,IC,AJ051610U03    I17 @T6G_MB_LIB.T6G(SCH_1):PAGE431
 U6013  BY1  GND48 PT5161LRS-PT5161LRS,SMLF,IC,AJ051610U03    I17 @T6G_MB_LIB.T6G(SCH_1):PAGE431
 U6013 BY35  GND49 PT5161LRS-PT5161LRS,SMLF,IC,AJ051610U03    I17 @T6G_MB_LIB.T6G(SCH_1):PAGE431
 U6013 CE13  GND50 PT5161LRS-PT5161LRS,SMLF,IC,AJ051610U03    I17 @T6G_MB_LIB.T6G(SCH_1):PAGE431
 U6013 CE22  GND51 PT5161LRS-PT5161LRS,SMLF,IC,AJ051610U03    I17 @T6G_MB_LIB.T6G(SCH_1):PAGE431
 U6013 CE32  GND52 PT5161LRS-PT5161LRS,SMLF,IC,AJ051610U03    I17 @T6G_MB_LIB.T6G(SCH_1):PAGE431
 U6013  CE4  GND53 PT5161LRS-PT5161LRS,SMLF,IC,AJ051610U03    I17 @T6G_MB_LIB.T6G(SCH_1):PAGE431
 U6013  CF2  GND54 PT5161LRS-PT5161LRS,SMLF,IC,AJ051610U03    I17 @T6G_MB_LIB.T6G(SCH_1):PAGE431
 U6013 CF34  GND55 PT5161LRS-PT5161LRS,SMLF,IC,AJ051610U03    I17 @T6G_MB_LIB.T6G(SCH_1):PAGE431
 U6013  CG1  GND56 PT5161LRS-PT5161LRS,SMLF,IC,AJ051610U03    I17 @T6G_MB_LIB.T6G(SCH_1):PAGE431
 U6013 CG35  GND57 PT5161LRS-PT5161LRS,SMLF,IC,AJ051610U03    I17 @T6G_MB_LIB.T6G(SCH_1):PAGE431
 U6013 CM13  GND58 PT5161LRS-PT5161LRS,SMLF,IC,AJ051610U03    I17 @T6G_MB_LIB.T6G(SCH_1):PAGE431
 U6013 CM22  GND59 PT5161LRS-PT5161LRS,SMLF,IC,AJ051610U03    I17 @T6G_MB_LIB.T6G(SCH_1):PAGE431
 U6013 CM32  GND60 PT5161LRS-PT5161LRS,SMLF,IC,AJ051610U03    I17 @T6G_MB_LIB.T6G(SCH_1):PAGE431
 U6013  CM4  GND61 PT5161LRS-PT5161LRS,SMLF,IC,AJ051610U03    I17 @T6G_MB_LIB.T6G(SCH_1):PAGE431
 U6013  CN2  GND62 PT5161LRS-PT5161LRS,SMLF,IC,AJ051610U03    I17 @T6G_MB_LIB.T6G(SCH_1):PAGE431
 U6013 CN34  GND63 PT5161LRS-PT5161LRS,SMLF,IC,AJ051610U03    I17 @T6G_MB_LIB.T6G(SCH_1):PAGE431
 U6013  CP1  GND64 PT5161LRS-PT5161LRS,SMLF,IC,AJ051610U03    I17 @T6G_MB_LIB.T6G(SCH_1):PAGE431
 U6013 CP35  GND65 PT5161LRS-PT5161LRS,SMLF,IC,AJ051610U03    I17 @T6G_MB_LIB.T6G(SCH_1):PAGE431
 U6013 CW13  GND66 PT5161LRS-PT5161LRS,SMLF,IC,AJ051610U03    I17 @T6G_MB_LIB.T6G(SCH_1):PAGE431
 U6013 CW22  GND67 PT5161LRS-PT5161LRS,SMLF,IC,AJ051610U03    I17 @T6G_MB_LIB.T6G(SCH_1):PAGE431
 U6013 CW32  GND68 PT5161LRS-PT5161LRS,SMLF,IC,AJ051610U03    I17 @T6G_MB_LIB.T6G(SCH_1):PAGE431
 U6013  CW4  GND69 PT5161LRS-PT5161LRS,SMLF,IC,AJ051610U03    I17 @T6G_MB_LIB.T6G(SCH_1):PAGE431
 U6013  CY2  GND70 PT5161LRS-PT5161LRS,SMLF,IC,AJ051610U03    I17 @T6G_MB_LIB.T6G(SCH_1):PAGE431
 U6013 CY34  GND71 PT5161LRS-PT5161LRS,SMLF,IC,AJ051610U03    I17 @T6G_MB_LIB.T6G(SCH_1):PAGE431
 U6013  DA1  GND72 PT5161LRS-PT5161LRS,SMLF,IC,AJ051610U03    I17 @T6G_MB_LIB.T6G(SCH_1):PAGE431
 U6013 DA35  GND73 PT5161LRS-PT5161LRS,SMLF,IC,AJ051610U03    I17 @T6G_MB_LIB.T6G(SCH_1):PAGE431
 U6013 DF13  GND74 PT5161LRS-PT5161LRS,SMLF,IC,AJ051610U03    I17 @T6G_MB_LIB.T6G(SCH_1):PAGE431
 U6013 DF22  GND75 PT5161LRS-PT5161LRS,SMLF,IC,AJ051610U03    I17 @T6G_MB_LIB.T6G(SCH_1):PAGE431
 U6013 DF32  GND76 PT5161LRS-PT5161LRS,SMLF,IC,AJ051610U03    I17 @T6G_MB_LIB.T6G(SCH_1):PAGE431
 U6013  DF4  GND77 PT5161LRS-PT5161LRS,SMLF,IC,AJ051610U03    I17 @T6G_MB_LIB.T6G(SCH_1):PAGE431
 U6013  DG2  GND78 PT5161LRS-PT5161LRS,SMLF,IC,AJ051610U03    I17 @T6G_MB_LIB.T6G(SCH_1):PAGE431
 U6013 DG34  GND79 PT5161LRS-PT5161LRS,SMLF,IC,AJ051610U03    I17 @T6G_MB_LIB.T6G(SCH_1):PAGE431
 U6013  DH1  GND80 PT5161LRS-PT5161LRS,SMLF,IC,AJ051610U03    I17 @T6G_MB_LIB.T6G(SCH_1):PAGE431
 U6013 DH35  GND81 PT5161LRS-PT5161LRS,SMLF,IC,AJ051610U03    I17 @T6G_MB_LIB.T6G(SCH_1):PAGE431
 U6013 DN13  GND82 PT5161LRS-PT5161LRS,SMLF,IC,AJ051610U03    I17 @T6G_MB_LIB.T6G(SCH_1):PAGE431
 U6013 DN22  GND83 PT5161LRS-PT5161LRS,SMLF,IC,AJ051610U03    I17 @T6G_MB_LIB.T6G(SCH_1):PAGE431
 U6013 DN32  GND84 PT5161LRS-PT5161LRS,SMLF,IC,AJ051610U03    I17 @T6G_MB_LIB.T6G(SCH_1):PAGE431
 U6013  DN4  GND85 PT5161LRS-PT5161LRS,SMLF,IC,AJ051610U03    I17 @T6G_MB_LIB.T6G(SCH_1):PAGE431
 U6013  DP2  GND86 PT5161LRS-PT5161LRS,SMLF,IC,AJ051610U03    I17 @T6G_MB_LIB.T6G(SCH_1):PAGE431
 U6013 DP34  GND87 PT5161LRS-PT5161LRS,SMLF,IC,AJ051610U03    I17 @T6G_MB_LIB.T6G(SCH_1):PAGE431
 U6013  DR1  GND88 PT5161LRS-PT5161LRS,SMLF,IC,AJ051610U03    I17 @T6G_MB_LIB.T6G(SCH_1):PAGE431
 U6013 DR35  GND89 PT5161LRS-PT5161LRS,SMLF,IC,AJ051610U03    I17 @T6G_MB_LIB.T6G(SCH_1):PAGE431
 U6013 DY13  GND90 PT5161LRS-PT5161LRS,SMLF,IC,AJ051610U03    I17 @T6G_MB_LIB.T6G(SCH_1):PAGE431
 U6013 DY22  GND91 PT5161LRS-PT5161LRS,SMLF,IC,AJ051610U03    I17 @T6G_MB_LIB.T6G(SCH_1):PAGE431
 U6013 DY32  GND92 PT5161LRS-PT5161LRS,SMLF,IC,AJ051610U03    I17 @T6G_MB_LIB.T6G(SCH_1):PAGE431
 U6013  DY4  GND93 PT5161LRS-PT5161LRS,SMLF,IC,AJ051610U03    I17 @T6G_MB_LIB.T6G(SCH_1):PAGE431
 U6013  E14  GND94 PT5161LRS-PT5161LRS,SMLF,IC,AJ051610U03    I17 @T6G_MB_LIB.T6G(SCH_1):PAGE431
 U6013  E27  GND95 PT5161LRS-PT5161LRS,SMLF,IC,AJ051610U03    I17 @T6G_MB_LIB.T6G(SCH_1):PAGE431
 U6013  E33  GND96 PT5161LRS-PT5161LRS,SMLF,IC,AJ051610U03    I17 @T6G_MB_LIB.T6G(SCH_1):PAGE431
 U6013  EA2  GND97 PT5161LRS-PT5161LRS,SMLF,IC,AJ051610U03    I17 @T6G_MB_LIB.T6G(SCH_1):PAGE431
 U6013 EA34  GND98 PT5161LRS-PT5161LRS,SMLF,IC,AJ051610U03    I17 @T6G_MB_LIB.T6G(SCH_1):PAGE431
 U6013  EB1  GND99 PT5161LRS-PT5161LRS,SMLF,IC,AJ051610U03    I17 @T6G_MB_LIB.T6G(SCH_1):PAGE431
 U6013 EB35 GND100 PT5161LRS-PT5161LRS,SMLF,IC,AJ051610U03    I17 @T6G_MB_LIB.T6G(SCH_1):PAGE431
 U6013 EG13 GND101 PT5161LRS-PT5161LRS,SMLF,IC,AJ051610U03    I17 @T6G_MB_LIB.T6G(SCH_1):PAGE431
 U6013 EG22 GND102 PT5161LRS-PT5161LRS,SMLF,IC,AJ051610U03    I17 @T6G_MB_LIB.T6G(SCH_1):PAGE431
 U6013 EG32 GND103 PT5161LRS-PT5161LRS,SMLF,IC,AJ051610U03    I17 @T6G_MB_LIB.T6G(SCH_1):PAGE431
 U6013  EG4 GND104 PT5161LRS-PT5161LRS,SMLF,IC,AJ051610U03    I17 @T6G_MB_LIB.T6G(SCH_1):PAGE431
 U6013  EH2 GND105 PT5161LRS-PT5161LRS,SMLF,IC,AJ051610U03    I17 @T6G_MB_LIB.T6G(SCH_1):PAGE431
 U6013 EH34 GND106 PT5161LRS-PT5161LRS,SMLF,IC,AJ051610U03    I17 @T6G_MB_LIB.T6G(SCH_1):PAGE431
 U6013  EJ1 GND107 PT5161LRS-PT5161LRS,SMLF,IC,AJ051610U03    I17 @T6G_MB_LIB.T6G(SCH_1):PAGE431
 U6013 EJ35 GND108 PT5161LRS-PT5161LRS,SMLF,IC,AJ051610U03    I17 @T6G_MB_LIB.T6G(SCH_1):PAGE431
 U6013 EP13 GND109 PT5161LRS-PT5161LRS,SMLF,IC,AJ051610U03    I17 @T6G_MB_LIB.T6G(SCH_1):PAGE431
 U6013 EP22 GND110 PT5161LRS-PT5161LRS,SMLF,IC,AJ051610U03    I17 @T6G_MB_LIB.T6G(SCH_1):PAGE431
 U6013 EP32 GND111 PT5161LRS-PT5161LRS,SMLF,IC,AJ051610U03    I17 @T6G_MB_LIB.T6G(SCH_1):PAGE431
 U6013  EP4 GND112 PT5161LRS-PT5161LRS,SMLF,IC,AJ051610U03    I17 @T6G_MB_LIB.T6G(SCH_1):PAGE431
 U6013  ER2 GND113 PT5161LRS-PT5161LRS,SMLF,IC,AJ051610U03    I17 @T6G_MB_LIB.T6G(SCH_1):PAGE431
 U6013 ER34 GND114 PT5161LRS-PT5161LRS,SMLF,IC,AJ051610U03    I17 @T6G_MB_LIB.T6G(SCH_1):PAGE431
 U6013  ET1 GND115 PT5161LRS-PT5161LRS,SMLF,IC,AJ051610U03    I17 @T6G_MB_LIB.T6G(SCH_1):PAGE431
 U6013 ET35 GND116 PT5161LRS-PT5161LRS,SMLF,IC,AJ051610U03    I17 @T6G_MB_LIB.T6G(SCH_1):PAGE431
 U6013 FA15 GND117 PT5161LRS-PT5161LRS,SMLF,IC,AJ051610U03    I17 @T6G_MB_LIB.T6G(SCH_1):PAGE431
 U6013 FA32 GND118 PT5161LRS-PT5161LRS,SMLF,IC,AJ051610U03    I17 @T6G_MB_LIB.T6G(SCH_1):PAGE431
 U6013  FB2 GND119 PT5161LRS-PT5161LRS,SMLF,IC,AJ051610U03    I17 @T6G_MB_LIB.T6G(SCH_1):PAGE431
 U6013 FB34 GND120 PT5161LRS-PT5161LRS,SMLF,IC,AJ051610U03    I17 @T6G_MB_LIB.T6G(SCH_1):PAGE431
 U6013 FC19 GND121 PT5161LRS-PT5161LRS,SMLF,IC,AJ051610U03    I17 @T6G_MB_LIB.T6G(SCH_1):PAGE431
 U6013 FC23 GND122 PT5161LRS-PT5161LRS,SMLF,IC,AJ051610U03    I17 @T6G_MB_LIB.T6G(SCH_1):PAGE431
 U6013 FC25 GND123 PT5161LRS-PT5161LRS,SMLF,IC,AJ051610U03    I17 @T6G_MB_LIB.T6G(SCH_1):PAGE431
 U6013 FC28 GND124 PT5161LRS-PT5161LRS,SMLF,IC,AJ051610U03    I17 @T6G_MB_LIB.T6G(SCH_1):PAGE431
 U6013  FC3 GND125 PT5161LRS-PT5161LRS,SMLF,IC,AJ051610U03    I17 @T6G_MB_LIB.T6G(SCH_1):PAGE431
 U6013  FC6 GND126 PT5161LRS-PT5161LRS,SMLF,IC,AJ051610U03    I17 @T6G_MB_LIB.T6G(SCH_1):PAGE431
 U6013  FC9 GND127 PT5161LRS-PT5161LRS,SMLF,IC,AJ051610U03    I17 @T6G_MB_LIB.T6G(SCH_1):PAGE431
 U6013  FD1 GND128 PT5161LRS-PT5161LRS,SMLF,IC,AJ051610U03    I17 @T6G_MB_LIB.T6G(SCH_1):PAGE431
 U6013 FD35 GND129 PT5161LRS-PT5161LRS,SMLF,IC,AJ051610U03    I17 @T6G_MB_LIB.T6G(SCH_1):PAGE431
 U6013 FF14 GND130 PT5161LRS-PT5161LRS,SMLF,IC,AJ051610U03    I17 @T6G_MB_LIB.T6G(SCH_1):PAGE431
 U6013 FF21 GND131 PT5161LRS-PT5161LRS,SMLF,IC,AJ051610U03    I17 @T6G_MB_LIB.T6G(SCH_1):PAGE431
 U6013 FJ12 GND132 PT5161LRS-PT5161LRS,SMLF,IC,AJ051610U03    I17 @T6G_MB_LIB.T6G(SCH_1):PAGE431
 U6013 FJ19 GND133 PT5161LRS-PT5161LRS,SMLF,IC,AJ051610U03    I17 @T6G_MB_LIB.T6G(SCH_1):PAGE431
 U6013  H12 GND134 PT5161LRS-PT5161LRS,SMLF,IC,AJ051610U03    I17 @T6G_MB_LIB.T6G(SCH_1):PAGE431
 U6013  H16 GND135 PT5161LRS-PT5161LRS,SMLF,IC,AJ051610U03    I17 @T6G_MB_LIB.T6G(SCH_1):PAGE431
 U6013  H19 GND136 PT5161LRS-PT5161LRS,SMLF,IC,AJ051610U03    I17 @T6G_MB_LIB.T6G(SCH_1):PAGE431
 U6013  H31 GND137 PT5161LRS-PT5161LRS,SMLF,IC,AJ051610U03    I17 @T6G_MB_LIB.T6G(SCH_1):PAGE431
 U6013  J22 GND138 PT5161LRS-PT5161LRS,SMLF,IC,AJ051610U03    I17 @T6G_MB_LIB.T6G(SCH_1):PAGE431
 U6013   J4 GND139 PT5161LRS-PT5161LRS,SMLF,IC,AJ051610U03    I17 @T6G_MB_LIB.T6G(SCH_1):PAGE431
 U6013   K2 GND140 PT5161LRS-PT5161LRS,SMLF,IC,AJ051610U03    I17 @T6G_MB_LIB.T6G(SCH_1):PAGE431
 U6013  K34 GND141 PT5161LRS-PT5161LRS,SMLF,IC,AJ051610U03    I17 @T6G_MB_LIB.T6G(SCH_1):PAGE431
 U6013   L1 GND142 PT5161LRS-PT5161LRS,SMLF,IC,AJ051610U03    I17 @T6G_MB_LIB.T6G(SCH_1):PAGE431
 U6013  L35 GND143 PT5161LRS-PT5161LRS,SMLF,IC,AJ051610U03    I17 @T6G_MB_LIB.T6G(SCH_1):PAGE431
 U6013  T13 GND144 PT5161LRS-PT5161LRS,SMLF,IC,AJ051610U03    I17 @T6G_MB_LIB.T6G(SCH_1):PAGE431
 U6013  T22 GND145 PT5161LRS-PT5161LRS,SMLF,IC,AJ051610U03    I17 @T6G_MB_LIB.T6G(SCH_1):PAGE431
 U6013  T32 GND146 PT5161LRS-PT5161LRS,SMLF,IC,AJ051610U03    I17 @T6G_MB_LIB.T6G(SCH_1):PAGE431
 U6013   T4 GND147 PT5161LRS-PT5161LRS,SMLF,IC,AJ051610U03    I17 @T6G_MB_LIB.T6G(SCH_1):PAGE431
 U6013   U2 GND148 PT5161LRS-PT5161LRS,SMLF,IC,AJ051610U03    I17 @T6G_MB_LIB.T6G(SCH_1):PAGE431
 U6013  U34 GND149 PT5161LRS-PT5161LRS,SMLF,IC,AJ051610U03    I17 @T6G_MB_LIB.T6G(SCH_1):PAGE431
 U6013   V1 GND150 PT5161LRS-PT5161LRS,SMLF,IC,AJ051610U03    I17 @T6G_MB_LIB.T6G(SCH_1):PAGE431
 U6013  V35 GND151 PT5161LRS-PT5161LRS,SMLF,IC,AJ051610U03    I17 @T6G_MB_LIB.T6G(SCH_1):PAGE431
 R1127    2      B Q_RES_0201LF-1K,1%,1/20W,CHIP,CS21001FE07    I18 @T6G_MB_LIB.T6G(SCH_1):PAGE432
 C1057    2      B Q_CAP_C0201-0.1UF,10V,10%,X7S,CH4102K6E00    I23 @T6G_MB_LIB.T6G(SCH_1):PAGE432
  C999    2      B Q_CAP_0201-1UF,4V,20%,X6S,CH-10KMEE00     I5 @T6G_MB_LIB.T6G(SCH_1):PAGE433
 C1002    2      B Q_CAP_C0201-0.1UF,10V,10%,X7S,CH4102K6E00     I6 @T6G_MB_LIB.T6G(SCH_1):PAGE433
  C991    2      B Q_CAP_C0805-100UF,4V,20%,X6S,CH710KMEA01    I12 @T6G_MB_LIB.T6G(SCH_1):PAGE433
  C993    2      B Q_CAP_C0402-22UF,4V,20%,X6S,CH622KMEB02    I13 @T6G_MB_LIB.T6G(SCH_1):PAGE433
  C995    2      B Q_CAP_C0402-10UF,6.3V,20%,X6S,CH6101MEB01    I15 @T6G_MB_LIB.T6G(SCH_1):PAGE433
  C996    2      B Q_CAP_0402-4.7UF,6.3V,20%,X6S,CH5471MEB01    I16 @T6G_MB_LIB.T6G(SCH_1):PAGE433
  C998    2      B Q_CAP_0201-1UF,4V,20%,X6S,CH-10KMEE00    I17 @T6G_MB_LIB.T6G(SCH_1):PAGE433
  C990    2      B Q_CAP_C0805-100UF,4V,20%,X6S,CH710KMEA01    I19 @T6G_MB_LIB.T6G(SCH_1):PAGE433
  C992    2      B Q_CAP_C0402-22UF,4V,20%,X6S,CH622KMEB02    I20 @T6G_MB_LIB.T6G(SCH_1):PAGE433
  C994    2      B Q_CAP_C0402-10UF,6.3V,20%,X6S,CH6101MEB01    I21 @T6G_MB_LIB.T6G(SCH_1):PAGE433
  C997    2      B Q_CAP_0402-4.7UF,6.3V,20%,X6S,CH5471MEB01    I22 @T6G_MB_LIB.T6G(SCH_1):PAGE433
 C1000    2      B Q_CAP_0201-1UF,4V,20%,X6S,CH-10KMEE00    I24 @T6G_MB_LIB.T6G(SCH_1):PAGE433
 C1001    2      B Q_CAP_C0201-0.1UF,10V,10%,X7S,CH4102K6E00    I25 @T6G_MB_LIB.T6G(SCH_1):PAGE433
 C1003    2      B Q_CAP_C0201-0.1UF,10V,10%,X7S,CH4102K6E00    I26 @T6G_MB_LIB.T6G(SCH_1):PAGE433
 C1004    2      B Q_CAP_C0201-0.1UF,10V,10%,X7S,CH4102K6E00    I27 @T6G_MB_LIB.T6G(SCH_1):PAGE433
 C1005    2      B Q_CAP_C0201-0.1UF,10V,10%,X7S,CH4102K6E00    I28 @T6G_MB_LIB.T6G(SCH_1):PAGE433
 C1014    2      B Q_CAP_C0201-0.1UF,10V,10%,X7S,CH4102K6E00    I30 @T6G_MB_LIB.T6G(SCH_1):PAGE433
 C1021    2      B Q_CAP_C0201-0.1UF,10V,10%,X7S,CH4102K6E00    I35 @T6G_MB_LIB.T6G(SCH_1):PAGE433
 C1024    2      B Q_CAP_0201-1UF,4V,20%,X6S,CH-10KMEE00    I37 @T6G_MB_LIB.T6G(SCH_1):PAGE433
 C1027    2      B Q_CAP_0201-1UF,4V,20%,X6S,CH-10KMEE00    I38 @T6G_MB_LIB.T6G(SCH_1):PAGE433
 C1023    2      B Q_CAP_C0402-10UF,6.3V,20%,X6S,CH6101MEB01    I39 @T6G_MB_LIB.T6G(SCH_1):PAGE433
 C1036    2      B Q_CAP_C0402-10UF,6.3V,20%,X6S,CH6101MEB01    I40 @T6G_MB_LIB.T6G(SCH_1):PAGE433
 C1010    2      B Q_CAP_C0201-0.1UF,10V,10%,X7S,CH4102K6E00    I41 @T6G_MB_LIB.T6G(SCH_1):PAGE433
 C1052    2      B Q_CAP_C0201-0.1UF,10V,10%,X7S,CH4102K6E00    I42 @T6G_MB_LIB.T6G(SCH_1):PAGE433
 C1055    2      B Q_CAP_C0201-0.1UF,10V,10%,X7S,CH4102K6E00    I43 @T6G_MB_LIB.T6G(SCH_1):PAGE433
 C1035    2      B Q_CAP_C0201-0.1UF,10V,10%,X7S,CH4102K6E00    I44 @T6G_MB_LIB.T6G(SCH_1):PAGE433
 C1031    2      B Q_CAP_0201-1UF,4V,20%,X6S,CH-10KMEE00    I45 @T6G_MB_LIB.T6G(SCH_1):PAGE433
 C1006    2      B Q_CAP_0201-1UF,4V,20%,X6S,CH-10KMEE00    I46 @T6G_MB_LIB.T6G(SCH_1):PAGE433
 C1034    2      B Q_CAP_0402-4.7UF,6.3V,20%,X6S,CH5471MEB01    I47 @T6G_MB_LIB.T6G(SCH_1):PAGE433
 C1039    2      B Q_CAP_0201-1UF,4V,20%,X6S,CH-10KMEE00    I48 @T6G_MB_LIB.T6G(SCH_1):PAGE433
 C1015    2      B Q_CAP_0201-1UF,4V,20%,X6S,CH-10KMEE00    I49 @T6G_MB_LIB.T6G(SCH_1):PAGE433
 C1054    2      B Q_CAP_0402-4.7UF,6.3V,20%,X6S,CH5471MEB01    I50 @T6G_MB_LIB.T6G(SCH_1):PAGE433
 C1056    2      B Q_CAP_0402-4.7UF,6.3V,20%,X6S,CH5471MEB01    I51 @T6G_MB_LIB.T6G(SCH_1):PAGE433
 C1008    2      B Q_CAP_C0201-0.1UF,10V,10%,X7S,CH4102K6E00    I52 @T6G_MB_LIB.T6G(SCH_1):PAGE433
 C1011    2      B Q_CAP_C0201-0.1UF,10V,10%,X7S,CH4102K6E00    I53 @T6G_MB_LIB.T6G(SCH_1):PAGE433
 C1043    2      B Q_CAP_C0201-0.1UF,10V,10%,X7S,CH4102K6E00    I54 @T6G_MB_LIB.T6G(SCH_1):PAGE433
 C1047    2      B Q_CAP_C0201-0.1UF,10V,10%,X7S,CH4102K6E00    I56 @T6G_MB_LIB.T6G(SCH_1):PAGE433
 C1019    2      B Q_CAP_0201-1UF,4V,20%,X6S,CH-10KMEE00    I57 @T6G_MB_LIB.T6G(SCH_1):PAGE433
 C1046    2      B Q_CAP_0201-1UF,4V,20%,X6S,CH-10KMEE00    I59 @T6G_MB_LIB.T6G(SCH_1):PAGE433
 C1050    2      B Q_CAP_0201-1UF,4V,20%,X6S,CH-10KMEE00    I60 @T6G_MB_LIB.T6G(SCH_1):PAGE433
 C1013    2      B Q_CAP_0201-1UF,4V,20%,X6S,CH-10KMEE00    I62 @T6G_MB_LIB.T6G(SCH_1):PAGE433
 C1017    2      B Q_CAP_0201-1UF,4V,20%,X6S,CH-10KMEE00    I63 @T6G_MB_LIB.T6G(SCH_1):PAGE433
 C1022    2      B Q_CAP_C0805-100UF,4V,20%,X6S,CH710KMEA01    I66 @T6G_MB_LIB.T6G(SCH_1):PAGE433
 C1025    2      B Q_CAP_C0805-100UF,4V,20%,X6S,CH710KMEA01    I67 @T6G_MB_LIB.T6G(SCH_1):PAGE433
 C1028    2      B Q_CAP_C0805-100UF,4V,20%,X6S,CH710KMEA01    I69 @T6G_MB_LIB.T6G(SCH_1):PAGE433
 C1029    2      B Q_CAP_C0805-100UF,4V,20%,X6S,CH710KMEA01    I70 @T6G_MB_LIB.T6G(SCH_1):PAGE433
 C1033    2      B Q_CAP_C0805-100UF,4V,20%,X6S,CH710KMEA01    I71 @T6G_MB_LIB.T6G(SCH_1):PAGE433
 C1026    2      B Q_CAP_C0402-22UF,4V,20%,X6S,CH622KMEB02    I72 @T6G_MB_LIB.T6G(SCH_1):PAGE433
 C1044    2      B Q_CAP_C0402-10UF,6.3V,20%,X6S,CH6101MEB01    I73 @T6G_MB_LIB.T6G(SCH_1):PAGE433
 C1032    2      B Q_CAP_C0402-22UF,4V,20%,X6S,CH622KMEB02    I74 @T6G_MB_LIB.T6G(SCH_1):PAGE433
 C1038    2      B Q_CAP_0402-4.7UF,6.3V,20%,X6S,CH5471MEB01    I75 @T6G_MB_LIB.T6G(SCH_1):PAGE433
 C1016    2      B Q_CAP_0201-1UF,4V,20%,X6S,CH-10KMEE00    I76 @T6G_MB_LIB.T6G(SCH_1):PAGE433
 C1030    2      B Q_CAP_C0402-22UF,4V,20%,X6S,CH622KMEB02    I77 @T6G_MB_LIB.T6G(SCH_1):PAGE433
 C1041    2      B Q_CAP_C0402-22UF,4V,20%,X6S,CH622KMEB02    I78 @T6G_MB_LIB.T6G(SCH_1):PAGE433
 C1037    2      B Q_CAP_C0402-10UF,6.3V,20%,X6S,CH6101MEB01    I79 @T6G_MB_LIB.T6G(SCH_1):PAGE433
 C1049    2      B Q_CAP_C0402-10UF,6.3V,20%,X6S,CH6101MEB01    I80 @T6G_MB_LIB.T6G(SCH_1):PAGE433
 C1007    2      B Q_CAP_C0201-0.1UF,10V,10%,X7S,CH4102K6E00    I81 @T6G_MB_LIB.T6G(SCH_1):PAGE433
 C1009    2      B Q_CAP_C0201-0.1UF,10V,10%,X7S,CH4102K6E00    I82 @T6G_MB_LIB.T6G(SCH_1):PAGE433
 C1012    2      B Q_CAP_C0201-0.1UF,10V,10%,X7S,CH4102K6E00    I84 @T6G_MB_LIB.T6G(SCH_1):PAGE433
 C1048    2      B Q_CAP_C0201-0.1UF,10V,10%,X7S,CH4102K6E00    I85 @T6G_MB_LIB.T6G(SCH_1):PAGE433
 C1040    2      B Q_CAP_C0402-22UF,4V,20%,X6S,CH622KMEB02    I86 @T6G_MB_LIB.T6G(SCH_1):PAGE433
 C1045    2      B Q_CAP_0402-4.7UF,6.3V,20%,X6S,CH5471MEB01    I87 @T6G_MB_LIB.T6G(SCH_1):PAGE433
 PR883    2      B Q_RES_0402LF-0,5%,1/16W,EMPTY,CS00002JB13   I210 @T6G_MB_LIB.T6G(SCH_1):PAGE475
 R9025    2      B Q_RES_0402LF-100K,1%,1/16W,EMPTY,CS41002FB09   I106 @T6G_MB_LIB.T6G(SCH_1):PAGE84
 Q9003    1     S1 MOSFET_NCH_DUAL-PJT138K,SMLF,IC,BAM138K0003   I111 @T6G_MB_LIB.T6G(SCH_1):PAGE84
 C9005    2      B Q_CAP_0402-0.1UF,25V,10%,X7R,CH4104K1B00   I116 @T6G_MB_LIB.T6G(SCH_1):PAGE84
 Q9003    4     S2 MOSFET_NCH_DUAL-PJT138K,SMLF,IC,BAM138K0003   I121 @T6G_MB_LIB.T6G(SCH_1):PAGE84
 C2515    2      B Q_CAP_C0402-10UF,6.3V,20%,X6S,CH6101MEB01    I25 @T6G_MB_LIB.T6G(SCH_1):PAGE70
 C2512    2      B Q_CAP_C0402-10UF,6.3V,20%,X6S,CH6101MEB01    I26 @T6G_MB_LIB.T6G(SCH_1):PAGE70
 C2662    2      B Q_CAP_C0402-10UF,6.3V,20%,X6S,CH6101MEB01    I25 @T6G_MB_LIB.T6G(SCH_1):PAGE74
 C2659    2      B Q_CAP_C0402-10UF,6.3V,20%,X6S,CH6101MEB01    I26 @T6G_MB_LIB.T6G(SCH_1):PAGE74
 R3471    2      B Q_RES_0402LF-10K,1%,1/16W,EMPTY,CS31002FB08   I187 @T6G_MB_LIB.T6G(SCH_1):PAGE299
 R3472    1      A Q_RES_0402LF-0,5%,1/16W,EMPTY,CS00002JB13   I198 @T6G_MB_LIB.T6G(SCH_1):PAGE299
  Q106    4     S2 MOSFET_NCH_DUAL-PJT138K,SMLF,IC,BAM138K0003   I200 @T6G_MB_LIB.T6G(SCH_1):PAGE299
  Q106    1     S1 MOSFET_NCH_DUAL-PJT138K,SMLF,IC,BAM138K0003   I201 @T6G_MB_LIB.T6G(SCH_1):PAGE299
 U9001    3    GND 74LVC1G08W57-74LVC1G08W5-7,SMLF,IC,AL1G0008020    I25 @T6G_MB_LIB.T6G(SCH_1):PAGE340
 C9007    2      B Q_CAP_0402-0.1UF,25V,10%,X7R,CH4104K1B00    I27 @T6G_MB_LIB.T6G(SCH_1):PAGE340
   U24    S SOURCE MOSFET_N_SMLF-BSS138K,BSS138K,IC,BAM138K0000    I31 @T6G_MB_LIB.T6G(SCH_1):PAGE340
   U23    3    GND 74LVC1G08W57-74LVC1G08W5-7,SMLF,IC,AL1G0008020    I36 @T6G_MB_LIB.T6G(SCH_1):PAGE340
 C1059    2      B Q_CAP_0402-0.1UF,25V,10%,X7R,CH4104K1B00    I40 @T6G_MB_LIB.T6G(SCH_1):PAGE340
   U28    3    GND SN74LVC1G07DBVR_SMLF-SN74LVC1G07DBVR,IC,AL1G0007024    I51 @T6G_MB_LIB.T6G(SCH_1):PAGE340
 C1058    2      B Q_CAP_0402-0.1UF,25V,10%,X7R,CH4104K1B00    I53 @T6G_MB_LIB.T6G(SCH_1):PAGE340
 R4069    2      B Q_RES_0402LF-4.7K,5%,1/16W,EMPTY,CS24702JB10   I127 @T6G_MB_LIB.T6G(SCH_1):PAGE338
 R6045    2      B Q_RES_0402LF-4.7K,5%,1/16W,EMPTY,CS24702JB10   I130 @T6G_MB_LIB.T6G(SCH_1):PAGE338
   U30    3    GND SN74LVC1G07DBVR_SMLF-SN74LVC1G07DBVR,IC,AL1G0007024    I66 @T6G_MB_LIB.T6G(SCH_1):PAGE340
 C1060    2      B Q_CAP_0402-0.1UF,25V,10%,X7R,CH4104K1B00    I69 @T6G_MB_LIB.T6G(SCH_1):PAGE340
 U9002    3    GND 74LVC1G32GW_SMLF-74LVC1G32GW,IC,ALVC1G32007    I74 @T6G_MB_LIB.T6G(SCH_1):PAGE340
 C9008    2      B Q_CAP_0402-0.1UF,25V,10%,X7R,CH4104K1B00    I75 @T6G_MB_LIB.T6G(SCH_1):PAGE340
 C1061    2      B Q_CAP_0402-0.1UF,25V,10%,X7R,CH4104K1B00     I5 @T6G_MB_LIB.T6G(SCH_1):PAGE257
 C1065    2      B Q_CAP_0402-0.1UF,25V,10%,X7R,CH4104K1B00    I14 @T6G_MB_LIB.T6G(SCH_1):PAGE257
   U32    S SOURCE MOSFET_N_SMLF-BSS138K,BSS138K,IC,BAM138K0000    I24 @T6G_MB_LIB.T6G(SCH_1):PAGE257
   U31    3    GND 74LVC1G08W57-74LVC1G08W5-7,SMLF,IC,AL1G0008020    I31 @T6G_MB_LIB.T6G(SCH_1):PAGE257
 C1062    2      B Q_CAP_0402-0.1UF,25V,10%,X7R,CH4104K1B00    I36 @T6G_MB_LIB.T6G(SCH_1):PAGE257
   U37    3    GND 74LVC1G32GW_SMLF-74LVC1G32GW,IC,ALVC1G32007    I40 @T6G_MB_LIB.T6G(SCH_1):PAGE257
   U34    3    GND SN74LVC1G07DBVR_SMLF-SN74LVC1G07DBVR,IC,AL1G0007024    I45 @T6G_MB_LIB.T6G(SCH_1):PAGE257
 C1064    2      B Q_CAP_0402-0.1UF,25V,10%,X7R,CH4104K1B00    I46 @T6G_MB_LIB.T6G(SCH_1):PAGE257
 C1063    2      B Q_CAP_0402-0.1UF,25V,10%,X7R,CH4104K1B00    I55 @T6G_MB_LIB.T6G(SCH_1):PAGE257
   U35    3    GND 74LVC1G08W57-74LVC1G08W5-7,SMLF,IC,AL1G0008020    I63 @T6G_MB_LIB.T6G(SCH_1):PAGE257
   U33    3    GND SN74LVC1G07DBVR_SMLF-SN74LVC1G07DBVR,IC,AL1G0007024    I64 @T6G_MB_LIB.T6G(SCH_1):PAGE257
 R6060    2      B Q_RES_0402LF-4.7K,5%,1/16W,EMPTY,CS24702JB10   I120 @T6G_MB_LIB.T6G(SCH_1):PAGE343
 R4066    2      B Q_RES_0402LF-4.7K,5%,1/16W,EMPTY,CS24702JB10   I121 @T6G_MB_LIB.T6G(SCH_1):PAGE343
   U45    5    GND PI3CSW12ZUAEX-PI3CSW12ZUAEX,SMLF,IC,AL3CSW12000    I22 @T6G_MB_LIB.T6G(SCH_1):PAGE376
 C1069    2      B Q_CAP_C0201-0.1UF,10V,10%,X7S,CH4102K6E00    I24 @T6G_MB_LIB.T6G(SCH_1):PAGE376
 R1215    1      A Q_RES_0201LF-1K,1%,1/20W,CHIP,CS21001FE07    I28 @T6G_MB_LIB.T6G(SCH_1):PAGE376
   U42    5    GND PI3CSW12ZUAEX-PI3CSW12ZUAEX,SMLF,IC,AL3CSW12000    I31 @T6G_MB_LIB.T6G(SCH_1):PAGE376
 C1067    2      B Q_CAP_C0201-0.1UF,10V,10%,X7S,CH4102K6E00    I37 @T6G_MB_LIB.T6G(SCH_1):PAGE376
 R1213    1      A Q_RES_0201LF-1K,1%,1/20W,CHIP,CS21001FE07    I41 @T6G_MB_LIB.T6G(SCH_1):PAGE376
   U41    5    GND PI3CSW12ZUAEX-PI3CSW12ZUAEX,SMLF,IC,AL3CSW12000    I46 @T6G_MB_LIB.T6G(SCH_1):PAGE376
 C1066    2      B Q_CAP_C0201-0.1UF,10V,10%,X7S,CH4102K6E00    I48 @T6G_MB_LIB.T6G(SCH_1):PAGE376
 R1212    1      A Q_RES_0201LF-1K,1%,1/20W,CHIP,CS21001FE07    I54 @T6G_MB_LIB.T6G(SCH_1):PAGE376
   U43    5    GND PI3CSW12ZUAEX-PI3CSW12ZUAEX,SMLF,IC,AL3CSW12000    I61 @T6G_MB_LIB.T6G(SCH_1):PAGE376
 C1068    2      B Q_CAP_C0201-0.1UF,10V,10%,X7S,CH4102K6E00    I65 @T6G_MB_LIB.T6G(SCH_1):PAGE376
 R1214    1      A Q_RES_0201LF-1K,1%,1/20W,CHIP,CS21001FE07    I69 @T6G_MB_LIB.T6G(SCH_1):PAGE376
   U48    5    GND PI3CSW12ZUAEX-PI3CSW12ZUAEX,SMLF,IC,AL3CSW12000    I76 @T6G_MB_LIB.T6G(SCH_1):PAGE376
 C1073    2      B Q_CAP_C0201-0.1UF,10V,10%,X7S,CH4102K6E00    I80 @T6G_MB_LIB.T6G(SCH_1):PAGE376
 C1072    2      B Q_CAP_C0201-0.1UF,10V,10%,X7S,CH4102K6E00    I84 @T6G_MB_LIB.T6G(SCH_1):PAGE376
   U49    5    GND PI3CSW12ZUAEX-PI3CSW12ZUAEX,SMLF,IC,AL3CSW12000    I85 @T6G_MB_LIB.T6G(SCH_1):PAGE376
 R1219    1      A Q_RES_0201LF-1K,1%,1/20W,CHIP,CS21001FE07    I87 @T6G_MB_LIB.T6G(SCH_1):PAGE376
 C1070    2      B Q_CAP_C0201-0.1UF,10V,10%,X7S,CH4102K6E00    I99 @T6G_MB_LIB.T6G(SCH_1):PAGE376
 C1071    2      B Q_CAP_C0201-0.1UF,10V,10%,X7S,CH4102K6E00   I105 @T6G_MB_LIB.T6G(SCH_1):PAGE376
   U46    5    GND PI3CSW12ZUAEX-PI3CSW12ZUAEX,SMLF,IC,AL3CSW12000   I108 @T6G_MB_LIB.T6G(SCH_1):PAGE376
 R1218    1      A Q_RES_0201LF-1K,1%,1/20W,CHIP,CS21001FE07   I110 @T6G_MB_LIB.T6G(SCH_1):PAGE376
 R1216    1      A Q_RES_0201LF-1K,1%,1/20W,CHIP,CS21001FE07   I116 @T6G_MB_LIB.T6G(SCH_1):PAGE376
   U47    5    GND PI3CSW12ZUAEX-PI3CSW12ZUAEX,SMLF,IC,AL3CSW12000   I121 @T6G_MB_LIB.T6G(SCH_1):PAGE376
 R1217    1      A Q_RES_0201LF-1K,1%,1/20W,CHIP,CS21001FE07   I122 @T6G_MB_LIB.T6G(SCH_1):PAGE376
 R1226    2      B Q_RES_0402LF-9.09K,1%,1/16W,CHIP,CS29092FB05    I12 @T6G_MB_LIB.T6G(SCH_1):PAGE263
 C1093    2      B Q_CAP_0402-0.1UF,25V,10%,X7R,CH4104K1B00    I43 @T6G_MB_LIB.T6G(SCH_1):PAGE263
 C1085    2      B Q_CAP_0402-100PF,50V,5%,EMPTY,CH11006JB18    I45 @T6G_MB_LIB.T6G(SCH_1):PAGE263
 R1240    2      B Q_RES_0402LF-1K,1%,1/16W,CHIP,CS21002FB06    I57 @T6G_MB_LIB.T6G(SCH_1):PAGE263
 R1242    2      B Q_RES_0402LF-1K,1%,1/16W,CHIP,CS21002FB06    I58 @T6G_MB_LIB.T6G(SCH_1):PAGE263
 C1094    2      B Q_CAP_0402-0.1UF,25V,10%,X7R,CH4104K1B00    I68 @T6G_MB_LIB.T6G(SCH_1):PAGE263
 C1092    2      B Q_CAP_0402-0.1UF,25V,10%,X7R,CH4104K1B00    I76 @T6G_MB_LIB.T6G(SCH_1):PAGE263
 C1084    2      B Q_CAP_0402-100PF,50V,5%,EMPTY,CH11006JB18    I77 @T6G_MB_LIB.T6G(SCH_1):PAGE263
 C1074    2      B Q_CAP_0402-0.1UF,25V,10%,X7R,CH4104K1B00   I115 @T6G_MB_LIB.T6G(SCH_1):PAGE263
 R1268    2      B Q_RES_0402LF-4.7K,1%,1/16W,EMPTY,CS24702FB06   I119 @T6G_MB_LIB.T6G(SCH_1):PAGE263
 C1095    2      B Q_CAP_0402-0.1UF,25V,10%,X7R,CH4104K1B00   I130 @T6G_MB_LIB.T6G(SCH_1):PAGE263
   U51    4    GND ADC128D818CIMTXNOPB-ADC128D818CIMTX/NOPB,SMLF,IC,AA   I142 @T6G_MB_LIB.T6G(SCH_1):PAGE263
 C1076    2      B Q_CAP_C0805-10UF,16V,10%,X6S,CH6103KEA00   I152 @T6G_MB_LIB.T6G(SCH_1):PAGE263
   U50    4   AIN8 MAX11617EEET-MAX11617EEE+T,SMLF,EMPTY,AL011617W00   I156 @T6G_MB_LIB.T6G(SCH_1):PAGE263
   U50    3   AIN9 MAX11617EEET-MAX11617EEE+T,SMLF,EMPTY,AL011617W00   I156 @T6G_MB_LIB.T6G(SCH_1):PAGE263
   U50    2  AIN10 MAX11617EEET-MAX11617EEE+T,SMLF,EMPTY,AL011617W00   I156 @T6G_MB_LIB.T6G(SCH_1):PAGE263
   U50   15    GND MAX11617EEET-MAX11617EEE+T,SMLF,EMPTY,AL011617W00   I156 @T6G_MB_LIB.T6G(SCH_1):PAGE263
 C1075    2      B Q_CAP_0402-0.1UF,25V,10%,X7R,CH4104K1B00   I165 @T6G_MB_LIB.T6G(SCH_1):PAGE263
 C1077    2      B Q_CAP_C0805-10UF,16V,10%,X6S,CH6103KEA00   I166 @T6G_MB_LIB.T6G(SCH_1):PAGE263
 C1078    2      B Q_CAP_0402-100PF,50V,5%,EMPTY,CH11006JB18   I173 @T6G_MB_LIB.T6G(SCH_1):PAGE263
 C1086    2      B Q_CAP_0402-0.1UF,25V,10%,X7R,CH4104K1B00   I175 @T6G_MB_LIB.T6G(SCH_1):PAGE263
 C1079    2      B Q_CAP_0402-100PF,50V,5%,EMPTY,CH11006JB18   I185 @T6G_MB_LIB.T6G(SCH_1):PAGE263
 C1087    2      B Q_CAP_0402-0.1UF,25V,10%,X7R,CH4104K1B00   I187 @T6G_MB_LIB.T6G(SCH_1):PAGE263
 C1083    2      B Q_CAP_0402-100PF,50V,5%,EMPTY,CH11006JB18   I198 @T6G_MB_LIB.T6G(SCH_1):PAGE263
 C1091    2      B Q_CAP_0402-0.1UF,25V,10%,X7R,CH4104K1B00   I200 @T6G_MB_LIB.T6G(SCH_1):PAGE263
 C1082    2      B Q_CAP_0402-100PF,50V,5%,EMPTY,CH11006JB18   I209 @T6G_MB_LIB.T6G(SCH_1):PAGE263
 C1089    2      B Q_CAP_0402-0.1UF,25V,10%,X7R,CH4104K1B00   I211 @T6G_MB_LIB.T6G(SCH_1):PAGE263
 R1224    2      B Q_RES_0402LF-4.7K,1%,1/16W,CHIP,CS24702FB06   I216 @T6G_MB_LIB.T6G(SCH_1):PAGE263
 C1080    2      B Q_CAP_0402-100PF,50V,5%,EMPTY,CH11006JB18   I221 @T6G_MB_LIB.T6G(SCH_1):PAGE263
 C1088    2      B Q_CAP_0402-0.1UF,25V,10%,X7R,CH4104K1B00   I223 @T6G_MB_LIB.T6G(SCH_1):PAGE263
 C1081    2      B Q_CAP_0402-100PF,50V,5%,EMPTY,CH11006JB18   I232 @T6G_MB_LIB.T6G(SCH_1):PAGE263
 C1090    2      B Q_CAP_0402-0.1UF,25V,10%,X7R,CH4104K1B00   I237 @T6G_MB_LIB.T6G(SCH_1):PAGE263
 C1108    2      B Q_CAP_0402-0.1UF,25V,10%,X7R,CH4104K1B00     I5 @T6G_MB_LIB.T6G(SCH_1):PAGE466
 R1306    1      A Q_RES_0402LF-4.7K,1%,1/16W,EMPTY,CS24702FB06    I12 @T6G_MB_LIB.T6G(SCH_1):PAGE466
 R1309    1      A Q_RES_0402LF-4.7K,1%,1/16W,EMPTY,CS24702FB06    I13 @T6G_MB_LIB.T6G(SCH_1):PAGE466
 C1097    2      B Q_CAP_0402-0.1UF,25V,10%,X7R,CH4104K1B00    I19 @T6G_MB_LIB.T6G(SCH_1):PAGE466
   U55   10    GND ISL28022FRZT-ISL28022FRZ-T,SMLF,IC,AL028022003    I28 @T6G_MB_LIB.T6G(SCH_1):PAGE466
   U55   TH TH_GND ISL28022FRZT-ISL28022FRZ-T,SMLF,IC,AL028022003    I28 @T6G_MB_LIB.T6G(SCH_1):PAGE466
   U56   10    GND ISL28022FRZT-ISL28022FRZ-T,SMLF,IC,AL028022003    I29 @T6G_MB_LIB.T6G(SCH_1):PAGE466
   U56   TH TH_GND ISL28022FRZT-ISL28022FRZ-T,SMLF,IC,AL028022003    I29 @T6G_MB_LIB.T6G(SCH_1):PAGE466
 C1106    2      B Q_CAP_0402-0.1UF,25V,10%,X7R,CH4104K1B00    I36 @T6G_MB_LIB.T6G(SCH_1):PAGE466
 R1307    1      A Q_RES_0402LF-4.7K,1%,1/16W,EMPTY,CS24702FB06    I44 @T6G_MB_LIB.T6G(SCH_1):PAGE466
 R1310    1      A Q_RES_0402LF-4.7K,1%,1/16W,EMPTY,CS24702FB06    I45 @T6G_MB_LIB.T6G(SCH_1):PAGE466
 C1109    2      B Q_CAP_0402-0.1UF,25V,10%,X7R,CH4104K1B00    I51 @T6G_MB_LIB.T6G(SCH_1):PAGE466
   U52   10    GND ISL28022FRZT-ISL28022FRZ-T,SMLF,IC,AL028022003    I57 @T6G_MB_LIB.T6G(SCH_1):PAGE466
   U52   TH TH_GND ISL28022FRZT-ISL28022FRZ-T,SMLF,IC,AL028022003    I57 @T6G_MB_LIB.T6G(SCH_1):PAGE466
 C1096    2      B Q_CAP_0402-0.1UF,25V,10%,X7R,CH4104K1B00    I66 @T6G_MB_LIB.T6G(SCH_1):PAGE466
 R1305    1      A Q_RES_0402LF-4.7K,1%,1/16W,EMPTY,CS24702FB06    I72 @T6G_MB_LIB.T6G(SCH_1):PAGE466
 C1107    2      B Q_CAP_0402-0.1UF,25V,10%,X7R,CH4104K1B00    I81 @T6G_MB_LIB.T6G(SCH_1):PAGE466
 PC393    2      B Q_CAPP_SMLF-270UF,16V,20%,OSCON,CC72703MZ11    I92 @T6G_MB_LIB.T6G(SCH_1):PAGE193
 PC390    2      B Q_CAPP_SMLF-270UF,16V,20%,OSCON,CC72703MZ11    I93 @T6G_MB_LIB.T6G(SCH_1):PAGE193
 PC454    2      B Q_CAPP_SMLF-270UF,16V,20%,OSCON,CC72703MZ11    I85 @T6G_MB_LIB.T6G(SCH_1):PAGE197
 R1308    1      A Q_RES_0402LF-4.7K,1%,1/16W,CHIP,CS24702FB06    I96 @T6G_MB_LIB.T6G(SCH_1):PAGE466
  U167    1    GND NCP698SQ15T1G-NCP698SQ15T1G,SMLF,EMPTY,AL000698000   I130 @T6G_MB_LIB.T6G(SCH_1):PAGE156
  U213    9 TH_GND IML3112Y2B000NCG8-IML3112-Y2B000NCG8,SMLF,EMPTY,ALA   I111 @T6G_MB_LIB.T6G(SCH_1):PAGE138
   C24    2      B Q_CAP_C0402-10UF,6.3V,20%,EMPTY,CH6101MEB01   I112 @T6G_MB_LIB.T6G(SCH_1):PAGE138
    C9    2      B Q_CAP_C0402-1UF,25V,10%,EMPTY,CH5104KEB02   I113 @T6G_MB_LIB.T6G(SCH_1):PAGE138
    U4    5    GND PI3CSW12ZUAEX-PI3CSW12ZUAEX,SMLF,IC,AL3CSW12000   I114 @T6G_MB_LIB.T6G(SCH_1):PAGE138
    U2    4    GND PCA9617ADP-PCA9617ADP,SMLF,IC,AL009617K02    I99 @T6G_MB_LIB.T6G(SCH_1):PAGE137
 R1364    2      B Q_RES_0201LF-1K,1%,1/20W,CHIP,CS21001FE07   I111 @T6G_MB_LIB.T6G(SCH_1):PAGE385
 R1370    2      B Q_RES_0201LF-10K,1%,1/20W,CHIP,CS31001FE17   I114 @T6G_MB_LIB.T6G(SCH_1):PAGE385
 R1368    2      B Q_RES_0201LF-4.7K,5%,1/20W,CHIP,CS24701JE04   I119 @T6G_MB_LIB.T6G(SCH_1):PAGE385
  R973    2      B Q_RES_0201LF-200,1%,1/20W,CHIP,CS12001FE12   I121 @T6G_MB_LIB.T6G(SCH_1):PAGE385
 R6809    2      B Q_RES_0201LF-200,1%,1/20W,CHIP,CS12001FE12    I18 @T6G_MB_LIB.T6G(SCH_1):PAGE386
 R1391    2      B Q_RES_0201LF-1K,1%,1/20W,CHIP,CS21001FE07    I84 @T6G_MB_LIB.T6G(SCH_1):PAGE408
 R1395    2      B Q_RES_0201LF-4.7K,5%,1/20W,CHIP,CS24701JE04    I94 @T6G_MB_LIB.T6G(SCH_1):PAGE408
 R1398    2      B Q_RES_0201LF-10K,1%,1/20W,CHIP,CS31001FE17    I98 @T6G_MB_LIB.T6G(SCH_1):PAGE408
 R1041    2      B Q_RES_0201LF-200,1%,1/20W,CHIP,CS12001FE12    I18 @T6G_MB_LIB.T6G(SCH_1):PAGE409
 R1022    2      B Q_RES_0201LF-200,1%,1/20W,CHIP,CS12001FE12   I102 @T6G_MB_LIB.T6G(SCH_1):PAGE408
 R1400    2      B Q_RES_0201LF-1K,1%,1/20W,CHIP,CS21001FE07    I84 @T6G_MB_LIB.T6G(SCH_1):PAGE419
 R1406    2      B Q_RES_0201LF-10K,1%,1/20W,CHIP,CS31001FE17    I95 @T6G_MB_LIB.T6G(SCH_1):PAGE419
 R1404    2      B Q_RES_0201LF-4.7K,5%,1/20W,CHIP,CS24701JE04    I99 @T6G_MB_LIB.T6G(SCH_1):PAGE419
 R1064    2      B Q_RES_0201LF-200,1%,1/20W,CHIP,CS12001FE12   I102 @T6G_MB_LIB.T6G(SCH_1):PAGE419
 R1082    2      B Q_RES_0201LF-200,1%,1/20W,CHIP,CS12001FE12    I18 @T6G_MB_LIB.T6G(SCH_1):PAGE420
 R1408    2      B Q_RES_0201LF-1K,1%,1/20W,CHIP,CS21001FE07    I85 @T6G_MB_LIB.T6G(SCH_1):PAGE430
 R1414    2      B Q_RES_0201LF-10K,1%,1/20W,CHIP,CS31001FE17    I96 @T6G_MB_LIB.T6G(SCH_1):PAGE430
 R1412    2      B Q_RES_0201LF-4.7K,5%,1/20W,CHIP,CS24701JE04   I101 @T6G_MB_LIB.T6G(SCH_1):PAGE430
 R1106    2      B Q_RES_0201LF-200,1%,1/20W,CHIP,CS12001FE12   I102 @T6G_MB_LIB.T6G(SCH_1):PAGE430
 R1124    2      B Q_RES_0201LF-200,1%,1/20W,CHIP,CS12001FE12    I18 @T6G_MB_LIB.T6G(SCH_1):PAGE431
 R1387    2      B Q_RES_0201LF-4.7K,5%,1/20W,CHIP,CS24701JE04   I108 @T6G_MB_LIB.T6G(SCH_1):PAGE401
 R1380    2      B Q_RES_0201LF-1K,1%,1/20W,CHIP,CS21001FE07   I112 @T6G_MB_LIB.T6G(SCH_1):PAGE401
 R1389    2      B Q_RES_0201LF-10K,1%,1/20W,CHIP,CS31001FE17   I124 @T6G_MB_LIB.T6G(SCH_1):PAGE401
 R6723    2      B Q_RES_0201LF-200,1%,1/20W,CHIP,CS12001FE12   I128 @T6G_MB_LIB.T6G(SCH_1):PAGE401
  R701    2      B Q_RES_0201LF-200,1%,1/20W,CHIP,CS12001FE12   I105 @T6G_MB_LIB.T6G(SCH_1):PAGE400
 R1376    2      B Q_RES_0201LF-4.7K,5%,1/20W,CHIP,CS24701JE04   I111 @T6G_MB_LIB.T6G(SCH_1):PAGE392
 R1372    2      B Q_RES_0201LF-1K,1%,1/20W,CHIP,CS21001FE07   I115 @T6G_MB_LIB.T6G(SCH_1):PAGE392
 R1378    2      B Q_RES_0201LF-10K,1%,1/20W,CHIP,CS31001FE17   I126 @T6G_MB_LIB.T6G(SCH_1):PAGE392
  R756    2      B Q_RES_0201LF-200,1%,1/20W,CHIP,CS12001FE12   I132 @T6G_MB_LIB.T6G(SCH_1):PAGE392
 R6731    2      B Q_RES_0201LF-200,1%,1/20W,CHIP,CS12001FE12    I20 @T6G_MB_LIB.T6G(SCH_1):PAGE391
 R1421    2      B Q_RES_0201LF-4.7K,5%,1/20W,CHIP,CS24701JE04    I98 @T6G_MB_LIB.T6G(SCH_1):PAGE451
 R1416    2      B Q_RES_0201LF-1K,1%,1/20W,CHIP,CS21001FE07   I102 @T6G_MB_LIB.T6G(SCH_1):PAGE451
 R1427    2      B Q_RES_0201LF-10K,1%,1/20W,CHIP,CS31001FE17   I113 @T6G_MB_LIB.T6G(SCH_1):PAGE451
  R869    2      B Q_RES_0201LF-200,1%,1/20W,CHIP,CS12001FE12   I119 @T6G_MB_LIB.T6G(SCH_1):PAGE451
 R6795    2      B Q_RES_0201LF-200,1%,1/20W,CHIP,CS12001FE12    I20 @T6G_MB_LIB.T6G(SCH_1):PAGE452
 R1433    2      B Q_RES_0201LF-4.7K,5%,1/20W,CHIP,CS24701JE04    I98 @T6G_MB_LIB.T6G(SCH_1):PAGE462
 R1429    2      B Q_RES_0201LF-1K,1%,1/20W,CHIP,CS21001FE07   I103 @T6G_MB_LIB.T6G(SCH_1):PAGE462
 R1435    2      B Q_RES_0201LF-10K,1%,1/20W,CHIP,CS31001FE17   I114 @T6G_MB_LIB.T6G(SCH_1):PAGE462
  R910    2      B Q_RES_0201LF-200,1%,1/20W,CHIP,CS12001FE12   I119 @T6G_MB_LIB.T6G(SCH_1):PAGE462
 R6901    2      B Q_RES_0201LF-200,1%,1/20W,CHIP,CS12001FE12    I18 @T6G_MB_LIB.T6G(SCH_1):PAGE463
 R1365    2      B Q_RES_0201LF-4.7K,5%,1/20W,CHIP,CS24701JE04   I123 @T6G_MB_LIB.T6G(SCH_1):PAGE385
 R1392    2      B Q_RES_0201LF-4.7K,5%,1/20W,CHIP,CS24701JE04   I119 @T6G_MB_LIB.T6G(SCH_1):PAGE408
 R1401    2      B Q_RES_0201LF-4.7K,5%,1/20W,CHIP,CS24701JE04   I120 @T6G_MB_LIB.T6G(SCH_1):PAGE419
 R1409    2      B Q_RES_0201LF-4.7K,5%,1/20W,CHIP,CS24701JE04   I117 @T6G_MB_LIB.T6G(SCH_1):PAGE430
 R1381    2      B Q_RES_0201LF-4.7K,5%,1/20W,CHIP,CS24701JE04   I144 @T6G_MB_LIB.T6G(SCH_1):PAGE401
 R1373    2      B Q_RES_0201LF-4.7K,5%,1/20W,CHIP,CS24701JE04   I150 @T6G_MB_LIB.T6G(SCH_1):PAGE392
 R1417    2      B Q_RES_0201LF-4.7K,5%,1/20W,CHIP,CS24701JE04   I136 @T6G_MB_LIB.T6G(SCH_1):PAGE451
 R1430    2      B Q_RES_0201LF-4.7K,5%,1/20W,CHIP,CS24701JE04   I136 @T6G_MB_LIB.T6G(SCH_1):PAGE462
  JP10    3      3 CONN3_210HP1030BR1-CONN3_210-HP1-030BR1,THLF,IO,DFA   I103 @T6G_MB_LIB.T6G(SCH_1):PAGE372
JP6500    3      3 CONN3_210HP1030BR1-CONN3_210-HP1-030BR1,THLF,IO,DFA   I116 @T6G_MB_LIB.T6G(SCH_1):PAGE378
   SW1    1      1 SW20S_DHNF10FQTR-SW20S_DHNF-10F-Q-T/R,SMLF,MECH,DHA    I90 @T6G_MB_LIB.T6G(SCH_1):PAGE144
   SW1    3      3 SW20S_DHNF10FQTR-SW20S_DHNF-10F-Q-T/R,SMLF,MECH,DHA    I90 @T6G_MB_LIB.T6G(SCH_1):PAGE144
   SW1    9      9 SW20S_DHNF10FQTR-SW20S_DHNF-10F-Q-T/R,SMLF,MECH,DHA    I90 @T6G_MB_LIB.T6G(SCH_1):PAGE144
 C8008    2      B Q_CAP_0402-0.1UF,25V,10%,X7R,CH4104K1B00    I79 @T6G_MB_LIB.T6G(SCH_1):PAGE340
 U8001    1    GND APX80929SAG7-APX809-29SAG-7,SMLF,IC,AL080929000    I80 @T6G_MB_LIB.T6G(SCH_1):PAGE340
 R8093    2      B Q_RES_0402LF-100K,1%,1/16W,CHIP,CS41002FB09    I84 @T6G_MB_LIB.T6G(SCH_1):PAGE340
 C8009    2      B Q_CAP_0402-0.1UF,25V,10%,X7R,CH4104K1B00    I66 @T6G_MB_LIB.T6G(SCH_1):PAGE257
 U8002    1    GND APX80929SAG7-APX809-29SAG-7,SMLF,IC,AL080929000    I67 @T6G_MB_LIB.T6G(SCH_1):PAGE257
 R8096    2      B Q_RES_0402LF-100K,1%,1/16W,CHIP,CS41002FB09    I70 @T6G_MB_LIB.T6G(SCH_1):PAGE257
PJ09_P0_N    1      1 Q_SHORT_SM-EMPTY,SHORT16   I215 @T6G_MB_LIB.T6G(SCH_1):PAGE475
PJ09_P1_N    1      1 Q_SHORT_SM-EMPTY,SHORT16    I96 @T6G_MB_LIB.T6G(SCH_1):PAGE477
  C542    2      B Q_CAP_0201-1UF,4V,20%,X6S,CH-10KMEE00    I90 @T6G_MB_LIB.T6G(SCH_1):PAGE388
  C545    2      B Q_CAP_0201-1UF,4V,20%,X6S,CH-10KMEE00    I91 @T6G_MB_LIB.T6G(SCH_1):PAGE388
  C583    2      B Q_CAP_C0201-0.1UF,10V,10%,X7S,CH4102K6E00    I93 @T6G_MB_LIB.T6G(SCH_1):PAGE388
  C566    2      B Q_CAP_C0201-0.1UF,10V,10%,X7S,CH4102K6E00    I94 @T6G_MB_LIB.T6G(SCH_1):PAGE388
  C621    2      B Q_CAP_0201-1UF,4V,20%,X6S,CH-10KMEE00    I90 @T6G_MB_LIB.T6G(SCH_1):PAGE411
  C624    2      B Q_CAP_0201-1UF,4V,20%,X6S,CH-10KMEE00    I91 @T6G_MB_LIB.T6G(SCH_1):PAGE411
  C658    2      B Q_CAP_C0201-0.1UF,10V,10%,X7S,CH4102K6E00    I92 @T6G_MB_LIB.T6G(SCH_1):PAGE411
  C659    2      B Q_CAP_C0201-0.1UF,10V,10%,X7S,CH4102K6E00    I93 @T6G_MB_LIB.T6G(SCH_1):PAGE411
  C660    2      B Q_CAP_0201-1UF,4V,20%,X6S,CH-10KMEE00    I94 @T6G_MB_LIB.T6G(SCH_1):PAGE411
  C787    2      B Q_CAP_0201-1UF,4V,20%,X6S,CH-10KMEE00    I90 @T6G_MB_LIB.T6G(SCH_1):PAGE422
  C793    2      B Q_CAP_0201-1UF,4V,20%,X6S,CH-10KMEE00    I91 @T6G_MB_LIB.T6G(SCH_1):PAGE422
  C972    2      B Q_CAP_C0201-0.1UF,10V,10%,X7S,CH4102K6E00    I92 @T6G_MB_LIB.T6G(SCH_1):PAGE422
  C985    2      B Q_CAP_C0201-0.1UF,10V,10%,X7S,CH4102K6E00    I93 @T6G_MB_LIB.T6G(SCH_1):PAGE422
 C1018    2      B Q_CAP_0201-1UF,4V,20%,X6S,CH-10KMEE00    I90 @T6G_MB_LIB.T6G(SCH_1):PAGE433
 C1020    2      B Q_CAP_0201-1UF,4V,20%,X6S,CH-10KMEE00    I91 @T6G_MB_LIB.T6G(SCH_1):PAGE433
 C1051    2      B Q_CAP_C0201-0.1UF,10V,10%,X7S,CH4102K6E00    I92 @T6G_MB_LIB.T6G(SCH_1):PAGE433
 C1053    2      B Q_CAP_C0201-0.1UF,10V,10%,X7S,CH4102K6E00    I93 @T6G_MB_LIB.T6G(SCH_1):PAGE433
  C187    2      B Q_CAP_0201-1UF,4V,20%,X6S,CH-10KMEE00    I99 @T6G_MB_LIB.T6G(SCH_1):PAGE398
  C201    2      B Q_CAP_0201-1UF,4V,20%,X6S,CH-10KMEE00   I100 @T6G_MB_LIB.T6G(SCH_1):PAGE398
  C281    2      B Q_CAP_C0201-0.1UF,10V,10%,X7S,CH4102K6E00   I101 @T6G_MB_LIB.T6G(SCH_1):PAGE398
  C283    2      B Q_CAP_C0201-0.1UF,10V,10%,X7S,CH4102K6E00   I102 @T6G_MB_LIB.T6G(SCH_1):PAGE398
  C306    2      B Q_CAP_0201-1UF,4V,20%,X6S,CH-10KMEE00    I90 @T6G_MB_LIB.T6G(SCH_1):PAGE443
  C315    2      B Q_CAP_0201-1UF,4V,20%,X6S,CH-10KMEE00    I91 @T6G_MB_LIB.T6G(SCH_1):PAGE443
  C341    2      B Q_CAP_C0201-0.1UF,10V,10%,X7S,CH4102K6E00    I92 @T6G_MB_LIB.T6G(SCH_1):PAGE443
  C350    2      B Q_CAP_C0201-0.1UF,10V,10%,X7S,CH4102K6E00    I93 @T6G_MB_LIB.T6G(SCH_1):PAGE443
  C390    2      B Q_CAP_0201-1UF,4V,20%,X6S,CH-10KMEE00    I90 @T6G_MB_LIB.T6G(SCH_1):PAGE454
  C394    2      B Q_CAP_0201-1UF,4V,20%,X6S,CH-10KMEE00    I91 @T6G_MB_LIB.T6G(SCH_1):PAGE454
  C426    2      B Q_CAP_C0201-0.1UF,10V,10%,X7S,CH4102K6E00    I92 @T6G_MB_LIB.T6G(SCH_1):PAGE454
  C428    2      B Q_CAP_C0201-0.1UF,10V,10%,X7S,CH4102K6E00    I93 @T6G_MB_LIB.T6G(SCH_1):PAGE454
  C456    2      B Q_CAP_0201-1UF,4V,20%,X6S,CH-10KMEE00    I90 @T6G_MB_LIB.T6G(SCH_1):PAGE465
  C460    2      B Q_CAP_0201-1UF,4V,20%,X6S,CH-10KMEE00    I91 @T6G_MB_LIB.T6G(SCH_1):PAGE465
  C496    2      B Q_CAP_C0201-0.1UF,10V,10%,X7S,CH4102K6E00    I92 @T6G_MB_LIB.T6G(SCH_1):PAGE465
  C498    2      B Q_CAP_C0201-0.1UF,10V,10%,X7S,CH4102K6E00    I93 @T6G_MB_LIB.T6G(SCH_1):PAGE465
PC6902    2      B Q_CAP_C0805-22UF,16V,20%,X6S,CH6223MEA01    I56 @T6G_MB_LIB.T6G(SCH_1):PAGE469
PC6901    2      B Q_CAP_C0805-22UF,16V,20%,X6S,CH6223MEA01    I57 @T6G_MB_LIB.T6G(SCH_1):PAGE469
PC6900    2      B Q_CAP_C0805-22UF,16V,20%,X6S,CH6223MEA01    I58 @T6G_MB_LIB.T6G(SCH_1):PAGE469
PC6905    2      B Q_CAP_C0805-22UF,16V,20%,X6S,CH6223MEA01    I55 @T6G_MB_LIB.T6G(SCH_1):PAGE470
PC6904    2      B Q_CAP_C0805-22UF,16V,20%,X6S,CH6223MEA01    I56 @T6G_MB_LIB.T6G(SCH_1):PAGE470
PC6903    2      B Q_CAP_C0805-22UF,16V,20%,X6S,CH6223MEA01    I57 @T6G_MB_LIB.T6G(SCH_1):PAGE470
   C71    2      B Q_CAP_C0402-4.7PF,50V,0.1P,NPO,CH-4716TB06    I75 @T6G_MB_LIB.T6G(SCH_1):PAGE232
   C94    2      B Q_CAP_C0402-4.7PF,50V,0.1P,NPO,CH-4716TB06    I76 @T6G_MB_LIB.T6G(SCH_1):PAGE232
  C215    2      B Q_CAP_C0402-8.2PF,50V,0.1P,NP0,CH-8216TB09   I230 @T6G_MB_LIB.T6G(SCH_1):PAGE28
  C216    2      B Q_CAP_C0402-8.2PF,50V,0.1P,NP0,CH-8216TB09   I231 @T6G_MB_LIB.T6G(SCH_1):PAGE28
   C93    2      B Q_CAP_0402-15PF,50V,5%,C0G,CH01506JB06    I91 @T6G_MB_LIB.T6G(SCH_1):PAGE153
 R1229    2      B Q_RES_0402LF-18K,1%,1/16W,CHIP,CS31802FB04   I242 @T6G_MB_LIB.T6G(SCH_1):PAGE263
 R1221    2      B Q_RES_0402LF-18K,1%,1/16W,CHIP,CS31802FB04   I243 @T6G_MB_LIB.T6G(SCH_1):PAGE263
 R1220    2      B Q_RES_0402LF-18K,1%,1/16W,CHIP,CS31802FB04   I244 @T6G_MB_LIB.T6G(SCH_1):PAGE263
 R1223    2      B Q_RES_0402LF-18K,1%,1/16W,CHIP,CS31802FB04   I245 @T6G_MB_LIB.T6G(SCH_1):PAGE263
 R1222    2      B Q_RES_0402LF-18K,1%,1/16W,CHIP,CS31802FB04   I246 @T6G_MB_LIB.T6G(SCH_1):PAGE263
 R1225    2      B Q_RES_0402LF-18K,1%,1/16W,CHIP,CS31802FB04   I247 @T6G_MB_LIB.T6G(SCH_1):PAGE263
 C7003    2      B Q_CAP_C0805-47UF,4V,20%,X6S,CH647KMEA04    I95 @T6G_MB_LIB.T6G(SCH_1):PAGE388
 C7002    2      B Q_CAP_C0805-47UF,4V,20%,X6S,CH647KMEA04    I96 @T6G_MB_LIB.T6G(SCH_1):PAGE388
 C7001    2      B Q_CAPP_SMLF-470UF,2.5V,20%,SPCAP,CH747LM8818    I97 @T6G_MB_LIB.T6G(SCH_1):PAGE388
 C7000    2      B Q_CAPP_SMLF-470UF,2.5V,20%,SPCAP,CH747LM8818    I98 @T6G_MB_LIB.T6G(SCH_1):PAGE388
 C7004    2      B Q_CAPP_SMLF-470UF,2.5V,20%,SPCAP,CH747LM8818    I94 @T6G_MB_LIB.T6G(SCH_1):PAGE454
 C7005    2      B Q_CAPP_SMLF-470UF,2.5V,20%,SPCAP,CH747LM8818    I95 @T6G_MB_LIB.T6G(SCH_1):PAGE454
 C7006    2      B Q_CAP_C0805-47UF,4V,20%,X6S,CH647KMEA04    I96 @T6G_MB_LIB.T6G(SCH_1):PAGE454
 C7007    2      B Q_CAP_C0805-47UF,4V,20%,X6S,CH647KMEA04    I97 @T6G_MB_LIB.T6G(SCH_1):PAGE454
 C7008    2      B Q_CAPP_SMLF-470UF,2.5V,20%,SPCAP,CH747LM8818    I99 @T6G_MB_LIB.T6G(SCH_1):PAGE388
 C7009    2      B Q_CAPP_SMLF-470UF,2.5V,20%,SPCAP,CH747LM8818   I100 @T6G_MB_LIB.T6G(SCH_1):PAGE388
 C7010    2      B Q_CAP_C0805-100UF,4V,20%,X6S,CH710KMEA01   I101 @T6G_MB_LIB.T6G(SCH_1):PAGE388
 C7011    2      B Q_CAPP_SMLF-470UF,2.5V,20%,SPCAP,CH747LM8818    I95 @T6G_MB_LIB.T6G(SCH_1):PAGE411
 C7012    2      B Q_CAPP_SMLF-470UF,2.5V,20%,SPCAP,CH747LM8818    I96 @T6G_MB_LIB.T6G(SCH_1):PAGE411
 C7013    2      B Q_CAP_C0805-100UF,4V,20%,X6S,CH710KMEA01    I97 @T6G_MB_LIB.T6G(SCH_1):PAGE411
 C7014    2      B Q_CAPP_SMLF-470UF,2.5V,20%,SPCAP,CH747LM8818    I94 @T6G_MB_LIB.T6G(SCH_1):PAGE422
 C7015    2      B Q_CAPP_SMLF-470UF,2.5V,20%,SPCAP,CH747LM8818    I95 @T6G_MB_LIB.T6G(SCH_1):PAGE422
 C7016    2      B Q_CAP_C0805-100UF,4V,20%,X6S,CH710KMEA01    I96 @T6G_MB_LIB.T6G(SCH_1):PAGE422
 C7017    2      B Q_CAPP_SMLF-470UF,2.5V,20%,SPCAP,CH747LM8818    I94 @T6G_MB_LIB.T6G(SCH_1):PAGE433
 C7018    2      B Q_CAPP_SMLF-470UF,2.5V,20%,SPCAP,CH747LM8818    I95 @T6G_MB_LIB.T6G(SCH_1):PAGE433
 C7019    2      B Q_CAP_C0805-100UF,4V,20%,X6S,CH710KMEA01    I96 @T6G_MB_LIB.T6G(SCH_1):PAGE433
 C7020    2      B Q_CAPP_SMLF-470UF,2.5V,20%,SPCAP,CH747LM8818   I103 @T6G_MB_LIB.T6G(SCH_1):PAGE398
 C7021    2      B Q_CAPP_SMLF-470UF,2.5V,20%,SPCAP,CH747LM8818   I104 @T6G_MB_LIB.T6G(SCH_1):PAGE398
 C7022    2      B Q_CAP_C0805-100UF,4V,20%,X6S,CH710KMEA01   I105 @T6G_MB_LIB.T6G(SCH_1):PAGE398
 C7023    2      B Q_CAPP_SMLF-470UF,2.5V,20%,SPCAP,CH747LM8818    I94 @T6G_MB_LIB.T6G(SCH_1):PAGE443
 C7024    2      B Q_CAPP_SMLF-470UF,2.5V,20%,SPCAP,CH747LM8818    I95 @T6G_MB_LIB.T6G(SCH_1):PAGE443
 C7025    2      B Q_CAP_C0805-100UF,4V,20%,X6S,CH710KMEA01    I96 @T6G_MB_LIB.T6G(SCH_1):PAGE443
 C7026    2      B Q_CAPP_SMLF-470UF,2.5V,20%,SPCAP,CH747LM8818    I98 @T6G_MB_LIB.T6G(SCH_1):PAGE454
 C7027    2      B Q_CAPP_SMLF-470UF,2.5V,20%,SPCAP,CH747LM8818    I99 @T6G_MB_LIB.T6G(SCH_1):PAGE454
 C7028    2      B Q_CAP_C0805-100UF,4V,20%,X6S,CH710KMEA01   I100 @T6G_MB_LIB.T6G(SCH_1):PAGE454
 C7029    2      B Q_CAPP_SMLF-470UF,2.5V,20%,SPCAP,CH747LM8818    I94 @T6G_MB_LIB.T6G(SCH_1):PAGE465
 C7030    2      B Q_CAPP_SMLF-470UF,2.5V,20%,SPCAP,CH747LM8818    I95 @T6G_MB_LIB.T6G(SCH_1):PAGE465
 C7031    2      B Q_CAP_C0805-100UF,4V,20%,X6S,CH710KMEA01    I96 @T6G_MB_LIB.T6G(SCH_1):PAGE465
PC7000    2      B Q_CAP_C0805-22UF,16V,20%,X6S,CH6223MEA01    I85 @T6G_MB_LIB.T6G(SCH_1):PAGE180
PC7001    2      B Q_CAP_C0805-22UF,16V,20%,X6S,CH6223MEA01    I86 @T6G_MB_LIB.T6G(SCH_1):PAGE197
PC7002    2      B Q_CAP_C0805-22UF,16V,20%,X6S,CH6223MEA01    I95 @T6G_MB_LIB.T6G(SCH_1):PAGE183
PC7003    2      B Q_CAP_C0805-22UF,16V,20%,X6S,CH6223MEA01    I95 @T6G_MB_LIB.T6G(SCH_1):PAGE200
  U247   10 GND_10 9FGL0251DKILFT-9FGL0251DKILFT,SMLF,IC,AL000251002    I77 @T6G_MB_LIB.T6G(SCH_1):PAGE232
  U247   21 GND_21 9FGL0251DKILFT-9FGL0251DKILFT,SMLF,IC,AL000251002    I77 @T6G_MB_LIB.T6G(SCH_1):PAGE232
  U247   15   GNDA 9FGL0251DKILFT-9FGL0251DKILFT,SMLF,IC,AL000251002    I77 @T6G_MB_LIB.T6G(SCH_1):PAGE232
  U247    6 GNDDIG 9FGL0251DKILFT-9FGL0251DKILFT,SMLF,IC,AL000251002    I77 @T6G_MB_LIB.T6G(SCH_1):PAGE232
  U247    5 GNDREF 9FGL0251DKILFT-9FGL0251DKILFT,SMLF,IC,AL000251002    I77 @T6G_MB_LIB.T6G(SCH_1):PAGE232
  U247   24 GNDXTAL 9FGL0251DKILFT-9FGL0251DKILFT,SMLF,IC,AL000251002    I77 @T6G_MB_LIB.T6G(SCH_1):PAGE232
  U247   25 TH_GND 9FGL0251DKILFT-9FGL0251DKILFT,SMLF,IC,AL000251002    I77 @T6G_MB_LIB.T6G(SCH_1):PAGE232
 C7032    2      B Q_CAPP_SMLF-470UF,2.5V,20%,SPCAP,CH747LM8818   I102 @T6G_MB_LIB.T6G(SCH_1):PAGE388
 C7033    2      B Q_CAP_C0805-47UF,4V,20%,X6S,CH647KMEA04   I103 @T6G_MB_LIB.T6G(SCH_1):PAGE388
 C7034    2      B Q_CAP_C0805-47UF,4V,20%,X6S,CH647KMEA04   I104 @T6G_MB_LIB.T6G(SCH_1):PAGE388
 C7035    2      B Q_CAP_C0805-47UF,4V,20%,X6S,CH647KMEA04   I105 @T6G_MB_LIB.T6G(SCH_1):PAGE388
 C7036    2      B Q_CAP_C0805-47UF,4V,20%,X6S,CH647KMEA04   I106 @T6G_MB_LIB.T6G(SCH_1):PAGE388
 C7037    2      B Q_CAPP_SMLF-470UF,2.5V,20%,SPCAP,CH747LM8818   I101 @T6G_MB_LIB.T6G(SCH_1):PAGE454
 C7038    2      B Q_CAP_C0805-47UF,4V,20%,X6S,CH647KMEA04   I102 @T6G_MB_LIB.T6G(SCH_1):PAGE454
 C7039    2      B Q_CAP_C0805-47UF,4V,20%,X6S,CH647KMEA04   I103 @T6G_MB_LIB.T6G(SCH_1):PAGE454
 C7040    2      B Q_CAP_C0805-47UF,4V,20%,X6S,CH647KMEA04   I104 @T6G_MB_LIB.T6G(SCH_1):PAGE454
 C7041    2      B Q_CAP_C0805-47UF,4V,20%,X6S,CH647KMEA04   I105 @T6G_MB_LIB.T6G(SCH_1):PAGE454
  R855    2      B Q_RES_0402LF-11.5K,1%,1/16W,EMPTY,CS31152FB03     I3 @T6G_MB_LIB.T6G(SCH_1):PAGE146
 C1113    2      B Q_CAP_C0805-22UF,16V,20%,EMPTY,CH6223MEA00     I6 @T6G_MB_LIB.T6G(SCH_1):PAGE146
 R1049    2      B Q_RES_0402LF-1K,1%,1/16W,EMPTY,CS21002FB06    I12 @T6G_MB_LIB.T6G(SCH_1):PAGE146
 R1474    2      B Q_RES_0402LF-10K,1%,1/16W,EMPTY,CS31002FB08    I14 @T6G_MB_LIB.T6G(SCH_1):PAGE146
 Q7001    1      1 MOSFET_NCH_1D3S-PSMNR58-30YLH,SMLF,EMPTY,BAMNR5800A    I16 @T6G_MB_LIB.T6G(SCH_1):PAGE146
 Q7001    2      2 MOSFET_NCH_1D3S-PSMNR58-30YLH,SMLF,EMPTY,BAMNR5800A    I16 @T6G_MB_LIB.T6G(SCH_1):PAGE146
 Q7001    3      3 MOSFET_NCH_1D3S-PSMNR58-30YLH,SMLF,EMPTY,BAMNR5800A    I16 @T6G_MB_LIB.T6G(SCH_1):PAGE146
 Q7003    1      1 MOSFET_NCH_1D3S-PSMNR58-30YLH,SMLF,EMPTY,BAMNR5800A    I22 @T6G_MB_LIB.T6G(SCH_1):PAGE146
 Q7003    2      2 MOSFET_NCH_1D3S-PSMNR58-30YLH,SMLF,EMPTY,BAMNR5800A    I22 @T6G_MB_LIB.T6G(SCH_1):PAGE146
 Q7003    3      3 MOSFET_NCH_1D3S-PSMNR58-30YLH,SMLF,EMPTY,BAMNR5800A    I22 @T6G_MB_LIB.T6G(SCH_1):PAGE146
 R1475    2      B Q_RES_0402LF-10K,1%,1/16W,EMPTY,CS31002FB08    I28 @T6G_MB_LIB.T6G(SCH_1):PAGE146
 C1114    2      B Q_CAP_C0805-22UF,16V,20%,EMPTY,CH6223MEA00    I30 @T6G_MB_LIB.T6G(SCH_1):PAGE146
  R954    2      B Q_RES_0402LF-11.5K,1%,1/16W,EMPTY,CS31152FB03    I36 @T6G_MB_LIB.T6G(SCH_1):PAGE146
 R1092    2      B Q_RES_0402LF-10M,1%,1/16W,EMPTY,CS61002FB02    I39 @T6G_MB_LIB.T6G(SCH_1):PAGE146
 U9050    3    GND 74LVC1G08W57-74LVC1G08W5-7,SMLF,IC,AL1G0008020    I91 @T6G_MB_LIB.T6G(SCH_1):PAGE340
 C9050    2      B Q_CAP_0402-0.1UF,25V,10%,X7R,CH4104K1B00    I94 @T6G_MB_LIB.T6G(SCH_1):PAGE340
 U9051    3    GND 74LVC1G08W57-74LVC1G08W5-7,SMLF,IC,AL1G0008020    I78 @T6G_MB_LIB.T6G(SCH_1):PAGE257
 C9051    2      B Q_CAP_0402-0.1UF,25V,10%,X7R,CH4104K1B00    I81 @T6G_MB_LIB.T6G(SCH_1):PAGE257
 C1115    2      B Q_CAP_C0805-22UF,16V,20%,EMPTY,CH6223MEA00   I478 @T6G_MB_LIB.T6G(SCH_1):PAGE363
  C213    2      B Q_CAP_C0402-3.9P,50V,0.1P,NPO,CH-3916TB01   I232 @T6G_MB_LIB.T6G(SCH_1):PAGE28
  C214    2      B Q_CAP_C0402-3.9P,50V,0.1P,NPO,CH-3916TB01   I233 @T6G_MB_LIB.T6G(SCH_1):PAGE28
 C6000    2      B Q_CAP_0402-0.1UF,25V,10%,X7R,CH4104K1B00   I219 @T6G_MB_LIB.T6G(SCH_1):PAGE348
 R4809    2      B Q_RES_0402LF-0,5%,1/16W,CHIP,CS00002JB13   I220 @T6G_MB_LIB.T6G(SCH_1):PAGE348
 R6133    2      B Q_RES_0402LF-1K,1%,1/16W,EMPTY,CS21002FB06   I132 @T6G_MB_LIB.T6G(SCH_1):PAGE83
 R6134    2      B Q_RES_0402LF-1K,1%,1/16W,CHIP,CS21002FB06   I133 @T6G_MB_LIB.T6G(SCH_1):PAGE83
 R6135    2      B Q_RES_0402LF-1K,1%,1/16W,CHIP,CS21002FB06   I136 @T6G_MB_LIB.T6G(SCH_1):PAGE83
 R6149    2      B Q_RES_0402LF-1K,1%,1/16W,EMPTY,CS21002FB06   I137 @T6G_MB_LIB.T6G(SCH_1):PAGE83
 R6150    2      B Q_RES_0402LF-1K,1%,1/16W,CHIP,CS21002FB06   I139 @T6G_MB_LIB.T6G(SCH_1):PAGE83
 R6151    2      B Q_RES_0402LF-1K,1%,1/16W,CHIP,CS21002FB06   I141 @T6G_MB_LIB.T6G(SCH_1):PAGE83
 PU299    3   ENTM RS31312R-RS31312R,SMLF,IC,AL031312000    I95 @T6G_MB_LIB.T6G(SCH_1):PAGE350
 PU299    7    GND RS31312R-RS31312R,SMLF,IC,AL031312000    I95 @T6G_MB_LIB.T6G(SCH_1):PAGE350
 PU299    2 LOADEN RS31312R-RS31312R,SMLF,IC,AL031312000    I95 @T6G_MB_LIB.T6G(SCH_1):PAGE350
 PU204    3   ENTM RS31312R-RS31312R,SMLF,IC,AL031312000   I137 @T6G_MB_LIB.T6G(SCH_1):PAGE339
 PU204    7    GND RS31312R-RS31312R,SMLF,IC,AL031312000   I137 @T6G_MB_LIB.T6G(SCH_1):PAGE339
 PU204    2 LOADEN RS31312R-RS31312R,SMLF,IC,AL031312000   I137 @T6G_MB_LIB.T6G(SCH_1):PAGE339
 PU206    3   ENTM RS31312R-RS31312R,SMLF,IC,AL031312000    I82 @T6G_MB_LIB.T6G(SCH_1):PAGE344
 PU206    7    GND RS31312R-RS31312R,SMLF,IC,AL031312000    I82 @T6G_MB_LIB.T6G(SCH_1):PAGE344
 PU206    2 LOADEN RS31312R-RS31312R,SMLF,IC,AL031312000    I82 @T6G_MB_LIB.T6G(SCH_1):PAGE344
 PU292    3   ENTM RS31312R-RS31312R,SMLF,IC,AL031312000    I76 @T6G_MB_LIB.T6G(SCH_1):PAGE323
 PU292    7    GND RS31312R-RS31312R,SMLF,IC,AL031312000    I76 @T6G_MB_LIB.T6G(SCH_1):PAGE323
 PU292    2 LOADEN RS31312R-RS31312R,SMLF,IC,AL031312000    I76 @T6G_MB_LIB.T6G(SCH_1):PAGE323
 R6284    2      B Q_RES_0402LF-10,1%,1/16W,CHIP,CS01002FB07   I171 @T6G_MB_LIB.T6G(SCH_1):PAGE157
 C6090    2      B Q_CAP_0402-27PF,50V,5%,NPO,CH02706JB06   I174 @T6G_MB_LIB.T6G(SCH_1):PAGE157
 C6091    2      B Q_CAP_0402-27PF,50V,5%,NPO,CH02706JB06   I175 @T6G_MB_LIB.T6G(SCH_1):PAGE157

GPIO2_RT_CPU0_P0 @T6G_MB_LIB.T6G(SCH_1):GPIO2_RT_CPU0_P0
  R979    1      A Q_RES_0201LF-10K,1%,1/20W,CHIP,CS31001FE17    I27 @T6G_MB_LIB.T6G(SCH_1):PAGE385
  R978    2      B Q_RES_0201LF-4.7K,5%,1/20W,EMPTY,CS24701JE04    I30 @T6G_MB_LIB.T6G(SCH_1):PAGE385
 U6010 FJ25  GPIO2 PT5161LRS-PT5161LRS,SMLF,IC,AJ051610U03    I53 @T6G_MB_LIB.T6G(SCH_1):PAGE385

GPIO2_RT_CPU0_P1 @T6G_MB_LIB.T6G(SCH_1):GPIO2_RT_CPU0_P1
 R1028    1      A Q_RES_0201LF-10K,1%,1/20W,CHIP,CS31001FE17     I7 @T6G_MB_LIB.T6G(SCH_1):PAGE408
 R1027    2      B Q_RES_0201LF-4.7K,5%,1/20W,EMPTY,CS24701JE04    I10 @T6G_MB_LIB.T6G(SCH_1):PAGE408
 U6011 FJ25  GPIO2 PT5161LRS-PT5161LRS,SMLF,IC,AJ051610U03    I83 @T6G_MB_LIB.T6G(SCH_1):PAGE408

GPIO2_RT_CPU0_P2 @T6G_MB_LIB.T6G(SCH_1):GPIO2_RT_CPU0_P2
 R1070    1      A Q_RES_0201LF-10K,1%,1/20W,CHIP,CS31001FE17     I7 @T6G_MB_LIB.T6G(SCH_1):PAGE419
 R1069    2      B Q_RES_0201LF-4.7K,5%,1/20W,EMPTY,CS24701JE04    I10 @T6G_MB_LIB.T6G(SCH_1):PAGE419
 U6012 FJ25  GPIO2 PT5161LRS-PT5161LRS,SMLF,IC,AJ051610U03    I83 @T6G_MB_LIB.T6G(SCH_1):PAGE419

GPIO2_RT_CPU0_P3 @T6G_MB_LIB.T6G(SCH_1):GPIO2_RT_CPU0_P3
 R1112    1      A Q_RES_0201LF-10K,1%,1/20W,CHIP,CS31001FE17     I7 @T6G_MB_LIB.T6G(SCH_1):PAGE430
 R1111    2      B Q_RES_0201LF-4.7K,5%,1/20W,EMPTY,CS24701JE04    I10 @T6G_MB_LIB.T6G(SCH_1):PAGE430
 U6013 FJ25  GPIO2 PT5161LRS-PT5161LRS,SMLF,IC,AJ051610U03    I83 @T6G_MB_LIB.T6G(SCH_1):PAGE430

GPIO2_RT_CPU1_P0 @T6G_MB_LIB.T6G(SCH_1):GPIO2_RT_CPU1_P0
 U6014 FJ25  GPIO2 PT5161LRS-PT5161LRS,SMLF,IC,AJ051610U03     I1 @T6G_MB_LIB.T6G(SCH_1):PAGE401
  R706    2      B Q_RES_0201LF-4.7K,5%,1/20W,EMPTY,CS24701JE04    I29 @T6G_MB_LIB.T6G(SCH_1):PAGE401
  R707    1      A Q_RES_0201LF-10K,1%,1/20W,CHIP,CS31001FE17    I36 @T6G_MB_LIB.T6G(SCH_1):PAGE401

GPIO2_RT_CPU1_P1 @T6G_MB_LIB.T6G(SCH_1):GPIO2_RT_CPU1_P1
  R782    1      A Q_RES_0201LF-10K,1%,1/20W,CHIP,CS31001FE17    I21 @T6G_MB_LIB.T6G(SCH_1):PAGE392
  R781    2      B Q_RES_0201LF-4.7K,5%,1/20W,EMPTY,CS24701JE04    I24 @T6G_MB_LIB.T6G(SCH_1):PAGE392
 U6015 FJ25  GPIO2 PT5161LRS-PT5161LRS,SMLF,IC,AJ051610U03    I47 @T6G_MB_LIB.T6G(SCH_1):PAGE392

GPIO2_RT_CPU1_P2 @T6G_MB_LIB.T6G(SCH_1):GPIO2_RT_CPU1_P2
  R875    1      A Q_RES_0201LF-10K,1%,1/20W,CHIP,CS31001FE17    I19 @T6G_MB_LIB.T6G(SCH_1):PAGE451
  R874    2      B Q_RES_0201LF-4.7K,5%,1/20W,EMPTY,CS24701JE04    I21 @T6G_MB_LIB.T6G(SCH_1):PAGE451
 U6016 FJ25  GPIO2 PT5161LRS-PT5161LRS,SMLF,IC,AJ051610U03    I97 @T6G_MB_LIB.T6G(SCH_1):PAGE451

GPIO2_RT_CPU1_P3 @T6G_MB_LIB.T6G(SCH_1):GPIO2_RT_CPU1_P3
  R916    1      A Q_RES_0201LF-10K,1%,1/20W,CHIP,CS31001FE17    I19 @T6G_MB_LIB.T6G(SCH_1):PAGE462
  R915    2      B Q_RES_0201LF-4.7K,5%,1/20W,EMPTY,CS24701JE04    I22 @T6G_MB_LIB.T6G(SCH_1):PAGE462
 U6017 FJ25  GPIO2 PT5161LRS-PT5161LRS,SMLF,IC,AJ051610U03    I97 @T6G_MB_LIB.T6G(SCH_1):PAGE462

GPIO3_RT_CPU0_P0 @T6G_MB_LIB.T6G(SCH_1):GPIO3_RT_CPU0_P0
  R980    1      A Q_RES_0201LF-10K,1%,1/20W,CHIP,CS31001FE17    I28 @T6G_MB_LIB.T6G(SCH_1):PAGE385
 U6010 FJ28  GPIO3 PT5161LRS-PT5161LRS,SMLF,IC,AJ051610U03    I53 @T6G_MB_LIB.T6G(SCH_1):PAGE385

GPIO3_RT_CPU0_P1 @T6G_MB_LIB.T6G(SCH_1):GPIO3_RT_CPU0_P1
 R1029    1      A Q_RES_0201LF-10K,1%,1/20W,CHIP,CS31001FE17     I8 @T6G_MB_LIB.T6G(SCH_1):PAGE408
 U6011 FJ28  GPIO3 PT5161LRS-PT5161LRS,SMLF,IC,AJ051610U03    I83 @T6G_MB_LIB.T6G(SCH_1):PAGE408

GPIO3_RT_CPU0_P2 @T6G_MB_LIB.T6G(SCH_1):GPIO3_RT_CPU0_P2
 R1072    1      A Q_RES_0201LF-10K,1%,1/20W,CHIP,CS31001FE17     I8 @T6G_MB_LIB.T6G(SCH_1):PAGE419
 U6012 FJ28  GPIO3 PT5161LRS-PT5161LRS,SMLF,IC,AJ051610U03    I83 @T6G_MB_LIB.T6G(SCH_1):PAGE419

GPIO3_RT_CPU0_P3 @T6G_MB_LIB.T6G(SCH_1):GPIO3_RT_CPU0_P3
 R1113    1      A Q_RES_0201LF-10K,1%,1/20W,CHIP,CS31001FE17     I8 @T6G_MB_LIB.T6G(SCH_1):PAGE430
 U6013 FJ28  GPIO3 PT5161LRS-PT5161LRS,SMLF,IC,AJ051610U03    I83 @T6G_MB_LIB.T6G(SCH_1):PAGE430

GPIO3_RT_CPU1_P0 @T6G_MB_LIB.T6G(SCH_1):GPIO3_RT_CPU1_P0
 U6014 FJ28  GPIO3 PT5161LRS-PT5161LRS,SMLF,IC,AJ051610U03     I1 @T6G_MB_LIB.T6G(SCH_1):PAGE401
  R715    1      A Q_RES_0201LF-10K,1%,1/20W,CHIP,CS31001FE17    I35 @T6G_MB_LIB.T6G(SCH_1):PAGE401

GPIO3_RT_CPU1_P1 @T6G_MB_LIB.T6G(SCH_1):GPIO3_RT_CPU1_P1
  R783    1      A Q_RES_0201LF-10K,1%,1/20W,CHIP,CS31001FE17    I22 @T6G_MB_LIB.T6G(SCH_1):PAGE392
 U6015 FJ28  GPIO3 PT5161LRS-PT5161LRS,SMLF,IC,AJ051610U03    I47 @T6G_MB_LIB.T6G(SCH_1):PAGE392

GPIO3_RT_CPU1_P2 @T6G_MB_LIB.T6G(SCH_1):GPIO3_RT_CPU1_P2
  R876    1      A Q_RES_0201LF-10K,1%,1/20W,CHIP,CS31001FE17    I20 @T6G_MB_LIB.T6G(SCH_1):PAGE451
 U6016 FJ28  GPIO3 PT5161LRS-PT5161LRS,SMLF,IC,AJ051610U03    I97 @T6G_MB_LIB.T6G(SCH_1):PAGE451

GPIO3_RT_CPU1_P3 @T6G_MB_LIB.T6G(SCH_1):GPIO3_RT_CPU1_P3
  R917    1      A Q_RES_0201LF-10K,1%,1/20W,CHIP,CS31001FE17    I20 @T6G_MB_LIB.T6G(SCH_1):PAGE462
 U6017 FJ28  GPIO3 PT5161LRS-PT5161LRS,SMLF,IC,AJ051610U03    I97 @T6G_MB_LIB.T6G(SCH_1):PAGE462

GPU_3V3IO_RSVD0_FFU @T6G_MB_LIB.T6G(SCH_1):GPU_3V3IO_RSVD0_FFU
  J109   N4     N4 CONN112_10137002101LF-CONN112_10137002-101LF,THLF,A    I76 @T6G_MB_LIB.T6G(SCH_1):PAGE319
 R4120    1      A Q_RES_0402LF-100K,1%,1/16W,EMPTY,CS41002FB09    I22 @T6G_MB_LIB.T6G(SCH_1):PAGE332
 R4119    2      B Q_RES_0402LF-54.9K,1%,1/16W,EMPTY,CS35492FB03    I23 @T6G_MB_LIB.T6G(SCH_1):PAGE332
  Q128    2     G1 MOSFET_NCH_DUAL-PJT138K,SMLF,IC,BAM138K0003    I37 @T6G_MB_LIB.T6G(SCH_1):PAGE332
 R4575    1      A Q_RES_0402LF-0,5%,1/16W,EMPTY,CS00002JB13    I44 @T6G_MB_LIB.T6G(SCH_1):PAGE332

GPU_3V3IO_RSVD0_FFU_ISO @T6G_MB_LIB.T6G(SCH_1):GPU_3V3IO_RSVD0_FFU_ISO
 R4143    2      B Q_RES_0402LF-33.2,1%,1/16W,CHIP,CS03322FB03   I231 @T6G_MB_LIB.T6G(SCH_1):PAGE80
  Q128    3     D2 MOSFET_NCH_DUAL-PJT138K,SMLF,IC,BAM138K0003    I42 @T6G_MB_LIB.T6G(SCH_1):PAGE332
 R4575    2      B Q_RES_0402LF-0,5%,1/16W,EMPTY,CS00002JB13    I44 @T6G_MB_LIB.T6G(SCH_1):PAGE332
   C12    1      A Q_CAP_0402-0.1UF,25V,10%,X7R,CH4104K1B00    I75 @T6G_MB_LIB.T6G(SCH_1):PAGE332
 R4128    2      B Q_RES_0402LF-100K,1%,1/16W,CHIP,CS41002FB09   I104 @T6G_MB_LIB.T6G(SCH_1):PAGE332

GPU_3V3IO_RSVD0_FFU_ISO_R @T6G_MB_LIB.T6G(SCH_1):GPU_3V3IO_RSVD0_FFU_ISO_R
   U18  W13  PB30D LCMXO3LF9400C5BG484C-LCMXO3LF-9400C-5BG484C,SMLF,IA   I216 @T6G_MB_LIB.T6G(SCH_1):PAGE80
 R4143    1      A Q_RES_0402LF-33.2,1%,1/16W,CHIP,CS03322FB03   I231 @T6G_MB_LIB.T6G(SCH_1):PAGE80

GPU_3V3IO_RSVD0_FFU_N @T6G_MB_LIB.T6G(SCH_1):GPU_3V3IO_RSVD0_FFU_N
  Q128    6     D1 MOSFET_NCH_DUAL-PJT138K,SMLF,IC,BAM138K0003    I37 @T6G_MB_LIB.T6G(SCH_1):PAGE332
 R4125    2      B Q_RES_0402LF-4.7K,5%,1/16W,CHIP,CS24702JB10    I39 @T6G_MB_LIB.T6G(SCH_1):PAGE332
  Q128    5     G2 MOSFET_NCH_DUAL-PJT138K,SMLF,IC,BAM138K0003    I42 @T6G_MB_LIB.T6G(SCH_1):PAGE332

GPU_3V3IO_RSVD1 @T6G_MB_LIB.T6G(SCH_1):GPU_3V3IO_RSVD1
 R4159    1      A Q_RES_0402LF-100K,1%,1/16W,EMPTY,CS41002FB09    I13 @T6G_MB_LIB.T6G(SCH_1):PAGE331
 R4158    2      B Q_RES_0402LF-54.9K,1%,1/16W,EMPTY,CS35492FB03    I14 @T6G_MB_LIB.T6G(SCH_1):PAGE331
  Q135    2     G1 MOSFET_NCH_DUAL-PJT138K,SMLF,IC,BAM138K0003    I25 @T6G_MB_LIB.T6G(SCH_1):PAGE331
 R4569    1      A Q_RES_0402LF-0,5%,1/16W,EMPTY,CS00002JB13   I107 @T6G_MB_LIB.T6G(SCH_1):PAGE331
  J105   A7     A7 CONN112_10137002101LF-CONN112_10137002-101LF,THLF,A    I76 @T6G_MB_LIB.T6G(SCH_1):PAGE326

GPU_3V3IO_RSVD1_FFU @T6G_MB_LIB.T6G(SCH_1):GPU_3V3IO_RSVD1_FFU
  J109   N6     N6 CONN112_10137002101LF-CONN112_10137002-101LF,THLF,A    I16 @T6G_MB_LIB.T6G(SCH_1):PAGE319
 R4123    2      B Q_RES_0402LF-54.9K,1%,1/16W,EMPTY,CS35492FB03    I18 @T6G_MB_LIB.T6G(SCH_1):PAGE332
  Q131    2     G1 MOSFET_NCH_DUAL-PJT138K,SMLF,IC,BAM138K0003    I30 @T6G_MB_LIB.T6G(SCH_1):PAGE332
 R4572    1      A Q_RES_0402LF-0,5%,1/16W,EMPTY,CS00002JB13    I41 @T6G_MB_LIB.T6G(SCH_1):PAGE332
 R4124    1      A Q_RES_0402LF-100K,1%,1/16W,EMPTY,CS41002FB09   I135 @T6G_MB_LIB.T6G(SCH_1):PAGE332

GPU_3V3IO_RSVD1_FFU_ISO @T6G_MB_LIB.T6G(SCH_1):GPU_3V3IO_RSVD1_FFU_ISO
 R4144    2      B Q_RES_0402LF-33.2,1%,1/16W,CHIP,CS03322FB03   I233 @T6G_MB_LIB.T6G(SCH_1):PAGE80
  Q131    3     D2 MOSFET_NCH_DUAL-PJT138K,SMLF,IC,BAM138K0003    I40 @T6G_MB_LIB.T6G(SCH_1):PAGE332
 R4572    2      B Q_RES_0402LF-0,5%,1/16W,EMPTY,CS00002JB13    I41 @T6G_MB_LIB.T6G(SCH_1):PAGE332
 R4130    2      B Q_RES_0402LF-100K,1%,1/16W,CHIP,CS41002FB09    I70 @T6G_MB_LIB.T6G(SCH_1):PAGE332
   C14    1      A Q_CAP_0402-0.1UF,25V,10%,X7R,CH4104K1B00    I73 @T6G_MB_LIB.T6G(SCH_1):PAGE332

GPU_3V3IO_RSVD1_FFU_ISO_R @T6G_MB_LIB.T6G(SCH_1):GPU_3V3IO_RSVD1_FFU_ISO_R
   U18  T13  PB32A LCMXO3LF9400C5BG484C-LCMXO3LF-9400C-5BG484C,SMLF,IA   I216 @T6G_MB_LIB.T6G(SCH_1):PAGE80
 R4144    1      A Q_RES_0402LF-33.2,1%,1/16W,CHIP,CS03322FB03   I233 @T6G_MB_LIB.T6G(SCH_1):PAGE80

GPU_3V3IO_RSVD1_FFU_N @T6G_MB_LIB.T6G(SCH_1):GPU_3V3IO_RSVD1_FFU_N
  Q131    6     D1 MOSFET_NCH_DUAL-PJT138K,SMLF,IC,BAM138K0003    I30 @T6G_MB_LIB.T6G(SCH_1):PAGE332
 R4127    2      B Q_RES_0402LF-4.7K,5%,1/16W,CHIP,CS24702JB10    I35 @T6G_MB_LIB.T6G(SCH_1):PAGE332
  Q131    5     G2 MOSFET_NCH_DUAL-PJT138K,SMLF,IC,BAM138K0003    I40 @T6G_MB_LIB.T6G(SCH_1):PAGE332

GPU_3V3IO_RSVD1_ISO @T6G_MB_LIB.T6G(SCH_1):GPU_3V3IO_RSVD1_ISO
  Q135    3     D2 MOSFET_NCH_DUAL-PJT138K,SMLF,IC,BAM138K0003    I29 @T6G_MB_LIB.T6G(SCH_1):PAGE331
    C4    1      A Q_CAP_0402-0.1UF,25V,10%,X7R,CH4104K1B00    I44 @T6G_MB_LIB.T6G(SCH_1):PAGE331
 R4167    2      B Q_RES_0402LF-100K,1%,1/16W,CHIP,CS41002FB09    I47 @T6G_MB_LIB.T6G(SCH_1):PAGE331
 R4569    2      B Q_RES_0402LF-0,5%,1/16W,EMPTY,CS00002JB13   I107 @T6G_MB_LIB.T6G(SCH_1):PAGE331
 R4170    2      B Q_RES_0402LF-33.2,1%,1/16W,CHIP,CS03322FB03   I220 @T6G_MB_LIB.T6G(SCH_1):PAGE80

GPU_3V3IO_RSVD1_ISO_R @T6G_MB_LIB.T6G(SCH_1):GPU_3V3IO_RSVD1_ISO_R
   U18 AB12 PB29A||PCLKT2_1 LCMXO3LF9400C5BG484C-LCMXO3LF-9400C-5BG484C,SMLF,IA   I216 @T6G_MB_LIB.T6G(SCH_1):PAGE80
 R4170    1      A Q_RES_0402LF-33.2,1%,1/16W,CHIP,CS03322FB03   I220 @T6G_MB_LIB.T6G(SCH_1):PAGE80

GPU_3V3IO_RSVD1_N @T6G_MB_LIB.T6G(SCH_1):GPU_3V3IO_RSVD1_N
  Q135    6     D1 MOSFET_NCH_DUAL-PJT138K,SMLF,IC,BAM138K0003    I25 @T6G_MB_LIB.T6G(SCH_1):PAGE331
 R4164    2      B Q_RES_0402LF-4.7K,5%,1/16W,CHIP,CS24702JB10    I27 @T6G_MB_LIB.T6G(SCH_1):PAGE331
  Q135    5     G2 MOSFET_NCH_DUAL-PJT138K,SMLF,IC,BAM138K0003    I29 @T6G_MB_LIB.T6G(SCH_1):PAGE331

GPU_3V3IO_RSVD3 @T6G_MB_LIB.T6G(SCH_1):GPU_3V3IO_RSVD3
 R4163    1      A Q_RES_0402LF-100K,1%,1/16W,EMPTY,CS41002FB09     I8 @T6G_MB_LIB.T6G(SCH_1):PAGE331
 R4162    2      B Q_RES_0402LF-54.9K,1%,1/16W,EMPTY,CS35492FB03     I9 @T6G_MB_LIB.T6G(SCH_1):PAGE331
  Q137    2     G1 MOSFET_NCH_DUAL-PJT138K,SMLF,IC,BAM138K0003    I21 @T6G_MB_LIB.T6G(SCH_1):PAGE331
 R4570    1      A Q_RES_0402LF-0,5%,1/16W,EMPTY,CS00002JB13   I109 @T6G_MB_LIB.T6G(SCH_1):PAGE331
  J105   A5     A5 CONN112_10137002101LF-CONN112_10137002-101LF,THLF,A    I76 @T6G_MB_LIB.T6G(SCH_1):PAGE326

GPU_3V3IO_RSVD3_FFU @T6G_MB_LIB.T6G(SCH_1):GPU_3V3IO_RSVD3_FFU
  J108   A1     A1 CONN112_10137002101LF-CONN112_10137002-101LF,THLF,A    I72 @T6G_MB_LIB.T6G(SCH_1):PAGE320
 R4132    1      A Q_RES_0402LF-100K,1%,1/16W,EMPTY,CS41002FB09    I96 @T6G_MB_LIB.T6G(SCH_1):PAGE332
 R4131    2      B Q_RES_0402LF-54.9K,1%,1/16W,EMPTY,CS35492FB03    I97 @T6G_MB_LIB.T6G(SCH_1):PAGE332
  Q130    2     G1 MOSFET_NCH_DUAL-PJT138K,SMLF,IC,BAM138K0003   I102 @T6G_MB_LIB.T6G(SCH_1):PAGE332
 R4577    1      A Q_RES_0402LF-0,5%,1/16W,EMPTY,CS00002JB13   I109 @T6G_MB_LIB.T6G(SCH_1):PAGE332

GPU_3V3IO_RSVD3_FFU_ISO @T6G_MB_LIB.T6G(SCH_1):GPU_3V3IO_RSVD3_FFU_ISO
 R4146    2      B Q_RES_0402LF-33.2,1%,1/16W,CHIP,CS03322FB03   I122 @T6G_MB_LIB.T6G(SCH_1):PAGE79
 R4577    2      B Q_RES_0402LF-0,5%,1/16W,EMPTY,CS00002JB13   I109 @T6G_MB_LIB.T6G(SCH_1):PAGE332
  Q130    3     D2 MOSFET_NCH_DUAL-PJT138K,SMLF,IC,BAM138K0003   I123 @T6G_MB_LIB.T6G(SCH_1):PAGE332
   C16    1      A Q_CAP_0402-0.1UF,25V,10%,X7R,CH4104K1B00   I130 @T6G_MB_LIB.T6G(SCH_1):PAGE332
 R4140    2      B Q_RES_0402LF-100K,1%,1/16W,CHIP,CS41002FB09   I131 @T6G_MB_LIB.T6G(SCH_1):PAGE332

GPU_3V3IO_RSVD3_FFU_ISO_R @T6G_MB_LIB.T6G(SCH_1):GPU_3V3IO_RSVD3_FFU_ISO_R
   U18  F12  PT28B LCMXO3LF9400C5BG484C-LCMXO3LF-9400C-5BG484C,SMLF,IA    I94 @T6G_MB_LIB.T6G(SCH_1):PAGE79
 R4146    1      A Q_RES_0402LF-33.2,1%,1/16W,CHIP,CS03322FB03   I122 @T6G_MB_LIB.T6G(SCH_1):PAGE79

GPU_3V3IO_RSVD3_FFU_N @T6G_MB_LIB.T6G(SCH_1):GPU_3V3IO_RSVD3_FFU_N
  Q130    6     D1 MOSFET_NCH_DUAL-PJT138K,SMLF,IC,BAM138K0003   I102 @T6G_MB_LIB.T6G(SCH_1):PAGE332
 R4137    2      B Q_RES_0402LF-4.7K,5%,1/16W,CHIP,CS24702JB10   I107 @T6G_MB_LIB.T6G(SCH_1):PAGE332
  Q130    5     G2 MOSFET_NCH_DUAL-PJT138K,SMLF,IC,BAM138K0003   I123 @T6G_MB_LIB.T6G(SCH_1):PAGE332

GPU_3V3IO_RSVD3_ISO @T6G_MB_LIB.T6G(SCH_1):GPU_3V3IO_RSVD3_ISO
  Q137    3     D2 MOSFET_NCH_DUAL-PJT138K,SMLF,IC,BAM138K0003    I28 @T6G_MB_LIB.T6G(SCH_1):PAGE331
 R4169    2      B Q_RES_0402LF-100K,1%,1/16W,CHIP,CS41002FB09    I39 @T6G_MB_LIB.T6G(SCH_1):PAGE331
    C7    1      A Q_CAP_0402-0.1UF,25V,10%,X7R,CH4104K1B00    I42 @T6G_MB_LIB.T6G(SCH_1):PAGE331
 R4570    2      B Q_RES_0402LF-0,5%,1/16W,EMPTY,CS00002JB13   I109 @T6G_MB_LIB.T6G(SCH_1):PAGE331
 R4171    2      B Q_RES_0402LF-33.2,1%,1/16W,CHIP,CS03322FB03   I223 @T6G_MB_LIB.T6G(SCH_1):PAGE80

GPU_3V3IO_RSVD3_ISO_R @T6G_MB_LIB.T6G(SCH_1):GPU_3V3IO_RSVD3_ISO_R
   U18 AA12 PB29B||PCLKC2_1 LCMXO3LF9400C5BG484C-LCMXO3LF-9400C-5BG484C,SMLF,IA   I216 @T6G_MB_LIB.T6G(SCH_1):PAGE80
 R4171    1      A Q_RES_0402LF-33.2,1%,1/16W,CHIP,CS03322FB03   I223 @T6G_MB_LIB.T6G(SCH_1):PAGE80

GPU_3V3IO_RSVD3_N @T6G_MB_LIB.T6G(SCH_1):GPU_3V3IO_RSVD3_N
  Q137    6     D1 MOSFET_NCH_DUAL-PJT138K,SMLF,IC,BAM138K0003    I21 @T6G_MB_LIB.T6G(SCH_1):PAGE331
 R4166    2      B Q_RES_0402LF-4.7K,5%,1/16W,CHIP,CS24702JB10    I23 @T6G_MB_LIB.T6G(SCH_1):PAGE331
  Q137    5     G2 MOSFET_NCH_DUAL-PJT138K,SMLF,IC,BAM138K0003    I28 @T6G_MB_LIB.T6G(SCH_1):PAGE331

GPU_3V3IO_RSVD4 @T6G_MB_LIB.T6G(SCH_1):GPU_3V3IO_RSVD4
 R4161    1      A Q_RES_0402LF-100K,1%,1/16W,EMPTY,CS41002FB09     I2 @T6G_MB_LIB.T6G(SCH_1):PAGE331
 R4160    2      B Q_RES_0402LF-54.9K,1%,1/16W,EMPTY,CS35492FB03     I4 @T6G_MB_LIB.T6G(SCH_1):PAGE331
  Q136    2     G1 MOSFET_NCH_DUAL-PJT138K,SMLF,IC,BAM138K0003    I17 @T6G_MB_LIB.T6G(SCH_1):PAGE331
 R4571    1      A Q_RES_0402LF-0,5%,1/16W,EMPTY,CS00002JB13   I108 @T6G_MB_LIB.T6G(SCH_1):PAGE331
  J105   A1     A1 CONN112_10137002101LF-CONN112_10137002-101LF,THLF,A    I75 @T6G_MB_LIB.T6G(SCH_1):PAGE326

GPU_3V3IO_RSVD4_ISO @T6G_MB_LIB.T6G(SCH_1):GPU_3V3IO_RSVD4_ISO
  Q136    3     D2 MOSFET_NCH_DUAL-PJT138K,SMLF,IC,BAM138K0003    I22 @T6G_MB_LIB.T6G(SCH_1):PAGE331
    C5    1      A Q_CAP_0402-0.1UF,25V,10%,X7R,CH4104K1B00    I33 @T6G_MB_LIB.T6G(SCH_1):PAGE331
 R4168    2      B Q_RES_0402LF-100K,1%,1/16W,CHIP,CS41002FB09    I35 @T6G_MB_LIB.T6G(SCH_1):PAGE331
 R4571    2      B Q_RES_0402LF-0,5%,1/16W,EMPTY,CS00002JB13   I108 @T6G_MB_LIB.T6G(SCH_1):PAGE331
 R4172    2      B Q_RES_0402LF-33.2,1%,1/16W,CHIP,CS03322FB03   I224 @T6G_MB_LIB.T6G(SCH_1):PAGE80

GPU_3V3IO_RSVD4_ISO_R @T6G_MB_LIB.T6G(SCH_1):GPU_3V3IO_RSVD4_ISO_R
   U18  V13  PB29C LCMXO3LF9400C5BG484C-LCMXO3LF-9400C-5BG484C,SMLF,IA   I216 @T6G_MB_LIB.T6G(SCH_1):PAGE80
 R4172    1      A Q_RES_0402LF-33.2,1%,1/16W,CHIP,CS03322FB03   I224 @T6G_MB_LIB.T6G(SCH_1):PAGE80

GPU_3V3IO_RSVD4_N @T6G_MB_LIB.T6G(SCH_1):GPU_3V3IO_RSVD4_N
  Q136    6     D1 MOSFET_NCH_DUAL-PJT138K,SMLF,IC,BAM138K0003    I17 @T6G_MB_LIB.T6G(SCH_1):PAGE331
 R4165    2      B Q_RES_0402LF-4.7K,5%,1/16W,CHIP,CS24702JB10    I18 @T6G_MB_LIB.T6G(SCH_1):PAGE331
  Q136    5     G2 MOSFET_NCH_DUAL-PJT138K,SMLF,IC,BAM138K0003    I22 @T6G_MB_LIB.T6G(SCH_1):PAGE331

GPU_3V3IO_RSVD5_FFU @T6G_MB_LIB.T6G(SCH_1):GPU_3V3IO_RSVD5_FFU
  J108   A5     A5 CONN112_10137002101LF-CONN112_10137002-101LF,THLF,A    I15 @T6G_MB_LIB.T6G(SCH_1):PAGE320
 R4134    1      A Q_RES_0402LF-100K,1%,1/16W,EMPTY,CS41002FB09    I81 @T6G_MB_LIB.T6G(SCH_1):PAGE332
 R4133    2      B Q_RES_0402LF-54.9K,1%,1/16W,EMPTY,CS35492FB03    I82 @T6G_MB_LIB.T6G(SCH_1):PAGE332
  Q129    2     G1 MOSFET_NCH_DUAL-PJT138K,SMLF,IC,BAM138K0003    I86 @T6G_MB_LIB.T6G(SCH_1):PAGE332
 R4576    1      A Q_RES_0402LF-0,5%,1/16W,EMPTY,CS00002JB13    I91 @T6G_MB_LIB.T6G(SCH_1):PAGE332

GPU_3V3IO_RSVD5_FFU_ISO @T6G_MB_LIB.T6G(SCH_1):GPU_3V3IO_RSVD5_FFU_ISO
 R4148    2      B Q_RES_0402LF-33.2,1%,1/16W,CHIP,CS03322FB03   I242 @T6G_MB_LIB.T6G(SCH_1):PAGE80
 R4576    2      B Q_RES_0402LF-0,5%,1/16W,EMPTY,CS00002JB13    I91 @T6G_MB_LIB.T6G(SCH_1):PAGE332
  Q129    3     D2 MOSFET_NCH_DUAL-PJT138K,SMLF,IC,BAM138K0003   I113 @T6G_MB_LIB.T6G(SCH_1):PAGE332
 R4141    2      B Q_RES_0402LF-100K,1%,1/16W,CHIP,CS41002FB09   I114 @T6G_MB_LIB.T6G(SCH_1):PAGE332
   C17    1      A Q_CAP_0402-0.1UF,25V,10%,X7R,CH4104K1B00   I118 @T6G_MB_LIB.T6G(SCH_1):PAGE332

GPU_3V3IO_RSVD5_FFU_ISO_R @T6G_MB_LIB.T6G(SCH_1):GPU_3V3IO_RSVD5_FFU_ISO_R
   U18 AB14  PB33A LCMXO3LF9400C5BG484C-LCMXO3LF-9400C-5BG484C,SMLF,IA   I216 @T6G_MB_LIB.T6G(SCH_1):PAGE80
 R4148    1      A Q_RES_0402LF-33.2,1%,1/16W,CHIP,CS03322FB03   I242 @T6G_MB_LIB.T6G(SCH_1):PAGE80

GPU_3V3IO_RSVD5_FFU_N @T6G_MB_LIB.T6G(SCH_1):GPU_3V3IO_RSVD5_FFU_N
  Q129    6     D1 MOSFET_NCH_DUAL-PJT138K,SMLF,IC,BAM138K0003    I86 @T6G_MB_LIB.T6G(SCH_1):PAGE332
 R4138    2      B Q_RES_0402LF-4.7K,5%,1/16W,CHIP,CS24702JB10    I88 @T6G_MB_LIB.T6G(SCH_1):PAGE332
  Q129    5     G2 MOSFET_NCH_DUAL-PJT138K,SMLF,IC,BAM138K0003   I113 @T6G_MB_LIB.T6G(SCH_1):PAGE332

GPU_BASE_HMC_READY @T6G_MB_LIB.T6G(SCH_1):GPU_BASE_HMC_READY
  Q102    2     G1 MOSFET_NCH_DUAL-PJT138K,SMLF,IC,BAM138K0003    I40 @T6G_MB_LIB.T6G(SCH_1):PAGE299
 R3429    2      B Q_RES_0402LF-100K,1%,1/16W,EMPTY,CS41002FB09   I130 @T6G_MB_LIB.T6G(SCH_1):PAGE299
 R3463    1      A Q_RES_0402LF-54.9K,1%,1/16W,CHIP,CS35492FB03   I131 @T6G_MB_LIB.T6G(SCH_1):PAGE299
  J110   A5     A5 CONN112_10137002101LF-CONN112_10137002-101LF,THLF,A    I16 @T6G_MB_LIB.T6G(SCH_1):PAGE318

GPU_BASE_HMC_READY_ISO @T6G_MB_LIB.T6G(SCH_1):GPU_BASE_HMC_READY_ISO
  Q102    3     D2 MOSFET_NCH_DUAL-PJT138K,SMLF,IC,BAM138K0003    I48 @T6G_MB_LIB.T6G(SCH_1):PAGE299
 R3438    2      B Q_RES_0402LF-100K,1%,1/16W,CHIP,CS41002FB09    I55 @T6G_MB_LIB.T6G(SCH_1):PAGE299
 C1973    1      A Q_CAP_0402-0.1UF,25V,10%,X7R,CH4104K1B00    I71 @T6G_MB_LIB.T6G(SCH_1):PAGE299
 R3480    2      B Q_RES_0402LF-33.2,1%,1/16W,CHIP,CS03322FB03   I247 @T6G_MB_LIB.T6G(SCH_1):PAGE80

GPU_BASE_HMC_READY_ISO_R @T6G_MB_LIB.T6G(SCH_1):GPU_BASE_HMC_READY_ISO_R
   U18 AB15  PB35A LCMXO3LF9400C5BG484C-LCMXO3LF-9400C-5BG484C,SMLF,IA   I216 @T6G_MB_LIB.T6G(SCH_1):PAGE80
 R3480    1      A Q_RES_0402LF-33.2,1%,1/16W,CHIP,CS03322FB03   I247 @T6G_MB_LIB.T6G(SCH_1):PAGE80

GPU_BASE_HMC_READY_N @T6G_MB_LIB.T6G(SCH_1):GPU_BASE_HMC_READY_N
  Q102    6     D1 MOSFET_NCH_DUAL-PJT138K,SMLF,IC,BAM138K0003    I40 @T6G_MB_LIB.T6G(SCH_1):PAGE299
  Q102    5     G2 MOSFET_NCH_DUAL-PJT138K,SMLF,IC,BAM138K0003    I48 @T6G_MB_LIB.T6G(SCH_1):PAGE299
 R3433    2      B Q_RES_0402LF-4.7K,5%,1/16W,CHIP,CS24702JB10    I49 @T6G_MB_LIB.T6G(SCH_1):PAGE299

GPU_BASE_ID0 @T6G_MB_LIB.T6G(SCH_1):GPU_BASE_ID0
  J111   A3     A3 CONN112_10137002101LF-CONN112_10137002-101LF,THLF,A    I76 @T6G_MB_LIB.T6G(SCH_1):PAGE328
 R3516    1      A Q_RES_0402LF-0,5%,1/16W,CHIP,CS00002JB13    I56 @T6G_MB_LIB.T6G(SCH_1):PAGE246
 R3440    1      A Q_RES_0402LF-0,5%,1/16W,EMPTY,CS00002JB13    I65 @T6G_MB_LIB.T6G(SCH_1):PAGE330

GPU_BASE_ID0_R @T6G_MB_LIB.T6G(SCH_1):GPU_BASE_ID0_R
 R3516    2      B Q_RES_0402LF-0,5%,1/16W,CHIP,CS00002JB13    I56 @T6G_MB_LIB.T6G(SCH_1):PAGE246
  U181   15  IO1_2 PCA9539RPW-PCA9539RPW,SMLF,IC,AL009539K07    I83 @T6G_MB_LIB.T6G(SCH_1):PAGE246

GPU_BASE_ID1 @T6G_MB_LIB.T6G(SCH_1):GPU_BASE_ID1
  J111   N8     N8 CONN112_10137002101LF-CONN112_10137002-101LF,THLF,A    I38 @T6G_MB_LIB.T6G(SCH_1):PAGE328
 R3499    1      A Q_RES_0402LF-0,5%,1/16W,CHIP,CS00002JB13    I57 @T6G_MB_LIB.T6G(SCH_1):PAGE246
 R3441    1      A Q_RES_0402LF-0,5%,1/16W,CHIP,CS00002JB13    I64 @T6G_MB_LIB.T6G(SCH_1):PAGE330

GPU_BASE_ID1_R @T6G_MB_LIB.T6G(SCH_1):GPU_BASE_ID1_R
 R3499    2      B Q_RES_0402LF-0,5%,1/16W,CHIP,CS00002JB13    I57 @T6G_MB_LIB.T6G(SCH_1):PAGE246
  U181   16  IO1_3 PCA9539RPW-PCA9539RPW,SMLF,IC,AL009539K07    I83 @T6G_MB_LIB.T6G(SCH_1):PAGE246

GPU_BASE_STBY_EN @T6G_MB_LIB.T6G(SCH_1):GPU_BASE_STBY_EN
  U253    3     A1 74LVC2G17GW-74LVC2G17GW,SMLF,IC,AL2G0017005    I26 @T6G_MB_LIB.T6G(SCH_1):PAGE334
 R3452    1      A Q_RES_0402LF-100K,1%,1/16W,CHIP,CS41002FB09    I95 @T6G_MB_LIB.T6G(SCH_1):PAGE334
 R3451    2      B Q_RES_0402LF-4.7K,5%,1/16W,EMPTY,CS24702JB10   I127 @T6G_MB_LIB.T6G(SCH_1):PAGE334
 R3479    2      B Q_RES_0402LF-33.2,1%,1/16W,CHIP,CS03322FB03   I281 @T6G_MB_LIB.T6G(SCH_1):PAGE80

GPU_BASE_STBY_EN_BUF @T6G_MB_LIB.T6G(SCH_1):GPU_BASE_STBY_EN_BUF
 R3392    2      B Q_RES_0402LF-49.9,1%,1/16W,CHIP,CS04992FB07    I62 @T6G_MB_LIB.T6G(SCH_1):PAGE334
  J110   A7     A7 CONN112_10137002101LF-CONN112_10137002-101LF,THLF,A    I16 @T6G_MB_LIB.T6G(SCH_1):PAGE318

GPU_BASE_STBY_EN_BUF_R @T6G_MB_LIB.T6G(SCH_1):GPU_BASE_STBY_EN_BUF_R
  U253    4     B1 74LVC2G17GW-74LVC2G17GW,SMLF,IC,AL2G0017005    I26 @T6G_MB_LIB.T6G(SCH_1):PAGE334
 R3392    1      A Q_RES_0402LF-49.9,1%,1/16W,CHIP,CS04992FB07    I62 @T6G_MB_LIB.T6G(SCH_1):PAGE334
 R3457    1      A Q_RES_0402LF-10K,1%,1/16W,CHIP,CS31002FB08   I123 @T6G_MB_LIB.T6G(SCH_1):PAGE334
 R3456    2      B Q_RES_0402LF-100K,1%,1/16W,EMPTY,CS41002FB09   I124 @T6G_MB_LIB.T6G(SCH_1):PAGE334

GPU_BASE_STBY_EN_R @T6G_MB_LIB.T6G(SCH_1):GPU_BASE_STBY_EN_R
   U18  Y19  PB44C LCMXO3LF9400C5BG484C-LCMXO3LF-9400C-5BG484C,SMLF,IA   I216 @T6G_MB_LIB.T6G(SCH_1):PAGE80
 R3479    1      A Q_RES_0402LF-33.2,1%,1/16W,CHIP,CS03322FB03   I281 @T6G_MB_LIB.T6G(SCH_1):PAGE80

GPU_FPGA_BOOT_EN @T6G_MB_LIB.T6G(SCH_1):GPU_FPGA_BOOT_EN
  U253    1     A0 74LVC2G17GW-74LVC2G17GW,SMLF,IC,AL2G0017005    I26 @T6G_MB_LIB.T6G(SCH_1):PAGE334
 R3448    2      B Q_RES_0402LF-4.7K,5%,1/16W,EMPTY,CS24702JB10   I168 @T6G_MB_LIB.T6G(SCH_1):PAGE334
 R3449    1      A Q_RES_0402LF-100K,1%,1/16W,CHIP,CS41002FB09   I170 @T6G_MB_LIB.T6G(SCH_1):PAGE334
 R3482    2      B Q_RES_0402LF-33.2,1%,1/16W,CHIP,CS03322FB03   I278 @T6G_MB_LIB.T6G(SCH_1):PAGE80

GPU_FPGA_BOOT_EN_BUF @T6G_MB_LIB.T6G(SCH_1):GPU_FPGA_BOOT_EN_BUF
 R3390    2      B Q_RES_0402LF-49.9,1%,1/16W,CHIP,CS04992FB07   I162 @T6G_MB_LIB.T6G(SCH_1):PAGE334
  J110   N2     N2 CONN112_10137002101LF-CONN112_10137002-101LF,THLF,A    I76 @T6G_MB_LIB.T6G(SCH_1):PAGE318

GPU_FPGA_BOOT_EN_BUF_R @T6G_MB_LIB.T6G(SCH_1):GPU_FPGA_BOOT_EN_BUF_R
  U253    6     B0 74LVC2G17GW-74LVC2G17GW,SMLF,IC,AL2G0017005    I26 @T6G_MB_LIB.T6G(SCH_1):PAGE334
 R3390    1      A Q_RES_0402LF-49.9,1%,1/16W,CHIP,CS04992FB07   I162 @T6G_MB_LIB.T6G(SCH_1):PAGE334
 R3453    2      B Q_RES_0402LF-100K,1%,1/16W,EMPTY,CS41002FB09   I164 @T6G_MB_LIB.T6G(SCH_1):PAGE334
 R3454    1      A Q_RES_0402LF-1K,1%,1/16W,CHIP,CS21002FB06   I165 @T6G_MB_LIB.T6G(SCH_1):PAGE334

GPU_FPGA_BOOT_EN_R @T6G_MB_LIB.T6G(SCH_1):GPU_FPGA_BOOT_EN_R
   U18  T15  PB43C LCMXO3LF9400C5BG484C-LCMXO3LF-9400C-5BG484C,SMLF,IA   I216 @T6G_MB_LIB.T6G(SCH_1):PAGE80
 R3482    1      A Q_RES_0402LF-33.2,1%,1/16W,CHIP,CS03322FB03   I278 @T6G_MB_LIB.T6G(SCH_1):PAGE80

GPU_FPGA_EROT_FATALERR @T6G_MB_LIB.T6G(SCH_1):GPU_FPGA_EROT_FATALERR
  Q108    5     G2 MOSFET_NCH_DUAL-PJT138K,SMLF,IC,BAM138K0003   I168 @T6G_MB_LIB.T6G(SCH_1):PAGE299
  Q108    6     D1 MOSFET_NCH_DUAL-PJT138K,SMLF,IC,BAM138K0003   I169 @T6G_MB_LIB.T6G(SCH_1):PAGE299
 R3503    2      B Q_RES_0402LF-4.7K,5%,1/16W,CHIP,CS24702JB10   I177 @T6G_MB_LIB.T6G(SCH_1):PAGE299

GPU_FPGA_EROT_FATALERR_ISO_N @T6G_MB_LIB.T6G(SCH_1):GPU_FPGA_EROT_FATALERR_ISO_N
  Q108    3     D2 MOSFET_NCH_DUAL-PJT138K,SMLF,IC,BAM138K0003   I168 @T6G_MB_LIB.T6G(SCH_1):PAGE299
 C1988    1      A Q_CAP_0402-0.1UF,25V,10%,X7R,CH4104K1B00   I171 @T6G_MB_LIB.T6G(SCH_1):PAGE299
 R3504    2      B Q_RES_0402LF-100K,1%,1/16W,CHIP,CS41002FB09   I174 @T6G_MB_LIB.T6G(SCH_1):PAGE299
 R3505    2      B Q_RES_0402LF-33.2,1%,1/16W,CHIP,CS03322FB03   I259 @T6G_MB_LIB.T6G(SCH_1):PAGE80

GPU_FPGA_EROT_FATALERR_ISO_R_N @T6G_MB_LIB.T6G(SCH_1):GPU_FPGA_EROT_FATALERR_ISO_R_N
   U18 AA16  PB38B LCMXO3LF9400C5BG484C-LCMXO3LF-9400C-5BG484C,SMLF,IA   I216 @T6G_MB_LIB.T6G(SCH_1):PAGE80
 R3505    1      A Q_RES_0402LF-33.2,1%,1/16W,CHIP,CS03322FB03   I259 @T6G_MB_LIB.T6G(SCH_1):PAGE80

GPU_FPGA_EROT_FATALERR_N @T6G_MB_LIB.T6G(SCH_1):GPU_FPGA_EROT_FATALERR_N
  Q108    2     G1 MOSFET_NCH_DUAL-PJT138K,SMLF,IC,BAM138K0003   I169 @T6G_MB_LIB.T6G(SCH_1):PAGE299
 R3502    1      A Q_RES_0402LF-100K,1%,1/16W,EMPTY,CS41002FB09   I181 @T6G_MB_LIB.T6G(SCH_1):PAGE299
 R3525    2      B Q_RES_0402LF-54.9K,1%,1/16W,CHIP,CS35492FB03   I184 @T6G_MB_LIB.T6G(SCH_1):PAGE299
  J109   N2     N2 CONN112_10137002101LF-CONN112_10137002-101LF,THLF,A    I76 @T6G_MB_LIB.T6G(SCH_1):PAGE319

GPU_FPGA_EROT_RECOV_BUF_N @T6G_MB_LIB.T6G(SCH_1):GPU_FPGA_EROT_RECOV_BUF_N
 R3497    2      B Q_RES_0402LF-33.2,1%,1/16W,CHIP,CS03322FB03    I53 @T6G_MB_LIB.T6G(SCH_1):PAGE255
  J110   A1     A1 CONN112_10137002101LF-CONN112_10137002-101LF,THLF,A    I76 @T6G_MB_LIB.T6G(SCH_1):PAGE318

GPU_FPGA_EROT_RECOV_BUF_R_N @T6G_MB_LIB.T6G(SCH_1):GPU_FPGA_EROT_RECOV_BUF_R_N
  U257    6     1Y 74LVC2G07DW7-74LVC2G07DW-7,SMLF,IC,AL002G07003    I50 @T6G_MB_LIB.T6G(SCH_1):PAGE255
 R3497    1      A Q_RES_0402LF-33.2,1%,1/16W,CHIP,CS03322FB03    I53 @T6G_MB_LIB.T6G(SCH_1):PAGE255
 R3494    2      B Q_RES_0402LF-54.9K,1%,1/16W,CHIP,CS35492FB03    I55 @T6G_MB_LIB.T6G(SCH_1):PAGE255
 R3495    1      A Q_RES_0402LF-100K,1%,1/16W,EMPTY,CS41002FB09    I62 @T6G_MB_LIB.T6G(SCH_1):PAGE255

GPU_FPGA_EROT_RECOV_N @T6G_MB_LIB.T6G(SCH_1):GPU_FPGA_EROT_RECOV_N
  U257    1     1A 74LVC2G07DW7-74LVC2G07DW-7,SMLF,IC,AL002G07003    I50 @T6G_MB_LIB.T6G(SCH_1):PAGE255
 R3490    2      B Q_RES_0402LF-1K,1%,1/16W,CHIP,CS21002FB06    I57 @T6G_MB_LIB.T6G(SCH_1):PAGE255
 R3491    1      A Q_RES_0402LF-100K,1%,1/16W,EMPTY,CS41002FB09    I70 @T6G_MB_LIB.T6G(SCH_1):PAGE255
 R3483    1      A Q_RES_0402LF-33.2,1%,1/16W,CHIP,CS03322FB03   I290 @T6G_MB_LIB.T6G(SCH_1):PAGE80

GPU_FPGA_EROT_RECOV_R_N @T6G_MB_LIB.T6G(SCH_1):GPU_FPGA_EROT_RECOV_R_N
   U18  AA5  PB10A LCMXO3LF9400C5BG484C-LCMXO3LF-9400C-5BG484C,SMLF,IA   I216 @T6G_MB_LIB.T6G(SCH_1):PAGE80
 R3483    2      B Q_RES_0402LF-33.2,1%,1/16W,CHIP,CS03322FB03   I290 @T6G_MB_LIB.T6G(SCH_1):PAGE80

GPU_FPGA_EROT_RST_BUF_N @T6G_MB_LIB.T6G(SCH_1):GPU_FPGA_EROT_RST_BUF_N
 R3496    2      B Q_RES_0402LF-33.2,1%,1/16W,CHIP,CS03322FB03    I45 @T6G_MB_LIB.T6G(SCH_1):PAGE255
  J110   N8     N8 CONN112_10137002101LF-CONN112_10137002-101LF,THLF,A    I16 @T6G_MB_LIB.T6G(SCH_1):PAGE318

GPU_FPGA_EROT_RST_BUF_R_N @T6G_MB_LIB.T6G(SCH_1):GPU_FPGA_EROT_RST_BUF_R_N
  U255    4     2Y 74LVC2G07DW7-74LVC2G07DW-7,SMLF,IC,AL002G07003    I16 @T6G_MB_LIB.T6G(SCH_1):PAGE255
 R3496    1      A Q_RES_0402LF-33.2,1%,1/16W,CHIP,CS03322FB03    I45 @T6G_MB_LIB.T6G(SCH_1):PAGE255
 R3492    2      B Q_RES_0402LF-54.9K,1%,1/16W,CHIP,CS35492FB03    I47 @T6G_MB_LIB.T6G(SCH_1):PAGE255
 R3493    1      A Q_RES_0402LF-100K,1%,1/16W,EMPTY,CS41002FB09    I48 @T6G_MB_LIB.T6G(SCH_1):PAGE255

GPU_FPGA_EROT_RST_N @T6G_MB_LIB.T6G(SCH_1):GPU_FPGA_EROT_RST_N
  U255    3     2A 74LVC2G07DW7-74LVC2G07DW-7,SMLF,IC,AL002G07003    I16 @T6G_MB_LIB.T6G(SCH_1):PAGE255
 R3488    2      B Q_RES_0402LF-1K,1%,1/16W,CHIP,CS21002FB06    I40 @T6G_MB_LIB.T6G(SCH_1):PAGE255
 R3489    1      A Q_RES_0402LF-100K,1%,1/16W,EMPTY,CS41002FB09    I42 @T6G_MB_LIB.T6G(SCH_1):PAGE255
 R3478    1      A Q_RES_0402LF-33.2,1%,1/16W,CHIP,CS03322FB03   I288 @T6G_MB_LIB.T6G(SCH_1):PAGE80

GPU_FPGA_EROT_RST_R_N @T6G_MB_LIB.T6G(SCH_1):GPU_FPGA_EROT_RST_R_N
   U18  AA4   PB8A LCMXO3LF9400C5BG484C-LCMXO3LF-9400C-5BG484C,SMLF,IA   I216 @T6G_MB_LIB.T6G(SCH_1):PAGE80
 R3478    2      B Q_RES_0402LF-33.2,1%,1/16W,CHIP,CS03322FB03   I288 @T6G_MB_LIB.T6G(SCH_1):PAGE80

GPU_FPGA_OVERT @T6G_MB_LIB.T6G(SCH_1):GPU_FPGA_OVERT
  Q104    6     D1 MOSFET_NCH_DUAL-PJT138K,SMLF,IC,BAM138K0003    I21 @T6G_MB_LIB.T6G(SCH_1):PAGE299
 R3435    2      B Q_RES_0402LF-4.7K,5%,1/16W,CHIP,CS24702JB10    I23 @T6G_MB_LIB.T6G(SCH_1):PAGE299
  Q104    5     G2 MOSFET_NCH_DUAL-PJT138K,SMLF,IC,BAM138K0003    I26 @T6G_MB_LIB.T6G(SCH_1):PAGE299

GPU_FPGA_OVERT_ISO_N @T6G_MB_LIB.T6G(SCH_1):GPU_FPGA_OVERT_ISO_N
  Q104    3     D2 MOSFET_NCH_DUAL-PJT138K,SMLF,IC,BAM138K0003    I26 @T6G_MB_LIB.T6G(SCH_1):PAGE299
 R3437    2      B Q_RES_0402LF-100K,1%,1/16W,CHIP,CS41002FB09    I27 @T6G_MB_LIB.T6G(SCH_1):PAGE299
 C1976    1      A Q_CAP_0402-0.1UF,25V,10%,X7R,CH4104K1B00    I30 @T6G_MB_LIB.T6G(SCH_1):PAGE299
 R3484    2      B Q_RES_0402LF-33.2,1%,1/16W,CHIP,CS03322FB03   I254 @T6G_MB_LIB.T6G(SCH_1):PAGE80

GPU_FPGA_OVERT_ISO_R_N @T6G_MB_LIB.T6G(SCH_1):GPU_FPGA_OVERT_ISO_R_N
   U18  Y15  PB35C LCMXO3LF9400C5BG484C-LCMXO3LF-9400C-5BG484C,SMLF,IA   I216 @T6G_MB_LIB.T6G(SCH_1):PAGE80
 R3484    1      A Q_RES_0402LF-33.2,1%,1/16W,CHIP,CS03322FB03   I254 @T6G_MB_LIB.T6G(SCH_1):PAGE80

GPU_FPGA_OVERT_N @T6G_MB_LIB.T6G(SCH_1):GPU_FPGA_OVERT_N
 R3430    1      A Q_RES_0402LF-100K,1%,1/16W,EMPTY,CS41002FB09     I3 @T6G_MB_LIB.T6G(SCH_1):PAGE299
  Q104    2     G1 MOSFET_NCH_DUAL-PJT138K,SMLF,IC,BAM138K0003    I21 @T6G_MB_LIB.T6G(SCH_1):PAGE299
 R3464    2      B Q_RES_0402LF-54.9K,1%,1/16W,CHIP,CS35492FB03   I134 @T6G_MB_LIB.T6G(SCH_1):PAGE299
  J108   A7     A7 CONN112_10137002101LF-CONN112_10137002-101LF,THLF,A    I15 @T6G_MB_LIB.T6G(SCH_1):PAGE320

GPU_FPGA_READY @T6G_MB_LIB.T6G(SCH_1):GPU_FPGA_READY
   Q96    2     G1 MOSFET_NCH_DUAL-PJT138K,SMLF,IC,BAM138K0003   I154 @T6G_MB_LIB.T6G(SCH_1):PAGE333
 R3318    2      B Q_RES_0402LF-100K,1%,1/16W,EMPTY,CS41002FB09   I171 @T6G_MB_LIB.T6G(SCH_1):PAGE333
 R3511    1      A Q_RES_0402LF-54.9K,1%,1/16W,CHIP,CS35492FB03   I172 @T6G_MB_LIB.T6G(SCH_1):PAGE333
  J112   T2     T2 CONN160_10131762101LF-CONN160_10131762-101LF,THLF,A   I102 @T6G_MB_LIB.T6G(SCH_1):PAGE329

GPU_FPGA_READY_ISO @T6G_MB_LIB.T6G(SCH_1):GPU_FPGA_READY_ISO
 C1881    1      A Q_CAP_0402-0.1UF,25V,10%,X7R,CH4104K1B00   I156 @T6G_MB_LIB.T6G(SCH_1):PAGE333
 R3321    2      B Q_RES_0402LF-100K,1%,1/16W,CHIP,CS41002FB09   I158 @T6G_MB_LIB.T6G(SCH_1):PAGE333
   Q96    3     D2 MOSFET_NCH_DUAL-PJT138K,SMLF,IC,BAM138K0003   I159 @T6G_MB_LIB.T6G(SCH_1):PAGE333
 R3324    2      B Q_RES_0402LF-33.2,1%,1/16W,CHIP,CS03322FB03   I276 @T6G_MB_LIB.T6G(SCH_1):PAGE80

GPU_FPGA_READY_ISO_R @T6G_MB_LIB.T6G(SCH_1):GPU_FPGA_READY_ISO_R
   U18 AB19  PB43A LCMXO3LF9400C5BG484C-LCMXO3LF-9400C-5BG484C,SMLF,IA   I216 @T6G_MB_LIB.T6G(SCH_1):PAGE80
 R3324    1      A Q_RES_0402LF-33.2,1%,1/16W,CHIP,CS03322FB03   I276 @T6G_MB_LIB.T6G(SCH_1):PAGE80

GPU_FPGA_READY_N @T6G_MB_LIB.T6G(SCH_1):GPU_FPGA_READY_N
   Q96    6     D1 MOSFET_NCH_DUAL-PJT138K,SMLF,IC,BAM138K0003   I154 @T6G_MB_LIB.T6G(SCH_1):PAGE333
   Q96    5     G2 MOSFET_NCH_DUAL-PJT138K,SMLF,IC,BAM138K0003   I159 @T6G_MB_LIB.T6G(SCH_1):PAGE333
 R3320    2      B Q_RES_0402LF-4.7K,5%,1/16W,CHIP,CS24702JB10   I162 @T6G_MB_LIB.T6G(SCH_1):PAGE333
 R3326    1      A Q_RES_0402LF-0,5%,1/16W,CHIP,CS00002JB13     I7 @T6G_MB_LIB.T6G(SCH_1):PAGE232

GPU_FPGA_READY_R_N @T6G_MB_LIB.T6G(SCH_1):GPU_FPGA_READY_R_N
 R3326    2      B Q_RES_0402LF-0,5%,1/16W,CHIP,CS00002JB13     I7 @T6G_MB_LIB.T6G(SCH_1):PAGE232
  U248    1     I0 74LVC1G32GW_SMLF-74LVC1G32GW,IC,ALVC1G32007    I26 @T6G_MB_LIB.T6G(SCH_1):PAGE232

GPU_FPGA_RST_N @T6G_MB_LIB.T6G(SCH_1):GPU_FPGA_RST_N
   U18   V7  PB11D LCMXO3LF9400C5BG484C-LCMXO3LF-9400C-5BG484C,SMLF,IA   I216 @T6G_MB_LIB.T6G(SCH_1):PAGE80
 R4608    2      B Q_RES_0402LF-33.2,1%,1/16W,CHIP,CS03322FB03   I295 @T6G_MB_LIB.T6G(SCH_1):PAGE80

GPU_FPGA_RST_R1_BUF_N @T6G_MB_LIB.T6G(SCH_1):GPU_FPGA_RST_R1_BUF_N
  U196    4     B1 74LVC2G17GW-74LVC2G17GW,SMLF,IC,AL2G0017005   I127 @T6G_MB_LIB.T6G(SCH_1):PAGE256
 R3315    1      A Q_RES_0402LF-33.2,1%,1/16W,CHIP,CS03322FB03   I181 @T6G_MB_LIB.T6G(SCH_1):PAGE256
 R3317    2      B Q_RES_0402LF-4.7K,5%,1/16W,EMPTY,CS24702JB10   I190 @T6G_MB_LIB.T6G(SCH_1):PAGE256
 R3509    1      A Q_RES_0402LF-10K,1%,1/16W,CHIP,CS31002FB08   I191 @T6G_MB_LIB.T6G(SCH_1):PAGE256

GPU_FPGA_RST_R_BUF_N @T6G_MB_LIB.T6G(SCH_1):GPU_FPGA_RST_R_BUF_N
 R3315    2      B Q_RES_0402LF-33.2,1%,1/16W,CHIP,CS03322FB03   I181 @T6G_MB_LIB.T6G(SCH_1):PAGE256
  J111   A7     A7 CONN112_10137002101LF-CONN112_10137002-101LF,THLF,A    I38 @T6G_MB_LIB.T6G(SCH_1):PAGE328

GPU_FPGA_RST_R_N @T6G_MB_LIB.T6G(SCH_1):GPU_FPGA_RST_R_N
  U196    3     A1 74LVC2G17GW-74LVC2G17GW,SMLF,IC,AL2G0017005   I127 @T6G_MB_LIB.T6G(SCH_1):PAGE256
 R3507    1      A Q_RES_0402LF-10K,1%,1/16W,CHIP,CS31002FB08   I192 @T6G_MB_LIB.T6G(SCH_1):PAGE256
 R3506    2      B Q_RES_0402LF-4.7K,5%,1/16W,EMPTY,CS24702JB10   I193 @T6G_MB_LIB.T6G(SCH_1):PAGE256
 R4608    1      A Q_RES_0402LF-33.2,1%,1/16W,CHIP,CS03322FB03   I295 @T6G_MB_LIB.T6G(SCH_1):PAGE80

GPU_FPGA_THERM_OVERT @T6G_MB_LIB.T6G(SCH_1):GPU_FPGA_THERM_OVERT
  Q101    6     D1 MOSFET_NCH_DUAL-PJT138K,SMLF,IC,BAM138K0003    I52 @T6G_MB_LIB.T6G(SCH_1):PAGE299
 R3432    2      B Q_RES_0402LF-4.7K,5%,1/16W,CHIP,CS24702JB10    I53 @T6G_MB_LIB.T6G(SCH_1):PAGE299
  Q101    5     G2 MOSFET_NCH_DUAL-PJT138K,SMLF,IC,BAM138K0003    I57 @T6G_MB_LIB.T6G(SCH_1):PAGE299

GPU_FPGA_THERM_OVERT_ISO_N @T6G_MB_LIB.T6G(SCH_1):GPU_FPGA_THERM_OVERT_ISO_N
  Q101    3     D2 MOSFET_NCH_DUAL-PJT138K,SMLF,IC,BAM138K0003    I57 @T6G_MB_LIB.T6G(SCH_1):PAGE299
 R3439    2      B Q_RES_0402LF-100K,1%,1/16W,CHIP,CS41002FB09    I59 @T6G_MB_LIB.T6G(SCH_1):PAGE299
 C1974    1      A Q_CAP_0402-0.1UF,25V,10%,X7R,CH4104K1B00    I74 @T6G_MB_LIB.T6G(SCH_1):PAGE299
 R3476    2      B Q_RES_0402LF-33.2,1%,1/16W,CHIP,CS03322FB03   I250 @T6G_MB_LIB.T6G(SCH_1):PAGE80

GPU_FPGA_THERM_OVERT_ISO_R_N @T6G_MB_LIB.T6G(SCH_1):GPU_FPGA_THERM_OVERT_ISO_R_N
   U18  W14  PB33D LCMXO3LF9400C5BG484C-LCMXO3LF-9400C-5BG484C,SMLF,IA   I216 @T6G_MB_LIB.T6G(SCH_1):PAGE80
 R3476    1      A Q_RES_0402LF-33.2,1%,1/16W,CHIP,CS03322FB03   I250 @T6G_MB_LIB.T6G(SCH_1):PAGE80

GPU_FPGA_THERM_OVERT_N @T6G_MB_LIB.T6G(SCH_1):GPU_FPGA_THERM_OVERT_N
 R3428    1      A Q_RES_0402LF-100K,1%,1/16W,EMPTY,CS41002FB09    I17 @T6G_MB_LIB.T6G(SCH_1):PAGE299
  Q101    2     G1 MOSFET_NCH_DUAL-PJT138K,SMLF,IC,BAM138K0003    I52 @T6G_MB_LIB.T6G(SCH_1):PAGE299
 R3498    2      B Q_RES_0402LF-54.9K,1%,1/16W,CHIP,CS35492FB03   I167 @T6G_MB_LIB.T6G(SCH_1):PAGE299
  J112   T6     T6 CONN160_10131762101LF-CONN160_10131762-101LF,THLF,A     I7 @T6G_MB_LIB.T6G(SCH_1):PAGE329

GPU_HMC_PRSNT @T6G_MB_LIB.T6G(SCH_1):GPU_HMC_PRSNT
  Q103    6     D1 MOSFET_NCH_DUAL-PJT138K,SMLF,IC,BAM138K0003    I37 @T6G_MB_LIB.T6G(SCH_1):PAGE299
 R3434    2      B Q_RES_0402LF-4.7K,5%,1/16W,CHIP,CS24702JB10    I39 @T6G_MB_LIB.T6G(SCH_1):PAGE299
  Q103    5     G2 MOSFET_NCH_DUAL-PJT138K,SMLF,IC,BAM138K0003    I43 @T6G_MB_LIB.T6G(SCH_1):PAGE299

GPU_HMC_PRSNT_ISO_N @T6G_MB_LIB.T6G(SCH_1):GPU_HMC_PRSNT_ISO_N
  Q103    3     D2 MOSFET_NCH_DUAL-PJT138K,SMLF,IC,BAM138K0003    I43 @T6G_MB_LIB.T6G(SCH_1):PAGE299
 R3436    2      B Q_RES_0402LF-100K,1%,1/16W,CHIP,CS41002FB09    I45 @T6G_MB_LIB.T6G(SCH_1):PAGE299
 C1975    1      A Q_CAP_0402-0.1UF,25V,10%,X7R,CH4104K1B00   I129 @T6G_MB_LIB.T6G(SCH_1):PAGE299
 R3481    2      B Q_RES_0402LF-33.2,1%,1/16W,CHIP,CS03322FB03   I251 @T6G_MB_LIB.T6G(SCH_1):PAGE80

GPU_HMC_PRSNT_ISO_R_N @T6G_MB_LIB.T6G(SCH_1):GPU_HMC_PRSNT_ISO_R_N
   U18 AA15  PB35B LCMXO3LF9400C5BG484C-LCMXO3LF-9400C-5BG484C,SMLF,IA   I216 @T6G_MB_LIB.T6G(SCH_1):PAGE80
 R3481    1      A Q_RES_0402LF-33.2,1%,1/16W,CHIP,CS03322FB03   I251 @T6G_MB_LIB.T6G(SCH_1):PAGE80

GPU_HMC_PRSNT_N @T6G_MB_LIB.T6G(SCH_1):GPU_HMC_PRSNT_N
  Q103    2     G1 MOSFET_NCH_DUAL-PJT138K,SMLF,IC,BAM138K0003    I37 @T6G_MB_LIB.T6G(SCH_1):PAGE299
 R3465    2      B Q_RES_0402LF-10K,1%,1/16W,CHIP,CS31002FB08   I132 @T6G_MB_LIB.T6G(SCH_1):PAGE299
 R3431    1      A Q_RES_0402LF-100K,1%,1/16W,EMPTY,CS41002FB09   I133 @T6G_MB_LIB.T6G(SCH_1):PAGE299
  J110   A3     A3 CONN112_10137002101LF-CONN112_10137002-101LF,THLF,A    I76 @T6G_MB_LIB.T6G(SCH_1):PAGE318

GPU_NVS_PWR_BRAKE_N @T6G_MB_LIB.T6G(SCH_1):GPU_NVS_PWR_BRAKE_N
  U255    1     1A 74LVC2G07DW7-74LVC2G07DW-7,SMLF,IC,AL002G07003    I16 @T6G_MB_LIB.T6G(SCH_1):PAGE255
 R3460    1      A Q_RES_0402LF-100K,1%,1/16W,EMPTY,CS41002FB09    I31 @T6G_MB_LIB.T6G(SCH_1):PAGE255
 R3477    1      A Q_RES_0402LF-33.2,1%,1/16W,CHIP,CS03322FB03   I286 @T6G_MB_LIB.T6G(SCH_1):PAGE80
 R3459    2      B Q_RES_0402LF-1K,1%,1/16W,CHIP,CS21002FB06    I75 @T6G_MB_LIB.T6G(SCH_1):PAGE255

GPU_NVS_PWR_BRAKE_N_BUF @T6G_MB_LIB.T6G(SCH_1):GPU_NVS_PWR_BRAKE_N_BUF
 R3397    2      B Q_RES_0402LF-33.2,1%,1/16W,CHIP,CS03322FB03    I37 @T6G_MB_LIB.T6G(SCH_1):PAGE255
  J112   T4     T4 CONN160_10131762101LF-CONN160_10131762-101LF,THLF,A   I102 @T6G_MB_LIB.T6G(SCH_1):PAGE329

GPU_NVS_PWR_BRAKE_N_R @T6G_MB_LIB.T6G(SCH_1):GPU_NVS_PWR_BRAKE_N_R
  U255    6     1Y 74LVC2G07DW7-74LVC2G07DW-7,SMLF,IC,AL002G07003    I16 @T6G_MB_LIB.T6G(SCH_1):PAGE255
 R3462    1      A Q_RES_0402LF-100K,1%,1/16W,EMPTY,CS41002FB09    I33 @T6G_MB_LIB.T6G(SCH_1):PAGE255
 R3461    2      B Q_RES_0402LF-54.9K,1%,1/16W,CHIP,CS35492FB03    I35 @T6G_MB_LIB.T6G(SCH_1):PAGE255
 R3397    1      A Q_RES_0402LF-33.2,1%,1/16W,CHIP,CS03322FB03    I37 @T6G_MB_LIB.T6G(SCH_1):PAGE255

GPU_NVS_PWR_BRAKE_R_N @T6G_MB_LIB.T6G(SCH_1):GPU_NVS_PWR_BRAKE_R_N
   U18  AB2   PB5B LCMXO3LF9400C5BG484C-LCMXO3LF-9400C-5BG484C,SMLF,IA   I216 @T6G_MB_LIB.T6G(SCH_1):PAGE80
 R3477    2      B Q_RES_0402LF-33.2,1%,1/16W,CHIP,CS03322FB03   I286 @T6G_MB_LIB.T6G(SCH_1):PAGE80

GPU_PEX_STRAP0 @T6G_MB_LIB.T6G(SCH_1):GPU_PEX_STRAP0
  J111   A5     A5 CONN112_10137002101LF-CONN112_10137002-101LF,THLF,A    I38 @T6G_MB_LIB.T6G(SCH_1):PAGE328
 R3518    1      A Q_RES_0402LF-0,5%,1/16W,CHIP,CS00002JB13    I47 @T6G_MB_LIB.T6G(SCH_1):PAGE246
 R3442    1      A Q_RES_0402LF-0,5%,1/16W,CHIP,CS00002JB13    I67 @T6G_MB_LIB.T6G(SCH_1):PAGE330

GPU_PEX_STRAP0_R @T6G_MB_LIB.T6G(SCH_1):GPU_PEX_STRAP0_R
 R3518    2      B Q_RES_0402LF-0,5%,1/16W,CHIP,CS00002JB13    I47 @T6G_MB_LIB.T6G(SCH_1):PAGE246
  U181   17  IO1_4 PCA9539RPW-PCA9539RPW,SMLF,IC,AL009539K07    I83 @T6G_MB_LIB.T6G(SCH_1):PAGE246

GPU_PEX_STRAP1 @T6G_MB_LIB.T6G(SCH_1):GPU_PEX_STRAP1
  J111   A1     A1 CONN112_10137002101LF-CONN112_10137002-101LF,THLF,A    I76 @T6G_MB_LIB.T6G(SCH_1):PAGE328
 R3517    1      A Q_RES_0402LF-0,5%,1/16W,CHIP,CS00002JB13    I55 @T6G_MB_LIB.T6G(SCH_1):PAGE246
 R3443    1      A Q_RES_0402LF-0,5%,1/16W,CHIP,CS00002JB13    I66 @T6G_MB_LIB.T6G(SCH_1):PAGE330

GPU_PEX_STRAP1_R @T6G_MB_LIB.T6G(SCH_1):GPU_PEX_STRAP1_R
 R3517    2      B Q_RES_0402LF-0,5%,1/16W,CHIP,CS00002JB13    I55 @T6G_MB_LIB.T6G(SCH_1):PAGE246
  U181   18  IO1_5 PCA9539RPW-PCA9539RPW,SMLF,IC,AL009539K07    I83 @T6G_MB_LIB.T6G(SCH_1):PAGE246

GPU_PRSNT @T6G_MB_LIB.T6G(SCH_1):GPU_PRSNT
  Q107    5     G2 MOSFET_NCH_DUAL-PJT138K,SMLF,IC,BAM138K0003   I157 @T6G_MB_LIB.T6G(SCH_1):PAGE299
 R3474    2      B Q_RES_0402LF-4.7K,5%,1/16W,CHIP,CS24702JB10   I158 @T6G_MB_LIB.T6G(SCH_1):PAGE299
  Q107    6     D1 MOSFET_NCH_DUAL-PJT138K,SMLF,IC,BAM138K0003   I160 @T6G_MB_LIB.T6G(SCH_1):PAGE299
 R3770    1      A Q_RES_0402LF-0,5%,1/16W,CHIP,CS00002JB13    I34 @T6G_MB_LIB.T6G(SCH_1):PAGE364

GPU_PRSNT_N @T6G_MB_LIB.T6G(SCH_1):GPU_PRSNT_N
  Q107    2     G1 MOSFET_NCH_DUAL-PJT138K,SMLF,IC,BAM138K0003   I160 @T6G_MB_LIB.T6G(SCH_1):PAGE299
 R3473    1      A Q_RES_0402LF-100K,1%,1/16W,EMPTY,CS41002FB09   I163 @T6G_MB_LIB.T6G(SCH_1):PAGE299
 R3487    2      B Q_RES_0402LF-10K,1%,1/16W,CHIP,CS31002FB08   I166 @T6G_MB_LIB.T6G(SCH_1):PAGE299
  J111   N2     N2 CONN112_10137002101LF-CONN112_10137002-101LF,THLF,A    I76 @T6G_MB_LIB.T6G(SCH_1):PAGE328

GPU_PRSNT_N_ISO @T6G_MB_LIB.T6G(SCH_1):GPU_PRSNT_N_ISO
 C1978    1      A Q_CAP_0402-0.1UF,25V,10%,X7R,CH4104K1B00   I152 @T6G_MB_LIB.T6G(SCH_1):PAGE299
 R3475    2      B Q_RES_0402LF-100K,1%,1/16W,CHIP,CS41002FB09   I154 @T6G_MB_LIB.T6G(SCH_1):PAGE299
  Q107    3     D2 MOSFET_NCH_DUAL-PJT138K,SMLF,IC,BAM138K0003   I157 @T6G_MB_LIB.T6G(SCH_1):PAGE299
 R3486    2      B Q_RES_0402LF-33.2,1%,1/16W,CHIP,CS03322FB03   I258 @T6G_MB_LIB.T6G(SCH_1):PAGE80
 R9001    1      A Q_RES_0402LF-0,5%,1/16W,CHIP,CS00002JB13    I46 @T6G_MB_LIB.T6G(SCH_1):PAGE246

GPU_PRSNT_N_ISO_R @T6G_MB_LIB.T6G(SCH_1):GPU_PRSNT_N_ISO_R
   U18 AB16  PB38A LCMXO3LF9400C5BG484C-LCMXO3LF-9400C-5BG484C,SMLF,IA   I216 @T6G_MB_LIB.T6G(SCH_1):PAGE80
 R3486    1      A Q_RES_0402LF-33.2,1%,1/16W,CHIP,CS03322FB03   I258 @T6G_MB_LIB.T6G(SCH_1):PAGE80

GPU_PRSNT_N_ISO_R1 @T6G_MB_LIB.T6G(SCH_1):GPU_PRSNT_N_ISO_R1
 R9001    2      B Q_RES_0402LF-0,5%,1/16W,CHIP,CS00002JB13    I46 @T6G_MB_LIB.T6G(SCH_1):PAGE246
  U181    9  IO0_5 PCA9539RPW-PCA9539RPW,SMLF,IC,AL009539K07    I83 @T6G_MB_LIB.T6G(SCH_1):PAGE246

GPU_PRSNT_R @T6G_MB_LIB.T6G(SCH_1):GPU_PRSNT_R
  U278    2      B 74LVC1G08W57-74LVC1G08W5-7,SMLF,IC,AL1G0008020    I31 @T6G_MB_LIB.T6G(SCH_1):PAGE364
 R3770    2      B Q_RES_0402LF-0,5%,1/16W,CHIP,CS00002JB13    I34 @T6G_MB_LIB.T6G(SCH_1):PAGE364

GPU_WP_HW_CTRL_ISO @T6G_MB_LIB.T6G(SCH_1):GPU_WP_HW_CTRL_ISO
 R9043    2      B Q_RES_0402LF-4.7K,5%,1/16W,CHIP,CS24702JB10   I192 @T6G_MB_LIB.T6G(SCH_1):PAGE299
  Q106    5     G2 MOSFET_NCH_DUAL-PJT138K,SMLF,IC,BAM138K0003   I200 @T6G_MB_LIB.T6G(SCH_1):PAGE299
  Q106    6     D1 MOSFET_NCH_DUAL-PJT138K,SMLF,IC,BAM138K0003   I201 @T6G_MB_LIB.T6G(SCH_1):PAGE299

GPU_WP_HW_CTRL_ISO_N @T6G_MB_LIB.T6G(SCH_1):GPU_WP_HW_CTRL_ISO_N
  J105   A3     A3 CONN112_10137002101LF-CONN112_10137002-101LF,THLF,A    I75 @T6G_MB_LIB.T6G(SCH_1):PAGE326
 R9044    2      B Q_RES_0402LF-4.7K,1%,1/16W,EMPTY,CS24702FB06   I195 @T6G_MB_LIB.T6G(SCH_1):PAGE299
 R3472    2      B Q_RES_0402LF-0,5%,1/16W,EMPTY,CS00002JB13   I198 @T6G_MB_LIB.T6G(SCH_1):PAGE299
  Q106    3     D2 MOSFET_NCH_DUAL-PJT138K,SMLF,IC,BAM138K0003   I200 @T6G_MB_LIB.T6G(SCH_1):PAGE299

GPU_WP_HW_CTRL_N @T6G_MB_LIB.T6G(SCH_1):GPU_WP_HW_CTRL_N
 R3485    2      B Q_RES_0402LF-33.2,1%,1/16W,CHIP,CS03322FB03   I255 @T6G_MB_LIB.T6G(SCH_1):PAGE80
 R3471    1      A Q_RES_0402LF-10K,1%,1/16W,EMPTY,CS31002FB08   I187 @T6G_MB_LIB.T6G(SCH_1):PAGE299
  Q106    2     G1 MOSFET_NCH_DUAL-PJT138K,SMLF,IC,BAM138K0003   I201 @T6G_MB_LIB.T6G(SCH_1):PAGE299
 R3470    2      B Q_RES_0402LF-1K,1%,1/16W,CHIP,CS21002FB06   I202 @T6G_MB_LIB.T6G(SCH_1):PAGE299

GPU_WP_HW_CTRL_R_N @T6G_MB_LIB.T6G(SCH_1):GPU_WP_HW_CTRL_R_N
   U18  W15  PB35D LCMXO3LF9400C5BG484C-LCMXO3LF-9400C-5BG484C,SMLF,IA   I216 @T6G_MB_LIB.T6G(SCH_1):PAGE80
 R3485    1      A Q_RES_0402LF-33.2,1%,1/16W,CHIP,CS03322FB03   I255 @T6G_MB_LIB.T6G(SCH_1):PAGE80

HDD_ACTIVITY_BUF @T6G_MB_LIB.T6G(SCH_1):HDD_ACTIVITY_BUF
  U259    6     1Y SN74LVC2G07DCKR_SMLF-SN74LVC2G07DCKR,IC,AL002G07006     I5 @T6G_MB_LIB.T6G(SCH_1):PAGE345
   Q95    2     G1 MOSFET_NCH_DUAL-PJT138K,SMLF,IC,BAM138K0003     I8 @T6G_MB_LIB.T6G(SCH_1):PAGE345
 R3296    2      B Q_RES_0402LF-4.7K,1%,1/16W,CHIP,CS24702FB06    I51 @T6G_MB_LIB.T6G(SCH_1):PAGE345

HDD_ACTIVITY_BUF_N @T6G_MB_LIB.T6G(SCH_1):HDD_ACTIVITY_BUF_N
   Q95    6     D1 MOSFET_NCH_DUAL-PJT138K,SMLF,IC,BAM138K0003     I8 @T6G_MB_LIB.T6G(SCH_1):PAGE345
 R3298    2      B Q_RES_0402LF-10K,1%,1/16W,CHIP,CS31002FB08    I58 @T6G_MB_LIB.T6G(SCH_1):PAGE345
 R5377    1      A Q_RES_0402LF-0,5%,1/16W,CHIP,CS00002JB13    I62 @T6G_MB_LIB.T6G(SCH_1):PAGE345

HDT_CPU0_HDT_CONN_TESTEN @T6G_MB_LIB.T6G(SCH_1):HDT_CPU0_HDT_CONN_TESTEN
 R1629    1      A Q_RES_0402LF-1K,1%,1/16W,CHIP,CS21002FB06   I112 @T6G_MB_LIB.T6G(SCH_1):PAGE149
 R1632    1      A Q_RES_0402LF-33,5%,1/16W,CHIP,CS03302JB10   I114 @T6G_MB_LIB.T6G(SCH_1):PAGE149
   J54   18     18 SCONN20_HSU2101L00007H-SCONN20_HSU2101-L0000-7H,SMA   I142 @T6G_MB_LIB.T6G(SCH_1):PAGE149

HDT_CPU0_XTRIG_L5 @T6G_MB_LIB.T6G(SCH_1):HDT_CPU0_XTRIG_L5
   J54   15     15 SCONN20_HSU2101L00007H-SCONN20_HSU2101-L0000-7H,SMA   I142 @T6G_MB_LIB.T6G(SCH_1):PAGE149
  R478    2      B Q_RES_0402LF-33,5%,1/16W,CHIP,CS03302JB10   I150 @T6G_MB_LIB.T6G(SCH_1):PAGE149

HDT_CPU0_XTRIG_L6 @T6G_MB_LIB.T6G(SCH_1):HDT_CPU0_XTRIG_L6
   J54   11     11 SCONN20_HSU2101L00007H-SCONN20_HSU2101-L0000-7H,SMA   I142 @T6G_MB_LIB.T6G(SCH_1):PAGE149
  R476    2      B Q_RES_0402LF-33,5%,1/16W,CHIP,CS03302JB10   I148 @T6G_MB_LIB.T6G(SCH_1):PAGE149

HDT_CPU0_XTRIG_L7 @T6G_MB_LIB.T6G(SCH_1):HDT_CPU0_XTRIG_L7
   J54   13     13 SCONN20_HSU2101L00007H-SCONN20_HSU2101-L0000-7H,SMA   I142 @T6G_MB_LIB.T6G(SCH_1):PAGE149
  R477    2      B Q_RES_0402LF-33,5%,1/16W,CHIP,CS03302JB10   I147 @T6G_MB_LIB.T6G(SCH_1):PAGE149

HDT_HDR_DBREQ_N @T6G_MB_LIB.T6G(SCH_1):HDT_HDR_DBREQ_N
  U149    6     A4 SN74AVC4T774PWR-SN74AVC4T774PWR,SMLF,IC,AL04T774K00    I31 @T6G_MB_LIB.T6G(SCH_1):PAGE149
 R1631    2      B Q_RES_0402LF-33,5%,1/16W,CHIP,CS03302JB10   I113 @T6G_MB_LIB.T6G(SCH_1):PAGE149
   C87    1      A Q_CAP_C0402-0.001UF,50V,10%,X7R,CH30106KB19   I134 @T6G_MB_LIB.T6G(SCH_1):PAGE149

HDT_HDR_DBREQ_R_N @T6G_MB_LIB.T6G(SCH_1):HDT_HDR_DBREQ_R_N
 R1631    1      A Q_RES_0402LF-33,5%,1/16W,CHIP,CS03302JB10   I113 @T6G_MB_LIB.T6G(SCH_1):PAGE149
 R1630    2      B Q_RES_0402LF-1K,1%,1/16W,CHIP,CS21002FB06   I118 @T6G_MB_LIB.T6G(SCH_1):PAGE149
   J54   16     16 SCONN20_HSU2101L00007H-SCONN20_HSU2101-L0000-7H,SMA   I142 @T6G_MB_LIB.T6G(SCH_1):PAGE149

HDT_HDR_PWROK @T6G_MB_LIB.T6G(SCH_1):HDT_HDR_PWROK
   J54   10     10 SCONN20_HSU2101L00007H-SCONN20_HSU2101-L0000-7H,SMA   I142 @T6G_MB_LIB.T6G(SCH_1):PAGE149
  R708    2      B Q_RES_0402LF-33,5%,1/16W,CHIP,CS03302JB10   I168 @T6G_MB_LIB.T6G(SCH_1):PAGE80

HDT_HDR_RESET_N @T6G_MB_LIB.T6G(SCH_1):HDT_HDR_RESET_N
   J54   12     12 SCONN20_HSU2101L00007H-SCONN20_HSU2101-L0000-7H,SMA   I142 @T6G_MB_LIB.T6G(SCH_1):PAGE149
  R856    2      B Q_RES_0402LF-0,5%,1/16W,CHIP,CS00002JB13   I167 @T6G_MB_LIB.T6G(SCH_1):PAGE80

HDT_HDR_R_TCK @T6G_MB_LIB.T6G(SCH_1):HDT_HDR_R_TCK
 R1352    1      A Q_RES_0402LF-0,5%,1/16W,CHIP,CS00002JB13   I132 @T6G_MB_LIB.T6G(SCH_1):PAGE149
   J54    2      2 SCONN20_HSU2101L00007H-SCONN20_HSU2101-L0000-7H,SMA   I142 @T6G_MB_LIB.T6G(SCH_1):PAGE149

HDT_HDR_R_TDI @T6G_MB_LIB.T6G(SCH_1):HDT_HDR_R_TDI
 R1354    1      A Q_RES_0402LF-0,5%,1/16W,CHIP,CS00002JB13   I109 @T6G_MB_LIB.T6G(SCH_1):PAGE149
   J54    6      6 SCONN20_HSU2101L00007H-SCONN20_HSU2101-L0000-7H,SMA   I142 @T6G_MB_LIB.T6G(SCH_1):PAGE149

HDT_HDR_R_TMS @T6G_MB_LIB.T6G(SCH_1):HDT_HDR_R_TMS
 R1353    1      A Q_RES_0402LF-0,5%,1/16W,CHIP,CS00002JB13   I133 @T6G_MB_LIB.T6G(SCH_1):PAGE149
   J54    4      4 SCONN20_HSU2101L00007H-SCONN20_HSU2101-L0000-7H,SMA   I142 @T6G_MB_LIB.T6G(SCH_1):PAGE149

HDT_HDR_TCK @T6G_MB_LIB.T6G(SCH_1):HDT_HDR_TCK
  U149    3     A1 SN74AVC4T774PWR-SN74AVC4T774PWR,SMLF,IC,AL04T774K00    I31 @T6G_MB_LIB.T6G(SCH_1):PAGE149
 R1624    2      B Q_RES_0402LF-1K,1%,1/16W,CHIP,CS21002FB06   I111 @T6G_MB_LIB.T6G(SCH_1):PAGE149
 R1352    2      B Q_RES_0402LF-0,5%,1/16W,CHIP,CS00002JB13   I132 @T6G_MB_LIB.T6G(SCH_1):PAGE149
  C604    1      A Q_CAP_C0402-0.001UF,50V,10%,X7R,CH30106KB19   I140 @T6G_MB_LIB.T6G(SCH_1):PAGE149

HDT_HDR_TDI @T6G_MB_LIB.T6G(SCH_1):HDT_HDR_TDI
  U146    8     A1 SN74AVC2T245RSWR-SN74AVC2T245RSWR,SMLF,IC,AL02T245A    I76 @T6G_MB_LIB.T6G(SCH_1):PAGE149
 R1354    2      B Q_RES_0402LF-0,5%,1/16W,CHIP,CS00002JB13   I109 @T6G_MB_LIB.T6G(SCH_1):PAGE149
 R1627    2      B Q_RES_0402LF-1K,1%,1/16W,CHIP,CS21002FB06   I116 @T6G_MB_LIB.T6G(SCH_1):PAGE149
  C605    1      A Q_CAP_C0402-0.001UF,50V,10%,X7R,CH30106KB19   I137 @T6G_MB_LIB.T6G(SCH_1):PAGE149

HDT_HDR_TDO @T6G_MB_LIB.T6G(SCH_1):HDT_HDR_TDO
 R1628    2      B Q_RES_0402LF-1K,1%,1/16W,CHIP,CS21002FB06   I117 @T6G_MB_LIB.T6G(SCH_1):PAGE149
   J54    8      8 SCONN20_HSU2101L00007H-SCONN20_HSU2101-L0000-7H,SMA   I142 @T6G_MB_LIB.T6G(SCH_1):PAGE149
 R6108    1      A Q_RES_0402LF-0,5%,1/16W,CHIP,CS00002JB13   I159 @T6G_MB_LIB.T6G(SCH_1):PAGE149

HDT_HDR_TDO_R @T6G_MB_LIB.T6G(SCH_1):HDT_HDR_TDO_R
  U146    9     A2 SN74AVC2T245RSWR-SN74AVC2T245RSWR,SMLF,IC,AL02T245A    I76 @T6G_MB_LIB.T6G(SCH_1):PAGE149
 R6108    2      B Q_RES_0402LF-0,5%,1/16W,CHIP,CS00002JB13   I159 @T6G_MB_LIB.T6G(SCH_1):PAGE149

HDT_HDR_TMS @T6G_MB_LIB.T6G(SCH_1):HDT_HDR_TMS
  U149    4     A2 SN74AVC4T774PWR-SN74AVC4T774PWR,SMLF,IC,AL04T774K00    I31 @T6G_MB_LIB.T6G(SCH_1):PAGE149
 R1626    2      B Q_RES_0402LF-1K,1%,1/16W,CHIP,CS21002FB06   I115 @T6G_MB_LIB.T6G(SCH_1):PAGE149
 R1353    2      B Q_RES_0402LF-0,5%,1/16W,CHIP,CS00002JB13   I133 @T6G_MB_LIB.T6G(SCH_1):PAGE149

HDT_HDR_TRST_N @T6G_MB_LIB.T6G(SCH_1):HDT_HDR_TRST_N
  U149    5     A3 SN74AVC4T774PWR-SN74AVC4T774PWR,SMLF,IC,AL04T774K00    I31 @T6G_MB_LIB.T6G(SCH_1):PAGE149
 R1620    1      A Q_RES_0402LF-33,5%,1/16W,CHIP,CS03302JB10   I149 @T6G_MB_LIB.T6G(SCH_1):PAGE149
   C85    1      A Q_CAP_C0402-0.001UF,50V,10%,X7R,CH30106KB19   I152 @T6G_MB_LIB.T6G(SCH_1):PAGE149

HDT_HDR_TRST_N_R @T6G_MB_LIB.T6G(SCH_1):HDT_HDR_TRST_N_R
   J54    9      9 SCONN20_HSU2101L00007H-SCONN20_HSU2101-L0000-7H,SMA   I142 @T6G_MB_LIB.T6G(SCH_1):PAGE149
 R1621    2      B Q_RES_0402LF-1K,1%,1/16W,CHIP,CS21002FB06   I146 @T6G_MB_LIB.T6G(SCH_1):PAGE149
 R1620    2      B Q_RES_0402LF-33,5%,1/16W,CHIP,CS03302JB10   I149 @T6G_MB_LIB.T6G(SCH_1):PAGE149

HGX_DETECT @T6G_MB_LIB.T6G(SCH_1):HGX_DETECT
  Q148    5     G2 MOSFET_NCH_DUAL-PJT138K,SMLF,IC,BAM138K0003    I55 @T6G_MB_LIB.T6G(SCH_1):PAGE331
 R4545    2      B Q_RES_0402LF-4.7K,5%,1/16W,CHIP,CS24702JB10    I57 @T6G_MB_LIB.T6G(SCH_1):PAGE331
  Q148    6     D1 MOSFET_NCH_DUAL-PJT138K,SMLF,IC,BAM138K0003    I61 @T6G_MB_LIB.T6G(SCH_1):PAGE331

HGX_DETECT_N @T6G_MB_LIB.T6G(SCH_1):HGX_DETECT_N
  Q148    2     G1 MOSFET_NCH_DUAL-PJT138K,SMLF,IC,BAM138K0003    I61 @T6G_MB_LIB.T6G(SCH_1):PAGE331
 R4544    1      A Q_RES_0402LF-100K,1%,1/16W,EMPTY,CS41002FB09    I62 @T6G_MB_LIB.T6G(SCH_1):PAGE331
 R4543    2      B Q_RES_0402LF-1K,1%,1/16W,CHIP,CS21002FB06    I85 @T6G_MB_LIB.T6G(SCH_1):PAGE331
 R4556    2      B Q_RES_0402LF-33.2,1%,1/16W,CHIP,CS03322FB03   I226 @T6G_MB_LIB.T6G(SCH_1):PAGE80

HGX_DETECT_N_ISO @T6G_MB_LIB.T6G(SCH_1):HGX_DETECT_N_ISO
  Q148    3     D2 MOSFET_NCH_DUAL-PJT138K,SMLF,IC,BAM138K0003    I55 @T6G_MB_LIB.T6G(SCH_1):PAGE331
 R4546    2      B Q_RES_0402LF-100K,1%,1/16W,EMPTY,CS41002FB09   I110 @T6G_MB_LIB.T6G(SCH_1):PAGE331
    C6    1      A Q_CAP_0402-0.1UF,25V,10%,EMPTY,CH4104K1B00   I111 @T6G_MB_LIB.T6G(SCH_1):PAGE331
  J112   A3     A3 CONN160_10131762101LF-CONN160_10131762-101LF,THLF,A   I102 @T6G_MB_LIB.T6G(SCH_1):PAGE329
 R2656    1      A Q_RES_0402LF-100,1%,1/16W,EMPTY,CS11002FB07    I69 @T6G_MB_LIB.T6G(SCH_1):PAGE330

HGX_DETECT_N_R @T6G_MB_LIB.T6G(SCH_1):HGX_DETECT_N_R
   U18  U13  PB29D LCMXO3LF9400C5BG484C-LCMXO3LF-9400C-5BG484C,SMLF,IA   I216 @T6G_MB_LIB.T6G(SCH_1):PAGE80
 R4556    1      A Q_RES_0402LF-33.2,1%,1/16W,CHIP,CS03322FB03   I226 @T6G_MB_LIB.T6G(SCH_1):PAGE80

HPDB_HSC_PWRGD @T6G_MB_LIB.T6G(SCH_1):HPDB_HSC_PWRGD
 R2802    2      B Q_RES_0402LF-0,5%,1/16W,CHIP,CS00002JB13   I387 @T6G_MB_LIB.T6G(SCH_1):PAGE363
 R4552    1      A Q_RES_0402LF-100K,1%,1/16W,CHIP,CS41002FB09    I50 @T6G_MB_LIB.T6G(SCH_1):PAGE364
 R4551    2      B Q_RES_0402LF-54.9K,1%,1/16W,EMPTY,CS35492FB03    I51 @T6G_MB_LIB.T6G(SCH_1):PAGE364
  Q145    2     G1 MOSFET_NCH_DUAL-PJT138K,SMLF,IC,BAM138K0003    I53 @T6G_MB_LIB.T6G(SCH_1):PAGE364

HPDB_HSC_PWRGD_ISO @T6G_MB_LIB.T6G(SCH_1):HPDB_HSC_PWRGD_ISO
  Q145    3     D2 MOSFET_NCH_DUAL-PJT138K,SMLF,IC,BAM138K0003    I58 @T6G_MB_LIB.T6G(SCH_1):PAGE364
 R4554    2      B Q_RES_0402LF-100K,1%,1/16W,CHIP,CS41002FB09    I59 @T6G_MB_LIB.T6G(SCH_1):PAGE364
   C70    1      A Q_CAP_0402-0.1UF,25V,10%,X7R,CH4104K1B00    I62 @T6G_MB_LIB.T6G(SCH_1):PAGE364
 R4557    1      A Q_RES_0402LF-33.2,1%,1/16W,CHIP,CS03322FB03   I301 @T6G_MB_LIB.T6G(SCH_1):PAGE80

HPDB_HSC_PWRGD_ISO_R @T6G_MB_LIB.T6G(SCH_1):HPDB_HSC_PWRGD_ISO_R
   U18  T12  PB27B LCMXO3LF9400C5BG484C-LCMXO3LF-9400C-5BG484C,SMLF,IA   I216 @T6G_MB_LIB.T6G(SCH_1):PAGE80
 R4557    2      B Q_RES_0402LF-33.2,1%,1/16W,CHIP,CS03322FB03   I301 @T6G_MB_LIB.T6G(SCH_1):PAGE80

HPDB_HSC_PWRGD_N @T6G_MB_LIB.T6G(SCH_1):HPDB_HSC_PWRGD_N
  Q145    6     D1 MOSFET_NCH_DUAL-PJT138K,SMLF,IC,BAM138K0003    I53 @T6G_MB_LIB.T6G(SCH_1):PAGE364
 R4553    2      B Q_RES_0402LF-4.7K,5%,1/16W,CHIP,CS24702JB10    I55 @T6G_MB_LIB.T6G(SCH_1):PAGE364
  Q145    5     G2 MOSFET_NCH_DUAL-PJT138K,SMLF,IC,BAM138K0003    I58 @T6G_MB_LIB.T6G(SCH_1):PAGE364

HPDB_HSC_PWRGD_R @T6G_MB_LIB.T6G(SCH_1):HPDB_HSC_PWRGD_R
 R2802    1      A Q_RES_0402LF-0,5%,1/16W,CHIP,CS00002JB13   I387 @T6G_MB_LIB.T6G(SCH_1):PAGE363
   C65    1      A Q_CAP_0402-0.1UF,25V,10%,EMPTY,CH4104K1B00   I454 @T6G_MB_LIB.T6G(SCH_1):PAGE363
   J45   C3     C3 CONN60_101062636003K02LF-CONN60_10106263-6003K02LFA   I466 @T6G_MB_LIB.T6G(SCH_1):PAGE363

HP_LVC3_E1S_0_HSC_PWRGD @T6G_MB_LIB.T6G(SCH_1):HP_LVC3_E1S_0_HSC_PWRGD
 R3948    2      B Q_RES_0402LF-10K,1%,1/16W,CHIP,CS31002FB08    I37 @T6G_MB_LIB.T6G(SCH_1):PAGE323
 R3972    2      B Q_RES_0402LF-0,5%,1/16W,CHIP,CS00002JB13    I71 @T6G_MB_LIB.T6G(SCH_1):PAGE324
 R6048    1      A Q_RES_0402LF-0,5%,1/16W,CHIP,CS00002JB13    I28 @T6G_MB_LIB.T6G(SCH_1):PAGE80
 R3978    2      B Q_RES_0402LF-100K,1%,1/16W,CHIP,CS41002FB09    I86 @T6G_MB_LIB.T6G(SCH_1):PAGE324
 PU292   10     PG RS31312R-RS31312R,SMLF,IC,AL031312000    I76 @T6G_MB_LIB.T6G(SCH_1):PAGE323

HP_LVC3_OCP_SFF_PRSNT2 @T6G_MB_LIB.T6G(SCH_1):HP_LVC3_OCP_SFF_PRSNT2
   U24    D  DRAIN MOSFET_N_SMLF-BSS138K,BSS138K,IC,BAM138K0000    I31 @T6G_MB_LIB.T6G(SCH_1):PAGE340
 R1128    2      B Q_RES_0402LF-1K,1%,1/16W,CHIP,CS21002FB06    I34 @T6G_MB_LIB.T6G(SCH_1):PAGE340
   U23    2      B 74LVC1G08W57-74LVC1G08W5-7,SMLF,IC,AL1G0008020    I36 @T6G_MB_LIB.T6G(SCH_1):PAGE340

HP_LVC3_OCP_SFF_PRSNT2_N @T6G_MB_LIB.T6G(SCH_1):HP_LVC3_OCP_SFF_PRSNT2_N
  R576    2      B Q_RES_0402LF-0,5%,1/16W,CHIP,CS00002JB13   I116 @T6G_MB_LIB.T6G(SCH_1):PAGE338
  R577    2      B Q_RES_0402LF-10K,1%,1/16W,CHIP,CS31002FB08   I118 @T6G_MB_LIB.T6G(SCH_1):PAGE338
   U24    G   GATE MOSFET_N_SMLF-BSS138K,BSS138K,IC,BAM138K0000    I31 @T6G_MB_LIB.T6G(SCH_1):PAGE340

HP_LVC3_OCP_SFF_PRSNT2_PLD_N @T6G_MB_LIB.T6G(SCH_1):HP_LVC3_OCP_SFF_PRSNT2_PLD_N
 R6046    1      A Q_RES_0402LF-100,1%,1/16W,CHIP,CS11002FB07    I64 @T6G_MB_LIB.T6G(SCH_1):PAGE80
 R1148    2      B Q_RES_0402LF-0,5%,1/16W,CHIP,CS00002JB13    I46 @T6G_MB_LIB.T6G(SCH_1):PAGE338
 R1150    2      B Q_RES_0402LF-10K,1%,1/16W,CHIP,CS31002FB08    I71 @T6G_MB_LIB.T6G(SCH_1):PAGE338

HP_LVC3_OCP_V3_1_P12V_PWRGD @T6G_MB_LIB.T6G(SCH_1):HP_LVC3_OCP_V3_1_P12V_PWRGD
 R3144    2      B Q_RES_0402LF-0,5%,1/16W,CHIP,CS00002JB13    I75 @T6G_MB_LIB.T6G(SCH_1):PAGE338
 R3797    2      B Q_RES_0402LF-100K,1%,1/16W,CHIP,CS41002FB09    I85 @T6G_MB_LIB.T6G(SCH_1):PAGE338
 R4532    2      B Q_RES_0402LF-10K,1%,1/16W,CHIP,CS31002FB08    I75 @T6G_MB_LIB.T6G(SCH_1):PAGE339
 R1129    1      A Q_RES_0402LF-0,5%,1/16W,CHIP,CS00002JB13    I57 @T6G_MB_LIB.T6G(SCH_1):PAGE340
 R1135    2      B Q_RES_0402LF-0,5%,1/16W,EMPTY,CS00002JB13    I41 @T6G_MB_LIB.T6G(SCH_1):PAGE248
 R1136    1      A Q_RES_0402LF-0,5%,1/16W,EMPTY,CS00002JB13   I133 @T6G_MB_LIB.T6G(SCH_1):PAGE338
 R1137    1      A Q_RES_0402LF-0,5%,1/16W,EMPTY,CS00002JB13   I135 @T6G_MB_LIB.T6G(SCH_1):PAGE339
 R1509    1      A Q_RES_0402LF-0,5%,1/16W,CHIP,CS00002JB13    I96 @T6G_MB_LIB.T6G(SCH_1):PAGE340
 PU204   10     PG RS31312R-RS31312R,SMLF,IC,AL031312000   I137 @T6G_MB_LIB.T6G(SCH_1):PAGE339

HP_LVC3_OCP_V3_1_P12V_R2_PWRGD @T6G_MB_LIB.T6G(SCH_1):HP_LVC3_OCP_V3_1_P12V_R2_PWRGD
 U9050    2      B 74LVC1G08W57-74LVC1G08W5-7,SMLF,IC,AL1G0008020    I91 @T6G_MB_LIB.T6G(SCH_1):PAGE340
 R1509    2      B Q_RES_0402LF-0,5%,1/16W,CHIP,CS00002JB13    I96 @T6G_MB_LIB.T6G(SCH_1):PAGE340

HP_LVC3_OCP_V3_1_P12V_R_PWRGD @T6G_MB_LIB.T6G(SCH_1):HP_LVC3_OCP_V3_1_P12V_R_PWRGD
   U28    2      A SN74LVC1G07DBVR_SMLF-SN74LVC1G07DBVR,IC,AL1G0007024    I51 @T6G_MB_LIB.T6G(SCH_1):PAGE340
 R1129    2      B Q_RES_0402LF-0,5%,1/16W,CHIP,CS00002JB13    I57 @T6G_MB_LIB.T6G(SCH_1):PAGE340

HP_LVC3_OCP_V3_1_PRSNT2_N_R @T6G_MB_LIB.T6G(SCH_1):HP_LVC3_OCP_V3_1_PRSNT2_N_R
    U8    6     1Y 74LVC2G07DW7-74LVC2G07DW-7,SMLF,IC,AL002G07003    I26 @T6G_MB_LIB.T6G(SCH_1):PAGE338
    U8    4     2Y 74LVC2G07DW7-74LVC2G07DW-7,SMLF,IC,AL002G07003    I26 @T6G_MB_LIB.T6G(SCH_1):PAGE338
  U211    6     1Y 74LVC2G07DW7-74LVC2G07DW-7,SMLF,IC,AL002G07003    I29 @T6G_MB_LIB.T6G(SCH_1):PAGE338
  U211    4     2Y 74LVC2G07DW7-74LVC2G07DW-7,SMLF,IC,AL002G07003    I29 @T6G_MB_LIB.T6G(SCH_1):PAGE338
 R1148    1      A Q_RES_0402LF-0,5%,1/16W,CHIP,CS00002JB13    I46 @T6G_MB_LIB.T6G(SCH_1):PAGE338
  R576    1      A Q_RES_0402LF-0,5%,1/16W,CHIP,CS00002JB13   I116 @T6G_MB_LIB.T6G(SCH_1):PAGE338

HP_LVC3_OCP_V3_1_PWRGD @T6G_MB_LIB.T6G(SCH_1):HP_LVC3_OCP_V3_1_PWRGD
 R9022    2      B Q_RES_0402LF-33.2,1%,1/16W,CHIP,CS03322FB03    I13 @T6G_MB_LIB.T6G(SCH_1):PAGE340
 U9001    2      B 74LVC1G08W57-74LVC1G08W5-7,SMLF,IC,AL1G0008020    I25 @T6G_MB_LIB.T6G(SCH_1):PAGE340

HP_LVC3_OCP_V3_1_PWRGD_R1 @T6G_MB_LIB.T6G(SCH_1):HP_LVC3_OCP_V3_1_PWRGD_R1
 R9034    2      B Q_RES_0402LF-33.2,1%,1/16W,CHIP,CS03322FB03     I3 @T6G_MB_LIB.T6G(SCH_1):PAGE340
 R9029    2      B Q_RES_0402LF-0,5%,1/16W,EMPTY,CS00002JB13    I18 @T6G_MB_LIB.T6G(SCH_1):PAGE340
 U9002    1     I0 74LVC1G32GW_SMLF-74LVC1G32GW,IC,ALVC1G32007    I74 @T6G_MB_LIB.T6G(SCH_1):PAGE340

HP_LVC3_OCP_V3_1_PWRGD_R2 @T6G_MB_LIB.T6G(SCH_1):HP_LVC3_OCP_V3_1_PWRGD_R2
 U9050    4      Y 74LVC1G08W57-74LVC1G08W5-7,SMLF,IC,AL1G0008020    I91 @T6G_MB_LIB.T6G(SCH_1):PAGE340
 R1518    1      A Q_RES_0402LF-0,5%,1/16W,CHIP,CS00002JB13   I102 @T6G_MB_LIB.T6G(SCH_1):PAGE340

HP_LVC3_OCP_V3_1_R_EN @T6G_MB_LIB.T6G(SCH_1):HP_LVC3_OCP_V3_1_R_EN
  U236    5     EN PCA9617ADP-PCA9617ADP,SMLF,IC,AL009617K02    I14 @T6G_MB_LIB.T6G(SCH_1):PAGE248
 R3263    1      A Q_RES_0402LF-0,5%,1/16W,EMPTY,CS00002JB13    I35 @T6G_MB_LIB.T6G(SCH_1):PAGE248
 R1135    1      A Q_RES_0402LF-0,5%,1/16W,EMPTY,CS00002JB13    I41 @T6G_MB_LIB.T6G(SCH_1):PAGE248
 R1500    1      A Q_RES_0402LF-0,5%,1/16W,CHIP,CS00002JB13    I43 @T6G_MB_LIB.T6G(SCH_1):PAGE248

HP_LVC3_OCP_V3_2_P12V_PWRGD @T6G_MB_LIB.T6G(SCH_1):HP_LVC3_OCP_V3_2_P12V_PWRGD
 R3825    2      B Q_RES_0402LF-100K,1%,1/16W,CHIP,CS41002FB09    I80 @T6G_MB_LIB.T6G(SCH_1):PAGE343
 R3848    2      B Q_RES_0402LF-10K,1%,1/16W,CHIP,CS31002FB08    I27 @T6G_MB_LIB.T6G(SCH_1):PAGE344
 R3831    2      B Q_RES_0402LF-0,5%,1/16W,CHIP,CS00002JB13    I77 @T6G_MB_LIB.T6G(SCH_1):PAGE343
 R1163    1      A Q_RES_0402LF-0,5%,1/16W,CHIP,CS00002JB13     I3 @T6G_MB_LIB.T6G(SCH_1):PAGE257
 R1180    2      B Q_RES_0402LF-0,5%,1/16W,EMPTY,CS00002JB13    I45 @T6G_MB_LIB.T6G(SCH_1):PAGE248
 R1182    1      A Q_RES_0402LF-0,5%,1/16W,EMPTY,CS00002JB13   I129 @T6G_MB_LIB.T6G(SCH_1):PAGE343
 R1196    1      A Q_RES_0402LF-0,5%,1/16W,EMPTY,CS00002JB13    I79 @T6G_MB_LIB.T6G(SCH_1):PAGE344
 R1523    1      A Q_RES_0402LF-0,5%,1/16W,CHIP,CS00002JB13    I84 @T6G_MB_LIB.T6G(SCH_1):PAGE257
 PU206   10     PG RS31312R-RS31312R,SMLF,IC,AL031312000    I82 @T6G_MB_LIB.T6G(SCH_1):PAGE344

HP_LVC3_OCP_V3_2_P12V_PWRGD_R @T6G_MB_LIB.T6G(SCH_1):HP_LVC3_OCP_V3_2_P12V_PWRGD_R
   U18  E13  PT28C LCMXO3LF9400C5BG484C-LCMXO3LF-9400C-5BG484C,SMLF,IA    I94 @T6G_MB_LIB.T6G(SCH_1):PAGE79
  R407    2      B Q_RES_0402LF-0,5%,1/16W,CHIP,CS00002JB13   I139 @T6G_MB_LIB.T6G(SCH_1):PAGE79

HP_LVC3_OCP_V3_2_P12V_PWRGD_R2 @T6G_MB_LIB.T6G(SCH_1):HP_LVC3_OCP_V3_2_P12V_PWRGD_R2
 U9051    2      B 74LVC1G08W57-74LVC1G08W5-7,SMLF,IC,AL1G0008020    I78 @T6G_MB_LIB.T6G(SCH_1):PAGE257
 R1523    2      B Q_RES_0402LF-0,5%,1/16W,CHIP,CS00002JB13    I84 @T6G_MB_LIB.T6G(SCH_1):PAGE257

HP_LVC3_OCP_V3_2_P12V_R_PWRGD @T6G_MB_LIB.T6G(SCH_1):HP_LVC3_OCP_V3_2_P12V_R_PWRGD
 R1163    2      B Q_RES_0402LF-0,5%,1/16W,CHIP,CS00002JB13     I3 @T6G_MB_LIB.T6G(SCH_1):PAGE257
   U33    2      A SN74LVC1G07DBVR_SMLF-SN74LVC1G07DBVR,IC,AL1G0007024    I64 @T6G_MB_LIB.T6G(SCH_1):PAGE257

HP_LVC3_OCP_V3_2_PRSNT2 @T6G_MB_LIB.T6G(SCH_1):HP_LVC3_OCP_V3_2_PRSNT2
   U32    D  DRAIN MOSFET_N_SMLF-BSS138K,BSS138K,IC,BAM138K0000    I24 @T6G_MB_LIB.T6G(SCH_1):PAGE257
 R1149    2      B Q_RES_0402LF-1K,1%,1/16W,CHIP,CS21002FB06    I25 @T6G_MB_LIB.T6G(SCH_1):PAGE257
   U31    2      B 74LVC1G08W57-74LVC1G08W5-7,SMLF,IC,AL1G0008020    I31 @T6G_MB_LIB.T6G(SCH_1):PAGE257

HP_LVC3_OCP_V3_2_PRSNT2_N @T6G_MB_LIB.T6G(SCH_1):HP_LVC3_OCP_V3_2_PRSNT2_N
   U32    G   GATE MOSFET_N_SMLF-BSS138K,BSS138K,IC,BAM138K0000    I24 @T6G_MB_LIB.T6G(SCH_1):PAGE257
 R1191    2      B Q_RES_0402LF-0,5%,1/16W,CHIP,CS00002JB13   I116 @T6G_MB_LIB.T6G(SCH_1):PAGE343
 R1192    2      B Q_RES_0402LF-1K,1%,1/16W,CHIP,CS21002FB06   I118 @T6G_MB_LIB.T6G(SCH_1):PAGE343

HP_LVC3_OCP_V3_2_PRSNT2_N_R @T6G_MB_LIB.T6G(SCH_1):HP_LVC3_OCP_V3_2_PRSNT2_N_R
   U58    6     1Y 74LVC2G07DW7-74LVC2G07DW-7,SMLF,IC,AL002G07003    I28 @T6G_MB_LIB.T6G(SCH_1):PAGE343
   U58    4     2Y 74LVC2G07DW7-74LVC2G07DW-7,SMLF,IC,AL002G07003    I28 @T6G_MB_LIB.T6G(SCH_1):PAGE343
 R3142    1      A Q_RES_0402LF-0,5%,1/16W,CHIP,CS00002JB13    I59 @T6G_MB_LIB.T6G(SCH_1):PAGE343
   U59    6     1Y 74LVC2G07DW7-74LVC2G07DW-7,SMLF,IC,AL002G07003    I22 @T6G_MB_LIB.T6G(SCH_1):PAGE343
   U59    4     2Y 74LVC2G07DW7-74LVC2G07DW-7,SMLF,IC,AL002G07003    I22 @T6G_MB_LIB.T6G(SCH_1):PAGE343
 R1191    1      A Q_RES_0402LF-0,5%,1/16W,CHIP,CS00002JB13   I116 @T6G_MB_LIB.T6G(SCH_1):PAGE343

HP_LVC3_OCP_V3_2_PRSNT2_PLD_N @T6G_MB_LIB.T6G(SCH_1):HP_LVC3_OCP_V3_2_PRSNT2_PLD_N
 R3142    2      B Q_RES_0402LF-0,5%,1/16W,CHIP,CS00002JB13    I59 @T6G_MB_LIB.T6G(SCH_1):PAGE343
 R3147    2      B Q_RES_0402LF-1K,1%,1/16W,CHIP,CS21002FB06    I69 @T6G_MB_LIB.T6G(SCH_1):PAGE343
 R6117    1      A Q_RES_0402LF-100,1%,1/16W,CHIP,CS11002FB07   I131 @T6G_MB_LIB.T6G(SCH_1):PAGE79

HP_LVC3_OCP_V3_2_PWRGD @T6G_MB_LIB.T6G(SCH_1):HP_LVC3_OCP_V3_2_PWRGD
 R1173    2      B Q_RES_0402LF-33.2,1%,1/16W,CHIP,CS03322FB03    I16 @T6G_MB_LIB.T6G(SCH_1):PAGE257
   U35    2      B 74LVC1G08W57-74LVC1G08W5-7,SMLF,IC,AL1G0008020    I63 @T6G_MB_LIB.T6G(SCH_1):PAGE257

HP_LVC3_OCP_V3_2_PWRGD_R1 @T6G_MB_LIB.T6G(SCH_1):HP_LVC3_OCP_V3_2_PWRGD_R1
 R1178    2      B Q_RES_0402LF-33.2,1%,1/16W,CHIP,CS03322FB03    I12 @T6G_MB_LIB.T6G(SCH_1):PAGE257
   U37    1     I0 74LVC1G32GW_SMLF-74LVC1G32GW,IC,ALVC1G32007    I40 @T6G_MB_LIB.T6G(SCH_1):PAGE257
 R1146    2      B Q_RES_0402LF-0,5%,1/16W,EMPTY,CS00002JB13    I41 @T6G_MB_LIB.T6G(SCH_1):PAGE257

HP_LVC3_OCP_V3_2_PWRGD_R2 @T6G_MB_LIB.T6G(SCH_1):HP_LVC3_OCP_V3_2_PWRGD_R2
 U9051    4      Y 74LVC1G08W57-74LVC1G08W5-7,SMLF,IC,AL1G0008020    I78 @T6G_MB_LIB.T6G(SCH_1):PAGE257
 R1524    1      A Q_RES_0402LF-0,5%,1/16W,CHIP,CS00002JB13    I89 @T6G_MB_LIB.T6G(SCH_1):PAGE257

HP_LVC3_OCP_V3_2_R_EN @T6G_MB_LIB.T6G(SCH_1):HP_LVC3_OCP_V3_2_R_EN
  U235    5     EN PCA9617ADP-PCA9617ADP,SMLF,IC,AL009617K02     I6 @T6G_MB_LIB.T6G(SCH_1):PAGE248
 R3264    1      A Q_RES_0402LF-0,5%,1/16W,EMPTY,CS00002JB13    I38 @T6G_MB_LIB.T6G(SCH_1):PAGE248
 R1522    1      A Q_RES_0402LF-0,5%,1/16W,CHIP,CS00002JB13    I44 @T6G_MB_LIB.T6G(SCH_1):PAGE248
 R1180    1      A Q_RES_0402LF-0,5%,1/16W,EMPTY,CS00002JB13    I45 @T6G_MB_LIB.T6G(SCH_1):PAGE248

HP_LVC3_SCM_HSC_PWRGD @T6G_MB_LIB.T6G(SCH_1):HP_LVC3_SCM_HSC_PWRGD
PR4012    2      B Q_RES_0402LF-0,5%,1/16W,CHIP,CS00002JB13    I73 @T6G_MB_LIB.T6G(SCH_1):PAGE350
 R4015    2      B Q_RES_0402LF-100K,1%,1/16W,CHIP,CS41002FB09    I78 @T6G_MB_LIB.T6G(SCH_1):PAGE350
 R6055    1      A Q_RES_0402LF-0,5%,1/16W,CHIP,CS00002JB13    I60 @T6G_MB_LIB.T6G(SCH_1):PAGE80
 R8012    2      B Q_RES_0402LF-0,5%,1/16W,CHIP,CS00002JB13    I89 @T6G_MB_LIB.T6G(SCH_1):PAGE350

HP_LVC3_SCM_HSC_PWRGD_R @T6G_MB_LIB.T6G(SCH_1):HP_LVC3_SCM_HSC_PWRGD_R
 R3836    2      B Q_RES_0402LF-10K,1%,1/16W,CHIP,CS31002FB08    I43 @T6G_MB_LIB.T6G(SCH_1):PAGE350
 R8012    1      A Q_RES_0402LF-0,5%,1/16W,CHIP,CS00002JB13    I89 @T6G_MB_LIB.T6G(SCH_1):PAGE350
 PU299   10     PG RS31312R-RS31312R,SMLF,IC,AL031312000    I95 @T6G_MB_LIB.T6G(SCH_1):PAGE350

HSC_ADDR @T6G_MB_LIB.T6G(SCH_1):HSC_ADDR
PR3930    2      B Q_RES_0402LF-0,5%,1/16W,CHIP,CS00002JB13    I52 @T6G_MB_LIB.T6G(SCH_1):PAGE267
PR3929    1      A Q_RES_0402LF-1K,1%,1/16W,EMPTY,CS21002FB06    I53 @T6G_MB_LIB.T6G(SCH_1):PAGE267
 PU289   23   ADDR MP5990GMA1111Z-MP5990GMA-1111-Z,SMLF,IC,AR0F0TP4023    I58 @T6G_MB_LIB.T6G(SCH_1):PAGE267

HSC_CS @T6G_MB_LIB.T6G(SCH_1):HSC_CS
 PU289   20     CS MP5990GMA1111Z-MP5990GMA-1111-Z,SMLF,IC,AR0F0TP4023    I58 @T6G_MB_LIB.T6G(SCH_1):PAGE267
PR1131    1      A Q_RES_0402LF-2K,0.1%,1/16W,CHIP,CS22002BB07    I65 @T6G_MB_LIB.T6G(SCH_1):PAGE267

HSC_CSOUT @T6G_MB_LIB.T6G(SCH_1):HSC_CSOUT
  PJ38   16     16 SCONN21_9193031121LF-SCONN21_91930-31121LF,SMLF,IOA    I42 @T6G_MB_LIB.T6G(SCH_1):PAGE371
 R6234    1      A Q_RES_0402LF-160K,1%,1/16W,EMPTY,CS41602FB05    I55 @T6G_MB_LIB.T6G(SCH_1):PAGE371
 R6232    1      A Q_RES_0402LF-160K,1%,1/16W,EMPTY,CS41602FB05    I56 @T6G_MB_LIB.T6G(SCH_1):PAGE371
 R6210    1      A Q_RES_0402LF-0,5%,1/16W,CHIP,CS00002JB13    I73 @T6G_MB_LIB.T6G(SCH_1):PAGE371
 R8108    1      A Q_RES_0402LF-160K,1%,1/16W,EMPTY,CS41602FB05    I84 @T6G_MB_LIB.T6G(SCH_1):PAGE371

HSC_CS_1 @T6G_MB_LIB.T6G(SCH_1):HSC_CS_1
PR3914    1      A Q_RES_0402LF-2K,0.1%,1/16W,CHIP,CS22002BB07    I31 @T6G_MB_LIB.T6G(SCH_1):PAGE301
 PU287   23     CS MP5991GLUZ-MP5991GLU-Z,SMLF,IC,AL005991A00    I35 @T6G_MB_LIB.T6G(SCH_1):PAGE301

HSC_CS_2 @T6G_MB_LIB.T6G(SCH_1):HSC_CS_2
PR3915    1      A Q_RES_0402LF-2K,0.1%,1/16W,CHIP,CS22002BB07    I13 @T6G_MB_LIB.T6G(SCH_1):PAGE301
 PU288   23     CS MP5991GLUZ-MP5991GLU-Z,SMLF,IC,AL005991A00    I16 @T6G_MB_LIB.T6G(SCH_1):PAGE301

HSC_CS_3 @T6G_MB_LIB.T6G(SCH_1):HSC_CS_3
PR3986    1      A Q_RES_0402LF-2K,0.1%,1/16W,CHIP,CS22002BB07    I31 @T6G_MB_LIB.T6G(SCH_1):PAGE325
 PU296   23     CS MP5991GLUZ-MP5991GLU-Z,SMLF,IC,AL005991A00    I35 @T6G_MB_LIB.T6G(SCH_1):PAGE325

HSC_CS_4 @T6G_MB_LIB.T6G(SCH_1):HSC_CS_4
PR3987    1      A Q_RES_0402LF-2K,0.1%,1/16W,CHIP,CS22002BB07    I13 @T6G_MB_LIB.T6G(SCH_1):PAGE325
 PU297   23     CS MP5991GLUZ-MP5991GLU-Z,SMLF,IC,AL005991A00    I17 @T6G_MB_LIB.T6G(SCH_1):PAGE325

HSC_D_OC @T6G_MB_LIB.T6G(SCH_1):HSC_D_OC
 R6039    2      B Q_RES_0402LF-0,5%,1/16W,CHIP,CS00002JB13    I20 @T6G_MB_LIB.T6G(SCH_1):PAGE79
 R3934    2      B Q_RES_0402LF-22,1%,1/16W,CHIP,CS02202FB02    I80 @T6G_MB_LIB.T6G(SCH_1):PAGE267
 R3936    2      B Q_RES_0402LF-4.7K,1%,1/16W,CHIP,CS24702FB06    I91 @T6G_MB_LIB.T6G(SCH_1):PAGE267
  U142    6   OUTB LT6700CS61TRPBF-LT6700CS6-1#TRPBF,SMLF,EMPTY,AL006A    I50 @T6G_MB_LIB.T6G(SCH_1):PAGE371
 R6239    2      B Q_RES_0402LF-10K,1%,1/16W,CHIP,CS31002FB08    I70 @T6G_MB_LIB.T6G(SCH_1):PAGE371
 R6238    2      B Q_RES_0402LF-0,5%,1/16W,EMPTY,CS00002JB13    I72 @T6G_MB_LIB.T6G(SCH_1):PAGE371
 R6210    2      B Q_RES_0402LF-0,5%,1/16W,CHIP,CS00002JB13    I73 @T6G_MB_LIB.T6G(SCH_1):PAGE371

HSC_D_OC_1 @T6G_MB_LIB.T6G(SCH_1):HSC_D_OC_1
 PU287    3   D_OC MP5991GLUZ-MP5991GLU-Z,SMLF,IC,AL005991A00    I35 @T6G_MB_LIB.T6G(SCH_1):PAGE301
PR3919    1      A Q_RES_0402LF-0,5%,1/16W,CHIP,CS00002JB13    I50 @T6G_MB_LIB.T6G(SCH_1):PAGE301

HSC_D_OC_2 @T6G_MB_LIB.T6G(SCH_1):HSC_D_OC_2
 PU288    3   D_OC MP5991GLUZ-MP5991GLU-Z,SMLF,IC,AL005991A00    I16 @T6G_MB_LIB.T6G(SCH_1):PAGE301
PR3921    1      A Q_RES_0402LF-0,5%,1/16W,CHIP,CS00002JB13    I40 @T6G_MB_LIB.T6G(SCH_1):PAGE301

HSC_D_OC_3 @T6G_MB_LIB.T6G(SCH_1):HSC_D_OC_3
 PU296    3   D_OC MP5991GLUZ-MP5991GLU-Z,SMLF,IC,AL005991A00    I35 @T6G_MB_LIB.T6G(SCH_1):PAGE325
PR3992    1      A Q_RES_0402LF-0,5%,1/16W,CHIP,CS00002JB13    I50 @T6G_MB_LIB.T6G(SCH_1):PAGE325

HSC_D_OC_4 @T6G_MB_LIB.T6G(SCH_1):HSC_D_OC_4
 PU297    3   D_OC MP5991GLUZ-MP5991GLU-Z,SMLF,IC,AL005991A00    I17 @T6G_MB_LIB.T6G(SCH_1):PAGE325
PR3994    1      A Q_RES_0402LF-0,5%,1/16W,CHIP,CS00002JB13    I40 @T6G_MB_LIB.T6G(SCH_1):PAGE325

HSC_D_OC_R @T6G_MB_LIB.T6G(SCH_1):HSC_D_OC_R
PR3921    2      B Q_RES_0402LF-0,5%,1/16W,CHIP,CS00002JB13    I40 @T6G_MB_LIB.T6G(SCH_1):PAGE301
PR3919    2      B Q_RES_0402LF-0,5%,1/16W,CHIP,CS00002JB13    I50 @T6G_MB_LIB.T6G(SCH_1):PAGE301
PR3994    2      B Q_RES_0402LF-0,5%,1/16W,CHIP,CS00002JB13    I40 @T6G_MB_LIB.T6G(SCH_1):PAGE325
PR3992    2      B Q_RES_0402LF-0,5%,1/16W,CHIP,CS00002JB13    I50 @T6G_MB_LIB.T6G(SCH_1):PAGE325
 PU289   37   D_OC MP5990GMA1111Z-MP5990GMA-1111-Z,SMLF,IC,AR0F0TP4023    I58 @T6G_MB_LIB.T6G(SCH_1):PAGE267
 R3934    1      A Q_RES_0402LF-22,1%,1/16W,CHIP,CS02202FB02    I80 @T6G_MB_LIB.T6G(SCH_1):PAGE267

HSC_D_OC_R2 @T6G_MB_LIB.T6G(SCH_1):HSC_D_OC_R2
 R8110    1      A Q_RES_0402LF-33.2,1%,1/16W,EMPTY,CS03322FB03    I96 @T6G_MB_LIB.T6G(SCH_1):PAGE371
 R8112    2      B Q_RES_0402LF-1M,1%,1/16W,EMPTY,CS51002FB05   I103 @T6G_MB_LIB.T6G(SCH_1):PAGE371
 U8006    4 OUTPUT AP331AWG7-AP331AWG-7,SMLF,EMPTY,AL000331011   I104 @T6G_MB_LIB.T6G(SCH_1):PAGE371

HSC_EN @T6G_MB_LIB.T6G(SCH_1):HSC_EN
 R2586    1      A Q_RES_0402LF-0,5%,1/16W,CHIP,CS00002JB13    I54 @T6G_MB_LIB.T6G(SCH_1):PAGE267
  U290    D      D MOSFET_NCH_GDS_ESD_PROTECTED-2N7002K,SMLF,IC,BAM70A    I11 @T6G_MB_LIB.T6G(SCH_1):PAGE372
 R2585    1      A Q_RES_0402LF-31.6K,1%,1/16W,CHIP,CS33162FB02    I13 @T6G_MB_LIB.T6G(SCH_1):PAGE372
 R4901    2      B Q_RES_0402LF-82K,1%,1/16W,CHIP,CS38202FB01    I19 @T6G_MB_LIB.T6G(SCH_1):PAGE372
 C2179    1      A Q_CAP_C0402-100NF,50V,10%,X7R,CH4106K1B01    I22 @T6G_MB_LIB.T6G(SCH_1):PAGE372
  PJ38   14     14 SCONN21_9193031121LF-SCONN21_91930-31121LF,SMLF,IOA    I42 @T6G_MB_LIB.T6G(SCH_1):PAGE371

HSC_EN_R @T6G_MB_LIB.T6G(SCH_1):HSC_EN_R
 R2586    2      B Q_RES_0402LF-0,5%,1/16W,CHIP,CS00002JB13    I54 @T6G_MB_LIB.T6G(SCH_1):PAGE267
 PU289   26     EN MP5990GMA1111Z-MP5990GMA-1111-Z,SMLF,IC,AR0F0TP4023    I58 @T6G_MB_LIB.T6G(SCH_1):PAGE267

HSC_FAULT @T6G_MB_LIB.T6G(SCH_1):HSC_FAULT
 PU288    5    GOK MP5991GLUZ-MP5991GLU-Z,SMLF,IC,AL005991A00    I16 @T6G_MB_LIB.T6G(SCH_1):PAGE301
 PU287    5    GOK MP5991GLUZ-MP5991GLU-Z,SMLF,IC,AL005991A00    I35 @T6G_MB_LIB.T6G(SCH_1):PAGE301
 PU297    5    GOK MP5991GLUZ-MP5991GLU-Z,SMLF,IC,AL005991A00    I17 @T6G_MB_LIB.T6G(SCH_1):PAGE325
 PU296    5    GOK MP5991GLUZ-MP5991GLU-Z,SMLF,IC,AL005991A00    I35 @T6G_MB_LIB.T6G(SCH_1):PAGE325
 PU289   39    GOK MP5990GMA1111Z-MP5990GMA-1111-Z,SMLF,IC,AR0F0TP4023    I58 @T6G_MB_LIB.T6G(SCH_1):PAGE267
 R2588    1      A Q_RES_0402LF-22,1%,1/16W,CHIP,CS02202FB02    I79 @T6G_MB_LIB.T6G(SCH_1):PAGE267

HSC_FLT_TYPE @T6G_MB_LIB.T6G(SCH_1):HSC_FLT_TYPE
PR3922    2      B Q_RES_0402LF-0,5%,1/16W,CHIP,CS00002JB13    I39 @T6G_MB_LIB.T6G(SCH_1):PAGE301
PR3920    2      B Q_RES_0402LF-0,5%,1/16W,CHIP,CS00002JB13    I49 @T6G_MB_LIB.T6G(SCH_1):PAGE301
PR3995    2      B Q_RES_0402LF-0,5%,1/16W,CHIP,CS00002JB13    I39 @T6G_MB_LIB.T6G(SCH_1):PAGE325
PR3993    2      B Q_RES_0402LF-0,5%,1/16W,CHIP,CS00002JB13    I49 @T6G_MB_LIB.T6G(SCH_1):PAGE325
 PU289   40 FLT_TYPE MP5990GMA1111Z-MP5990GMA-1111-Z,SMLF,IC,AR0F0TP4023    I58 @T6G_MB_LIB.T6G(SCH_1):PAGE267

HSC_FLT_TYPE_1 @T6G_MB_LIB.T6G(SCH_1):HSC_FLT_TYPE_1
 PU287    6 FLT_TYPE MP5991GLUZ-MP5991GLU-Z,SMLF,IC,AL005991A00    I35 @T6G_MB_LIB.T6G(SCH_1):PAGE301
PR3920    1      A Q_RES_0402LF-0,5%,1/16W,CHIP,CS00002JB13    I49 @T6G_MB_LIB.T6G(SCH_1):PAGE301

HSC_FLT_TYPE_2 @T6G_MB_LIB.T6G(SCH_1):HSC_FLT_TYPE_2
 PU288    6 FLT_TYPE MP5991GLUZ-MP5991GLU-Z,SMLF,IC,AL005991A00    I16 @T6G_MB_LIB.T6G(SCH_1):PAGE301
PR3922    1      A Q_RES_0402LF-0,5%,1/16W,CHIP,CS00002JB13    I39 @T6G_MB_LIB.T6G(SCH_1):PAGE301

HSC_FLT_TYPE_3 @T6G_MB_LIB.T6G(SCH_1):HSC_FLT_TYPE_3
 PU296    6 FLT_TYPE MP5991GLUZ-MP5991GLU-Z,SMLF,IC,AL005991A00    I35 @T6G_MB_LIB.T6G(SCH_1):PAGE325
PR3993    1      A Q_RES_0402LF-0,5%,1/16W,CHIP,CS00002JB13    I49 @T6G_MB_LIB.T6G(SCH_1):PAGE325

HSC_FLT_TYPE_4 @T6G_MB_LIB.T6G(SCH_1):HSC_FLT_TYPE_4
 PU297    6 FLT_TYPE MP5991GLUZ-MP5991GLU-Z,SMLF,IC,AL005991A00    I17 @T6G_MB_LIB.T6G(SCH_1):PAGE325
PR3995    1      A Q_RES_0402LF-0,5%,1/16W,CHIP,CS00002JB13    I39 @T6G_MB_LIB.T6G(SCH_1):PAGE325

HSC_IMON @T6G_MB_LIB.T6G(SCH_1):HSC_IMON
PR1101    1      A Q_RES_0402LF-2K,0.1%,1/16W,CHIP,CS22002BB07    I15 @T6G_MB_LIB.T6G(SCH_1):PAGE301
 PU288   22   IMON MP5991GLUZ-MP5991GLU-Z,SMLF,IC,AL005991A00    I16 @T6G_MB_LIB.T6G(SCH_1):PAGE301
PR3918    1      A Q_RES_0402LF-2K,0.1%,1/16W,CHIP,CS22002BB07    I34 @T6G_MB_LIB.T6G(SCH_1):PAGE301
 PU287   22   IMON MP5991GLUZ-MP5991GLU-Z,SMLF,IC,AL005991A00    I35 @T6G_MB_LIB.T6G(SCH_1):PAGE301
PR3991    1      A Q_RES_0402LF-2K,0.1%,1/16W,CHIP,CS22002BB07    I14 @T6G_MB_LIB.T6G(SCH_1):PAGE325
 PU297   22   IMON MP5991GLUZ-MP5991GLU-Z,SMLF,IC,AL005991A00    I17 @T6G_MB_LIB.T6G(SCH_1):PAGE325
PR3990    1      A Q_RES_0402LF-2K,0.1%,1/16W,CHIP,CS22002BB07    I34 @T6G_MB_LIB.T6G(SCH_1):PAGE325
 PU296   22   IMON MP5991GLUZ-MP5991GLU-Z,SMLF,IC,AL005991A00    I35 @T6G_MB_LIB.T6G(SCH_1):PAGE325
 PU289   21   IMON MP5990GMA1111Z-MP5990GMA-1111-Z,SMLF,IC,AR0F0TP4023    I58 @T6G_MB_LIB.T6G(SCH_1):PAGE267
PC2193    1      A Q_CAP_C0402-0.047UF,25V,10%,X7R,CH3474K1B04    I84 @T6G_MB_LIB.T6G(SCH_1):PAGE267
PR1133    1      A Q_RES_0402LF-2K,0.1%,1/16W,CHIP,CS22002BB07    I86 @T6G_MB_LIB.T6G(SCH_1):PAGE267

HSC_MODE @T6G_MB_LIB.T6G(SCH_1):HSC_MODE
 PU289   41   MODE MP5990GMA1111Z-MP5990GMA-1111-Z,SMLF,IC,AR0F0TP4023    I58 @T6G_MB_LIB.T6G(SCH_1):PAGE267
PR3937    1      A Q_RES_0402LF-120K,1%,1/16W,CHIP,CS41202FB05    I85 @T6G_MB_LIB.T6G(SCH_1):PAGE267

HSC_MODE_1 @T6G_MB_LIB.T6G(SCH_1):HSC_MODE_1
PR1134    2      B Q_RES_0402LF-120K,1%,1/16W,CHIP,CS41202FB05    I29 @T6G_MB_LIB.T6G(SCH_1):PAGE301
 PU287    8   MODE MP5991GLUZ-MP5991GLU-Z,SMLF,IC,AL005991A00    I35 @T6G_MB_LIB.T6G(SCH_1):PAGE301

HSC_MODE_2 @T6G_MB_LIB.T6G(SCH_1):HSC_MODE_2
PR3912    2      B Q_RES_0402LF-120K,1%,1/16W,CHIP,CS41202FB05    I11 @T6G_MB_LIB.T6G(SCH_1):PAGE301
 PU288    8   MODE MP5991GLUZ-MP5991GLU-Z,SMLF,IC,AL005991A00    I16 @T6G_MB_LIB.T6G(SCH_1):PAGE301

HSC_MODE_3 @T6G_MB_LIB.T6G(SCH_1):HSC_MODE_3
PR3982    2      B Q_RES_0402LF-120K,1%,1/16W,CHIP,CS41202FB05    I28 @T6G_MB_LIB.T6G(SCH_1):PAGE325
 PU296    8   MODE MP5991GLUZ-MP5991GLU-Z,SMLF,IC,AL005991A00    I35 @T6G_MB_LIB.T6G(SCH_1):PAGE325

HSC_MODE_4 @T6G_MB_LIB.T6G(SCH_1):HSC_MODE_4
PR3984    2      B Q_RES_0402LF-120K,1%,1/16W,CHIP,CS41202FB05    I11 @T6G_MB_LIB.T6G(SCH_1):PAGE325
 PU297    8   MODE MP5991GLUZ-MP5991GLU-Z,SMLF,IC,AL005991A00    I17 @T6G_MB_LIB.T6G(SCH_1):PAGE325

HSC_NC1_1 @T6G_MB_LIB.T6G(SCH_1):HSC_NC1_1
 PU287    7    NC1 MP5991GLUZ-MP5991GLU-Z,SMLF,IC,AL005991A00    I35 @T6G_MB_LIB.T6G(SCH_1):PAGE301

HSC_NC1_2 @T6G_MB_LIB.T6G(SCH_1):HSC_NC1_2
 PU288    7    NC1 MP5991GLUZ-MP5991GLU-Z,SMLF,IC,AL005991A00    I16 @T6G_MB_LIB.T6G(SCH_1):PAGE301

HSC_NC1_3 @T6G_MB_LIB.T6G(SCH_1):HSC_NC1_3
 PU296    7    NC1 MP5991GLUZ-MP5991GLU-Z,SMLF,IC,AL005991A00    I35 @T6G_MB_LIB.T6G(SCH_1):PAGE325

HSC_NC1_4 @T6G_MB_LIB.T6G(SCH_1):HSC_NC1_4
 PU297    7    NC1 MP5991GLUZ-MP5991GLU-Z,SMLF,IC,AL005991A00    I17 @T6G_MB_LIB.T6G(SCH_1):PAGE325

HSC_OCREF @T6G_MB_LIB.T6G(SCH_1):HSC_OCREF
PC2348    1      A Q_CAP_0402-1NF,50V,10%,EMPTY,CH21006KB16    I12 @T6G_MB_LIB.T6G(SCH_1):PAGE301
 PU288   24  OCREF MP5991GLUZ-MP5991GLU-Z,SMLF,IC,AL005991A00    I16 @T6G_MB_LIB.T6G(SCH_1):PAGE301
PC2347    1      A Q_CAP_0402-1NF,50V,10%,EMPTY,CH21006KB16    I30 @T6G_MB_LIB.T6G(SCH_1):PAGE301
 PU287   24  OCREF MP5991GLUZ-MP5991GLU-Z,SMLF,IC,AL005991A00    I35 @T6G_MB_LIB.T6G(SCH_1):PAGE301
PC2349    1      A Q_CAP_0402-1NF,50V,10%,EMPTY,CH21006KB16    I12 @T6G_MB_LIB.T6G(SCH_1):PAGE325
 PU297   24  OCREF MP5991GLUZ-MP5991GLU-Z,SMLF,IC,AL005991A00    I17 @T6G_MB_LIB.T6G(SCH_1):PAGE325
PC2350    1      A Q_CAP_0402-1NF,50V,10%,EMPTY,CH21006KB16    I30 @T6G_MB_LIB.T6G(SCH_1):PAGE325
 PU296   24  OCREF MP5991GLUZ-MP5991GLU-Z,SMLF,IC,AL005991A00    I35 @T6G_MB_LIB.T6G(SCH_1):PAGE325
 PU289   22  OCREF MP5990GMA1111Z-MP5990GMA-1111-Z,SMLF,IC,AR0F0TP4023    I58 @T6G_MB_LIB.T6G(SCH_1):PAGE267

HSC_OC_VOL @T6G_MB_LIB.T6G(SCH_1):HSC_OC_VOL
 R8109    1      A Q_RES_0402LF-10K,1%,1/16W,EMPTY,CS31002FB08    I82 @T6G_MB_LIB.T6G(SCH_1):PAGE371
 R8108    2      B Q_RES_0402LF-160K,1%,1/16W,EMPTY,CS41602FB05    I84 @T6G_MB_LIB.T6G(SCH_1):PAGE371
 C8015    1      A Q_CAP_C0402-100NF,50V,10%,EMPTY,CH4106K1B01    I89 @T6G_MB_LIB.T6G(SCH_1):PAGE371
 R8112    1      A Q_RES_0402LF-1M,1%,1/16W,EMPTY,CS51002FB05   I103 @T6G_MB_LIB.T6G(SCH_1):PAGE371
 U8006    3    IN+ AP331AWG7-AP331AWG-7,SMLF,EMPTY,AL000331011   I104 @T6G_MB_LIB.T6G(SCH_1):PAGE371

HSC_ON @T6G_MB_LIB.T6G(SCH_1):HSC_ON
PC2183    1      A Q_CAP_0402-220PF,50V,10%,EMPTY,TMP_QCH12206KB14     I2 @T6G_MB_LIB.T6G(SCH_1):PAGE301
 PU288    4     ON MP5991GLUZ-MP5991GLU-Z,SMLF,IC,AL005991A00    I16 @T6G_MB_LIB.T6G(SCH_1):PAGE301
PC2182    1      A Q_CAP_0402-220PF,50V,10%,X7R,TMP_QCH12206KB14    I24 @T6G_MB_LIB.T6G(SCH_1):PAGE301
 PU287    4     ON MP5991GLUZ-MP5991GLU-Z,SMLF,IC,AL005991A00    I35 @T6G_MB_LIB.T6G(SCH_1):PAGE301
PC2225    1      A Q_CAP_0402-220PF,50V,10%,EMPTY,TMP_QCH12206KB14     I2 @T6G_MB_LIB.T6G(SCH_1):PAGE325
 PU297    4     ON MP5991GLUZ-MP5991GLU-Z,SMLF,IC,AL005991A00    I17 @T6G_MB_LIB.T6G(SCH_1):PAGE325
PC2224    1      A Q_CAP_0402-220PF,50V,10%,EMPTY,TMP_QCH12206KB14    I24 @T6G_MB_LIB.T6G(SCH_1):PAGE325
 PU296    4     ON MP5991GLUZ-MP5991GLU-Z,SMLF,IC,AL005991A00    I35 @T6G_MB_LIB.T6G(SCH_1):PAGE325
PR3928    1      A Q_RES_0402LF-0,5%,1/16W,CHIP,CS00002JB13    I51 @T6G_MB_LIB.T6G(SCH_1):PAGE267

HSC_ON_R @T6G_MB_LIB.T6G(SCH_1):HSC_ON_R
PR3928    2      B Q_RES_0402LF-0,5%,1/16W,CHIP,CS00002JB13    I51 @T6G_MB_LIB.T6G(SCH_1):PAGE267
 PU289   38     ON MP5990GMA1111Z-MP5990GMA-1111-Z,SMLF,IC,AR0F0TP4023    I58 @T6G_MB_LIB.T6G(SCH_1):PAGE267

HSC_SCREF @T6G_MB_LIB.T6G(SCH_1):HSC_SCREF
PR3917    1      A Q_RES_0402LF-0,5%,1/16W,CHIP,CS00002JB13    I17 @T6G_MB_LIB.T6G(SCH_1):PAGE301
PR3916    1      A Q_RES_0402LF-0,5%,1/16W,CHIP,CS00002JB13    I33 @T6G_MB_LIB.T6G(SCH_1):PAGE301
PR3989    1      A Q_RES_0402LF-0,5%,1/16W,CHIP,CS00002JB13    I16 @T6G_MB_LIB.T6G(SCH_1):PAGE325
PR3988    1      A Q_RES_0402LF-0,5%,1/16W,CHIP,CS00002JB13    I33 @T6G_MB_LIB.T6G(SCH_1):PAGE325
 PU289   25 SCREF_OCWREF MP5990GMA1111Z-MP5990GMA-1111-Z,SMLF,IC,AR0F0TP4023    I58 @T6G_MB_LIB.T6G(SCH_1):PAGE267

HSC_SCREF_1 @T6G_MB_LIB.T6G(SCH_1):HSC_SCREF_1
PR3916    2      B Q_RES_0402LF-0,5%,1/16W,CHIP,CS00002JB13    I33 @T6G_MB_LIB.T6G(SCH_1):PAGE301
 PU287   17 SCREF_OCWREF MP5991GLUZ-MP5991GLU-Z,SMLF,IC,AL005991A00    I35 @T6G_MB_LIB.T6G(SCH_1):PAGE301

HSC_SCREF_2 @T6G_MB_LIB.T6G(SCH_1):HSC_SCREF_2
 PU288   17 SCREF_OCWREF MP5991GLUZ-MP5991GLU-Z,SMLF,IC,AL005991A00    I16 @T6G_MB_LIB.T6G(SCH_1):PAGE301
PR3917    2      B Q_RES_0402LF-0,5%,1/16W,CHIP,CS00002JB13    I17 @T6G_MB_LIB.T6G(SCH_1):PAGE301

HSC_SCREF_3 @T6G_MB_LIB.T6G(SCH_1):HSC_SCREF_3
PR3988    2      B Q_RES_0402LF-0,5%,1/16W,CHIP,CS00002JB13    I33 @T6G_MB_LIB.T6G(SCH_1):PAGE325
 PU296   17 SCREF_OCWREF MP5991GLUZ-MP5991GLU-Z,SMLF,IC,AL005991A00    I35 @T6G_MB_LIB.T6G(SCH_1):PAGE325

HSC_SCREF_4 @T6G_MB_LIB.T6G(SCH_1):HSC_SCREF_4
PR3989    2      B Q_RES_0402LF-0,5%,1/16W,CHIP,CS00002JB13    I16 @T6G_MB_LIB.T6G(SCH_1):PAGE325
 PU297   17 SCREF_OCWREF MP5991GLUZ-MP5991GLU-Z,SMLF,IC,AL005991A00    I17 @T6G_MB_LIB.T6G(SCH_1):PAGE325

HSC_SS @T6G_MB_LIB.T6G(SCH_1):HSC_SS
 PU288   19     SS MP5991GLUZ-MP5991GLU-Z,SMLF,IC,AL005991A00    I16 @T6G_MB_LIB.T6G(SCH_1):PAGE301
 PU287   19     SS MP5991GLUZ-MP5991GLU-Z,SMLF,IC,AL005991A00    I35 @T6G_MB_LIB.T6G(SCH_1):PAGE301
PC2185    1      A Q_CAP_0402-0.068UF,16V,10%,X7R,CH3683K1B09    I38 @T6G_MB_LIB.T6G(SCH_1):PAGE301
PC2184    1      A Q_CAP_0402-0.068UF,16V,10%,X7R,CH3683K1B09    I47 @T6G_MB_LIB.T6G(SCH_1):PAGE301
 PU297   19     SS MP5991GLUZ-MP5991GLU-Z,SMLF,IC,AL005991A00    I17 @T6G_MB_LIB.T6G(SCH_1):PAGE325
 PU296   19     SS MP5991GLUZ-MP5991GLU-Z,SMLF,IC,AL005991A00    I35 @T6G_MB_LIB.T6G(SCH_1):PAGE325
PC2227    1      A Q_CAP_0402-0.068UF,16V,10%,X7R,CH3683K1B09    I38 @T6G_MB_LIB.T6G(SCH_1):PAGE325
PC2226    1      A Q_CAP_0402-0.068UF,16V,10%,X7R,CH3683K1B09    I47 @T6G_MB_LIB.T6G(SCH_1):PAGE325
 PU289   16     SS MP5990GMA1111Z-MP5990GMA-1111-Z,SMLF,IC,AR0F0TP4023    I58 @T6G_MB_LIB.T6G(SCH_1):PAGE267
PC2191    1      A Q_CAP_0402-0.068UF,16V,10%,X7R,CH3683K1B09    I75 @T6G_MB_LIB.T6G(SCH_1):PAGE267

HSC_TYPE_ADC @T6G_MB_LIB.T6G(SCH_1):HSC_TYPE_ADC
  PJ38   17     17 SCONN21_9193031121LF-SCONN21_91930-31121LF,SMLF,IOA    I42 @T6G_MB_LIB.T6G(SCH_1):PAGE371
 C6086    1      A Q_CAP_0402-0.1UF,25V,10%,X7R,CH4104K1B00    I11 @T6G_MB_LIB.T6G(SCH_1):PAGE271
 U6005   11   VBUS ISL28022FRZT-ISL28022FRZ-T,SMLF,IC,AL028022003    I28 @T6G_MB_LIB.T6G(SCH_1):PAGE271

HSC_TYPE_ADC_A0 @T6G_MB_LIB.T6G(SCH_1):HSC_TYPE_ADC_A0
 R6251    2      B Q_RES_0402LF-4.7K,1%,1/16W,EMPTY,CS24702FB06    I14 @T6G_MB_LIB.T6G(SCH_1):PAGE271
 U6005    2     A0 ISL28022FRZT-ISL28022FRZ-T,SMLF,IC,AL028022003    I28 @T6G_MB_LIB.T6G(SCH_1):PAGE271
 R6254    1      A Q_RES_0402LF-0,5%,1/16W,CHIP,CS00002JB13    I29 @T6G_MB_LIB.T6G(SCH_1):PAGE271

HSC_TYPE_ADC_A1 @T6G_MB_LIB.T6G(SCH_1):HSC_TYPE_ADC_A1
 U6005    1     A1 ISL28022FRZT-ISL28022FRZ-T,SMLF,IC,AL028022003    I28 @T6G_MB_LIB.T6G(SCH_1):PAGE271
 R6250    2      B Q_RES_0402LF-4.7K,1%,1/16W,CHIP,CS24702FB06    I30 @T6G_MB_LIB.T6G(SCH_1):PAGE271

HSC_TYPE_ADC_ALERT @T6G_MB_LIB.T6G(SCH_1):HSC_TYPE_ADC_ALERT
 R6247    2      B Q_RES_0402LF-4.7K,1%,1/16W,CHIP,CS24702FB06    I25 @T6G_MB_LIB.T6G(SCH_1):PAGE271
 U6005    3 EXT_CLK||INT ISL28022FRZT-ISL28022FRZ-T,SMLF,IC,AL028022003    I28 @T6G_MB_LIB.T6G(SCH_1):PAGE271

HSC_VDD @T6G_MB_LIB.T6G(SCH_1):HSC_VDD
PR3911    2      B Q_RES_0402LF-0,5%,1/16W,CHIP,CS00002JB13     I5 @T6G_MB_LIB.T6G(SCH_1):PAGE301
PR3910    2      B Q_RES_0402LF-0,5%,1/16W,CHIP,CS00002JB13    I21 @T6G_MB_LIB.T6G(SCH_1):PAGE301
PR3981    2      B Q_RES_0402LF-0,5%,1/16W,CHIP,CS00002JB13     I6 @T6G_MB_LIB.T6G(SCH_1):PAGE325
PR3980    2      B Q_RES_0402LF-0,5%,1/16W,CHIP,CS00002JB13    I21 @T6G_MB_LIB.T6G(SCH_1):PAGE325
PR2149    2      B Q_RES_0402LF-0,5%,1/16W,CHIP,CS00002JB13    I39 @T6G_MB_LIB.T6G(SCH_1):PAGE267
PR2106    1      A Q_RES_0402LF-10K,1%,1/16W,CHIP,CS31002FB08    I56 @T6G_MB_LIB.T6G(SCH_1):PAGE267
 R3936    1      A Q_RES_0402LF-4.7K,1%,1/16W,CHIP,CS24702FB06    I91 @T6G_MB_LIB.T6G(SCH_1):PAGE267
 R2587    2      B Q_RES_0402LF-1K,1%,1/16W,CHIP,CS21002FB06    I99 @T6G_MB_LIB.T6G(SCH_1):PAGE267

HSC_VDD18 @T6G_MB_LIB.T6G(SCH_1):HSC_VDD18
PC2103    1      A Q_CAP_C0402-1UF,25V,10%,X6S,CH5104KEB02    I50 @T6G_MB_LIB.T6G(SCH_1):PAGE267
PR3929    2      B Q_RES_0402LF-1K,1%,1/16W,EMPTY,CS21002FB06    I53 @T6G_MB_LIB.T6G(SCH_1):PAGE267
 PU289   19  VDD18 MP5990GMA1111Z-MP5990GMA-1111-Z,SMLF,IC,AR0F0TP4023    I58 @T6G_MB_LIB.T6G(SCH_1):PAGE267

HSC_VDD_R @T6G_MB_LIB.T6G(SCH_1):HSC_VDD_R
PC2186    1      A Q_CAP_C0402-1UF,25V,10%,X6S,CH5104KEB02    I27 @T6G_MB_LIB.T6G(SCH_1):PAGE267
PC2187    1      A Q_CAP_C0402-1UF,25V,10%,X6S,CH5104KEB02    I30 @T6G_MB_LIB.T6G(SCH_1):PAGE267
PR2149    1      A Q_RES_0402LF-0,5%,1/16W,CHIP,CS00002JB13    I39 @T6G_MB_LIB.T6G(SCH_1):PAGE267
 PU289   17 VDD33_1 MP5990GMA1111Z-MP5990GMA-1111-Z,SMLF,IC,AR0F0TP4023    I58 @T6G_MB_LIB.T6G(SCH_1):PAGE267
 PU289   45 VDD33_2 MP5990GMA1111Z-MP5990GMA-1111-Z,SMLF,IC,AR0F0TP4023    I58 @T6G_MB_LIB.T6G(SCH_1):PAGE267

HSC_VDD_R_1 @T6G_MB_LIB.T6G(SCH_1):HSC_VDD_R_1
PC1525    1      A Q_CAP_C0402-1UF,25V,10%,X6S,CH5104KEB02    I20 @T6G_MB_LIB.T6G(SCH_1):PAGE301
PR3910    1      A Q_RES_0402LF-0,5%,1/16W,CHIP,CS00002JB13    I21 @T6G_MB_LIB.T6G(SCH_1):PAGE301
 PU287   21  VDD33 MP5991GLUZ-MP5991GLU-Z,SMLF,IC,AL005991A00    I35 @T6G_MB_LIB.T6G(SCH_1):PAGE301

HSC_VDD_R_2 @T6G_MB_LIB.T6G(SCH_1):HSC_VDD_R_2
PC2181    1      A Q_CAP_C0402-1UF,25V,10%,X6S,CH5104KEB02     I4 @T6G_MB_LIB.T6G(SCH_1):PAGE301
PR3911    1      A Q_RES_0402LF-0,5%,1/16W,CHIP,CS00002JB13     I5 @T6G_MB_LIB.T6G(SCH_1):PAGE301
 PU288   21  VDD33 MP5991GLUZ-MP5991GLU-Z,SMLF,IC,AL005991A00    I16 @T6G_MB_LIB.T6G(SCH_1):PAGE301

HSC_VDD_R_3 @T6G_MB_LIB.T6G(SCH_1):HSC_VDD_R_3
PC3272    1      A Q_CAP_C0402-1UF,25V,10%,X6S,CH5104KEB02    I20 @T6G_MB_LIB.T6G(SCH_1):PAGE325
PR3980    1      A Q_RES_0402LF-0,5%,1/16W,CHIP,CS00002JB13    I21 @T6G_MB_LIB.T6G(SCH_1):PAGE325
 PU296   21  VDD33 MP5991GLUZ-MP5991GLU-Z,SMLF,IC,AL005991A00    I35 @T6G_MB_LIB.T6G(SCH_1):PAGE325

HSC_VDD_R_4 @T6G_MB_LIB.T6G(SCH_1):HSC_VDD_R_4
PC2223    1      A Q_CAP_C0402-1UF,25V,10%,X6S,CH5104KEB02     I4 @T6G_MB_LIB.T6G(SCH_1):PAGE325
PR3981    1      A Q_RES_0402LF-0,5%,1/16W,CHIP,CS00002JB13     I6 @T6G_MB_LIB.T6G(SCH_1):PAGE325
 PU297   21  VDD33 MP5991GLUZ-MP5991GLU-Z,SMLF,IC,AL005991A00    I17 @T6G_MB_LIB.T6G(SCH_1):PAGE325

HSC_VIN_UVW_N @T6G_MB_LIB.T6G(SCH_1):HSC_VIN_UVW_N
PR2106    2      B Q_RES_0402LF-10K,1%,1/16W,CHIP,CS31002FB08    I56 @T6G_MB_LIB.T6G(SCH_1):PAGE267
 PU289   14 VIN_UVW# MP5990GMA1111Z-MP5990GMA-1111-Z,SMLF,IC,AR0F0TP4023    I58 @T6G_MB_LIB.T6G(SCH_1):PAGE267

HSC_VOSEN @T6G_MB_LIB.T6G(SCH_1):HSC_VOSEN
 PU289   24  VOSEN MP5990GMA1111Z-MP5990GMA-1111-Z,SMLF,IC,AR0F0TP4023    I58 @T6G_MB_LIB.T6G(SCH_1):PAGE267
PR3932    1      A Q_RES_0402LF-4.99K,0.1%,1/16W,CHIP,CS24992BB04    I70 @T6G_MB_LIB.T6G(SCH_1):PAGE267
PR3931    2      B Q_RES_0402LF-75K,0.1%,1/16W,CHIP,CS37502BB01    I71 @T6G_MB_LIB.T6G(SCH_1):PAGE267
PC2190    1      A Q_CAP_C0402-0.01UF,50V,10%,X7R,CH31006KB18    I72 @T6G_MB_LIB.T6G(SCH_1):PAGE267

HSC_VSENSE @T6G_MB_LIB.T6G(SCH_1):HSC_VSENSE
PR3927    1      A Q_RES_0402LF-4.99K,0.1%,1/16W,CHIP,CS24992BB04    I47 @T6G_MB_LIB.T6G(SCH_1):PAGE267
PR3926    2      B Q_RES_0402LF-75K,0.1%,1/16W,CHIP,CS37502BB01    I48 @T6G_MB_LIB.T6G(SCH_1):PAGE267
 PU289    9 VINSEN MP5990GMA1111Z-MP5990GMA-1111-Z,SMLF,IC,AR0F0TP4023    I58 @T6G_MB_LIB.T6G(SCH_1):PAGE267
PC2189    1      A Q_CAP_C0402-0.01UF,50V,10%,X7R,CH31006KB18    I59 @T6G_MB_LIB.T6G(SCH_1):PAGE267

HSC_VTEMP @T6G_MB_LIB.T6G(SCH_1):HSC_VTEMP
 PU288   18  VTEMP MP5991GLUZ-MP5991GLU-Z,SMLF,IC,AL005991A00    I16 @T6G_MB_LIB.T6G(SCH_1):PAGE301
 PU287   18  VTEMP MP5991GLUZ-MP5991GLU-Z,SMLF,IC,AL005991A00    I35 @T6G_MB_LIB.T6G(SCH_1):PAGE301
 PU297   18  VTEMP MP5991GLUZ-MP5991GLU-Z,SMLF,IC,AL005991A00    I17 @T6G_MB_LIB.T6G(SCH_1):PAGE325
 PU296   18  VTEMP MP5991GLUZ-MP5991GLU-Z,SMLF,IC,AL005991A00    I35 @T6G_MB_LIB.T6G(SCH_1):PAGE325
 PU289   15  VTEMP MP5990GMA1111Z-MP5990GMA-1111-Z,SMLF,IC,AR0F0TP4023    I58 @T6G_MB_LIB.T6G(SCH_1):PAGE267
PC2192    1      A Q_CAP_C0402-0.001UF,50V,10%,X7R,CH30106KB19    I78 @T6G_MB_LIB.T6G(SCH_1):PAGE267
PR3935    1      A Q_RES_0402LF-10K,1%,1/16W,CHIP,CS31002FB08    I81 @T6G_MB_LIB.T6G(SCH_1):PAGE267

I3C_0_SPD_DDRAF_CPU0_R_SCL @T6G_MB_LIB.T6G(SCH_1):I3C_0_SPD_DDRAF_CPU0_R_SCL
  R426    2      B Q_RES_0402LF-0,5%,1/16W,CHIP,CS00002JB13    I99 @T6G_MB_LIB.T6G(SCH_1):PAGE136
 R2310    1      A Q_RES_0402LF-0,5%,1/16W,EMPTY,CS00002JB13   I123 @T6G_MB_LIB.T6G(SCH_1):PAGE136
  R425    2      B Q_RES_0402LF-1K,1%,1/16W,EMPTY,CS21002FB06    I25 @T6G_MB_LIB.T6G(SCH_1):PAGE28
   U25  A71 I3C0_SCL||I2C0_SCL||SPD0_SCL||SMBUS0_SCL||AGPIO145 GENOA_SP5-SOCKET6096_13568-001,SMLF,IO,DGA^6000030   I188 @T6G_MB_LIB.T6G(SCH_1):PAGE28

I3C_0_SPD_DDRAF_CPU0_R_SDA @T6G_MB_LIB.T6G(SCH_1):I3C_0_SPD_DDRAF_CPU0_R_SDA
  R427    2      B Q_RES_0402LF-0,5%,1/16W,CHIP,CS00002JB13   I100 @T6G_MB_LIB.T6G(SCH_1):PAGE136
 R2311    1      A Q_RES_0402LF-0,5%,1/16W,EMPTY,CS00002JB13   I124 @T6G_MB_LIB.T6G(SCH_1):PAGE136
  R423    2      B Q_RES_0402LF-1K,1%,1/16W,EMPTY,CS21002FB06    I24 @T6G_MB_LIB.T6G(SCH_1):PAGE28
   U25  B71 I3C0_SDA||I2C0_SDA||SPD0_SDA||SMBUS0_SDA||AGPIO146 GENOA_SP5-SOCKET6096_13568-001,SMLF,IO,DGA^6000030   I188 @T6G_MB_LIB.T6G(SCH_1):PAGE28

I3C_0_SPD_DDRAF_CPU0_SCL @T6G_MB_LIB.T6G(SCH_1):I3C_0_SPD_DDRAF_CPU0_SCL
  U105    1    1D+ PI3CSW12ZUAEX-PI3CSW12ZUAEX,SMLF,IC,AL3CSW12000    I47 @T6G_MB_LIB.T6G(SCH_1):PAGE136
  R426    1      A Q_RES_0402LF-0,5%,1/16W,CHIP,CS00002JB13    I99 @T6G_MB_LIB.T6G(SCH_1):PAGE136

I3C_0_SPD_DDRAF_CPU0_SDA @T6G_MB_LIB.T6G(SCH_1):I3C_0_SPD_DDRAF_CPU0_SDA
  U105    2    1D- PI3CSW12ZUAEX-PI3CSW12ZUAEX,SMLF,IC,AL3CSW12000    I47 @T6G_MB_LIB.T6G(SCH_1):PAGE136
  R427    1      A Q_RES_0402LF-0,5%,1/16W,CHIP,CS00002JB13   I100 @T6G_MB_LIB.T6G(SCH_1):PAGE136

I3C_0_SPD_DDRAF_CPU1_R_SCL @T6G_MB_LIB.T6G(SCH_1):I3C_0_SPD_DDRAF_CPU1_R_SCL
   U26  A71 I3C0_SCL||I2C0_SCL||SPD0_SCL||SMBUS0_SCL||AGPIO145 GENOA_SP5-SOCKET6096_13568-001,SMLF,IO,DGA^6000030   I182 @T6G_MB_LIB.T6G(SCH_1):PAGE55
  R564    2      B Q_RES_0402LF-0,5%,1/16W,CHIP,CS00002JB13   I108 @T6G_MB_LIB.T6G(SCH_1):PAGE136
  R988    1      A Q_RES_0402LF-0,5%,1/16W,EMPTY,CS00002JB13   I138 @T6G_MB_LIB.T6G(SCH_1):PAGE136
  R563    2      B Q_RES_0402LF-1K,1%,1/16W,EMPTY,CS21002FB06   I368 @T6G_MB_LIB.T6G(SCH_1):PAGE55

I3C_0_SPD_DDRAF_CPU1_R_SDA @T6G_MB_LIB.T6G(SCH_1):I3C_0_SPD_DDRAF_CPU1_R_SDA
   U26  B71 I3C0_SDA||I2C0_SDA||SPD0_SDA||SMBUS0_SDA||AGPIO146 GENOA_SP5-SOCKET6096_13568-001,SMLF,IO,DGA^6000030   I182 @T6G_MB_LIB.T6G(SCH_1):PAGE55
  R565    2      B Q_RES_0402LF-0,5%,1/16W,CHIP,CS00002JB13   I107 @T6G_MB_LIB.T6G(SCH_1):PAGE136
  R989    1      A Q_RES_0402LF-0,5%,1/16W,EMPTY,CS00002JB13   I137 @T6G_MB_LIB.T6G(SCH_1):PAGE136
  R543    2      B Q_RES_0402LF-1K,1%,1/16W,EMPTY,CS21002FB06   I367 @T6G_MB_LIB.T6G(SCH_1):PAGE55

I3C_0_SPD_DDRAF_CPU1_SCL @T6G_MB_LIB.T6G(SCH_1):I3C_0_SPD_DDRAF_CPU1_SCL
  U107    1    1D+ PI3CSW12ZUAEX-PI3CSW12ZUAEX,SMLF,IC,AL3CSW12000    I63 @T6G_MB_LIB.T6G(SCH_1):PAGE136
  R564    1      A Q_RES_0402LF-0,5%,1/16W,CHIP,CS00002JB13   I108 @T6G_MB_LIB.T6G(SCH_1):PAGE136

I3C_0_SPD_DDRAF_CPU1_SDA @T6G_MB_LIB.T6G(SCH_1):I3C_0_SPD_DDRAF_CPU1_SDA
  U107    2    1D- PI3CSW12ZUAEX-PI3CSW12ZUAEX,SMLF,IC,AL3CSW12000    I63 @T6G_MB_LIB.T6G(SCH_1):PAGE136
  R565    1      A Q_RES_0402LF-0,5%,1/16W,CHIP,CS00002JB13   I107 @T6G_MB_LIB.T6G(SCH_1):PAGE136

I3C_1_SPD_DDRGL_CPU0_R_SCL @T6G_MB_LIB.T6G(SCH_1):I3C_1_SPD_DDRGL_CPU0_R_SCL
  R428    2      B Q_RES_0402LF-0,5%,1/16W,CHIP,CS00002JB13   I103 @T6G_MB_LIB.T6G(SCH_1):PAGE136
  R986    1      A Q_RES_0402LF-0,5%,1/16W,EMPTY,CS00002JB13   I135 @T6G_MB_LIB.T6G(SCH_1):PAGE136
  R421    2      B Q_RES_0402LF-1K,1%,1/16W,EMPTY,CS21002FB06    I23 @T6G_MB_LIB.T6G(SCH_1):PAGE28
   U25   C7 I3C1_SCL||I2C1_SCL||SPD1_SCL||AGPIO147 GENOA_SP5-SOCKET6096_13568-001,SMLF,IO,DGA^6000030   I188 @T6G_MB_LIB.T6G(SCH_1):PAGE28

I3C_1_SPD_DDRGL_CPU0_R_SDA @T6G_MB_LIB.T6G(SCH_1):I3C_1_SPD_DDRGL_CPU0_R_SDA
  R429    2      B Q_RES_0402LF-0,5%,1/16W,CHIP,CS00002JB13   I104 @T6G_MB_LIB.T6G(SCH_1):PAGE136
  R987    1      A Q_RES_0402LF-0,5%,1/16W,EMPTY,CS00002JB13   I136 @T6G_MB_LIB.T6G(SCH_1):PAGE136
  R420    2      B Q_RES_0402LF-1K,1%,1/16W,EMPTY,CS21002FB06    I22 @T6G_MB_LIB.T6G(SCH_1):PAGE28
   U25   A5 I3C1_SDA||I2C1_SDA||SPD1_SDA||AGPIO148 GENOA_SP5-SOCKET6096_13568-001,SMLF,IO,DGA^6000030   I188 @T6G_MB_LIB.T6G(SCH_1):PAGE28

I3C_1_SPD_DDRGL_CPU0_SCL @T6G_MB_LIB.T6G(SCH_1):I3C_1_SPD_DDRGL_CPU0_SCL
  U106    1    1D+ PI3CSW12ZUAEX-PI3CSW12ZUAEX,SMLF,IC,AL3CSW12000    I54 @T6G_MB_LIB.T6G(SCH_1):PAGE136
  R428    1      A Q_RES_0402LF-0,5%,1/16W,CHIP,CS00002JB13   I103 @T6G_MB_LIB.T6G(SCH_1):PAGE136

I3C_1_SPD_DDRGL_CPU0_SDA @T6G_MB_LIB.T6G(SCH_1):I3C_1_SPD_DDRGL_CPU0_SDA
  U106    2    1D- PI3CSW12ZUAEX-PI3CSW12ZUAEX,SMLF,IC,AL3CSW12000    I54 @T6G_MB_LIB.T6G(SCH_1):PAGE136
  R429    1      A Q_RES_0402LF-0,5%,1/16W,CHIP,CS00002JB13   I104 @T6G_MB_LIB.T6G(SCH_1):PAGE136

I3C_1_SPD_DDRGL_CPU1_R_SCL @T6G_MB_LIB.T6G(SCH_1):I3C_1_SPD_DDRGL_CPU1_R_SCL
   U26   C7 I3C1_SCL||I2C1_SCL||SPD1_SCL||AGPIO147 GENOA_SP5-SOCKET6096_13568-001,SMLF,IO,DGA^6000030   I182 @T6G_MB_LIB.T6G(SCH_1):PAGE55
  R566    2      B Q_RES_0402LF-0,5%,1/16W,CHIP,CS00002JB13   I111 @T6G_MB_LIB.T6G(SCH_1):PAGE136
  R990    1      A Q_RES_0402LF-0,5%,1/16W,EMPTY,CS00002JB13   I142 @T6G_MB_LIB.T6G(SCH_1):PAGE136
  R542    2      B Q_RES_0402LF-1K,1%,1/16W,EMPTY,CS21002FB06   I366 @T6G_MB_LIB.T6G(SCH_1):PAGE55

I3C_1_SPD_DDRGL_CPU1_R_SDA @T6G_MB_LIB.T6G(SCH_1):I3C_1_SPD_DDRGL_CPU1_R_SDA
   U26   A5 I3C1_SDA||I2C1_SDA||SPD1_SDA||AGPIO148 GENOA_SP5-SOCKET6096_13568-001,SMLF,IO,DGA^6000030   I182 @T6G_MB_LIB.T6G(SCH_1):PAGE55
  R567    2      B Q_RES_0402LF-0,5%,1/16W,CHIP,CS00002JB13   I112 @T6G_MB_LIB.T6G(SCH_1):PAGE136
  R991    1      A Q_RES_0402LF-0,5%,1/16W,EMPTY,CS00002JB13   I141 @T6G_MB_LIB.T6G(SCH_1):PAGE136
  R541    2      B Q_RES_0402LF-1K,1%,1/16W,EMPTY,CS21002FB06   I365 @T6G_MB_LIB.T6G(SCH_1):PAGE55

I3C_1_SPD_DDRGL_CPU1_SCL @T6G_MB_LIB.T6G(SCH_1):I3C_1_SPD_DDRGL_CPU1_SCL
  U108    1    1D+ PI3CSW12ZUAEX-PI3CSW12ZUAEX,SMLF,IC,AL3CSW12000    I68 @T6G_MB_LIB.T6G(SCH_1):PAGE136
  R566    1      A Q_RES_0402LF-0,5%,1/16W,CHIP,CS00002JB13   I111 @T6G_MB_LIB.T6G(SCH_1):PAGE136

I3C_1_SPD_DDRGL_CPU1_SDA @T6G_MB_LIB.T6G(SCH_1):I3C_1_SPD_DDRGL_CPU1_SDA
  U108    2    1D- PI3CSW12ZUAEX-PI3CSW12ZUAEX,SMLF,IC,AL3CSW12000    I68 @T6G_MB_LIB.T6G(SCH_1):PAGE136
  R567    1      A Q_RES_0402LF-0,5%,1/16W,CHIP,CS00002JB13   I112 @T6G_MB_LIB.T6G(SCH_1):PAGE136

I3C_BMC_SWB_BUF_R_SCL @T6G_MB_LIB.T6G(SCH_1):I3C_BMC_SWB_BUF_R_SCL
 R2725    2      B Q_RES_0402LF-0,5%,1/16W,CHIP,CS00002JB13    I28 @T6G_MB_LIB.T6G(SCH_1):PAGE249
  U176    2 SCL_OUT LTC4307CMS8-LTC4307CMS8,SMLF,EMPTY,AL004307000    I30 @T6G_MB_LIB.T6G(SCH_1):PAGE249
 R2670    2      B Q_RES_0402LF-4.7K,5%,1/16W,EMPTY,CS24702JB10    I63 @T6G_MB_LIB.T6G(SCH_1):PAGE249
 R2675    1      A Q_RES_0402LF-33.2,1%,1/16W,CHIP,CS03322FB03    I69 @T6G_MB_LIB.T6G(SCH_1):PAGE249

I3C_BMC_SWB_BUF_R_SDA @T6G_MB_LIB.T6G(SCH_1):I3C_BMC_SWB_BUF_R_SDA
 R2706    2      B Q_RES_0402LF-0,5%,1/16W,CHIP,CS00002JB13    I27 @T6G_MB_LIB.T6G(SCH_1):PAGE249
  U176    7 SDA_OUT LTC4307CMS8-LTC4307CMS8,SMLF,EMPTY,AL004307000    I30 @T6G_MB_LIB.T6G(SCH_1):PAGE249
 R2668    2      B Q_RES_0402LF-4.7K,5%,1/16W,EMPTY,CS24702JB10    I62 @T6G_MB_LIB.T6G(SCH_1):PAGE249
 R2674    1      A Q_RES_0402LF-27,5%,1/16W,CHIP,CS02702JB02    I86 @T6G_MB_LIB.T6G(SCH_1):PAGE249

I3C_BMC_SWB_BUF_SCL @T6G_MB_LIB.T6G(SCH_1):I3C_BMC_SWB_BUF_SCL
 R2675    2      B Q_RES_0402LF-33.2,1%,1/16W,CHIP,CS03322FB03    I69 @T6G_MB_LIB.T6G(SCH_1):PAGE249
  J106   N4     N4 CONN112_10137002101LF-CONN112_10137002-101LF,THLF,A    I74 @T6G_MB_LIB.T6G(SCH_1):PAGE327

I3C_BMC_SWB_BUF_SDA @T6G_MB_LIB.T6G(SCH_1):I3C_BMC_SWB_BUF_SDA
  J106   N2     N2 CONN112_10137002101LF-CONN112_10137002-101LF,THLF,A    I74 @T6G_MB_LIB.T6G(SCH_1):PAGE327
 R2674    2      B Q_RES_0402LF-27,5%,1/16W,CHIP,CS02702JB02    I86 @T6G_MB_LIB.T6G(SCH_1):PAGE249

I3C_BMC_SWB_R_SCL @T6G_MB_LIB.T6G(SCH_1):I3C_BMC_SWB_R_SCL
 R3112    2      B Q_RES_0402LF-33.2,1%,1/16W,CHIP,CS03322FB03    I25 @T6G_MB_LIB.T6G(SCH_1):PAGE249
 R2725    1      A Q_RES_0402LF-0,5%,1/16W,CHIP,CS00002JB13    I28 @T6G_MB_LIB.T6G(SCH_1):PAGE249
  U176    3 SCL_IN LTC4307CMS8-LTC4307CMS8,SMLF,EMPTY,AL004307000    I30 @T6G_MB_LIB.T6G(SCH_1):PAGE249

I3C_BMC_SWB_R_SDA @T6G_MB_LIB.T6G(SCH_1):I3C_BMC_SWB_R_SDA
 R2706    1      A Q_RES_0402LF-0,5%,1/16W,CHIP,CS00002JB13    I27 @T6G_MB_LIB.T6G(SCH_1):PAGE249
  U176    6 SDA_IN LTC4307CMS8-LTC4307CMS8,SMLF,EMPTY,AL004307000    I30 @T6G_MB_LIB.T6G(SCH_1):PAGE249
 R3111    2      B Q_RES_0402LF-0,5%,1/16W,CHIP,CS00002JB13    I85 @T6G_MB_LIB.T6G(SCH_1):PAGE249

I3C_BMC_SWB_SCL @T6G_MB_LIB.T6G(SCH_1):I3C_BMC_SWB_SCL
   J41   A9 SMRST# SCONN168_ME1016810202011-SCONN168_ME1016810202011,A   I176 @T6G_MB_LIB.T6G(SCH_1):PAGE348
  R332    1      A Q_RES_0402LF-2.2K,5%,1/16W,EMPTY,CS22202JB07   I128 @T6G_MB_LIB.T6G(SCH_1):PAGE349
 R3112    1      A Q_RES_0402LF-33.2,1%,1/16W,CHIP,CS03322FB03    I25 @T6G_MB_LIB.T6G(SCH_1):PAGE249

I3C_BMC_SWB_SDA @T6G_MB_LIB.T6G(SCH_1):I3C_BMC_SWB_SDA
   J41  A10 PRSNTA# SCONN168_ME1016810202011-SCONN168_ME1016810202011,A   I176 @T6G_MB_LIB.T6G(SCH_1):PAGE348
 R1460    1      A Q_RES_0402LF-2.2K,5%,1/16W,EMPTY,CS22202JB07   I127 @T6G_MB_LIB.T6G(SCH_1):PAGE349
 R3111    1      A Q_RES_0402LF-0,5%,1/16W,CHIP,CS00002JB13    I85 @T6G_MB_LIB.T6G(SCH_1):PAGE249

I3C_MUX_CPU0_VIO @T6G_MB_LIB.T6G(SCH_1):I3C_MUX_CPU0_VIO
  R139    1      A Q_RES_0402LF-0,5%,1/16W,EMPTY,CS00002JB13    I30 @T6G_MB_LIB.T6G(SCH_1):PAGE138
  U213    7    VIO IML3112Y2B000NCG8-IML3112-Y2B000NCG8,SMLF,EMPTY,ALA   I111 @T6G_MB_LIB.T6G(SCH_1):PAGE138
    C9    1      A Q_CAP_C0402-1UF,25V,10%,EMPTY,CH5104KEB02   I113 @T6G_MB_LIB.T6G(SCH_1):PAGE138

I3C_SCM_0_R_SCL @T6G_MB_LIB.T6G(SCH_1):I3C_SCM_0_R_SCL
  U105    3    2D+ PI3CSW12ZUAEX-PI3CSW12ZUAEX,SMLF,IC,AL3CSW12000    I47 @T6G_MB_LIB.T6G(SCH_1):PAGE136
 R5014    2      B Q_RES_0402LF-1K,1%,1/16W,EMPTY,CS21002FB06   I159 @T6G_MB_LIB.T6G(SCH_1):PAGE136
 R6000    2      B Q_RES_0402LF-0,5%,1/16W,CHIP,CS00002JB13   I123 @T6G_MB_LIB.T6G(SCH_1):PAGE348

I3C_SCM_0_R_SDA @T6G_MB_LIB.T6G(SCH_1):I3C_SCM_0_R_SDA
  U105    4    2D- PI3CSW12ZUAEX-PI3CSW12ZUAEX,SMLF,IC,AL3CSW12000    I47 @T6G_MB_LIB.T6G(SCH_1):PAGE136
 R5015    2      B Q_RES_0402LF-1K,1%,1/16W,EMPTY,CS21002FB06   I157 @T6G_MB_LIB.T6G(SCH_1):PAGE136
 R6001    2      B Q_RES_0402LF-0,5%,1/16W,CHIP,CS00002JB13   I124 @T6G_MB_LIB.T6G(SCH_1):PAGE348

I3C_SCM_0_SCL @T6G_MB_LIB.T6G(SCH_1):I3C_SCM_0_SCL
   J41  OA5 RBT_ARB_OUT SCONN168_ME1016810202011-SCONN168_ME1016810202011,A   I176 @T6G_MB_LIB.T6G(SCH_1):PAGE348
 R6000    1      A Q_RES_0402LF-0,5%,1/16W,CHIP,CS00002JB13   I123 @T6G_MB_LIB.T6G(SCH_1):PAGE348

I3C_SCM_0_SDA @T6G_MB_LIB.T6G(SCH_1):I3C_SCM_0_SDA
 R6001    1      A Q_RES_0402LF-0,5%,1/16W,CHIP,CS00002JB13   I124 @T6G_MB_LIB.T6G(SCH_1):PAGE348
   J41  OA6 SLOT_ID1 SCONN168_ME1016810202011-SCONN168_ME1016810202011,A   I176 @T6G_MB_LIB.T6G(SCH_1):PAGE348

I3C_SCM_1_R_SCL @T6G_MB_LIB.T6G(SCH_1):I3C_SCM_1_R_SCL
  U106    3    2D+ PI3CSW12ZUAEX-PI3CSW12ZUAEX,SMLF,IC,AL3CSW12000    I54 @T6G_MB_LIB.T6G(SCH_1):PAGE136
 R5016    2      B Q_RES_0402LF-1K,1%,1/16W,EMPTY,CS21002FB06   I162 @T6G_MB_LIB.T6G(SCH_1):PAGE136
 R6002    2      B Q_RES_0402LF-0,5%,1/16W,CHIP,CS00002JB13   I122 @T6G_MB_LIB.T6G(SCH_1):PAGE348

I3C_SCM_1_R_SDA @T6G_MB_LIB.T6G(SCH_1):I3C_SCM_1_R_SDA
  U106    4    2D- PI3CSW12ZUAEX-PI3CSW12ZUAEX,SMLF,IC,AL3CSW12000    I54 @T6G_MB_LIB.T6G(SCH_1):PAGE136
 R5017    2      B Q_RES_0402LF-1K,1%,1/16W,EMPTY,CS21002FB06   I161 @T6G_MB_LIB.T6G(SCH_1):PAGE136
 R6003    2      B Q_RES_0402LF-0,5%,1/16W,CHIP,CS00002JB13   I121 @T6G_MB_LIB.T6G(SCH_1):PAGE348

I3C_SCM_1_SCL @T6G_MB_LIB.T6G(SCH_1):I3C_SCM_1_SCL
 R6002    1      A Q_RES_0402LF-0,5%,1/16W,CHIP,CS00002JB13   I122 @T6G_MB_LIB.T6G(SCH_1):PAGE348
   J41  OA7 RBT_TX_EN SCONN168_ME1016810202011-SCONN168_ME1016810202011,A   I176 @T6G_MB_LIB.T6G(SCH_1):PAGE348

I3C_SCM_1_SDA @T6G_MB_LIB.T6G(SCH_1):I3C_SCM_1_SDA
 R6003    1      A Q_RES_0402LF-0,5%,1/16W,CHIP,CS00002JB13   I121 @T6G_MB_LIB.T6G(SCH_1):PAGE348
   J41  OA8 RBT_TXD1 SCONN168_ME1016810202011-SCONN168_ME1016810202011,A   I176 @T6G_MB_LIB.T6G(SCH_1):PAGE348

I3C_SCM_2_R_SCL @T6G_MB_LIB.T6G(SCH_1):I3C_SCM_2_R_SCL
  U107    3    2D+ PI3CSW12ZUAEX-PI3CSW12ZUAEX,SMLF,IC,AL3CSW12000    I63 @T6G_MB_LIB.T6G(SCH_1):PAGE136
 R5018    2      B Q_RES_0402LF-1K,1%,1/16W,EMPTY,CS21002FB06   I163 @T6G_MB_LIB.T6G(SCH_1):PAGE136
 R6004    2      B Q_RES_0402LF-0,5%,1/16W,CHIP,CS00002JB13   I120 @T6G_MB_LIB.T6G(SCH_1):PAGE348

I3C_SCM_2_R_SDA @T6G_MB_LIB.T6G(SCH_1):I3C_SCM_2_R_SDA
  U107    4    2D- PI3CSW12ZUAEX-PI3CSW12ZUAEX,SMLF,IC,AL3CSW12000    I63 @T6G_MB_LIB.T6G(SCH_1):PAGE136
 R5019    2      B Q_RES_0402LF-1K,1%,1/16W,EMPTY,CS21002FB06   I164 @T6G_MB_LIB.T6G(SCH_1):PAGE136
 R6005    2      B Q_RES_0402LF-0,5%,1/16W,CHIP,CS00002JB13   I118 @T6G_MB_LIB.T6G(SCH_1):PAGE348

I3C_SCM_2_SCL @T6G_MB_LIB.T6G(SCH_1):I3C_SCM_2_SCL
 R6004    1      A Q_RES_0402LF-0,5%,1/16W,CHIP,CS00002JB13   I120 @T6G_MB_LIB.T6G(SCH_1):PAGE348
   J41  OA9 RBT_TXD0 SCONN168_ME1016810202011-SCONN168_ME1016810202011,A   I176 @T6G_MB_LIB.T6G(SCH_1):PAGE348

I3C_SCM_2_SDA @T6G_MB_LIB.T6G(SCH_1):I3C_SCM_2_SDA
 R6005    1      A Q_RES_0402LF-0,5%,1/16W,CHIP,CS00002JB13   I118 @T6G_MB_LIB.T6G(SCH_1):PAGE348
   J41 OA10 GND_OA10 SCONN168_ME1016810202011-SCONN168_ME1016810202011,A   I176 @T6G_MB_LIB.T6G(SCH_1):PAGE348

I3C_SCM_3_R_SCL @T6G_MB_LIB.T6G(SCH_1):I3C_SCM_3_R_SCL
  U108    3    2D+ PI3CSW12ZUAEX-PI3CSW12ZUAEX,SMLF,IC,AL3CSW12000    I68 @T6G_MB_LIB.T6G(SCH_1):PAGE136
 R5020    2      B Q_RES_0402LF-1K,1%,1/16W,EMPTY,CS21002FB06   I167 @T6G_MB_LIB.T6G(SCH_1):PAGE136
 R6006    2      B Q_RES_0402LF-0,5%,1/16W,CHIP,CS00002JB13   I117 @T6G_MB_LIB.T6G(SCH_1):PAGE348

I3C_SCM_3_R_SDA @T6G_MB_LIB.T6G(SCH_1):I3C_SCM_3_R_SDA
  U108    4    2D- PI3CSW12ZUAEX-PI3CSW12ZUAEX,SMLF,IC,AL3CSW12000    I68 @T6G_MB_LIB.T6G(SCH_1):PAGE136
 R5021    2      B Q_RES_0402LF-1K,1%,1/16W,EMPTY,CS21002FB06   I166 @T6G_MB_LIB.T6G(SCH_1):PAGE136
 R6007    2      B Q_RES_0402LF-0,5%,1/16W,CHIP,CS00002JB13   I119 @T6G_MB_LIB.T6G(SCH_1):PAGE348

I3C_SCM_3_SCL @T6G_MB_LIB.T6G(SCH_1):I3C_SCM_3_SCL
 R6006    1      A Q_RES_0402LF-0,5%,1/16W,CHIP,CS00002JB13   I117 @T6G_MB_LIB.T6G(SCH_1):PAGE348
   J41 OA11 REFCLKN3 SCONN168_ME1016810202011-SCONN168_ME1016810202011,A   I176 @T6G_MB_LIB.T6G(SCH_1):PAGE348

I3C_SCM_3_SDA @T6G_MB_LIB.T6G(SCH_1):I3C_SCM_3_SDA
 R6007    1      A Q_RES_0402LF-0,5%,1/16W,CHIP,CS00002JB13   I119 @T6G_MB_LIB.T6G(SCH_1):PAGE348
   J41 OA12 REFCLKP3 SCONN168_ME1016810202011-SCONN168_ME1016810202011,A   I176 @T6G_MB_LIB.T6G(SCH_1):PAGE348

I3C_SPD_DDRAF_CPU0_BYPASS_SCL @T6G_MB_LIB.T6G(SCH_1):I3C_SPD_DDRAF_CPU0_BYPASS_SCL
 R2310    2      B Q_RES_0402LF-0,5%,1/16W,EMPTY,CS00002JB13   I123 @T6G_MB_LIB.T6G(SCH_1):PAGE136
 R1330    1      A Q_RES_0402LF-0,5%,1/16W,EMPTY,CS00002JB13   I131 @T6G_MB_LIB.T6G(SCH_1):PAGE136

I3C_SPD_DDRAF_CPU0_BYPASS_SDA @T6G_MB_LIB.T6G(SCH_1):I3C_SPD_DDRAF_CPU0_BYPASS_SDA
 R2311    2      B Q_RES_0402LF-0,5%,1/16W,EMPTY,CS00002JB13   I124 @T6G_MB_LIB.T6G(SCH_1):PAGE136
 R1331    1      A Q_RES_0402LF-0,5%,1/16W,EMPTY,CS00002JB13   I132 @T6G_MB_LIB.T6G(SCH_1):PAGE136

I3C_SPD_DDRAF_CPU0_LVC1_SCL @T6G_MB_LIB.T6G(SCH_1):I3C_SPD_DDRAF_CPU0_LVC1_SCL
 R1297    2      B Q_RES_0402LF-0,5%,1/16W,CHIP,CS00002JB13    I31 @T6G_MB_LIB.T6G(SCH_1):PAGE136
  U105    8     D+ PI3CSW12ZUAEX-PI3CSW12ZUAEX,SMLF,IC,AL3CSW12000    I47 @T6G_MB_LIB.T6G(SCH_1):PAGE136
 R5006    2      B Q_RES_0402LF-1K,1%,1/16W,EMPTY,CS21002FB06   I145 @T6G_MB_LIB.T6G(SCH_1):PAGE136

I3C_SPD_DDRAF_CPU0_LVC1_SDA @T6G_MB_LIB.T6G(SCH_1):I3C_SPD_DDRAF_CPU0_LVC1_SDA
 R1298    2      B Q_RES_0402LF-0,5%,1/16W,CHIP,CS00002JB13    I32 @T6G_MB_LIB.T6G(SCH_1):PAGE136
  U105    7     D- PI3CSW12ZUAEX-PI3CSW12ZUAEX,SMLF,IC,AL3CSW12000    I47 @T6G_MB_LIB.T6G(SCH_1):PAGE136
 R5007    2      B Q_RES_0402LF-1K,1%,1/16W,EMPTY,CS21002FB06   I147 @T6G_MB_LIB.T6G(SCH_1):PAGE136

I3C_SPD_DDRAF_CPU0_SCL @T6G_MB_LIB.T6G(SCH_1):I3C_SPD_DDRAF_CPU0_SCL
 R1297    1      A Q_RES_0402LF-0,5%,1/16W,CHIP,CS00002JB13    I31 @T6G_MB_LIB.T6G(SCH_1):PAGE136
 R1330    2      B Q_RES_0402LF-0,5%,1/16W,EMPTY,CS00002JB13   I131 @T6G_MB_LIB.T6G(SCH_1):PAGE136
 R1568    1      A Q_RES_0402LF-49.9,1%,1/16W,CHIP,CS04992FB07   I539 @T6G_MB_LIB.T6G(SCH_1):PAGE85
 R1569    1      A Q_RES_0402LF-49.9,1%,1/16W,CHIP,CS04992FB07   I372 @T6G_MB_LIB.T6G(SCH_1):PAGE86
 R1572    1      A Q_RES_0402LF-49.9,1%,1/16W,CHIP,CS04992FB07   I416 @T6G_MB_LIB.T6G(SCH_1):PAGE89
 R1570    1      A Q_RES_0402LF-49.9,1%,1/16W,CHIP,CS04992FB07   I417 @T6G_MB_LIB.T6G(SCH_1):PAGE87
    R1    1      A Q_RES_0402LF-49.9,1%,1/16W,CHIP,CS04992FB07   I421 @T6G_MB_LIB.T6G(SCH_1):PAGE88
 R1573    1      A Q_RES_0402LF-49.9,1%,1/16W,CHIP,CS04992FB07   I418 @T6G_MB_LIB.T6G(SCH_1):PAGE90

I3C_SPD_DDRAF_CPU0_SDA @T6G_MB_LIB.T6G(SCH_1):I3C_SPD_DDRAF_CPU0_SDA
 R1298    1      A Q_RES_0402LF-0,5%,1/16W,CHIP,CS00002JB13    I32 @T6G_MB_LIB.T6G(SCH_1):PAGE136
 R1331    2      B Q_RES_0402LF-0,5%,1/16W,EMPTY,CS00002JB13   I132 @T6G_MB_LIB.T6G(SCH_1):PAGE136
 R1674    1      A Q_RES_0402LF-10,1%,1/16W,CHIP,CS01002FB07   I554 @T6G_MB_LIB.T6G(SCH_1):PAGE85
 R1675    1      A Q_RES_0402LF-10,1%,1/16W,CHIP,CS01002FB07   I373 @T6G_MB_LIB.T6G(SCH_1):PAGE86
 R1677    1      A Q_RES_0402LF-10,1%,1/16W,CHIP,CS01002FB07   I418 @T6G_MB_LIB.T6G(SCH_1):PAGE87
 R1676    1      A Q_RES_0402LF-10,1%,1/16W,CHIP,CS01002FB07   I422 @T6G_MB_LIB.T6G(SCH_1):PAGE88
 R1678    1      A Q_RES_0402LF-10,1%,1/16W,CHIP,CS01002FB07   I418 @T6G_MB_LIB.T6G(SCH_1):PAGE89
 R1679    1      A Q_RES_0402LF-10,1%,1/16W,CHIP,CS01002FB07   I419 @T6G_MB_LIB.T6G(SCH_1):PAGE90

I3C_SPD_DDRAF_CPU1_BYPASS_SCL @T6G_MB_LIB.T6G(SCH_1):I3C_SPD_DDRAF_CPU1_BYPASS_SCL
  R988    2      B Q_RES_0402LF-0,5%,1/16W,EMPTY,CS00002JB13   I138 @T6G_MB_LIB.T6G(SCH_1):PAGE136
 R1334    1      A Q_RES_0402LF-0,5%,1/16W,EMPTY,CS00002JB13   I139 @T6G_MB_LIB.T6G(SCH_1):PAGE136

I3C_SPD_DDRAF_CPU1_BYPASS_SDA @T6G_MB_LIB.T6G(SCH_1):I3C_SPD_DDRAF_CPU1_BYPASS_SDA
  R989    2      B Q_RES_0402LF-0,5%,1/16W,EMPTY,CS00002JB13   I137 @T6G_MB_LIB.T6G(SCH_1):PAGE136
 R1335    1      A Q_RES_0402LF-0,5%,1/16W,EMPTY,CS00002JB13   I140 @T6G_MB_LIB.T6G(SCH_1):PAGE136

I3C_SPD_DDRAF_CPU1_LVC1_SCL @T6G_MB_LIB.T6G(SCH_1):I3C_SPD_DDRAF_CPU1_LVC1_SCL
 R1293    2      B Q_RES_0402LF-0,5%,1/16W,CHIP,CS00002JB13    I35 @T6G_MB_LIB.T6G(SCH_1):PAGE136
  U107    8     D+ PI3CSW12ZUAEX-PI3CSW12ZUAEX,SMLF,IC,AL3CSW12000    I63 @T6G_MB_LIB.T6G(SCH_1):PAGE136
 R5010    2      B Q_RES_0402LF-1K,1%,1/16W,EMPTY,CS21002FB06   I151 @T6G_MB_LIB.T6G(SCH_1):PAGE136

I3C_SPD_DDRAF_CPU1_LVC1_SDA @T6G_MB_LIB.T6G(SCH_1):I3C_SPD_DDRAF_CPU1_LVC1_SDA
 R1294    2      B Q_RES_0402LF-0,5%,1/16W,CHIP,CS00002JB13    I36 @T6G_MB_LIB.T6G(SCH_1):PAGE136
  U107    7     D- PI3CSW12ZUAEX-PI3CSW12ZUAEX,SMLF,IC,AL3CSW12000    I63 @T6G_MB_LIB.T6G(SCH_1):PAGE136
 R5011    2      B Q_RES_0402LF-1K,1%,1/16W,EMPTY,CS21002FB06   I152 @T6G_MB_LIB.T6G(SCH_1):PAGE136

I3C_SPD_DDRAF_CPU1_SCL @T6G_MB_LIB.T6G(SCH_1):I3C_SPD_DDRAF_CPU1_SCL
 R1293    1      A Q_RES_0402LF-0,5%,1/16W,CHIP,CS00002JB13    I35 @T6G_MB_LIB.T6G(SCH_1):PAGE136
 R1334    2      B Q_RES_0402LF-0,5%,1/16W,EMPTY,CS00002JB13   I139 @T6G_MB_LIB.T6G(SCH_1):PAGE136
 R1582    1      A Q_RES_0402LF-49.9,1%,1/16W,CHIP,CS04992FB07   I242 @T6G_MB_LIB.T6G(SCH_1):PAGE99
 R1581    1      A Q_RES_0402LF-49.9,1%,1/16W,CHIP,CS04992FB07   I242 @T6G_MB_LIB.T6G(SCH_1):PAGE98
 R1580    1      A Q_RES_0402LF-49.9,1%,1/16W,CHIP,CS04992FB07   I244 @T6G_MB_LIB.T6G(SCH_1):PAGE97
 R1584    1      A Q_RES_0402LF-49.9,1%,1/16W,CHIP,CS04992FB07   I242 @T6G_MB_LIB.T6G(SCH_1):PAGE101
 R1583    1      A Q_RES_0402LF-49.9,1%,1/16W,CHIP,CS04992FB07   I242 @T6G_MB_LIB.T6G(SCH_1):PAGE100
 R1585    1      A Q_RES_0402LF-49.9,1%,1/16W,CHIP,CS04992FB07   I242 @T6G_MB_LIB.T6G(SCH_1):PAGE102

I3C_SPD_DDRAF_CPU1_SDA @T6G_MB_LIB.T6G(SCH_1):I3C_SPD_DDRAF_CPU1_SDA
 R1294    1      A Q_RES_0402LF-0,5%,1/16W,CHIP,CS00002JB13    I36 @T6G_MB_LIB.T6G(SCH_1):PAGE136
 R1335    2      B Q_RES_0402LF-0,5%,1/16W,EMPTY,CS00002JB13   I140 @T6G_MB_LIB.T6G(SCH_1):PAGE136
 R1687    1      A Q_RES_0402LF-10,1%,1/16W,CHIP,CS01002FB07   I256 @T6G_MB_LIB.T6G(SCH_1):PAGE97
 R1696    1      A Q_RES_0402LF-10,1%,1/16W,CHIP,CS01002FB07   I243 @T6G_MB_LIB.T6G(SCH_1):PAGE98
 R1697    1      A Q_RES_0402LF-10,1%,1/16W,CHIP,CS01002FB07   I243 @T6G_MB_LIB.T6G(SCH_1):PAGE99
 R1699    1      A Q_RES_0402LF-10,1%,1/16W,CHIP,CS01002FB07   I243 @T6G_MB_LIB.T6G(SCH_1):PAGE100
 R1701    1      A Q_RES_0402LF-10,1%,1/16W,CHIP,CS01002FB07   I243 @T6G_MB_LIB.T6G(SCH_1):PAGE101
 R1704    1      A Q_RES_0402LF-10,1%,1/16W,CHIP,CS01002FB07   I243 @T6G_MB_LIB.T6G(SCH_1):PAGE102

I3C_SPD_DDRA_CPU0_SCL @T6G_MB_LIB.T6G(SCH_1):I3C_SPD_DDRA_CPU0_SCL
    J1    4   HSCL SCONN288_DDR506112002KQ-SCONN288_DDR506112002KQ,SMA   I536 @T6G_MB_LIB.T6G(SCH_1):PAGE85
 R1568    2      B Q_RES_0402LF-49.9,1%,1/16W,CHIP,CS04992FB07   I539 @T6G_MB_LIB.T6G(SCH_1):PAGE85

I3C_SPD_DDRA_CPU0_SDA @T6G_MB_LIB.T6G(SCH_1):I3C_SPD_DDRA_CPU0_SDA
    J1    5   HSDA SCONN288_DDR506112002KQ-SCONN288_DDR506112002KQ,SMA   I536 @T6G_MB_LIB.T6G(SCH_1):PAGE85
 R1674    2      B Q_RES_0402LF-10,1%,1/16W,CHIP,CS01002FB07   I554 @T6G_MB_LIB.T6G(SCH_1):PAGE85

I3C_SPD_DDRA_CPU1_SCL @T6G_MB_LIB.T6G(SCH_1):I3C_SPD_DDRA_CPU1_SCL
   J24    4   HSCL SCONN288_DDR506112002KQ-SCONN288_DDR506112002KQ,SMA    I22 @T6G_MB_LIB.T6G(SCH_1):PAGE97
 R1580    2      B Q_RES_0402LF-49.9,1%,1/16W,CHIP,CS04992FB07   I244 @T6G_MB_LIB.T6G(SCH_1):PAGE97

I3C_SPD_DDRA_CPU1_SDA @T6G_MB_LIB.T6G(SCH_1):I3C_SPD_DDRA_CPU1_SDA
   J24    5   HSDA SCONN288_DDR506112002KQ-SCONN288_DDR506112002KQ,SMA    I22 @T6G_MB_LIB.T6G(SCH_1):PAGE97
 R1687    2      B Q_RES_0402LF-10,1%,1/16W,CHIP,CS01002FB07   I256 @T6G_MB_LIB.T6G(SCH_1):PAGE97

I3C_SPD_DDRB_CPU0_SCL @T6G_MB_LIB.T6G(SCH_1):I3C_SPD_DDRB_CPU0_SCL
   J15    4   HSCL SCONN288_DDR506112002KQ-SCONN288_DDR506112002KQ,SMA   I350 @T6G_MB_LIB.T6G(SCH_1):PAGE86
 R1569    2      B Q_RES_0402LF-49.9,1%,1/16W,CHIP,CS04992FB07   I372 @T6G_MB_LIB.T6G(SCH_1):PAGE86

I3C_SPD_DDRB_CPU0_SDA @T6G_MB_LIB.T6G(SCH_1):I3C_SPD_DDRB_CPU0_SDA
   J15    5   HSDA SCONN288_DDR506112002KQ-SCONN288_DDR506112002KQ,SMA   I350 @T6G_MB_LIB.T6G(SCH_1):PAGE86
 R1675    2      B Q_RES_0402LF-10,1%,1/16W,CHIP,CS01002FB07   I373 @T6G_MB_LIB.T6G(SCH_1):PAGE86

I3C_SPD_DDRB_CPU1_SCL @T6G_MB_LIB.T6G(SCH_1):I3C_SPD_DDRB_CPU1_SCL
   J26    4   HSCL SCONN288_DDR506112002KQ-SCONN288_DDR506112002KQ,SMA    I22 @T6G_MB_LIB.T6G(SCH_1):PAGE98
 R1581    2      B Q_RES_0402LF-49.9,1%,1/16W,CHIP,CS04992FB07   I242 @T6G_MB_LIB.T6G(SCH_1):PAGE98

I3C_SPD_DDRB_CPU1_SDA @T6G_MB_LIB.T6G(SCH_1):I3C_SPD_DDRB_CPU1_SDA
   J26    5   HSDA SCONN288_DDR506112002KQ-SCONN288_DDR506112002KQ,SMA    I22 @T6G_MB_LIB.T6G(SCH_1):PAGE98
 R1696    2      B Q_RES_0402LF-10,1%,1/16W,CHIP,CS01002FB07   I243 @T6G_MB_LIB.T6G(SCH_1):PAGE98

I3C_SPD_DDRC_CPU0_SCL @T6G_MB_LIB.T6G(SCH_1):I3C_SPD_DDRC_CPU0_SCL
   J17    4   HSCL SCONN288_DDR506112002KQ-SCONN288_DDR506112002KQ,SMA   I350 @T6G_MB_LIB.T6G(SCH_1):PAGE87
 R1570    2      B Q_RES_0402LF-49.9,1%,1/16W,CHIP,CS04992FB07   I417 @T6G_MB_LIB.T6G(SCH_1):PAGE87

I3C_SPD_DDRC_CPU0_SDA @T6G_MB_LIB.T6G(SCH_1):I3C_SPD_DDRC_CPU0_SDA
   J17    5   HSDA SCONN288_DDR506112002KQ-SCONN288_DDR506112002KQ,SMA   I350 @T6G_MB_LIB.T6G(SCH_1):PAGE87
 R1677    2      B Q_RES_0402LF-10,1%,1/16W,CHIP,CS01002FB07   I418 @T6G_MB_LIB.T6G(SCH_1):PAGE87

I3C_SPD_DDRC_CPU1_SCL @T6G_MB_LIB.T6G(SCH_1):I3C_SPD_DDRC_CPU1_SCL
   J28    4   HSCL SCONN288_DDR506112002KQ-SCONN288_DDR506112002KQ,SMA    I22 @T6G_MB_LIB.T6G(SCH_1):PAGE99
 R1582    2      B Q_RES_0402LF-49.9,1%,1/16W,CHIP,CS04992FB07   I242 @T6G_MB_LIB.T6G(SCH_1):PAGE99

I3C_SPD_DDRC_CPU1_SDA @T6G_MB_LIB.T6G(SCH_1):I3C_SPD_DDRC_CPU1_SDA
   J28    5   HSDA SCONN288_DDR506112002KQ-SCONN288_DDR506112002KQ,SMA    I22 @T6G_MB_LIB.T6G(SCH_1):PAGE99
 R1697    2      B Q_RES_0402LF-10,1%,1/16W,CHIP,CS01002FB07   I243 @T6G_MB_LIB.T6G(SCH_1):PAGE99

I3C_SPD_DDRD_CPU0_SCL @T6G_MB_LIB.T6G(SCH_1):I3C_SPD_DDRD_CPU0_SCL
   J19    4   HSCL SCONN288_DDR506112002KQ-SCONN288_DDR506112002KQ,SMA   I350 @T6G_MB_LIB.T6G(SCH_1):PAGE88
    R1    2      B Q_RES_0402LF-49.9,1%,1/16W,CHIP,CS04992FB07   I421 @T6G_MB_LIB.T6G(SCH_1):PAGE88

I3C_SPD_DDRD_CPU0_SDA @T6G_MB_LIB.T6G(SCH_1):I3C_SPD_DDRD_CPU0_SDA
   J19    5   HSDA SCONN288_DDR506112002KQ-SCONN288_DDR506112002KQ,SMA   I350 @T6G_MB_LIB.T6G(SCH_1):PAGE88
 R1676    2      B Q_RES_0402LF-10,1%,1/16W,CHIP,CS01002FB07   I422 @T6G_MB_LIB.T6G(SCH_1):PAGE88

I3C_SPD_DDRD_CPU1_SCL @T6G_MB_LIB.T6G(SCH_1):I3C_SPD_DDRD_CPU1_SCL
   J30    4   HSCL SCONN288_DDR506112002KQ-SCONN288_DDR506112002KQ,SMA    I52 @T6G_MB_LIB.T6G(SCH_1):PAGE100
 R1583    2      B Q_RES_0402LF-49.9,1%,1/16W,CHIP,CS04992FB07   I242 @T6G_MB_LIB.T6G(SCH_1):PAGE100

I3C_SPD_DDRD_CPU1_SDA @T6G_MB_LIB.T6G(SCH_1):I3C_SPD_DDRD_CPU1_SDA
   J30    5   HSDA SCONN288_DDR506112002KQ-SCONN288_DDR506112002KQ,SMA    I52 @T6G_MB_LIB.T6G(SCH_1):PAGE100
 R1699    2      B Q_RES_0402LF-10,1%,1/16W,CHIP,CS01002FB07   I243 @T6G_MB_LIB.T6G(SCH_1):PAGE100

I3C_SPD_DDRE_CPU0_SCL @T6G_MB_LIB.T6G(SCH_1):I3C_SPD_DDRE_CPU0_SCL
   J21    4   HSCL SCONN288_DDR506112002KQ-SCONN288_DDR506112002KQ,SMA   I348 @T6G_MB_LIB.T6G(SCH_1):PAGE89
 R1572    2      B Q_RES_0402LF-49.9,1%,1/16W,CHIP,CS04992FB07   I416 @T6G_MB_LIB.T6G(SCH_1):PAGE89

I3C_SPD_DDRE_CPU0_SDA @T6G_MB_LIB.T6G(SCH_1):I3C_SPD_DDRE_CPU0_SDA
   J21    5   HSDA SCONN288_DDR506112002KQ-SCONN288_DDR506112002KQ,SMA   I348 @T6G_MB_LIB.T6G(SCH_1):PAGE89
 R1678    2      B Q_RES_0402LF-10,1%,1/16W,CHIP,CS01002FB07   I418 @T6G_MB_LIB.T6G(SCH_1):PAGE89

I3C_SPD_DDRE_CPU1_SCL @T6G_MB_LIB.T6G(SCH_1):I3C_SPD_DDRE_CPU1_SCL
   J32    4   HSCL SCONN288_DDR506112002KQ-SCONN288_DDR506112002KQ,SMA    I52 @T6G_MB_LIB.T6G(SCH_1):PAGE101
 R1584    2      B Q_RES_0402LF-49.9,1%,1/16W,CHIP,CS04992FB07   I242 @T6G_MB_LIB.T6G(SCH_1):PAGE101

I3C_SPD_DDRE_CPU1_SDA @T6G_MB_LIB.T6G(SCH_1):I3C_SPD_DDRE_CPU1_SDA
   J32    5   HSDA SCONN288_DDR506112002KQ-SCONN288_DDR506112002KQ,SMA    I52 @T6G_MB_LIB.T6G(SCH_1):PAGE101
 R1701    2      B Q_RES_0402LF-10,1%,1/16W,CHIP,CS01002FB07   I243 @T6G_MB_LIB.T6G(SCH_1):PAGE101

I3C_SPD_DDRF_CPU0_SCL @T6G_MB_LIB.T6G(SCH_1):I3C_SPD_DDRF_CPU0_SCL
   J23    4   HSCL SCONN288_DDR506112002KQ-SCONN288_DDR506112002KQ,SMA   I350 @T6G_MB_LIB.T6G(SCH_1):PAGE90
 R1573    2      B Q_RES_0402LF-49.9,1%,1/16W,CHIP,CS04992FB07   I418 @T6G_MB_LIB.T6G(SCH_1):PAGE90

I3C_SPD_DDRF_CPU0_SDA @T6G_MB_LIB.T6G(SCH_1):I3C_SPD_DDRF_CPU0_SDA
   J23    5   HSDA SCONN288_DDR506112002KQ-SCONN288_DDR506112002KQ,SMA   I350 @T6G_MB_LIB.T6G(SCH_1):PAGE90
 R1679    2      B Q_RES_0402LF-10,1%,1/16W,CHIP,CS01002FB07   I419 @T6G_MB_LIB.T6G(SCH_1):PAGE90

I3C_SPD_DDRF_CPU1_SCL @T6G_MB_LIB.T6G(SCH_1):I3C_SPD_DDRF_CPU1_SCL
   J33    4   HSCL SCONN288_DDR506112002KQ-SCONN288_DDR506112002KQ,SMA    I22 @T6G_MB_LIB.T6G(SCH_1):PAGE102
 R1585    2      B Q_RES_0402LF-49.9,1%,1/16W,CHIP,CS04992FB07   I242 @T6G_MB_LIB.T6G(SCH_1):PAGE102

I3C_SPD_DDRF_CPU1_SDA @T6G_MB_LIB.T6G(SCH_1):I3C_SPD_DDRF_CPU1_SDA
   J33    5   HSDA SCONN288_DDR506112002KQ-SCONN288_DDR506112002KQ,SMA    I22 @T6G_MB_LIB.T6G(SCH_1):PAGE102
 R1704    2      B Q_RES_0402LF-10,1%,1/16W,CHIP,CS01002FB07   I243 @T6G_MB_LIB.T6G(SCH_1):PAGE102

I3C_SPD_DDRGL_CPU0_BYPASS_SCL @T6G_MB_LIB.T6G(SCH_1):I3C_SPD_DDRGL_CPU0_BYPASS_SCL
 R1332    1      A Q_RES_0402LF-0,5%,1/16W,EMPTY,CS00002JB13   I134 @T6G_MB_LIB.T6G(SCH_1):PAGE136
  R986    2      B Q_RES_0402LF-0,5%,1/16W,EMPTY,CS00002JB13   I135 @T6G_MB_LIB.T6G(SCH_1):PAGE136

I3C_SPD_DDRGL_CPU0_BYPASS_SDA @T6G_MB_LIB.T6G(SCH_1):I3C_SPD_DDRGL_CPU0_BYPASS_SDA
 R1333    1      A Q_RES_0402LF-0,5%,1/16W,EMPTY,CS00002JB13   I133 @T6G_MB_LIB.T6G(SCH_1):PAGE136
  R987    2      B Q_RES_0402LF-0,5%,1/16W,EMPTY,CS00002JB13   I136 @T6G_MB_LIB.T6G(SCH_1):PAGE136

I3C_SPD_DDRGL_CPU0_LVC1_SCL @T6G_MB_LIB.T6G(SCH_1):I3C_SPD_DDRGL_CPU0_LVC1_SCL
 R1299    2      B Q_RES_0402LF-0,5%,1/16W,CHIP,CS00002JB13    I33 @T6G_MB_LIB.T6G(SCH_1):PAGE136
  U106    8     D+ PI3CSW12ZUAEX-PI3CSW12ZUAEX,SMLF,IC,AL3CSW12000    I54 @T6G_MB_LIB.T6G(SCH_1):PAGE136
 R5008    2      B Q_RES_0402LF-1K,1%,1/16W,EMPTY,CS21002FB06   I148 @T6G_MB_LIB.T6G(SCH_1):PAGE136

I3C_SPD_DDRGL_CPU0_LVC1_SDA @T6G_MB_LIB.T6G(SCH_1):I3C_SPD_DDRGL_CPU0_LVC1_SDA
 R1300    2      B Q_RES_0402LF-0,5%,1/16W,CHIP,CS00002JB13    I34 @T6G_MB_LIB.T6G(SCH_1):PAGE136
  U106    7     D- PI3CSW12ZUAEX-PI3CSW12ZUAEX,SMLF,IC,AL3CSW12000    I54 @T6G_MB_LIB.T6G(SCH_1):PAGE136
 R5009    2      B Q_RES_0402LF-1K,1%,1/16W,EMPTY,CS21002FB06   I150 @T6G_MB_LIB.T6G(SCH_1):PAGE136

I3C_SPD_DDRGL_CPU0_SCL @T6G_MB_LIB.T6G(SCH_1):I3C_SPD_DDRGL_CPU0_SCL
 R1299    1      A Q_RES_0402LF-0,5%,1/16W,CHIP,CS00002JB13    I33 @T6G_MB_LIB.T6G(SCH_1):PAGE136
 R1332    2      B Q_RES_0402LF-0,5%,1/16W,EMPTY,CS00002JB13   I134 @T6G_MB_LIB.T6G(SCH_1):PAGE136
 R1579    1      A Q_RES_0402LF-49.9,1%,1/16W,CHIP,CS04992FB07   I242 @T6G_MB_LIB.T6G(SCH_1):PAGE96
 R1575    1      A Q_RES_0402LF-49.9,1%,1/16W,CHIP,CS04992FB07   I243 @T6G_MB_LIB.T6G(SCH_1):PAGE92
 R1576    1      A Q_RES_0402LF-49.9,1%,1/16W,CHIP,CS04992FB07   I242 @T6G_MB_LIB.T6G(SCH_1):PAGE93
 R1574    1      A Q_RES_0402LF-49.9,1%,1/16W,CHIP,CS04992FB07   I242 @T6G_MB_LIB.T6G(SCH_1):PAGE91
 R1577    1      A Q_RES_0402LF-49.9,1%,1/16W,CHIP,CS04992FB07   I242 @T6G_MB_LIB.T6G(SCH_1):PAGE94
 R1578    1      A Q_RES_0402LF-49.9,1%,1/16W,CHIP,CS04992FB07   I242 @T6G_MB_LIB.T6G(SCH_1):PAGE95

I3C_SPD_DDRGL_CPU0_SDA @T6G_MB_LIB.T6G(SCH_1):I3C_SPD_DDRGL_CPU0_SDA
 R1300    1      A Q_RES_0402LF-0,5%,1/16W,CHIP,CS00002JB13    I34 @T6G_MB_LIB.T6G(SCH_1):PAGE136
 R1333    2      B Q_RES_0402LF-0,5%,1/16W,EMPTY,CS00002JB13   I133 @T6G_MB_LIB.T6G(SCH_1):PAGE136
 R1680    1      A Q_RES_0402LF-10,1%,1/16W,CHIP,CS01002FB07   I254 @T6G_MB_LIB.T6G(SCH_1):PAGE91
 R1681    1      A Q_RES_0402LF-10,1%,1/16W,CHIP,CS01002FB07   I244 @T6G_MB_LIB.T6G(SCH_1):PAGE92
 R1683    1      A Q_RES_0402LF-10,1%,1/16W,CHIP,CS01002FB07   I243 @T6G_MB_LIB.T6G(SCH_1):PAGE93
 R1684    1      A Q_RES_0402LF-10,1%,1/16W,CHIP,CS01002FB07   I243 @T6G_MB_LIB.T6G(SCH_1):PAGE94
 R1685    1      A Q_RES_0402LF-10,1%,1/16W,CHIP,CS01002FB07   I243 @T6G_MB_LIB.T6G(SCH_1):PAGE95
 R1686    1      A Q_RES_0402LF-10,1%,1/16W,CHIP,CS01002FB07   I243 @T6G_MB_LIB.T6G(SCH_1):PAGE96

I3C_SPD_DDRGL_CPU1_BYPASS_SCL @T6G_MB_LIB.T6G(SCH_1):I3C_SPD_DDRGL_CPU1_BYPASS_SCL
  R990    2      B Q_RES_0402LF-0,5%,1/16W,EMPTY,CS00002JB13   I142 @T6G_MB_LIB.T6G(SCH_1):PAGE136
 R1336    1      A Q_RES_0402LF-0,5%,1/16W,EMPTY,CS00002JB13   I143 @T6G_MB_LIB.T6G(SCH_1):PAGE136

I3C_SPD_DDRGL_CPU1_BYPASS_SDA @T6G_MB_LIB.T6G(SCH_1):I3C_SPD_DDRGL_CPU1_BYPASS_SDA
  R991    2      B Q_RES_0402LF-0,5%,1/16W,EMPTY,CS00002JB13   I141 @T6G_MB_LIB.T6G(SCH_1):PAGE136
 R1337    1      A Q_RES_0402LF-0,5%,1/16W,EMPTY,CS00002JB13   I144 @T6G_MB_LIB.T6G(SCH_1):PAGE136

I3C_SPD_DDRGL_CPU1_LVC1_SCL @T6G_MB_LIB.T6G(SCH_1):I3C_SPD_DDRGL_CPU1_LVC1_SCL
 R1295    2      B Q_RES_0402LF-0,5%,1/16W,CHIP,CS00002JB13    I37 @T6G_MB_LIB.T6G(SCH_1):PAGE136
  U108    8     D+ PI3CSW12ZUAEX-PI3CSW12ZUAEX,SMLF,IC,AL3CSW12000    I68 @T6G_MB_LIB.T6G(SCH_1):PAGE136
 R5012    2      B Q_RES_0402LF-1K,1%,1/16W,EMPTY,CS21002FB06   I156 @T6G_MB_LIB.T6G(SCH_1):PAGE136

I3C_SPD_DDRGL_CPU1_LVC1_SDA @T6G_MB_LIB.T6G(SCH_1):I3C_SPD_DDRGL_CPU1_LVC1_SDA
 R1296    2      B Q_RES_0402LF-0,5%,1/16W,CHIP,CS00002JB13    I38 @T6G_MB_LIB.T6G(SCH_1):PAGE136
  U108    7     D- PI3CSW12ZUAEX-PI3CSW12ZUAEX,SMLF,IC,AL3CSW12000    I68 @T6G_MB_LIB.T6G(SCH_1):PAGE136
 R5013    2      B Q_RES_0402LF-1K,1%,1/16W,EMPTY,CS21002FB06   I154 @T6G_MB_LIB.T6G(SCH_1):PAGE136

I3C_SPD_DDRGL_CPU1_SCL @T6G_MB_LIB.T6G(SCH_1):I3C_SPD_DDRGL_CPU1_SCL
 R1295    1      A Q_RES_0402LF-0,5%,1/16W,CHIP,CS00002JB13    I37 @T6G_MB_LIB.T6G(SCH_1):PAGE136
 R1336    2      B Q_RES_0402LF-0,5%,1/16W,EMPTY,CS00002JB13   I143 @T6G_MB_LIB.T6G(SCH_1):PAGE136
 R1591    1      A Q_RES_0402LF-49.9,1%,1/16W,CHIP,CS04992FB07   I241 @T6G_MB_LIB.T6G(SCH_1):PAGE108
 R1586    1      A Q_RES_0402LF-49.9,1%,1/16W,CHIP,CS04992FB07   I244 @T6G_MB_LIB.T6G(SCH_1):PAGE103
 R1587    1      A Q_RES_0402LF-49.9,1%,1/16W,CHIP,CS04992FB07   I244 @T6G_MB_LIB.T6G(SCH_1):PAGE104
 R1588    1      A Q_RES_0402LF-49.9,1%,1/16W,CHIP,CS04992FB07   I242 @T6G_MB_LIB.T6G(SCH_1):PAGE105
 R1589    1      A Q_RES_0402LF-49.9,1%,1/16W,CHIP,CS04992FB07   I242 @T6G_MB_LIB.T6G(SCH_1):PAGE106
 R1590    1      A Q_RES_0402LF-49.9,1%,1/16W,CHIP,CS04992FB07   I241 @T6G_MB_LIB.T6G(SCH_1):PAGE107

I3C_SPD_DDRGL_CPU1_SDA @T6G_MB_LIB.T6G(SCH_1):I3C_SPD_DDRGL_CPU1_SDA
 R1296    1      A Q_RES_0402LF-0,5%,1/16W,CHIP,CS00002JB13    I38 @T6G_MB_LIB.T6G(SCH_1):PAGE136
 R1337    2      B Q_RES_0402LF-0,5%,1/16W,EMPTY,CS00002JB13   I144 @T6G_MB_LIB.T6G(SCH_1):PAGE136
 R1705    1      A Q_RES_0402LF-10,1%,1/16W,CHIP,CS01002FB07   I256 @T6G_MB_LIB.T6G(SCH_1):PAGE103
 R1707    1      A Q_RES_0402LF-10,1%,1/16W,CHIP,CS01002FB07   I245 @T6G_MB_LIB.T6G(SCH_1):PAGE104
 R1708    1      A Q_RES_0402LF-10,1%,1/16W,CHIP,CS01002FB07   I243 @T6G_MB_LIB.T6G(SCH_1):PAGE105
 R1709    1      A Q_RES_0402LF-10,1%,1/16W,CHIP,CS01002FB07   I243 @T6G_MB_LIB.T6G(SCH_1):PAGE106
 R1710    1      A Q_RES_0402LF-10,1%,1/16W,CHIP,CS01002FB07   I242 @T6G_MB_LIB.T6G(SCH_1):PAGE107
 R1711    1      A Q_RES_0402LF-10,1%,1/16W,CHIP,CS01002FB07   I242 @T6G_MB_LIB.T6G(SCH_1):PAGE108

I3C_SPD_DDRG_CPU0_SCL @T6G_MB_LIB.T6G(SCH_1):I3C_SPD_DDRG_CPU0_SCL
   J16    4   HSCL SCONN288_DDR506112002KQ-SCONN288_DDR506112002KQ,SMA    I22 @T6G_MB_LIB.T6G(SCH_1):PAGE91
 R1574    2      B Q_RES_0402LF-49.9,1%,1/16W,CHIP,CS04992FB07   I242 @T6G_MB_LIB.T6G(SCH_1):PAGE91

I3C_SPD_DDRG_CPU0_SDA @T6G_MB_LIB.T6G(SCH_1):I3C_SPD_DDRG_CPU0_SDA
   J16    5   HSDA SCONN288_DDR506112002KQ-SCONN288_DDR506112002KQ,SMA    I22 @T6G_MB_LIB.T6G(SCH_1):PAGE91
 R1680    2      B Q_RES_0402LF-10,1%,1/16W,CHIP,CS01002FB07   I254 @T6G_MB_LIB.T6G(SCH_1):PAGE91

I3C_SPD_DDRG_CPU1_SCL @T6G_MB_LIB.T6G(SCH_1):I3C_SPD_DDRG_CPU1_SCL
  J102    4   HSCL SCONN288_DDR506112002KQ-SCONN288_DDR506112002KQ,SMA    I22 @T6G_MB_LIB.T6G(SCH_1):PAGE103
 R1586    2      B Q_RES_0402LF-49.9,1%,1/16W,CHIP,CS04992FB07   I244 @T6G_MB_LIB.T6G(SCH_1):PAGE103

I3C_SPD_DDRG_CPU1_SDA @T6G_MB_LIB.T6G(SCH_1):I3C_SPD_DDRG_CPU1_SDA
  J102    5   HSDA SCONN288_DDR506112002KQ-SCONN288_DDR506112002KQ,SMA    I22 @T6G_MB_LIB.T6G(SCH_1):PAGE103
 R1705    2      B Q_RES_0402LF-10,1%,1/16W,CHIP,CS01002FB07   I256 @T6G_MB_LIB.T6G(SCH_1):PAGE103

I3C_SPD_DDRH_CPU0_SCL @T6G_MB_LIB.T6G(SCH_1):I3C_SPD_DDRH_CPU0_SCL
   J69    4   HSCL SCONN288_DDR506112002KQ-SCONN288_DDR506112002KQ,SMA    I22 @T6G_MB_LIB.T6G(SCH_1):PAGE92
 R1575    2      B Q_RES_0402LF-49.9,1%,1/16W,CHIP,CS04992FB07   I243 @T6G_MB_LIB.T6G(SCH_1):PAGE92

I3C_SPD_DDRH_CPU0_SDA @T6G_MB_LIB.T6G(SCH_1):I3C_SPD_DDRH_CPU0_SDA
   J69    5   HSDA SCONN288_DDR506112002KQ-SCONN288_DDR506112002KQ,SMA    I22 @T6G_MB_LIB.T6G(SCH_1):PAGE92
 R1681    2      B Q_RES_0402LF-10,1%,1/16W,CHIP,CS01002FB07   I244 @T6G_MB_LIB.T6G(SCH_1):PAGE92

I3C_SPD_DDRH_CPU1_SCL @T6G_MB_LIB.T6G(SCH_1):I3C_SPD_DDRH_CPU1_SCL
   J27    4   HSCL SCONN288_DDR506112002KQ-SCONN288_DDR506112002KQ,SMA    I22 @T6G_MB_LIB.T6G(SCH_1):PAGE104
 R1587    2      B Q_RES_0402LF-49.9,1%,1/16W,CHIP,CS04992FB07   I244 @T6G_MB_LIB.T6G(SCH_1):PAGE104

I3C_SPD_DDRH_CPU1_SDA @T6G_MB_LIB.T6G(SCH_1):I3C_SPD_DDRH_CPU1_SDA
   J27    5   HSDA SCONN288_DDR506112002KQ-SCONN288_DDR506112002KQ,SMA    I22 @T6G_MB_LIB.T6G(SCH_1):PAGE104
 R1707    2      B Q_RES_0402LF-10,1%,1/16W,CHIP,CS01002FB07   I245 @T6G_MB_LIB.T6G(SCH_1):PAGE104

I3C_SPD_DDRI_CPU0_SCL @T6G_MB_LIB.T6G(SCH_1):I3C_SPD_DDRI_CPU0_SCL
   J18    4   HSCL SCONN288_DDR506112002KQ-SCONN288_DDR506112002KQ,SMA    I22 @T6G_MB_LIB.T6G(SCH_1):PAGE93
 R1576    2      B Q_RES_0402LF-49.9,1%,1/16W,CHIP,CS04992FB07   I242 @T6G_MB_LIB.T6G(SCH_1):PAGE93

I3C_SPD_DDRI_CPU0_SDA @T6G_MB_LIB.T6G(SCH_1):I3C_SPD_DDRI_CPU0_SDA
   J18    5   HSDA SCONN288_DDR506112002KQ-SCONN288_DDR506112002KQ,SMA    I22 @T6G_MB_LIB.T6G(SCH_1):PAGE93
 R1683    2      B Q_RES_0402LF-10,1%,1/16W,CHIP,CS01002FB07   I243 @T6G_MB_LIB.T6G(SCH_1):PAGE93

I3C_SPD_DDRI_CPU1_SCL @T6G_MB_LIB.T6G(SCH_1):I3C_SPD_DDRI_CPU1_SCL
  J100    4   HSCL SCONN288_DDR506112002KQ-SCONN288_DDR506112002KQ,SMA    I22 @T6G_MB_LIB.T6G(SCH_1):PAGE105
 R1588    2      B Q_RES_0402LF-49.9,1%,1/16W,CHIP,CS04992FB07   I242 @T6G_MB_LIB.T6G(SCH_1):PAGE105

I3C_SPD_DDRI_CPU1_SDA @T6G_MB_LIB.T6G(SCH_1):I3C_SPD_DDRI_CPU1_SDA
  J100    5   HSDA SCONN288_DDR506112002KQ-SCONN288_DDR506112002KQ,SMA    I22 @T6G_MB_LIB.T6G(SCH_1):PAGE105
 R1708    2      B Q_RES_0402LF-10,1%,1/16W,CHIP,CS01002FB07   I243 @T6G_MB_LIB.T6G(SCH_1):PAGE105

I3C_SPD_DDRJ_CPU0_SCL @T6G_MB_LIB.T6G(SCH_1):I3C_SPD_DDRJ_CPU0_SCL
   J68    4   HSCL SCONN288_DDR506112002KQ-SCONN288_DDR506112002KQ,SMA    I22 @T6G_MB_LIB.T6G(SCH_1):PAGE94
 R1577    2      B Q_RES_0402LF-49.9,1%,1/16W,CHIP,CS04992FB07   I242 @T6G_MB_LIB.T6G(SCH_1):PAGE94

I3C_SPD_DDRJ_CPU0_SDA @T6G_MB_LIB.T6G(SCH_1):I3C_SPD_DDRJ_CPU0_SDA
   J68    5   HSDA SCONN288_DDR506112002KQ-SCONN288_DDR506112002KQ,SMA    I22 @T6G_MB_LIB.T6G(SCH_1):PAGE94
 R1684    2      B Q_RES_0402LF-10,1%,1/16W,CHIP,CS01002FB07   I243 @T6G_MB_LIB.T6G(SCH_1):PAGE94

I3C_SPD_DDRJ_CPU1_SCL @T6G_MB_LIB.T6G(SCH_1):I3C_SPD_DDRJ_CPU1_SCL
   J29    4   HSCL SCONN288_DDR506112002KQ-SCONN288_DDR506112002KQ,SMA    I22 @T6G_MB_LIB.T6G(SCH_1):PAGE106
 R1589    2      B Q_RES_0402LF-49.9,1%,1/16W,CHIP,CS04992FB07   I242 @T6G_MB_LIB.T6G(SCH_1):PAGE106

I3C_SPD_DDRJ_CPU1_SDA @T6G_MB_LIB.T6G(SCH_1):I3C_SPD_DDRJ_CPU1_SDA
   J29    5   HSDA SCONN288_DDR506112002KQ-SCONN288_DDR506112002KQ,SMA    I22 @T6G_MB_LIB.T6G(SCH_1):PAGE106
 R1709    2      B Q_RES_0402LF-10,1%,1/16W,CHIP,CS01002FB07   I243 @T6G_MB_LIB.T6G(SCH_1):PAGE106

I3C_SPD_DDRK_CPU0_SCL @T6G_MB_LIB.T6G(SCH_1):I3C_SPD_DDRK_CPU0_SCL
   J20    4   HSCL SCONN288_DDR506112002KQ-SCONN288_DDR506112002KQ,SMA    I22 @T6G_MB_LIB.T6G(SCH_1):PAGE95
 R1578    2      B Q_RES_0402LF-49.9,1%,1/16W,CHIP,CS04992FB07   I242 @T6G_MB_LIB.T6G(SCH_1):PAGE95

I3C_SPD_DDRK_CPU0_SDA @T6G_MB_LIB.T6G(SCH_1):I3C_SPD_DDRK_CPU0_SDA
   J20    5   HSDA SCONN288_DDR506112002KQ-SCONN288_DDR506112002KQ,SMA    I22 @T6G_MB_LIB.T6G(SCH_1):PAGE95
 R1685    2      B Q_RES_0402LF-10,1%,1/16W,CHIP,CS01002FB07   I243 @T6G_MB_LIB.T6G(SCH_1):PAGE95

I3C_SPD_DDRK_CPU1_SCL @T6G_MB_LIB.T6G(SCH_1):I3C_SPD_DDRK_CPU1_SCL
   J99    4   HSCL SCONN288_DDR506112002KQ-SCONN288_DDR506112002KQ,SMA    I22 @T6G_MB_LIB.T6G(SCH_1):PAGE107
 R1590    2      B Q_RES_0402LF-49.9,1%,1/16W,CHIP,CS04992FB07   I241 @T6G_MB_LIB.T6G(SCH_1):PAGE107

I3C_SPD_DDRK_CPU1_SDA @T6G_MB_LIB.T6G(SCH_1):I3C_SPD_DDRK_CPU1_SDA
   J99    5   HSDA SCONN288_DDR506112002KQ-SCONN288_DDR506112002KQ,SMA    I22 @T6G_MB_LIB.T6G(SCH_1):PAGE107
 R1710    2      B Q_RES_0402LF-10,1%,1/16W,CHIP,CS01002FB07   I242 @T6G_MB_LIB.T6G(SCH_1):PAGE107

I3C_SPD_DDRL_CPU0_SCL @T6G_MB_LIB.T6G(SCH_1):I3C_SPD_DDRL_CPU0_SCL
   J67    4   HSCL SCONN288_DDR506112002KQ-SCONN288_DDR506112002KQ,SMA    I22 @T6G_MB_LIB.T6G(SCH_1):PAGE96
 R1579    2      B Q_RES_0402LF-49.9,1%,1/16W,CHIP,CS04992FB07   I242 @T6G_MB_LIB.T6G(SCH_1):PAGE96

I3C_SPD_DDRL_CPU0_SDA @T6G_MB_LIB.T6G(SCH_1):I3C_SPD_DDRL_CPU0_SDA
   J67    5   HSDA SCONN288_DDR506112002KQ-SCONN288_DDR506112002KQ,SMA    I22 @T6G_MB_LIB.T6G(SCH_1):PAGE96
 R1686    2      B Q_RES_0402LF-10,1%,1/16W,CHIP,CS01002FB07   I243 @T6G_MB_LIB.T6G(SCH_1):PAGE96

I3C_SPD_DDRL_CPU1_SCL @T6G_MB_LIB.T6G(SCH_1):I3C_SPD_DDRL_CPU1_SCL
   J37    4   HSCL SCONN288_DDR506112002KQ-SCONN288_DDR506112002KQ,SMA    I22 @T6G_MB_LIB.T6G(SCH_1):PAGE108
 R1591    2      B Q_RES_0402LF-49.9,1%,1/16W,CHIP,CS04992FB07   I241 @T6G_MB_LIB.T6G(SCH_1):PAGE108

I3C_SPD_DDRL_CPU1_SDA @T6G_MB_LIB.T6G(SCH_1):I3C_SPD_DDRL_CPU1_SDA
   J37    5   HSDA SCONN288_DDR506112002KQ-SCONN288_DDR506112002KQ,SMA    I22 @T6G_MB_LIB.T6G(SCH_1):PAGE108
 R1711    2      B Q_RES_0402LF-10,1%,1/16W,CHIP,CS01002FB07   I242 @T6G_MB_LIB.T6G(SCH_1):PAGE108

INA230_1_A0 @T6G_MB_LIB.T6G(SCH_1):INA230_1_A0
  U266    2     A0 ISL28022FRZT-ISL28022FRZ-T,SMLF,IC,AL028022003    I30 @T6G_MB_LIB.T6G(SCH_1):PAGE295
 R3617    2      B Q_RES_0402LF-4.7K,1%,1/16W,EMPTY,CS24702FB06    I40 @T6G_MB_LIB.T6G(SCH_1):PAGE295
 R3627    2      B Q_RES_0402LF-4.7K,1%,1/16W,CHIP,CS24702FB06    I89 @T6G_MB_LIB.T6G(SCH_1):PAGE295

INA230_1_A1 @T6G_MB_LIB.T6G(SCH_1):INA230_1_A1
  U266    1     A1 ISL28022FRZT-ISL28022FRZ-T,SMLF,IC,AL028022003    I30 @T6G_MB_LIB.T6G(SCH_1):PAGE295
 R3616    2      B Q_RES_0402LF-4.7K,1%,1/16W,CHIP,CS24702FB06    I31 @T6G_MB_LIB.T6G(SCH_1):PAGE295
 R3628    2      B Q_RES_0402LF-4.7K,1%,1/16W,EMPTY,CS24702FB06    I88 @T6G_MB_LIB.T6G(SCH_1):PAGE295

INA230_2_A0 @T6G_MB_LIB.T6G(SCH_1):INA230_2_A0
  U276    2     A0 ISL28022FRZT-ISL28022FRZ-T,SMLF,IC,AL028022003   I129 @T6G_MB_LIB.T6G(SCH_1):PAGE295
 R3764    2      B Q_RES_0402LF-4.7K,1%,1/16W,EMPTY,CS24702FB06   I135 @T6G_MB_LIB.T6G(SCH_1):PAGE295
 R3751    1      A Q_RES_0402LF-0,5%,1/16W,CHIP,CS00002JB13   I146 @T6G_MB_LIB.T6G(SCH_1):PAGE295

INA230_2_A1 @T6G_MB_LIB.T6G(SCH_1):INA230_2_A1
  U276    1     A1 ISL28022FRZT-ISL28022FRZ-T,SMLF,IC,AL028022003   I129 @T6G_MB_LIB.T6G(SCH_1):PAGE295
 R3763    2      B Q_RES_0402LF-4.7K,1%,1/16W,CHIP,CS24702FB06   I136 @T6G_MB_LIB.T6G(SCH_1):PAGE295

INA230_3_A0 @T6G_MB_LIB.T6G(SCH_1):INA230_3_A0
  U263    2     A0 ISL28022FRZT-ISL28022FRZ-T,SMLF,IC,AL028022003    I94 @T6G_MB_LIB.T6G(SCH_1):PAGE360
 R3620    1      A Q_RES_0402LF-0,5%,1/16W,CHIP,CS00002JB13   I100 @T6G_MB_LIB.T6G(SCH_1):PAGE360
 R3609    2      B Q_RES_0402LF-4.7K,1%,1/16W,EMPTY,CS24702FB06   I104 @T6G_MB_LIB.T6G(SCH_1):PAGE360

INA230_3_A1 @T6G_MB_LIB.T6G(SCH_1):INA230_3_A1
  U263    1     A1 ISL28022FRZT-ISL28022FRZ-T,SMLF,IC,AL028022003    I94 @T6G_MB_LIB.T6G(SCH_1):PAGE360
 R3608    2      B Q_RES_0402LF-4.7K,1%,1/16W,CHIP,CS24702FB06   I103 @T6G_MB_LIB.T6G(SCH_1):PAGE360

INA230_4_A0 @T6G_MB_LIB.T6G(SCH_1):INA230_4_A0
 R3611    2      B Q_RES_0402LF-4.7K,1%,1/16W,CHIP,CS24702FB06    I36 @T6G_MB_LIB.T6G(SCH_1):PAGE360
  U264    2     A0 ISL28022FRZT-ISL28022FRZ-T,SMLF,IC,AL028022003    I46 @T6G_MB_LIB.T6G(SCH_1):PAGE360
 R3621    2      B Q_RES_0402LF-4.7K,1%,1/16W,EMPTY,CS24702FB06    I87 @T6G_MB_LIB.T6G(SCH_1):PAGE360

INA230_4_A1 @T6G_MB_LIB.T6G(SCH_1):INA230_4_A1
 R3610    2      B Q_RES_0402LF-4.7K,1%,1/16W,EMPTY,CS24702FB06    I45 @T6G_MB_LIB.T6G(SCH_1):PAGE360
  U264    1     A1 ISL28022FRZT-ISL28022FRZ-T,SMLF,IC,AL028022003    I46 @T6G_MB_LIB.T6G(SCH_1):PAGE360
 R3623    2      B Q_RES_0402LF-4.7K,1%,1/16W,CHIP,CS24702FB06    I86 @T6G_MB_LIB.T6G(SCH_1):PAGE360

INA230_5_A0 @T6G_MB_LIB.T6G(SCH_1):INA230_5_A0
 R3613    2      B Q_RES_0402LF-4.7K,1%,1/16W,EMPTY,CS24702FB06    I59 @T6G_MB_LIB.T6G(SCH_1):PAGE360
  U265    2     A0 ISL28022FRZT-ISL28022FRZ-T,SMLF,IC,AL028022003    I69 @T6G_MB_LIB.T6G(SCH_1):PAGE360
 R3622    2      B Q_RES_0402LF-4.7K,1%,1/16W,CHIP,CS24702FB06    I90 @T6G_MB_LIB.T6G(SCH_1):PAGE360

INA230_5_A1 @T6G_MB_LIB.T6G(SCH_1):INA230_5_A1
 R3612    2      B Q_RES_0402LF-4.7K,1%,1/16W,EMPTY,CS24702FB06    I68 @T6G_MB_LIB.T6G(SCH_1):PAGE360
  U265    1     A1 ISL28022FRZT-ISL28022FRZ-T,SMLF,IC,AL028022003    I69 @T6G_MB_LIB.T6G(SCH_1):PAGE360
 R3624    2      B Q_RES_0402LF-4.7K,1%,1/16W,CHIP,CS24702FB06    I89 @T6G_MB_LIB.T6G(SCH_1):PAGE360

INA230_6_A0 @T6G_MB_LIB.T6G(SCH_1):INA230_6_A0
 R1309    2      B Q_RES_0402LF-4.7K,1%,1/16W,EMPTY,CS24702FB06    I13 @T6G_MB_LIB.T6G(SCH_1):PAGE466
   U55    2     A0 ISL28022FRZT-ISL28022FRZ-T,SMLF,IC,AL028022003    I28 @T6G_MB_LIB.T6G(SCH_1):PAGE466
 R1355    1      A Q_RES_0402LF-0,5%,1/16W,CHIP,CS00002JB13    I92 @T6G_MB_LIB.T6G(SCH_1):PAGE466

INA230_6_A1 @T6G_MB_LIB.T6G(SCH_1):INA230_6_A1
 R1306    2      B Q_RES_0402LF-4.7K,1%,1/16W,EMPTY,CS24702FB06    I12 @T6G_MB_LIB.T6G(SCH_1):PAGE466
 R1320    2      B Q_RES_0402LF-4.7K,1%,1/16W,CHIP,CS24702FB06    I17 @T6G_MB_LIB.T6G(SCH_1):PAGE466
   U55    1     A1 ISL28022FRZT-ISL28022FRZ-T,SMLF,IC,AL028022003    I28 @T6G_MB_LIB.T6G(SCH_1):PAGE466

INA230_7_A0 @T6G_MB_LIB.T6G(SCH_1):INA230_7_A0
   U56    2     A0 ISL28022FRZT-ISL28022FRZ-T,SMLF,IC,AL028022003    I29 @T6G_MB_LIB.T6G(SCH_1):PAGE466
 R1310    2      B Q_RES_0402LF-4.7K,1%,1/16W,EMPTY,CS24702FB06    I45 @T6G_MB_LIB.T6G(SCH_1):PAGE466
 R1360    1      A Q_RES_0402LF-0,5%,1/16W,CHIP,CS00002JB13    I93 @T6G_MB_LIB.T6G(SCH_1):PAGE466

INA230_7_A1 @T6G_MB_LIB.T6G(SCH_1):INA230_7_A1
   U56    1     A1 ISL28022FRZT-ISL28022FRZ-T,SMLF,IC,AL028022003    I29 @T6G_MB_LIB.T6G(SCH_1):PAGE466
 R1322    2      B Q_RES_0402LF-4.7K,1%,1/16W,CHIP,CS24702FB06    I39 @T6G_MB_LIB.T6G(SCH_1):PAGE466
 R1307    2      B Q_RES_0402LF-4.7K,1%,1/16W,EMPTY,CS24702FB06    I44 @T6G_MB_LIB.T6G(SCH_1):PAGE466

INA230_8_A0 @T6G_MB_LIB.T6G(SCH_1):INA230_8_A0
   U52    2     A0 ISL28022FRZT-ISL28022FRZ-T,SMLF,IC,AL028022003    I57 @T6G_MB_LIB.T6G(SCH_1):PAGE466
 R1308    2      B Q_RES_0402LF-4.7K,1%,1/16W,CHIP,CS24702FB06    I96 @T6G_MB_LIB.T6G(SCH_1):PAGE466

INA230_8_A1 @T6G_MB_LIB.T6G(SCH_1):INA230_8_A1
   U52    1     A1 ISL28022FRZT-ISL28022FRZ-T,SMLF,IC,AL028022003    I57 @T6G_MB_LIB.T6G(SCH_1):PAGE466
 R1305    2      B Q_RES_0402LF-4.7K,1%,1/16W,EMPTY,CS24702FB06    I72 @T6G_MB_LIB.T6G(SCH_1):PAGE466
 R1350    1      A Q_RES_0402LF-0,5%,1/16W,CHIP,CS00002JB13    I94 @T6G_MB_LIB.T6G(SCH_1):PAGE466
 R1317    2      B Q_RES_0402LF-4.7K,1%,1/16W,EMPTY,CS24702FB06    I95 @T6G_MB_LIB.T6G(SCH_1):PAGE466

IND_CPU0_P0_CPL0 @T6G_MB_LIB.T6G(SCH_1):IND_CPU0_P0_CPL0
  PL50    2      2 Q_INDUCTOR_SMLF-120NH/69A,IND,CV+12^0EZ03    I51 @T6G_MB_LIB.T6G(SCH_1):PAGE171
  PL70    2      2 Q_INDUCTOR4P_14-150NH,SMLF,IND,CV+15^0TZ04    I52 @T6G_MB_LIB.T6G(SCH_1):PAGE171

IND_CPU0_P0_CPL1 @T6G_MB_LIB.T6G(SCH_1):IND_CPU0_P0_CPL1
  PL52    2      2 Q_INDUCTOR4P_14-150NH,SMLF,IND,CV+15^0TZ04    I62 @T6G_MB_LIB.T6G(SCH_1):PAGE169
  PL51    3      3 Q_INDUCTOR4P_14-150NH,SMLF,IND,CV+15^0TZ04    I77 @T6G_MB_LIB.T6G(SCH_1):PAGE169

IND_CPU0_P0_CPL2 @T6G_MB_LIB.T6G(SCH_1):IND_CPU0_P0_CPL2
  PL52    3      3 Q_INDUCTOR4P_14-150NH,SMLF,IND,CV+15^0TZ04    I62 @T6G_MB_LIB.T6G(SCH_1):PAGE169
  PL59    2      2 Q_INDUCTOR4P_14-150NH,SMLF,IND,CV+15^0TZ04    I64 @T6G_MB_LIB.T6G(SCH_1):PAGE170

IND_CPU0_P0_CPL3 @T6G_MB_LIB.T6G(SCH_1):IND_CPU0_P0_CPL3
  PL60    2      2 Q_INDUCTOR4P_14-150NH,SMLF,IND,CV+15^0TZ04    I52 @T6G_MB_LIB.T6G(SCH_1):PAGE170
  PL59    3      3 Q_INDUCTOR4P_14-150NH,SMLF,IND,CV+15^0TZ04    I64 @T6G_MB_LIB.T6G(SCH_1):PAGE170

IND_CPU0_P0_CPL5 @T6G_MB_LIB.T6G(SCH_1):IND_CPU0_P0_CPL5
  PL51    2      2 Q_INDUCTOR4P_14-150NH,SMLF,IND,CV+15^0TZ04    I77 @T6G_MB_LIB.T6G(SCH_1):PAGE169
  PL61    3      3 Q_INDUCTOR4P_14-150NH,SMLF,IND,CV+15^0TZ04    I64 @T6G_MB_LIB.T6G(SCH_1):PAGE171

IND_CPU0_P0_CPL6 @T6G_MB_LIB.T6G(SCH_1):IND_CPU0_P0_CPL6
  PL70    3      3 Q_INDUCTOR4P_14-150NH,SMLF,IND,CV+15^0TZ04    I52 @T6G_MB_LIB.T6G(SCH_1):PAGE171
  PL61    2      2 Q_INDUCTOR4P_14-150NH,SMLF,IND,CV+15^0TZ04    I64 @T6G_MB_LIB.T6G(SCH_1):PAGE171

IND_CPU0_P1_CPL0 @T6G_MB_LIB.T6G(SCH_1):IND_CPU0_P1_CPL0
  PL27    2      2 Q_INDUCTOR_SMLF-120NH/69A,IND,CV+12^0EZ03    I51 @T6G_MB_LIB.T6G(SCH_1):PAGE188
   PL8    2      2 Q_INDUCTOR4P_14-150NH,SMLF,IND,CV+15^0TZ04    I53 @T6G_MB_LIB.T6G(SCH_1):PAGE188

IND_CPU0_P1_CPL1 @T6G_MB_LIB.T6G(SCH_1):IND_CPU0_P1_CPL1
  PL29    2      2 Q_INDUCTOR4P_14-150NH,SMLF,IND,CV+15^0TZ04    I56 @T6G_MB_LIB.T6G(SCH_1):PAGE186
  PL28    3      3 Q_INDUCTOR4P_14-150NH,SMLF,IND,CV+15^0TZ04    I90 @T6G_MB_LIB.T6G(SCH_1):PAGE186

IND_CPU0_P1_CPL2 @T6G_MB_LIB.T6G(SCH_1):IND_CPU0_P1_CPL2
  PL29    3      3 Q_INDUCTOR4P_14-150NH,SMLF,IND,CV+15^0TZ04    I56 @T6G_MB_LIB.T6G(SCH_1):PAGE186
  PL31    2      2 Q_INDUCTOR4P_14-150NH,SMLF,IND,CV+15^0TZ04    I67 @T6G_MB_LIB.T6G(SCH_1):PAGE187

IND_CPU0_P1_CPL3 @T6G_MB_LIB.T6G(SCH_1):IND_CPU0_P1_CPL3
  PL32    2      2 Q_INDUCTOR4P_14-150NH,SMLF,IND,CV+15^0TZ04    I53 @T6G_MB_LIB.T6G(SCH_1):PAGE187
  PL31    3      3 Q_INDUCTOR4P_14-150NH,SMLF,IND,CV+15^0TZ04    I67 @T6G_MB_LIB.T6G(SCH_1):PAGE187

IND_CPU0_P1_CPL5 @T6G_MB_LIB.T6G(SCH_1):IND_CPU0_P1_CPL5
  PL28    2      2 Q_INDUCTOR4P_14-150NH,SMLF,IND,CV+15^0TZ04    I90 @T6G_MB_LIB.T6G(SCH_1):PAGE186
  PL33    3      3 Q_INDUCTOR4P_14-150NH,SMLF,IND,CV+15^0TZ04    I64 @T6G_MB_LIB.T6G(SCH_1):PAGE188

IND_CPU0_P1_CPL6 @T6G_MB_LIB.T6G(SCH_1):IND_CPU0_P1_CPL6
   PL8    3      3 Q_INDUCTOR4P_14-150NH,SMLF,IND,CV+15^0TZ04    I53 @T6G_MB_LIB.T6G(SCH_1):PAGE188
  PL33    2      2 Q_INDUCTOR4P_14-150NH,SMLF,IND,CV+15^0TZ04    I64 @T6G_MB_LIB.T6G(SCH_1):PAGE188

IND_CPU1_P0_CPL0 @T6G_MB_LIB.T6G(SCH_1):IND_CPU1_P0_CPL0
   PL9    1      1 Q_INDUCTOR_SMLF-120NH/69A,IND,CV+12^0EZ03    I36 @T6G_MB_LIB.T6G(SCH_1):PAGE178
   PL7    2      2 Q_INDUCTOR4P_14-150NH,SMLF,IND,CV+15^0TZ04    I38 @T6G_MB_LIB.T6G(SCH_1):PAGE178

IND_CPU1_P0_CPL1 @T6G_MB_LIB.T6G(SCH_1):IND_CPU1_P0_CPL1
  PL11    2      2 Q_INDUCTOR4P_14-150NH,SMLF,IND,CV+15^0TZ04    I46 @T6G_MB_LIB.T6G(SCH_1):PAGE176
  PL10    3      3 Q_INDUCTOR4P_14-150NH,SMLF,IND,CV+15^0TZ04    I62 @T6G_MB_LIB.T6G(SCH_1):PAGE176

IND_CPU1_P0_CPL2 @T6G_MB_LIB.T6G(SCH_1):IND_CPU1_P0_CPL2
  PL11    3      3 Q_INDUCTOR4P_14-150NH,SMLF,IND,CV+15^0TZ04    I46 @T6G_MB_LIB.T6G(SCH_1):PAGE176
  PL14    2      2 Q_INDUCTOR4P_14-150NH,SMLF,IND,CV+15^0TZ04    I64 @T6G_MB_LIB.T6G(SCH_1):PAGE177

IND_CPU1_P0_CPL3 @T6G_MB_LIB.T6G(SCH_1):IND_CPU1_P0_CPL3
  PL13    2      2 Q_INDUCTOR4P_14-150NH,SMLF,IND,CV+15^0TZ04    I42 @T6G_MB_LIB.T6G(SCH_1):PAGE177
  PL14    3      3 Q_INDUCTOR4P_14-150NH,SMLF,IND,CV+15^0TZ04    I64 @T6G_MB_LIB.T6G(SCH_1):PAGE177

IND_CPU1_P0_CPL5 @T6G_MB_LIB.T6G(SCH_1):IND_CPU1_P0_CPL5
  PL10    2      2 Q_INDUCTOR4P_14-150NH,SMLF,IND,CV+15^0TZ04    I62 @T6G_MB_LIB.T6G(SCH_1):PAGE176
  PL15    3      3 Q_INDUCTOR4P_14-150NH,SMLF,IND,CV+15^0TZ04    I63 @T6G_MB_LIB.T6G(SCH_1):PAGE178

IND_CPU1_P0_CPL6 @T6G_MB_LIB.T6G(SCH_1):IND_CPU1_P0_CPL6
   PL7    3      3 Q_INDUCTOR4P_14-150NH,SMLF,IND,CV+15^0TZ04    I38 @T6G_MB_LIB.T6G(SCH_1):PAGE178
  PL15    2      2 Q_INDUCTOR4P_14-150NH,SMLF,IND,CV+15^0TZ04    I63 @T6G_MB_LIB.T6G(SCH_1):PAGE178

IND_CPU1_P1_CPL0 @T6G_MB_LIB.T6G(SCH_1):IND_CPU1_P1_CPL0
  PL39    1      1 Q_INDUCTOR_SMLF-120NH/69A,IND,CV+12^0EZ03    I37 @T6G_MB_LIB.T6G(SCH_1):PAGE195
  PL69    2      2 Q_INDUCTOR4P_14-150NH,SMLF,IND,CV+15^0TZ04    I50 @T6G_MB_LIB.T6G(SCH_1):PAGE195

IND_CPU1_P1_CPL1 @T6G_MB_LIB.T6G(SCH_1):IND_CPU1_P1_CPL1
  PL41    2      2 Q_INDUCTOR4P_14-150NH,SMLF,IND,CV+15^0TZ04    I62 @T6G_MB_LIB.T6G(SCH_1):PAGE193
  PL40    3      3 Q_INDUCTOR4P_14-150NH,SMLF,IND,CV+15^0TZ04    I77 @T6G_MB_LIB.T6G(SCH_1):PAGE193

IND_CPU1_P1_CPL2 @T6G_MB_LIB.T6G(SCH_1):IND_CPU1_P1_CPL2
  PL41    3      3 Q_INDUCTOR4P_14-150NH,SMLF,IND,CV+15^0TZ04    I62 @T6G_MB_LIB.T6G(SCH_1):PAGE193
  PL44    2      2 Q_INDUCTOR4P_14-150NH,SMLF,IND,CV+15^0TZ04    I62 @T6G_MB_LIB.T6G(SCH_1):PAGE194

IND_CPU1_P1_CPL3 @T6G_MB_LIB.T6G(SCH_1):IND_CPU1_P1_CPL3
  PL43    2      2 Q_INDUCTOR4P_14-150NH,SMLF,IND,CV+15^0TZ04    I50 @T6G_MB_LIB.T6G(SCH_1):PAGE194
  PL44    3      3 Q_INDUCTOR4P_14-150NH,SMLF,IND,CV+15^0TZ04    I62 @T6G_MB_LIB.T6G(SCH_1):PAGE194

IND_CPU1_P1_CPL5 @T6G_MB_LIB.T6G(SCH_1):IND_CPU1_P1_CPL5
  PL40    2      2 Q_INDUCTOR4P_14-150NH,SMLF,IND,CV+15^0TZ04    I77 @T6G_MB_LIB.T6G(SCH_1):PAGE193
  PL45    3      3 Q_INDUCTOR4P_14-150NH,SMLF,IND,CV+15^0TZ04    I63 @T6G_MB_LIB.T6G(SCH_1):PAGE195

IND_CPU1_P1_CPL6 @T6G_MB_LIB.T6G(SCH_1):IND_CPU1_P1_CPL6
  PL69    3      3 Q_INDUCTOR4P_14-150NH,SMLF,IND,CV+15^0TZ04    I50 @T6G_MB_LIB.T6G(SCH_1):PAGE195
  PL45    2      2 Q_INDUCTOR4P_14-150NH,SMLF,IND,CV+15^0TZ04    I63 @T6G_MB_LIB.T6G(SCH_1):PAGE195

IND_PVDDIO_P0_CPL0 @T6G_MB_LIB.T6G(SCH_1):IND_PVDDIO_P0_CPL0
  PL20    2      2 Q_INDUCTOR4P_14-150NH,SMLF,IND,CV+15^0TZ04    I42 @T6G_MB_LIB.T6G(SCH_1):PAGE181
  PL16    1      1 Q_INDUCTOR_SMLF-0.22UH/33A,IND,CV+22Y0EZ00    I43 @T6G_MB_LIB.T6G(SCH_1):PAGE181

IND_PVDDIO_P0_CPL2 @T6G_MB_LIB.T6G(SCH_1):IND_PVDDIO_P0_CPL2
  PL18    3      3 Q_INDUCTOR4P_14-150NH,SMLF,IND,CV+15^0TZ04    I40 @T6G_MB_LIB.T6G(SCH_1):PAGE180
  PL17    2      2 Q_INDUCTOR4P_14-150NH,SMLF,IND,CV+15^0TZ04    I64 @T6G_MB_LIB.T6G(SCH_1):PAGE180

IND_PVDDIO_P0_CPL3 @T6G_MB_LIB.T6G(SCH_1):IND_PVDDIO_P0_CPL3
  PL18    2      2 Q_INDUCTOR4P_14-150NH,SMLF,IND,CV+15^0TZ04    I40 @T6G_MB_LIB.T6G(SCH_1):PAGE180
  PL21    3      3 Q_INDUCTOR4P_14-150NH,SMLF,IND,CV+15^0TZ04    I61 @T6G_MB_LIB.T6G(SCH_1):PAGE181

IND_PVDDIO_P0_CPL4 @T6G_MB_LIB.T6G(SCH_1):IND_PVDDIO_P0_CPL4
  PL20    3      3 Q_INDUCTOR4P_14-150NH,SMLF,IND,CV+15^0TZ04    I42 @T6G_MB_LIB.T6G(SCH_1):PAGE181
  PL21    2      2 Q_INDUCTOR4P_14-150NH,SMLF,IND,CV+15^0TZ04    I61 @T6G_MB_LIB.T6G(SCH_1):PAGE181

IND_PVDDIO_P1_CPL0 @T6G_MB_LIB.T6G(SCH_1):IND_PVDDIO_P1_CPL0
  PL67    2      2 Q_INDUCTOR4P_14-150NH,SMLF,IND,CV+15^0TZ04    I42 @T6G_MB_LIB.T6G(SCH_1):PAGE198
  PL46    1      1 Q_INDUCTOR_SMLF-0.22UH/33A,IND,CV+22Y0EZ00    I43 @T6G_MB_LIB.T6G(SCH_1):PAGE198

IND_PVDDIO_P1_CPL2 @T6G_MB_LIB.T6G(SCH_1):IND_PVDDIO_P1_CPL2
  PL47    2      2 Q_INDUCTOR4P_14-150NH,SMLF,IND,CV+15^0TZ04    I71 @T6G_MB_LIB.T6G(SCH_1):PAGE197
  PL48    3      3 Q_INDUCTOR4P_14-150NH,SMLF,IND,CV+15^0TZ04    I83 @T6G_MB_LIB.T6G(SCH_1):PAGE197

IND_PVDDIO_P1_CPL3 @T6G_MB_LIB.T6G(SCH_1):IND_PVDDIO_P1_CPL3
  PL48    2      2 Q_INDUCTOR4P_14-150NH,SMLF,IND,CV+15^0TZ04    I83 @T6G_MB_LIB.T6G(SCH_1):PAGE197
  PL68    3      3 Q_INDUCTOR4P_14-150NH,SMLF,IND,CV+15^0TZ04    I62 @T6G_MB_LIB.T6G(SCH_1):PAGE198

IND_PVDDIO_P1_CPL4 @T6G_MB_LIB.T6G(SCH_1):IND_PVDDIO_P1_CPL4
  PL67    3      3 Q_INDUCTOR4P_14-150NH,SMLF,IND,CV+15^0TZ04    I42 @T6G_MB_LIB.T6G(SCH_1):PAGE198
  PL68    2      2 Q_INDUCTOR4P_14-150NH,SMLF,IND,CV+15^0TZ04    I62 @T6G_MB_LIB.T6G(SCH_1):PAGE198

IND_SOC_P0_CPL0 @T6G_MB_LIB.T6G(SCH_1):IND_SOC_P0_CPL0
  PL66    2      2 Q_INDUCTOR4P_14-150NH,SMLF,IND,CV+15^0TZ04    I25 @T6G_MB_LIB.T6G(SCH_1):PAGE174
  PL62    2      2 Q_INDUCTOR_SMLF-0.22UH/33A,IND,CV+22Y0EZ00    I24 @T6G_MB_LIB.T6G(SCH_1):PAGE174

IND_SOC_P0_CPL2 @T6G_MB_LIB.T6G(SCH_1):IND_SOC_P0_CPL2
  PL63    2      2 Q_INDUCTOR4P_14-150NH,SMLF,IND,CV+15^0TZ04    I69 @T6G_MB_LIB.T6G(SCH_1):PAGE173
  PL64    3      3 Q_INDUCTOR4P_14-150NH,SMLF,IND,CV+15^0TZ04    I53 @T6G_MB_LIB.T6G(SCH_1):PAGE173

IND_SOC_P0_CPL3 @T6G_MB_LIB.T6G(SCH_1):IND_SOC_P0_CPL3
  PL66    3      3 Q_INDUCTOR4P_14-150NH,SMLF,IND,CV+15^0TZ04    I25 @T6G_MB_LIB.T6G(SCH_1):PAGE174
  PL64    2      2 Q_INDUCTOR4P_14-150NH,SMLF,IND,CV+15^0TZ04    I53 @T6G_MB_LIB.T6G(SCH_1):PAGE173

IND_SOC_P1_CPL0 @T6G_MB_LIB.T6G(SCH_1):IND_SOC_P1_CPL0
  PL34    2      2 Q_INDUCTOR_SMLF-0.22UH/33A,IND,CV+22Y0EZ00    I25 @T6G_MB_LIB.T6G(SCH_1):PAGE191
  PL38    2      2 Q_INDUCTOR4P_14-150NH,SMLF,IND,CV+15^0TZ04    I26 @T6G_MB_LIB.T6G(SCH_1):PAGE191

IND_SOC_P1_CPL2 @T6G_MB_LIB.T6G(SCH_1):IND_SOC_P1_CPL2
  PL36    3      3 Q_INDUCTOR4P_14-150NH,SMLF,IND,CV+15^0TZ04    I52 @T6G_MB_LIB.T6G(SCH_1):PAGE190
  PL35    2      2 Q_INDUCTOR4P_14-150NH,SMLF,IND,CV+15^0TZ04    I69 @T6G_MB_LIB.T6G(SCH_1):PAGE190

IND_SOC_P1_CPL3 @T6G_MB_LIB.T6G(SCH_1):IND_SOC_P1_CPL3
  PL36    2      2 Q_INDUCTOR4P_14-150NH,SMLF,IND,CV+15^0TZ04    I52 @T6G_MB_LIB.T6G(SCH_1):PAGE190
  PL38    3      3 Q_INDUCTOR4P_14-150NH,SMLF,IND,CV+15^0TZ04    I26 @T6G_MB_LIB.T6G(SCH_1):PAGE191

INT_CPU1_HP_UBM_N @T6G_MB_LIB.T6G(SCH_1):INT_CPU1_HP_UBM_N
   U26 DJ35 GENINT_L||PM_INTR_L||UBM_CPRSNT_CHANGE_DET_L||AGPIO89 GENOA_SP5-SOCKET6096_13568-001,SMLF,IO,DGA^6000030   I182 @T6G_MB_LIB.T6G(SCH_1):PAGE55
 R1424    2      B Q_RES_0402LF-2.2K,5%,1/16W,CHIP,CS22202JB07   I292 @T6G_MB_LIB.T6G(SCH_1):PAGE55

IRQ0_A56 @T6G_MB_LIB.T6G(SCH_1):IRQ0_A56
  R321    2      B Q_RES_0402LF-0,5%,1/16W,CHIP,CS00002JB13    I24 @T6G_MB_LIB.T6G(SCH_1):PAGE348
   J41  A56 PERN12 SCONN168_ME1016810202011-SCONN168_ME1016810202011,A   I176 @T6G_MB_LIB.T6G(SCH_1):PAGE348

IRQ_BMC_SMI_N @T6G_MB_LIB.T6G(SCH_1):IRQ_BMC_SMI_N
  R244    1      A Q_RES_0402LF-0,5%,1/16W,CHIP,CS00002JB13    I72 @T6G_MB_LIB.T6G(SCH_1):PAGE81
 R5028    2      B Q_RES_0402LF-4.7K,5%,1/16W,EMPTY,CS24702JB10    I60 @T6G_MB_LIB.T6G(SCH_1):PAGE28
  R445    1      A Q_RES_0402LF-4.7K,5%,1/16W,CHIP,CS24702JB10    I66 @T6G_MB_LIB.T6G(SCH_1):PAGE28
   U25 DE40 AGPIO6||DEVSLP1||SATA_ZP1_L GENOA_SP5-SOCKET6096_13568-001,SMLF,IO,DGA^6000030   I188 @T6G_MB_LIB.T6G(SCH_1):PAGE28

IRQ_BMC_SMI_R_N @T6G_MB_LIB.T6G(SCH_1):IRQ_BMC_SMI_R_N
  R244    2      B Q_RES_0402LF-0,5%,1/16W,CHIP,CS00002JB13    I72 @T6G_MB_LIB.T6G(SCH_1):PAGE81
   U18   F5 PL3B||L_GPLLC_FB LCMXO3LF9400C5BG484C-LCMXO3LF-9400C-5BG484C,SMLF,IA   I143 @T6G_MB_LIB.T6G(SCH_1):PAGE81

IRQ_CPU_BMC_NMI_N @T6G_MB_LIB.T6G(SCH_1):IRQ_CPU_BMC_NMI_N
   U26 DF40 AGPIO5||DEVSLP0||SATA_ZP0_L GENOA_SP5-SOCKET6096_13568-001,SMLF,IO,DGA^6000030   I182 @T6G_MB_LIB.T6G(SCH_1):PAGE55
  R187    1      A Q_RES_0402LF-0,5%,1/16W,CHIP,CS00002JB13    I68 @T6G_MB_LIB.T6G(SCH_1):PAGE81
 R5032    2      B Q_RES_0402LF-4.7K,5%,1/16W,EMPTY,CS24702JB10   I330 @T6G_MB_LIB.T6G(SCH_1):PAGE55
  R544    1      A Q_RES_0402LF-4.7K,5%,1/16W,CHIP,CS24702JB10   I336 @T6G_MB_LIB.T6G(SCH_1):PAGE55

IRQ_CPU_BMC_NMI_R_N @T6G_MB_LIB.T6G(SCH_1):IRQ_CPU_BMC_NMI_R_N
  R187    2      B Q_RES_0402LF-0,5%,1/16W,CHIP,CS00002JB13    I68 @T6G_MB_LIB.T6G(SCH_1):PAGE81
   U18   H7   PL3D LCMXO3LF9400C5BG484C-LCMXO3LF-9400C-5BG484C,SMLF,IA   I143 @T6G_MB_LIB.T6G(SCH_1):PAGE81

IRQ_HSC_FAULT @T6G_MB_LIB.T6G(SCH_1):IRQ_HSC_FAULT
 Q9003    6     D1 MOSFET_NCH_DUAL-PJT138K,SMLF,IC,BAM138K0003   I111 @T6G_MB_LIB.T6G(SCH_1):PAGE84
 R9026    2      B Q_RES_0402LF-4.7K,5%,1/16W,CHIP,CS24702JB10   I112 @T6G_MB_LIB.T6G(SCH_1):PAGE84
 Q9003    5     G2 MOSFET_NCH_DUAL-PJT138K,SMLF,IC,BAM138K0003   I121 @T6G_MB_LIB.T6G(SCH_1):PAGE84

IRQ_HSC_FAULT_BUF_N @T6G_MB_LIB.T6G(SCH_1):IRQ_HSC_FAULT_BUF_N
 R6095    2      B Q_RES_0402LF-0,5%,1/16W,CHIP,CS00002JB13   I112 @T6G_MB_LIB.T6G(SCH_1):PAGE79
 R9027    2      B Q_RES_0402LF-100K,1%,1/16W,CHIP,CS41002FB09   I114 @T6G_MB_LIB.T6G(SCH_1):PAGE84
 C9005    1      A Q_CAP_0402-0.1UF,25V,10%,X7R,CH4104K1B00   I116 @T6G_MB_LIB.T6G(SCH_1):PAGE84
 R9028    2      B Q_RES_0402LF-0,5%,1/16W,EMPTY,CS00002JB13   I118 @T6G_MB_LIB.T6G(SCH_1):PAGE84
 Q9003    3     D2 MOSFET_NCH_DUAL-PJT138K,SMLF,IC,BAM138K0003   I121 @T6G_MB_LIB.T6G(SCH_1):PAGE84

IRQ_HSC_FAULT_BUF_R_N @T6G_MB_LIB.T6G(SCH_1):IRQ_HSC_FAULT_BUF_R_N
   U18   B6  PT14A LCMXO3LF9400C5BG484C-LCMXO3LF-9400C-5BG484C,SMLF,IA    I94 @T6G_MB_LIB.T6G(SCH_1):PAGE79
 R6095    1      A Q_RES_0402LF-0,5%,1/16W,CHIP,CS00002JB13   I112 @T6G_MB_LIB.T6G(SCH_1):PAGE79

IRQ_HSC_FAULT_N @T6G_MB_LIB.T6G(SCH_1):IRQ_HSC_FAULT_N
 R2588    2      B Q_RES_0402LF-22,1%,1/16W,CHIP,CS02202FB02    I79 @T6G_MB_LIB.T6G(SCH_1):PAGE267
  PJ38   13     13 SCONN21_9193031121LF-SCONN21_91930-31121LF,SMLF,IOA    I42 @T6G_MB_LIB.T6G(SCH_1):PAGE371
 R9025    1      A Q_RES_0402LF-100K,1%,1/16W,EMPTY,CS41002FB09   I106 @T6G_MB_LIB.T6G(SCH_1):PAGE84
 Q9003    2     G1 MOSFET_NCH_DUAL-PJT138K,SMLF,IC,BAM138K0003   I111 @T6G_MB_LIB.T6G(SCH_1):PAGE84
 R9028    1      A Q_RES_0402LF-0,5%,1/16W,EMPTY,CS00002JB13   I118 @T6G_MB_LIB.T6G(SCH_1):PAGE84
 R2587    1      A Q_RES_0402LF-1K,1%,1/16W,CHIP,CS21002FB06    I99 @T6G_MB_LIB.T6G(SCH_1):PAGE267
 R9024    2      B Q_RES_0402LF-54.9K,1%,1/16W,CHIP,CS35492FB03   I113 @T6G_MB_LIB.T6G(SCH_1):PAGE371

IRQ_LVC3_OCP_SFF_WAKE_N @T6G_MB_LIB.T6G(SCH_1):IRQ_LVC3_OCP_SFF_WAKE_N
   J38  OA3  WAKE# SCONN168_ME1016810202011-SCONN168_ME1016810202011,A   I168 @T6G_MB_LIB.T6G(SCH_1):PAGE335
 U8082    2      A 74LVC1G126SE7-74LVC1G126SE-7,SMLF,IC,AL1G0126009     I8 @T6G_MB_LIB.T6G(SCH_1):PAGE337
 R1824    2      B Q_RES_0402LF-10K,1%,1/16W,CHIP,CS31002FB08    I11 @T6G_MB_LIB.T6G(SCH_1):PAGE337

IRQ_LVC3_OCP_V3_2_WAKE_N @T6G_MB_LIB.T6G(SCH_1):IRQ_LVC3_OCP_V3_2_WAKE_N
   J35  OA3  WAKE# SCONN168_ME1016810202011-SCONN168_ME1016810202011,A   I168 @T6G_MB_LIB.T6G(SCH_1):PAGE341
 R3182    2      B Q_RES_0402LF-10K,1%,1/16W,CHIP,CS31002FB08     I3 @T6G_MB_LIB.T6G(SCH_1):PAGE342
  U217    2      A 74LVC1G126SE7-74LVC1G126SE-7,SMLF,IC,AL1G0126009    I14 @T6G_MB_LIB.T6G(SCH_1):PAGE342

IRQ_LVC3_V3_2_WAKE_BUF_N @T6G_MB_LIB.T6G(SCH_1):IRQ_LVC3_V3_2_WAKE_BUF_N
 R3192    2      B Q_RES_0402LF-4.7K,1%,1/16W,EMPTY,CS24702FB06    I44 @T6G_MB_LIB.T6G(SCH_1):PAGE342
  U219    4      Y 74LVC1G07GV-74LVC1G07GV,SMLF,IC,AL1G0007001    I32 @T6G_MB_LIB.T6G(SCH_1):PAGE342
 R3193    1      A Q_RES_0402LF-33.2,1%,1/16W,CHIP,CS03322FB03    I43 @T6G_MB_LIB.T6G(SCH_1):PAGE342

IRQ_LVC3_WAKE @T6G_MB_LIB.T6G(SCH_1):IRQ_LVC3_WAKE
    Q4    6     D1 MOSFET_DUAL_6P-2N7002KDW,SMLF,IC,BAM70020047    I12 @T6G_MB_LIB.T6G(SCH_1):PAGE132
    Q4    5     G2 MOSFET_DUAL_6P-2N7002KDW,SMLF,IC,BAM70020047    I12 @T6G_MB_LIB.T6G(SCH_1):PAGE132
 R1009    2      B Q_RES_0402LF-10K,1%,1/16W,CHIP,CS31002FB08    I10 @T6G_MB_LIB.T6G(SCH_1):PAGE132

IRQ_LVC3_WAKE_BUF_N @T6G_MB_LIB.T6G(SCH_1):IRQ_LVC3_WAKE_BUF_N
 R2487    2      B Q_RES_0402LF-4.7K,1%,1/16W,EMPTY,CS24702FB06    I56 @T6G_MB_LIB.T6G(SCH_1):PAGE337
  U157    4      Y 74LVC1G07GV-74LVC1G07GV,SMLF,IC,AL1G0007001    I25 @T6G_MB_LIB.T6G(SCH_1):PAGE337
 R2489    1      A Q_RES_0402LF-33.2,1%,1/16W,CHIP,CS03322FB03    I50 @T6G_MB_LIB.T6G(SCH_1):PAGE337

IRQ_LVC3_WAKE_N @T6G_MB_LIB.T6G(SCH_1):IRQ_LVC3_WAKE_N
    Q4    2     G1 MOSFET_DUAL_6P-2N7002KDW,SMLF,IC,BAM70020047    I12 @T6G_MB_LIB.T6G(SCH_1):PAGE132
 R1005    2      B Q_RES_0402LF-33,5%,1/16W,CHIP,CS03302JB10     I4 @T6G_MB_LIB.T6G(SCH_1):PAGE132
  R116    2      B Q_RES_0402LF-33,5%,1/16W,CHIP,CS03302JB10     I5 @T6G_MB_LIB.T6G(SCH_1):PAGE132
 R6063    2      B Q_RES_0402LF-33,5%,1/16W,CHIP,CS03302JB10     I6 @T6G_MB_LIB.T6G(SCH_1):PAGE132
  R994    2      B Q_RES_0402LF-10K,1%,1/16W,CHIP,CS31002FB08     I7 @T6G_MB_LIB.T6G(SCH_1):PAGE132

IRQ_OCP_SFF_WAKE_BUF_N @T6G_MB_LIB.T6G(SCH_1):IRQ_OCP_SFF_WAKE_BUF_N
 R2489    2      B Q_RES_0402LF-33.2,1%,1/16W,CHIP,CS03322FB03    I50 @T6G_MB_LIB.T6G(SCH_1):PAGE337
  R116    1      A Q_RES_0402LF-33,5%,1/16W,CHIP,CS03302JB10     I5 @T6G_MB_LIB.T6G(SCH_1):PAGE132

IRQ_OCP_V3_2_WAKE_BUF_N @T6G_MB_LIB.T6G(SCH_1):IRQ_OCP_V3_2_WAKE_BUF_N
 R3193    2      B Q_RES_0402LF-33.2,1%,1/16W,CHIP,CS03322FB03    I43 @T6G_MB_LIB.T6G(SCH_1):PAGE342
 R6063    1      A Q_RES_0402LF-33,5%,1/16W,CHIP,CS03302JB10     I6 @T6G_MB_LIB.T6G(SCH_1):PAGE132

IRQ_SMI_ACTIVE_N @T6G_MB_LIB.T6G(SCH_1):IRQ_SMI_ACTIVE_N
  R245    1      A Q_RES_0402LF-0,5%,1/16W,CHIP,CS00002JB13    I67 @T6G_MB_LIB.T6G(SCH_1):PAGE81
 R5027    2      B Q_RES_0402LF-4.7K,5%,1/16W,EMPTY,CS24702JB10    I59 @T6G_MB_LIB.T6G(SCH_1):PAGE28
  R446    1      A Q_RES_0402LF-4.7K,5%,1/16W,CHIP,CS24702JB10    I64 @T6G_MB_LIB.T6G(SCH_1):PAGE28
   U25 DH16 AGPIO115||CLK_REQ11_L GENOA_SP5-SOCKET6096_13568-001,SMLF,IO,DGA^6000030   I188 @T6G_MB_LIB.T6G(SCH_1):PAGE28

IRQ_SMI_ACTIVE_N_R @T6G_MB_LIB.T6G(SCH_1):IRQ_SMI_ACTIVE_N_R
  R245    2      B Q_RES_0402LF-0,5%,1/16W,CHIP,CS00002JB13    I67 @T6G_MB_LIB.T6G(SCH_1):PAGE81
   U18   G5   PL4C LCMXO3LF9400C5BG484C-LCMXO3LF-9400C-5BG484C,SMLF,IA   I143 @T6G_MB_LIB.T6G(SCH_1):PAGE81

IRQ_SML1_PMBUS_ALERT @T6G_MB_LIB.T6G(SCH_1):IRQ_SML1_PMBUS_ALERT
 R3924    2      B Q_RES_0402LF-0,5%,1/16W,CHIP,CS00002JB13    I24 @T6G_MB_LIB.T6G(SCH_1):PAGE267
 R3925    1      A Q_RES_0402LF-1K,1%,1/16W,CHIP,CS21002FB06    I34 @T6G_MB_LIB.T6G(SCH_1):PAGE267
 PU289   10   ALT# MP5990GMA1111Z-MP5990GMA-1111-Z,SMLF,IC,AR0F0TP4023    I58 @T6G_MB_LIB.T6G(SCH_1):PAGE267

IRQ_SML1_PMBUS_ALERT_N @T6G_MB_LIB.T6G(SCH_1):IRQ_SML1_PMBUS_ALERT_N
   U18  B21 PT43B||R_GPLLC LCMXO3LF9400C5BG484C-LCMXO3LF-9400C-5BG484C,SMLF,IA    I94 @T6G_MB_LIB.T6G(SCH_1):PAGE79
 R3924    1      A Q_RES_0402LF-0,5%,1/16W,CHIP,CS00002JB13    I24 @T6G_MB_LIB.T6G(SCH_1):PAGE267
  PJ38   20     20 SCONN21_9193031121LF-SCONN21_91930-31121LF,SMLF,IOA    I42 @T6G_MB_LIB.T6G(SCH_1):PAGE371

IRQ_TPM_SPI_R1_N @T6G_MB_LIB.T6G(SCH_1):IRQ_TPM_SPI_R1_N
  R246    2      B Q_RES_0402LF-0,5%,1/16W,CHIP,CS00002JB13    I65 @T6G_MB_LIB.T6G(SCH_1):PAGE81
   U18   H6   PL4D LCMXO3LF9400C5BG484C-LCMXO3LF-9400C-5BG484C,SMLF,IA   I143 @T6G_MB_LIB.T6G(SCH_1):PAGE81

IRQ_TPM_SPI_R_N @T6G_MB_LIB.T6G(SCH_1):IRQ_TPM_SPI_R_N
  R246    1      A Q_RES_0402LF-0,5%,1/16W,CHIP,CS00002JB13    I65 @T6G_MB_LIB.T6G(SCH_1):PAGE81
 R5029    2      B Q_RES_0402LF-4.7K,5%,1/16W,EMPTY,CS24702JB10    I62 @T6G_MB_LIB.T6G(SCH_1):PAGE28
  R447    1      A Q_RES_0402LF-4.7K,5%,1/16W,CHIP,CS24702JB10    I65 @T6G_MB_LIB.T6G(SCH_1):PAGE28
   U25 DH15 AGPIO116||CLK_REQ12_L GENOA_SP5-SOCKET6096_13568-001,SMLF,IO,DGA^6000030   I188 @T6G_MB_LIB.T6G(SCH_1):PAGE28

IRQ_UV_DETECT_N @T6G_MB_LIB.T6G(SCH_1):IRQ_UV_DETECT_N
 R6038    2      B Q_RES_0402LF-0,5%,1/16W,CHIP,CS00002JB13    I21 @T6G_MB_LIB.T6G(SCH_1):PAGE79
  U325    D  DRAIN MOSFET_N_SMLF-BSS138K,BSS138K,EMPTY,BAM138K0000    I42 @T6G_MB_LIB.T6G(SCH_1):PAGE372
 R4620    2      B Q_RES_0402LF-1K,1%,1/16W,EMPTY,CS21002FB06    I46 @T6G_MB_LIB.T6G(SCH_1):PAGE372
 R8124    2      B Q_RES_0402LF-33.2,1%,1/16W,CHIP,CS03322FB03    I85 @T6G_MB_LIB.T6G(SCH_1):PAGE372
 R8125    2      B Q_RES_0402LF-1K,1%,1/16W,CHIP,CS21002FB06   I104 @T6G_MB_LIB.T6G(SCH_1):PAGE372

IRQ_UV_DETECT_R2_N @T6G_MB_LIB.T6G(SCH_1):IRQ_UV_DETECT_R2_N
 U8010    4 OUTPUT AP331AWG7-AP331AWG-7,SMLF,IC,AL000331011    I80 @T6G_MB_LIB.T6G(SCH_1):PAGE372
 R8123    2      B Q_RES_0402LF-1M,1%,1/16W,CHIP,CS51002FB05    I81 @T6G_MB_LIB.T6G(SCH_1):PAGE372
 R8124    1      A Q_RES_0402LF-33.2,1%,1/16W,CHIP,CS03322FB03    I85 @T6G_MB_LIB.T6G(SCH_1):PAGE372

IRQ_WAKE_N @T6G_MB_LIB.T6G(SCH_1):IRQ_WAKE_N
   U26 DJ10 WAKE_L||AGPIO2 GENOA_SP5-SOCKET6096_13568-001,SMLF,IO,DGA^6000030   I182 @T6G_MB_LIB.T6G(SCH_1):PAGE55
   U25 DJ10 WAKE_L||AGPIO2 GENOA_SP5-SOCKET6096_13568-001,SMLF,IO,DGA^6000030   I188 @T6G_MB_LIB.T6G(SCH_1):PAGE28
 R1311    2      B Q_RES_0402LF-33,5%,1/16W,CHIP,CS03302JB10    I16 @T6G_MB_LIB.T6G(SCH_1):PAGE132
  R437    2      B Q_RES_0402LF-2.2K,5%,1/16W,CHIP,CS22202JB07    I18 @T6G_MB_LIB.T6G(SCH_1):PAGE132

IRQ_WAKE_R_N @T6G_MB_LIB.T6G(SCH_1):IRQ_WAKE_R_N
    Q4    3     D2 MOSFET_DUAL_6P-2N7002KDW,SMLF,IC,BAM70020047    I12 @T6G_MB_LIB.T6G(SCH_1):PAGE132
 R1311    1      A Q_RES_0402LF-33,5%,1/16W,CHIP,CS03302JB10    I16 @T6G_MB_LIB.T6G(SCH_1):PAGE132

JTAG_BMC_OE @T6G_MB_LIB.T6G(SCH_1):JTAG_BMC_OE
  U124    4      Y SN74LVC1G07DBVR_SMLF-SN74LVC1G07DBVR,IC,AL1G0007024    I38 @T6G_MB_LIB.T6G(SCH_1):PAGE144
 R1619    1      A Q_RES_0402LF-0,5%,1/16W,CHIP,CS00002JB13    I92 @T6G_MB_LIB.T6G(SCH_1):PAGE149
   Q62    G   GATE MOSFET_N_SMLF-BSS138K,BSS138K,IC,BAM138K0000   I102 @T6G_MB_LIB.T6G(SCH_1):PAGE149
    R8    2      B Q_RES_0402LF-100K,1%,1/16W,CHIP,CS41002FB09    I47 @T6G_MB_LIB.T6G(SCH_1):PAGE144

JTAG_BMC_OE_N @T6G_MB_LIB.T6G(SCH_1):JTAG_BMC_OE_N
  U147    2   OE_# SN74AVC2T245RSWR-SN74AVC2T245RSWR,SMLF,IC,AL02T245A     I1 @T6G_MB_LIB.T6G(SCH_1):PAGE149
  U148    9     OE SN74AVC4T774PWR-SN74AVC4T774PWR,SMLF,IC,AL04T774K00    I34 @T6G_MB_LIB.T6G(SCH_1):PAGE149
 R1622    2      B Q_RES_0402LF-4.7K,5%,1/16W,CHIP,CS24702JB10    I83 @T6G_MB_LIB.T6G(SCH_1):PAGE149
   Q62    D  DRAIN MOSFET_N_SMLF-BSS138K,BSS138K,IC,BAM138K0000   I102 @T6G_MB_LIB.T6G(SCH_1):PAGE149

JTAG_BMC_R_D_OE @T6G_MB_LIB.T6G(SCH_1):JTAG_BMC_R_D_OE
  U149    9     OE SN74AVC4T774PWR-SN74AVC4T774PWR,SMLF,IC,AL04T774K00    I31 @T6G_MB_LIB.T6G(SCH_1):PAGE149
  U146    2   OE_# SN74AVC2T245RSWR-SN74AVC2T245RSWR,SMLF,IC,AL02T245A    I76 @T6G_MB_LIB.T6G(SCH_1):PAGE149
 R1619    2      B Q_RES_0402LF-0,5%,1/16W,CHIP,CS00002JB13    I92 @T6G_MB_LIB.T6G(SCH_1):PAGE149
  R617    2      B Q_RES_0402LF-4.7K,5%,1/16W,CHIP,CS24702JB10   I101 @T6G_MB_LIB.T6G(SCH_1):PAGE149
 C8006    1      A Q_CAP_0402-0.1UF,25V,10%,X7R,CH4104K1B00   I163 @T6G_MB_LIB.T6G(SCH_1):PAGE149

JTAG_CPU0_BYPASS @T6G_MB_LIB.T6G(SCH_1):JTAG_CPU0_BYPASS
  U153    6     2B SN74AUC2G66DCTR-SN74AUC2G66DCTR,SMLF,IC,AL2G0066C00     I1 @T6G_MB_LIB.T6G(SCH_1):PAGE151
 R6104    1      A Q_RES_0402LF-0,5%,1/16W,CHIP,CS00002JB13    I48 @T6G_MB_LIB.T6G(SCH_1):PAGE151

JTAG_CPU0_BYPASS_R1 @T6G_MB_LIB.T6G(SCH_1):JTAG_CPU0_BYPASS_R1
   U13    5     2A SN74AUC2G66DCTR-SN74AUC2G66DCTR,SMLF,IC,AL2G0066C00    I17 @T6G_MB_LIB.T6G(SCH_1):PAGE151
 R6104    2      B Q_RES_0402LF-0,5%,1/16W,CHIP,CS00002JB13    I48 @T6G_MB_LIB.T6G(SCH_1):PAGE151

JTAG_CPU0_DBREQ_N @T6G_MB_LIB.T6G(SCH_1):JTAG_CPU0_DBREQ_N
   U25  C16 DBREQ_L GENOA_SP5-SOCKET6096_13568-001,SMLF,IO,DGA^6000030   I227 @T6G_MB_LIB.T6G(SCH_1):PAGE27
  R403    2      B Q_RES_0402LF-1K,1%,1/16W,CHIP,CS21002FB06   I294 @T6G_MB_LIB.T6G(SCH_1):PAGE27
  C212    1      A Q_CAP_C0402-0.001UF,50V,10%,EMPTY,CH30106KB19   I295 @T6G_MB_LIB.T6G(SCH_1):PAGE27
 R1641    2      B Q_RES_0402LF-22,1%,1/16W,CHIP,CS02202FB02    I24 @T6G_MB_LIB.T6G(SCH_1):PAGE150

JTAG_CPU0_R_TDI @T6G_MB_LIB.T6G(SCH_1):JTAG_CPU0_R_TDI
  U153    2     1B SN74AUC2G66DCTR-SN74AUC2G66DCTR,SMLF,IC,AL2G0066C00     I1 @T6G_MB_LIB.T6G(SCH_1):PAGE151
 R1648    1      A Q_RES_0402LF-0,5%,1/16W,CHIP,CS00002JB13     I2 @T6G_MB_LIB.T6G(SCH_1):PAGE151

JTAG_CPU0_R_TDO @T6G_MB_LIB.T6G(SCH_1):JTAG_CPU0_R_TDO
  R404    1      A Q_RES_0402LF-0,5%,1/16W,CHIP,CS00002JB13   I170 @T6G_MB_LIB.T6G(SCH_1):PAGE27
   U25  C18    TDO GENOA_SP5-SOCKET6096_13568-001,SMLF,IO,DGA^6000030   I227 @T6G_MB_LIB.T6G(SCH_1):PAGE27

JTAG_CPU0_TCK @T6G_MB_LIB.T6G(SCH_1):JTAG_CPU0_TCK
   U25  B17    TCK GENOA_SP5-SOCKET6096_13568-001,SMLF,IO,DGA^6000030   I227 @T6G_MB_LIB.T6G(SCH_1):PAGE27
  R401    2      B Q_RES_0402LF-1K,1%,1/16W,CHIP,CS21002FB06   I300 @T6G_MB_LIB.T6G(SCH_1):PAGE27
  C210    1      A Q_CAP_C0402-0.001UF,50V,10%,EMPTY,CH30106KB19   I302 @T6G_MB_LIB.T6G(SCH_1):PAGE27
 R1638    2      B Q_RES_0402LF-22,1%,1/16W,CHIP,CS02202FB02    I27 @T6G_MB_LIB.T6G(SCH_1):PAGE150

JTAG_CPU0_TDI @T6G_MB_LIB.T6G(SCH_1):JTAG_CPU0_TDI
   U25  C17    TDI GENOA_SP5-SOCKET6096_13568-001,SMLF,IO,DGA^6000030   I227 @T6G_MB_LIB.T6G(SCH_1):PAGE27
  R399    2      B Q_RES_0402LF-1K,1%,1/16W,CHIP,CS21002FB06   I304 @T6G_MB_LIB.T6G(SCH_1):PAGE27
  C208    1      A Q_CAP_C0402-0.001UF,50V,10%,EMPTY,CH30106KB19   I306 @T6G_MB_LIB.T6G(SCH_1):PAGE27
 R1648    2      B Q_RES_0402LF-0,5%,1/16W,CHIP,CS00002JB13     I2 @T6G_MB_LIB.T6G(SCH_1):PAGE151
 C1520    1      A Q_CAP_C0402-0.01UF,50V,10%,EMPTY,CH31006KB18     I4 @T6G_MB_LIB.T6G(SCH_1):PAGE151

JTAG_CPU0_TDO @T6G_MB_LIB.T6G(SCH_1):JTAG_CPU0_TDO
  R404    2      B Q_RES_0402LF-0,5%,1/16W,CHIP,CS00002JB13   I170 @T6G_MB_LIB.T6G(SCH_1):PAGE27
  R398    2      B Q_RES_0402LF-1K,1%,1/16W,CHIP,CS21002FB06   I305 @T6G_MB_LIB.T6G(SCH_1):PAGE27
  C207    1      A Q_CAP_C0402-0.001UF,50V,10%,EMPTY,CH30106KB19   I307 @T6G_MB_LIB.T6G(SCH_1):PAGE27
   U13    1     1A SN74AUC2G66DCTR-SN74AUC2G66DCTR,SMLF,IC,AL2G0066C00    I17 @T6G_MB_LIB.T6G(SCH_1):PAGE151

JTAG_CPU0_TDO_CPU1_TDI @T6G_MB_LIB.T6G(SCH_1):JTAG_CPU0_TDO_CPU1_TDI
   U13    2     1B SN74AUC2G66DCTR-SN74AUC2G66DCTR,SMLF,IC,AL2G0066C00    I17 @T6G_MB_LIB.T6G(SCH_1):PAGE151
   U14    1     1A SN74AUC2G66DCTR-SN74AUC2G66DCTR,SMLF,IC,AL2G0066C00    I23 @T6G_MB_LIB.T6G(SCH_1):PAGE151
   U14    5     2A SN74AUC2G66DCTR-SN74AUC2G66DCTR,SMLF,IC,AL2G0066C00    I23 @T6G_MB_LIB.T6G(SCH_1):PAGE151
 R6105    2      B Q_RES_0402LF-0,5%,1/16W,CHIP,CS00002JB13    I49 @T6G_MB_LIB.T6G(SCH_1):PAGE151

JTAG_CPU0_TDO_CPU1_TDI_R1 @T6G_MB_LIB.T6G(SCH_1):JTAG_CPU0_TDO_CPU1_TDI_R1
   U13    6     2B SN74AUC2G66DCTR-SN74AUC2G66DCTR,SMLF,IC,AL2G0066C00    I17 @T6G_MB_LIB.T6G(SCH_1):PAGE151
 R6105    1      A Q_RES_0402LF-0,5%,1/16W,CHIP,CS00002JB13    I49 @T6G_MB_LIB.T6G(SCH_1):PAGE151

JTAG_CPU0_TMS @T6G_MB_LIB.T6G(SCH_1):JTAG_CPU0_TMS
   U25  A16    TMS GENOA_SP5-SOCKET6096_13568-001,SMLF,IO,DGA^6000030   I227 @T6G_MB_LIB.T6G(SCH_1):PAGE27
  R402    2      B Q_RES_0402LF-1K,1%,1/16W,CHIP,CS21002FB06   I296 @T6G_MB_LIB.T6G(SCH_1):PAGE27
  C211    1      A Q_CAP_C0402-0.001UF,50V,10%,EMPTY,CH30106KB19   I297 @T6G_MB_LIB.T6G(SCH_1):PAGE27
 R1639    2      B Q_RES_0402LF-22,1%,1/16W,CHIP,CS02202FB02    I25 @T6G_MB_LIB.T6G(SCH_1):PAGE150

JTAG_CPU0_TRST_N @T6G_MB_LIB.T6G(SCH_1):JTAG_CPU0_TRST_N
   U25  A17 TRST_L GENOA_SP5-SOCKET6096_13568-001,SMLF,IO,DGA^6000030   I227 @T6G_MB_LIB.T6G(SCH_1):PAGE27
  R400    2      B Q_RES_0402LF-1K,1%,1/16W,CHIP,CS21002FB06   I301 @T6G_MB_LIB.T6G(SCH_1):PAGE27
  C209    1      A Q_CAP_C0402-0.001UF,50V,10%,EMPTY,CH30106KB19   I303 @T6G_MB_LIB.T6G(SCH_1):PAGE27
 R1640    2      B Q_RES_0402LF-22,1%,1/16W,CHIP,CS02202FB02    I26 @T6G_MB_LIB.T6G(SCH_1):PAGE150

JTAG_CPU1_BYPASS @T6G_MB_LIB.T6G(SCH_1):JTAG_CPU1_BYPASS
   U14    6     2B SN74AUC2G66DCTR-SN74AUC2G66DCTR,SMLF,IC,AL2G0066C00    I23 @T6G_MB_LIB.T6G(SCH_1):PAGE151
  U154    5     2A SN74AUC2G66DCTR-SN74AUC2G66DCTR,SMLF,IC,AL2G0066C00    I31 @T6G_MB_LIB.T6G(SCH_1):PAGE151

JTAG_CPU1_DBREQ_N @T6G_MB_LIB.T6G(SCH_1):JTAG_CPU1_DBREQ_N
   U26  C16 DBREQ_L GENOA_SP5-SOCKET6096_13568-001,SMLF,IO,DGA^6000030   I190 @T6G_MB_LIB.T6G(SCH_1):PAGE54
  R528    2      B Q_RES_0402LF-1K,1%,1/16W,CHIP,CS21002FB06   I308 @T6G_MB_LIB.T6G(SCH_1):PAGE54
  C235    1      A Q_CAP_C0402-0.001UF,50V,10%,EMPTY,CH30106KB19   I310 @T6G_MB_LIB.T6G(SCH_1):PAGE54
 R1645    2      B Q_RES_0402LF-22,1%,1/16W,CHIP,CS02202FB02    I36 @T6G_MB_LIB.T6G(SCH_1):PAGE150

JTAG_CPU1_R_TDI @T6G_MB_LIB.T6G(SCH_1):JTAG_CPU1_R_TDI
   U14    2     1B SN74AUC2G66DCTR-SN74AUC2G66DCTR,SMLF,IC,AL2G0066C00    I23 @T6G_MB_LIB.T6G(SCH_1):PAGE151
 R1651    1      A Q_RES_0402LF-0,5%,1/16W,CHIP,CS00002JB13    I34 @T6G_MB_LIB.T6G(SCH_1):PAGE151

JTAG_CPU1_R_TDO @T6G_MB_LIB.T6G(SCH_1):JTAG_CPU1_R_TDO
   U26  C18    TDO GENOA_SP5-SOCKET6096_13568-001,SMLF,IO,DGA^6000030   I190 @T6G_MB_LIB.T6G(SCH_1):PAGE54
  R529    1      A Q_RES_0402LF-0,5%,1/16W,CHIP,CS00002JB13   I203 @T6G_MB_LIB.T6G(SCH_1):PAGE54

JTAG_CPU1_TCK @T6G_MB_LIB.T6G(SCH_1):JTAG_CPU1_TCK
   U26  B17    TCK GENOA_SP5-SOCKET6096_13568-001,SMLF,IO,DGA^6000030   I190 @T6G_MB_LIB.T6G(SCH_1):PAGE54
  R526    2      B Q_RES_0402LF-1K,1%,1/16W,CHIP,CS21002FB06   I314 @T6G_MB_LIB.T6G(SCH_1):PAGE54
  C233    1      A Q_CAP_C0402-0.001UF,50V,10%,EMPTY,CH30106KB19   I315 @T6G_MB_LIB.T6G(SCH_1):PAGE54
 R1642    2      B Q_RES_0402LF-22,1%,1/16W,CHIP,CS02202FB02    I33 @T6G_MB_LIB.T6G(SCH_1):PAGE150

JTAG_CPU1_TDI @T6G_MB_LIB.T6G(SCH_1):JTAG_CPU1_TDI
   U26  C17    TDI GENOA_SP5-SOCKET6096_13568-001,SMLF,IO,DGA^6000030   I190 @T6G_MB_LIB.T6G(SCH_1):PAGE54
  R524    2      B Q_RES_0402LF-1K,1%,1/16W,CHIP,CS21002FB06   I317 @T6G_MB_LIB.T6G(SCH_1):PAGE54
  C231    1      A Q_CAP_C0402-0.001UF,50V,10%,EMPTY,CH30106KB19   I319 @T6G_MB_LIB.T6G(SCH_1):PAGE54
 R1651    2      B Q_RES_0402LF-0,5%,1/16W,CHIP,CS00002JB13    I34 @T6G_MB_LIB.T6G(SCH_1):PAGE151

JTAG_CPU1_TDO @T6G_MB_LIB.T6G(SCH_1):JTAG_CPU1_TDO
  R529    2      B Q_RES_0402LF-0,5%,1/16W,CHIP,CS00002JB13   I203 @T6G_MB_LIB.T6G(SCH_1):PAGE54
  R523    2      B Q_RES_0402LF-1K,1%,1/16W,CHIP,CS21002FB06   I324 @T6G_MB_LIB.T6G(SCH_1):PAGE54
  C230    1      A Q_CAP_C0402-0.001UF,50V,10%,EMPTY,CH30106KB19   I325 @T6G_MB_LIB.T6G(SCH_1):PAGE54
  U154    1     1A SN74AUC2G66DCTR-SN74AUC2G66DCTR,SMLF,IC,AL2G0066C00    I31 @T6G_MB_LIB.T6G(SCH_1):PAGE151

JTAG_CPU1_TMS @T6G_MB_LIB.T6G(SCH_1):JTAG_CPU1_TMS
   U26  A16    TMS GENOA_SP5-SOCKET6096_13568-001,SMLF,IO,DGA^6000030   I190 @T6G_MB_LIB.T6G(SCH_1):PAGE54
  R527    2      B Q_RES_0402LF-1K,1%,1/16W,CHIP,CS21002FB06   I309 @T6G_MB_LIB.T6G(SCH_1):PAGE54
  C234    1      A Q_CAP_C0402-0.001UF,50V,10%,EMPTY,CH30106KB19   I311 @T6G_MB_LIB.T6G(SCH_1):PAGE54
 R1643    2      B Q_RES_0402LF-22,1%,1/16W,CHIP,CS02202FB02    I34 @T6G_MB_LIB.T6G(SCH_1):PAGE150

JTAG_CPU1_TRST_N @T6G_MB_LIB.T6G(SCH_1):JTAG_CPU1_TRST_N
   U26  A17 TRST_L GENOA_SP5-SOCKET6096_13568-001,SMLF,IO,DGA^6000030   I190 @T6G_MB_LIB.T6G(SCH_1):PAGE54
  R525    2      B Q_RES_0402LF-1K,1%,1/16W,CHIP,CS21002FB06   I316 @T6G_MB_LIB.T6G(SCH_1):PAGE54
  C232    1      A Q_CAP_C0402-0.001UF,50V,10%,EMPTY,CH30106KB19   I318 @T6G_MB_LIB.T6G(SCH_1):PAGE54
 R1644    2      B Q_RES_0402LF-22,1%,1/16W,CHIP,CS02202FB02    I35 @T6G_MB_LIB.T6G(SCH_1):PAGE150

JTAG_CPUX_TDI @T6G_MB_LIB.T6G(SCH_1):JTAG_CPUX_TDI
  U153    1     1A SN74AUC2G66DCTR-SN74AUC2G66DCTR,SMLF,IC,AL2G0066C00     I1 @T6G_MB_LIB.T6G(SCH_1):PAGE151
  U153    5     2A SN74AUC2G66DCTR-SN74AUC2G66DCTR,SMLF,IC,AL2G0066C00     I1 @T6G_MB_LIB.T6G(SCH_1):PAGE151
 R6103    2      B Q_RES_0402LF-0,5%,1/16W,CHIP,CS00002JB13    I76 @T6G_MB_LIB.T6G(SCH_1):PAGE150

JTAG_CPUX_TDI_R1 @T6G_MB_LIB.T6G(SCH_1):JTAG_CPUX_TDI_R1
  U152    5     B1 SN74AVC2T245RSWR-SN74AVC2T245RSWR,SMLF,IC,AL02T245A    I60 @T6G_MB_LIB.T6G(SCH_1):PAGE150
 R6103    1      A Q_RES_0402LF-0,5%,1/16W,CHIP,CS00002JB13    I76 @T6G_MB_LIB.T6G(SCH_1):PAGE150

JTAG_CPUX_TDO @T6G_MB_LIB.T6G(SCH_1):JTAG_CPUX_TDO
  U152    4     B2 SN74AVC2T245RSWR-SN74AVC2T245RSWR,SMLF,IC,AL02T245A    I60 @T6G_MB_LIB.T6G(SCH_1):PAGE150
 R6110    2      B Q_RES_0402LF-0,5%,1/16W,CHIP,CS00002JB13    I50 @T6G_MB_LIB.T6G(SCH_1):PAGE151

JTAG_CPUX_TDO_R @T6G_MB_LIB.T6G(SCH_1):JTAG_CPUX_TDO_R
  U154    2     1B SN74AUC2G66DCTR-SN74AUC2G66DCTR,SMLF,IC,AL2G0066C00    I31 @T6G_MB_LIB.T6G(SCH_1):PAGE151
  U154    6     2B SN74AUC2G66DCTR-SN74AUC2G66DCTR,SMLF,IC,AL2G0066C00    I31 @T6G_MB_LIB.T6G(SCH_1):PAGE151
 R6110    1      A Q_RES_0402LF-0,5%,1/16W,CHIP,CS00002JB13    I50 @T6G_MB_LIB.T6G(SCH_1):PAGE151

JTAG_DBREQ_N @T6G_MB_LIB.T6G(SCH_1):JTAG_DBREQ_N
 R1636    2      B Q_RES_0402LF-22,1%,1/16W,CHIP,CS02202FB02     I9 @T6G_MB_LIB.T6G(SCH_1):PAGE149
 C1512    1      A Q_CAP_0402-33PF,50V,5%,NPO,TMP_QCH03306JB04    I21 @T6G_MB_LIB.T6G(SCH_1):PAGE149
  U150    6     A4 SN74AVC4T774PWR-SN74AVC4T774PWR,SMLF,IC,AL04T774K00     I8 @T6G_MB_LIB.T6G(SCH_1):PAGE150
  U151    6     A4 SN74AVC4T774PWR-SN74AVC4T774PWR,SMLF,IC,AL04T774K00    I28 @T6G_MB_LIB.T6G(SCH_1):PAGE150

JTAG_DBREQ_R_N @T6G_MB_LIB.T6G(SCH_1):JTAG_DBREQ_R_N
 R1636    1      A Q_RES_0402LF-22,1%,1/16W,CHIP,CS02202FB02     I9 @T6G_MB_LIB.T6G(SCH_1):PAGE149
  U149   11     B4 SN74AVC4T774PWR-SN74AVC4T774PWR,SMLF,IC,AL04T774K00    I31 @T6G_MB_LIB.T6G(SCH_1):PAGE149
  U148   11     B4 SN74AVC4T774PWR-SN74AVC4T774PWR,SMLF,IC,AL04T774K00    I34 @T6G_MB_LIB.T6G(SCH_1):PAGE149

JTAG_P0_R_DBREQ_N @T6G_MB_LIB.T6G(SCH_1):JTAG_P0_R_DBREQ_N
  U150   11     B4 SN74AVC4T774PWR-SN74AVC4T774PWR,SMLF,IC,AL04T774K00     I8 @T6G_MB_LIB.T6G(SCH_1):PAGE150
 R1641    1      A Q_RES_0402LF-22,1%,1/16W,CHIP,CS02202FB02    I24 @T6G_MB_LIB.T6G(SCH_1):PAGE150

JTAG_P0_R_TCK @T6G_MB_LIB.T6G(SCH_1):JTAG_P0_R_TCK
  U150   14     B1 SN74AVC4T774PWR-SN74AVC4T774PWR,SMLF,IC,AL04T774K00     I8 @T6G_MB_LIB.T6G(SCH_1):PAGE150
 R1638    1      A Q_RES_0402LF-22,1%,1/16W,CHIP,CS02202FB02    I27 @T6G_MB_LIB.T6G(SCH_1):PAGE150

JTAG_P0_R_TMS @T6G_MB_LIB.T6G(SCH_1):JTAG_P0_R_TMS
  U150   13     B2 SN74AVC4T774PWR-SN74AVC4T774PWR,SMLF,IC,AL04T774K00     I8 @T6G_MB_LIB.T6G(SCH_1):PAGE150
 R1639    1      A Q_RES_0402LF-22,1%,1/16W,CHIP,CS02202FB02    I25 @T6G_MB_LIB.T6G(SCH_1):PAGE150

JTAG_P0_R_TRST_N @T6G_MB_LIB.T6G(SCH_1):JTAG_P0_R_TRST_N
  U150   12     B3 SN74AVC4T774PWR-SN74AVC4T774PWR,SMLF,IC,AL04T774K00     I8 @T6G_MB_LIB.T6G(SCH_1):PAGE150
 R1640    1      A Q_RES_0402LF-22,1%,1/16W,CHIP,CS02202FB02    I26 @T6G_MB_LIB.T6G(SCH_1):PAGE150

JTAG_P1_R_DBREQ_N @T6G_MB_LIB.T6G(SCH_1):JTAG_P1_R_DBREQ_N
  U151   11     B4 SN74AVC4T774PWR-SN74AVC4T774PWR,SMLF,IC,AL04T774K00    I28 @T6G_MB_LIB.T6G(SCH_1):PAGE150
 R1645    1      A Q_RES_0402LF-22,1%,1/16W,CHIP,CS02202FB02    I36 @T6G_MB_LIB.T6G(SCH_1):PAGE150

JTAG_P1_R_TCK @T6G_MB_LIB.T6G(SCH_1):JTAG_P1_R_TCK
  U151   14     B1 SN74AVC4T774PWR-SN74AVC4T774PWR,SMLF,IC,AL04T774K00    I28 @T6G_MB_LIB.T6G(SCH_1):PAGE150
 R1642    1      A Q_RES_0402LF-22,1%,1/16W,CHIP,CS02202FB02    I33 @T6G_MB_LIB.T6G(SCH_1):PAGE150

JTAG_P1_R_TMS @T6G_MB_LIB.T6G(SCH_1):JTAG_P1_R_TMS
  U151   13     B2 SN74AVC4T774PWR-SN74AVC4T774PWR,SMLF,IC,AL04T774K00    I28 @T6G_MB_LIB.T6G(SCH_1):PAGE150
 R1643    1      A Q_RES_0402LF-22,1%,1/16W,CHIP,CS02202FB02    I34 @T6G_MB_LIB.T6G(SCH_1):PAGE150

JTAG_P1_R_TRST_N @T6G_MB_LIB.T6G(SCH_1):JTAG_P1_R_TRST_N
  U151   12     B3 SN74AVC4T774PWR-SN74AVC4T774PWR,SMLF,IC,AL04T774K00    I28 @T6G_MB_LIB.T6G(SCH_1):PAGE150
 R1644    1      A Q_RES_0402LF-22,1%,1/16W,CHIP,CS02202FB02    I35 @T6G_MB_LIB.T6G(SCH_1):PAGE150

JTAG_PLD_TCK @T6G_MB_LIB.T6G(SCH_1):JTAG_PLD_TCK
   J57    8      8 CONN8_HBB1081L200D8H-CONN8_HBB1081-L200D-8H,THLF,IA    I41 @T6G_MB_LIB.T6G(SCH_1):PAGE84
   R15    1      A Q_RES_0402LF-0,5%,1/16W,CHIP,CS00002JB13    I35 @T6G_MB_LIB.T6G(SCH_1):PAGE84

JTAG_PLD_TDI @T6G_MB_LIB.T6G(SCH_1):JTAG_PLD_TDI
    R9    1      A Q_RES_0402LF-0,5%,1/16W,CHIP,CS00002JB13    I37 @T6G_MB_LIB.T6G(SCH_1):PAGE84
   J57    2      2 CONN8_HBB1081L200D8H-CONN8_HBB1081-L200D-8H,THLF,IA    I41 @T6G_MB_LIB.T6G(SCH_1):PAGE84

JTAG_PLD_TDO @T6G_MB_LIB.T6G(SCH_1):JTAG_PLD_TDO
   R13    1      A Q_RES_0402LF-0,5%,1/16W,CHIP,CS00002JB13    I38 @T6G_MB_LIB.T6G(SCH_1):PAGE84
   J57    3      3 CONN8_HBB1081L200D8H-CONN8_HBB1081-L200D-8H,THLF,IA    I41 @T6G_MB_LIB.T6G(SCH_1):PAGE84

JTAG_PLD_TMS @T6G_MB_LIB.T6G(SCH_1):JTAG_PLD_TMS
   R14    1      A Q_RES_0402LF-0,5%,1/16W,CHIP,CS00002JB13    I36 @T6G_MB_LIB.T6G(SCH_1):PAGE84
   J57    6      6 CONN8_HBB1081L200D8H-CONN8_HBB1081-L200D-8H,THLF,IA    I41 @T6G_MB_LIB.T6G(SCH_1):PAGE84

JTAG_SCM_DBREQ_N @T6G_MB_LIB.T6G(SCH_1):JTAG_SCM_DBREQ_N
  U148    6     A4 SN74AVC4T774PWR-SN74AVC4T774PWR,SMLF,IC,AL04T774K00    I34 @T6G_MB_LIB.T6G(SCH_1):PAGE149
 R6032    1      A Q_RES_0402LF-0,5%,1/16W,CHIP,CS00002JB13    I28 @T6G_MB_LIB.T6G(SCH_1):PAGE348
 R6070    2      B Q_RES_0402LF-4.7K,5%,1/16W,EMPTY,CS24702JB10   I161 @T6G_MB_LIB.T6G(SCH_1):PAGE349

JTAG_SCM_MUX_R_TCK @T6G_MB_LIB.T6G(SCH_1):JTAG_SCM_MUX_R_TCK
  U160   14    1Y1 74LV4052PW-74LV4052PW,SMLF,IC,ALLV4052K19   I266 @T6G_MB_LIB.T6G(SCH_1):PAGE148
 R1736    1      A Q_RES_0402LF-0,5%,1/16W,CHIP,CS00002JB13   I363 @T6G_MB_LIB.T6G(SCH_1):PAGE148

JTAG_SCM_MUX_R_TDI @T6G_MB_LIB.T6G(SCH_1):JTAG_SCM_MUX_R_TDI
  U212   14    1Y1 74LV4052PW-74LV4052PW,SMLF,IC,ALLV4052K19   I302 @T6G_MB_LIB.T6G(SCH_1):PAGE148
 R1738    1      A Q_RES_0402LF-0,5%,1/16W,CHIP,CS00002JB13   I349 @T6G_MB_LIB.T6G(SCH_1):PAGE148

JTAG_SCM_MUX_R_TDO @T6G_MB_LIB.T6G(SCH_1):JTAG_SCM_MUX_R_TDO
  U212    5    2Y1 74LV4052PW-74LV4052PW,SMLF,IC,ALLV4052K19   I302 @T6G_MB_LIB.T6G(SCH_1):PAGE148
 R1739    1      A Q_RES_0402LF-0,5%,1/16W,CHIP,CS00002JB13   I388 @T6G_MB_LIB.T6G(SCH_1):PAGE148

JTAG_SCM_MUX_R_TMS @T6G_MB_LIB.T6G(SCH_1):JTAG_SCM_MUX_R_TMS
  U160    5    2Y1 74LV4052PW-74LV4052PW,SMLF,IC,ALLV4052K19   I266 @T6G_MB_LIB.T6G(SCH_1):PAGE148
 R1737    1      A Q_RES_0402LF-0,5%,1/16W,CHIP,CS00002JB13   I357 @T6G_MB_LIB.T6G(SCH_1):PAGE148

JTAG_SCM_MUX_TCK @T6G_MB_LIB.T6G(SCH_1):JTAG_SCM_MUX_TCK
 R1747    2      B Q_RES_0402LF-10K,1%,1/16W,CHIP,CS31002FB08   I255 @T6G_MB_LIB.T6G(SCH_1):PAGE148
 R1748    1      A Q_RES_0402LF-10K,1%,1/16W,EMPTY,CS31002FB08   I258 @T6G_MB_LIB.T6G(SCH_1):PAGE148
 R1736    2      B Q_RES_0402LF-0,5%,1/16W,CHIP,CS00002JB13   I363 @T6G_MB_LIB.T6G(SCH_1):PAGE148
  U148    3     A1 SN74AVC4T774PWR-SN74AVC4T774PWR,SMLF,IC,AL04T774K00    I34 @T6G_MB_LIB.T6G(SCH_1):PAGE149

JTAG_SCM_MUX_TDI @T6G_MB_LIB.T6G(SCH_1):JTAG_SCM_MUX_TDI
 R1744    2      B Q_RES_0402LF-10K,1%,1/16W,CHIP,CS31002FB08   I261 @T6G_MB_LIB.T6G(SCH_1):PAGE148
 R1738    2      B Q_RES_0402LF-0,5%,1/16W,CHIP,CS00002JB13   I349 @T6G_MB_LIB.T6G(SCH_1):PAGE148
  U147    9     A2 SN74AVC2T245RSWR-SN74AVC2T245RSWR,SMLF,IC,AL02T245A     I1 @T6G_MB_LIB.T6G(SCH_1):PAGE149

JTAG_SCM_MUX_TDO @T6G_MB_LIB.T6G(SCH_1):JTAG_SCM_MUX_TDO
 R1745    2      B Q_RES_0402LF-10K,1%,1/16W,CHIP,CS31002FB08   I257 @T6G_MB_LIB.T6G(SCH_1):PAGE148
  U147    8     A1 SN74AVC2T245RSWR-SN74AVC2T245RSWR,SMLF,IC,AL02T245A     I1 @T6G_MB_LIB.T6G(SCH_1):PAGE149
 R1739    2      B Q_RES_0402LF-0,5%,1/16W,CHIP,CS00002JB13   I388 @T6G_MB_LIB.T6G(SCH_1):PAGE148

JTAG_SCM_MUX_TMS @T6G_MB_LIB.T6G(SCH_1):JTAG_SCM_MUX_TMS
 R1746    2      B Q_RES_0402LF-10K,1%,1/16W,CHIP,CS31002FB08   I256 @T6G_MB_LIB.T6G(SCH_1):PAGE148
 R1737    2      B Q_RES_0402LF-0,5%,1/16W,CHIP,CS00002JB13   I357 @T6G_MB_LIB.T6G(SCH_1):PAGE148
  U148    4     A2 SN74AVC4T774PWR-SN74AVC4T774PWR,SMLF,IC,AL04T774K00    I34 @T6G_MB_LIB.T6G(SCH_1):PAGE149

JTAG_SCM_PLD_R_TCK @T6G_MB_LIB.T6G(SCH_1):JTAG_SCM_PLD_R_TCK
  U160   15    1Y2 74LV4052PW-74LV4052PW,SMLF,IC,ALLV4052K19   I266 @T6G_MB_LIB.T6G(SCH_1):PAGE148
  U160   11    1Y3 74LV4052PW-74LV4052PW,SMLF,IC,ALLV4052K19   I266 @T6G_MB_LIB.T6G(SCH_1):PAGE148
 R1740    1      A Q_RES_0402LF-22,1%,1/16W,CHIP,CS02202FB02   I368 @T6G_MB_LIB.T6G(SCH_1):PAGE148

JTAG_SCM_PLD_R_TDI @T6G_MB_LIB.T6G(SCH_1):JTAG_SCM_PLD_R_TDI
  U212   15    1Y2 74LV4052PW-74LV4052PW,SMLF,IC,ALLV4052K19   I302 @T6G_MB_LIB.T6G(SCH_1):PAGE148
  U212   11    1Y3 74LV4052PW-74LV4052PW,SMLF,IC,ALLV4052K19   I302 @T6G_MB_LIB.T6G(SCH_1):PAGE148
 R1742    1      A Q_RES_0402LF-22,1%,1/16W,CHIP,CS02202FB02   I352 @T6G_MB_LIB.T6G(SCH_1):PAGE148

JTAG_SCM_PLD_R_TDO @T6G_MB_LIB.T6G(SCH_1):JTAG_SCM_PLD_R_TDO
  U212    2    2Y2 74LV4052PW-74LV4052PW,SMLF,IC,ALLV4052K19   I302 @T6G_MB_LIB.T6G(SCH_1):PAGE148
  U212    4    2Y3 74LV4052PW-74LV4052PW,SMLF,IC,ALLV4052K19   I302 @T6G_MB_LIB.T6G(SCH_1):PAGE148
 R1743    1      A Q_RES_0402LF-22,1%,1/16W,CHIP,CS02202FB02   I332 @T6G_MB_LIB.T6G(SCH_1):PAGE148

JTAG_SCM_PLD_R_TMS @T6G_MB_LIB.T6G(SCH_1):JTAG_SCM_PLD_R_TMS
  U160    2    2Y2 74LV4052PW-74LV4052PW,SMLF,IC,ALLV4052K19   I266 @T6G_MB_LIB.T6G(SCH_1):PAGE148
  U160    4    2Y3 74LV4052PW-74LV4052PW,SMLF,IC,ALLV4052K19   I266 @T6G_MB_LIB.T6G(SCH_1):PAGE148
 R1741    1      A Q_RES_0402LF-22,1%,1/16W,CHIP,CS02202FB02   I366 @T6G_MB_LIB.T6G(SCH_1):PAGE148

JTAG_SCM_PLD_TCK @T6G_MB_LIB.T6G(SCH_1):JTAG_SCM_PLD_TCK
 R1740    2      B Q_RES_0402LF-22,1%,1/16W,CHIP,CS02202FB02   I368 @T6G_MB_LIB.T6G(SCH_1):PAGE148
   U18  D10 PT22C||TCK LCMXO3LF9400C5BG484C-LCMXO3LF-9400C-5BG484C,SMLF,IA    I25 @T6G_MB_LIB.T6G(SCH_1):PAGE79
   R15    2      B Q_RES_0402LF-0,5%,1/16W,CHIP,CS00002JB13    I35 @T6G_MB_LIB.T6G(SCH_1):PAGE84
 R6090    1      A Q_RES_0402LF-4.7K,5%,1/16W,CHIP,CS24702JB10    I77 @T6G_MB_LIB.T6G(SCH_1):PAGE84

JTAG_SCM_PLD_TDI @T6G_MB_LIB.T6G(SCH_1):JTAG_SCM_PLD_TDI
 R1742    2      B Q_RES_0402LF-22,1%,1/16W,CHIP,CS02202FB02   I352 @T6G_MB_LIB.T6G(SCH_1):PAGE148
    R9    2      B Q_RES_0402LF-0,5%,1/16W,CHIP,CS00002JB13    I37 @T6G_MB_LIB.T6G(SCH_1):PAGE84
   U18   E8 PT15C||TDO LCMXO3LF9400C5BG484C-LCMXO3LF-9400C-5BG484C,SMLF,IA    I25 @T6G_MB_LIB.T6G(SCH_1):PAGE79

JTAG_SCM_PLD_TDO @T6G_MB_LIB.T6G(SCH_1):JTAG_SCM_PLD_TDO
 R1743    2      B Q_RES_0402LF-22,1%,1/16W,CHIP,CS02202FB02   I332 @T6G_MB_LIB.T6G(SCH_1):PAGE148
   R13    2      B Q_RES_0402LF-0,5%,1/16W,CHIP,CS00002JB13    I38 @T6G_MB_LIB.T6G(SCH_1):PAGE84
   U18   E9 PT15D||TDI LCMXO3LF9400C5BG484C-LCMXO3LF-9400C-5BG484C,SMLF,IA    I25 @T6G_MB_LIB.T6G(SCH_1):PAGE79

JTAG_SCM_PLD_TMS @T6G_MB_LIB.T6G(SCH_1):JTAG_SCM_PLD_TMS
 R1741    2      B Q_RES_0402LF-22,1%,1/16W,CHIP,CS02202FB02   I366 @T6G_MB_LIB.T6G(SCH_1):PAGE148
   R14    2      B Q_RES_0402LF-0,5%,1/16W,CHIP,CS00002JB13    I36 @T6G_MB_LIB.T6G(SCH_1):PAGE84
   U18  C10 PT22D||TMS LCMXO3LF9400C5BG484C-LCMXO3LF-9400C-5BG484C,SMLF,IA    I25 @T6G_MB_LIB.T6G(SCH_1):PAGE79

JTAG_SCM_TCK @T6G_MB_LIB.T6G(SCH_1):JTAG_SCM_TCK
 R1734    2      B Q_RES_0402LF-10K,1%,1/16W,CHIP,CS31002FB08   I244 @T6G_MB_LIB.T6G(SCH_1):PAGE148
 R1735    1      A Q_RES_0402LF-10K,1%,1/16W,EMPTY,CS31002FB08   I246 @T6G_MB_LIB.T6G(SCH_1):PAGE148
  U160   13     1Z 74LV4052PW-74LV4052PW,SMLF,IC,ALLV4052K19   I266 @T6G_MB_LIB.T6G(SCH_1):PAGE148
   J41  A34  PERP5 SCONN168_ME1016810202011-SCONN168_ME1016810202011,A   I176 @T6G_MB_LIB.T6G(SCH_1):PAGE348

JTAG_SCM_TDI @T6G_MB_LIB.T6G(SCH_1):JTAG_SCM_TDI
 R1728    2      B Q_RES_0402LF-10K,1%,1/16W,EMPTY,CS31002FB08   I249 @T6G_MB_LIB.T6G(SCH_1):PAGE148
  U212   13     1Z 74LV4052PW-74LV4052PW,SMLF,IC,ALLV4052K19   I302 @T6G_MB_LIB.T6G(SCH_1):PAGE148
 R6066    2      B Q_RES_0402LF-0,5%,1/16W,EMPTY,CS00002JB13   I150 @T6G_MB_LIB.T6G(SCH_1):PAGE349
 R6067    2      B Q_RES_0402LF-0,5%,1/16W,CHIP,CS00002JB13   I159 @T6G_MB_LIB.T6G(SCH_1):PAGE349

JTAG_SCM_TDI_R @T6G_MB_LIB.T6G(SCH_1):JTAG_SCM_TDI_R
   J41  A36  PERN6 SCONN168_ME1016810202011-SCONN168_ME1016810202011,A   I176 @T6G_MB_LIB.T6G(SCH_1):PAGE348
 R6066    1      A Q_RES_0402LF-0,5%,1/16W,EMPTY,CS00002JB13   I150 @T6G_MB_LIB.T6G(SCH_1):PAGE349
 R6069    1      A Q_RES_0402LF-0,5%,1/16W,CHIP,CS00002JB13   I158 @T6G_MB_LIB.T6G(SCH_1):PAGE349

JTAG_SCM_TDO @T6G_MB_LIB.T6G(SCH_1):JTAG_SCM_TDO
 R1727    2      B Q_RES_0402LF-10K,1%,1/16W,EMPTY,CS31002FB08   I250 @T6G_MB_LIB.T6G(SCH_1):PAGE148
  U212    3     2Z 74LV4052PW-74LV4052PW,SMLF,IC,ALLV4052K19   I302 @T6G_MB_LIB.T6G(SCH_1):PAGE148
 R6068    2      B Q_RES_0402LF-0,5%,1/16W,EMPTY,CS00002JB13   I151 @T6G_MB_LIB.T6G(SCH_1):PAGE349
 R6069    2      B Q_RES_0402LF-0,5%,1/16W,CHIP,CS00002JB13   I158 @T6G_MB_LIB.T6G(SCH_1):PAGE349

JTAG_SCM_TDO_R @T6G_MB_LIB.T6G(SCH_1):JTAG_SCM_TDO_R
   J41  A37  PERP6 SCONN168_ME1016810202011-SCONN168_ME1016810202011,A   I176 @T6G_MB_LIB.T6G(SCH_1):PAGE348
 R6068    1      A Q_RES_0402LF-0,5%,1/16W,EMPTY,CS00002JB13   I151 @T6G_MB_LIB.T6G(SCH_1):PAGE349
 R6067    1      A Q_RES_0402LF-0,5%,1/16W,CHIP,CS00002JB13   I159 @T6G_MB_LIB.T6G(SCH_1):PAGE349

JTAG_SCM_TMS @T6G_MB_LIB.T6G(SCH_1):JTAG_SCM_TMS
 R1731    2      B Q_RES_0402LF-10K,1%,1/16W,EMPTY,CS31002FB08   I245 @T6G_MB_LIB.T6G(SCH_1):PAGE148
  U160    3     2Z 74LV4052PW-74LV4052PW,SMLF,IC,ALLV4052K19   I266 @T6G_MB_LIB.T6G(SCH_1):PAGE148
   J41  A35 GND_A35 SCONN168_ME1016810202011-SCONN168_ME1016810202011,A   I176 @T6G_MB_LIB.T6G(SCH_1):PAGE348

JTAG_SCM_TRST_N @T6G_MB_LIB.T6G(SCH_1):JTAG_SCM_TRST_N
  U148    5     A3 SN74AVC4T774PWR-SN74AVC4T774PWR,SMLF,IC,AL04T774K00    I34 @T6G_MB_LIB.T6G(SCH_1):PAGE149
  R160    2      B Q_RES_0402LF-33,5%,1/16W,CHIP,CS03302JB10    I16 @T6G_MB_LIB.T6G(SCH_1):PAGE79

JTAG_SCM_TRST_R_N @T6G_MB_LIB.T6G(SCH_1):JTAG_SCM_TRST_R_N
  R160    1      A Q_RES_0402LF-33,5%,1/16W,CHIP,CS03302JB10    I16 @T6G_MB_LIB.T6G(SCH_1):PAGE79
   U18  D11  PT24D LCMXO3LF9400C5BG484C-LCMXO3LF-9400C-5BG484C,SMLF,IA    I94 @T6G_MB_LIB.T6G(SCH_1):PAGE79

JTAG_TCK @T6G_MB_LIB.T6G(SCH_1):JTAG_TCK
 R1633    2      B Q_RES_0402LF-0,5%,1/16W,CHIP,CS00002JB13     I7 @T6G_MB_LIB.T6G(SCH_1):PAGE149
 C1510    1      A Q_CAP_0402-33PF,50V,5%,NPO,TMP_QCH03306JB04    I25 @T6G_MB_LIB.T6G(SCH_1):PAGE149
  U150    3     A1 SN74AVC4T774PWR-SN74AVC4T774PWR,SMLF,IC,AL04T774K00     I8 @T6G_MB_LIB.T6G(SCH_1):PAGE150
  U151    3     A1 SN74AVC4T774PWR-SN74AVC4T774PWR,SMLF,IC,AL04T774K00    I28 @T6G_MB_LIB.T6G(SCH_1):PAGE150

JTAG_TCK_R @T6G_MB_LIB.T6G(SCH_1):JTAG_TCK_R
 R1633    1      A Q_RES_0402LF-0,5%,1/16W,CHIP,CS00002JB13     I7 @T6G_MB_LIB.T6G(SCH_1):PAGE149
  U149   14     B1 SN74AVC4T774PWR-SN74AVC4T774PWR,SMLF,IC,AL04T774K00    I31 @T6G_MB_LIB.T6G(SCH_1):PAGE149
  U148   14     B1 SN74AVC4T774PWR-SN74AVC4T774PWR,SMLF,IC,AL04T774K00    I34 @T6G_MB_LIB.T6G(SCH_1):PAGE149

JTAG_TCK_RT_CPU0_P0 @T6G_MB_LIB.T6G(SCH_1):JTAG_TCK_RT_CPU0_P0
 U6010   B3 JTAG_TCK PT5161LRS-PT5161LRS,SMLF,IC,AJ051610U03    I53 @T6G_MB_LIB.T6G(SCH_1):PAGE385
 R1365    1      A Q_RES_0201LF-4.7K,5%,1/20W,CHIP,CS24701JE04   I123 @T6G_MB_LIB.T6G(SCH_1):PAGE385
 R1446    2      B Q_RES_0201LF-4.7K,5%,1/20W,EMPTY,CS24701JE04   I143 @T6G_MB_LIB.T6G(SCH_1):PAGE385

JTAG_TCK_RT_CPU0_P1 @T6G_MB_LIB.T6G(SCH_1):JTAG_TCK_RT_CPU0_P1
 U6011   B3 JTAG_TCK PT5161LRS-PT5161LRS,SMLF,IC,AJ051610U03    I83 @T6G_MB_LIB.T6G(SCH_1):PAGE408
 R1392    1      A Q_RES_0201LF-4.7K,5%,1/20W,CHIP,CS24701JE04   I119 @T6G_MB_LIB.T6G(SCH_1):PAGE408
 R1473    2      B Q_RES_0201LF-4.7K,5%,1/20W,EMPTY,CS24701JE04   I122 @T6G_MB_LIB.T6G(SCH_1):PAGE408

JTAG_TCK_RT_CPU0_P2 @T6G_MB_LIB.T6G(SCH_1):JTAG_TCK_RT_CPU0_P2
 U6012   B3 JTAG_TCK PT5161LRS-PT5161LRS,SMLF,IC,AJ051610U03    I83 @T6G_MB_LIB.T6G(SCH_1):PAGE419
 R1401    1      A Q_RES_0201LF-4.7K,5%,1/20W,CHIP,CS24701JE04   I120 @T6G_MB_LIB.T6G(SCH_1):PAGE419
 R1479    2      B Q_RES_0201LF-4.7K,5%,1/20W,EMPTY,CS24701JE04   I121 @T6G_MB_LIB.T6G(SCH_1):PAGE419

JTAG_TCK_RT_CPU0_P3 @T6G_MB_LIB.T6G(SCH_1):JTAG_TCK_RT_CPU0_P3
 U6013   B3 JTAG_TCK PT5161LRS-PT5161LRS,SMLF,IC,AJ051610U03    I83 @T6G_MB_LIB.T6G(SCH_1):PAGE430
 R1409    1      A Q_RES_0201LF-4.7K,5%,1/20W,CHIP,CS24701JE04   I117 @T6G_MB_LIB.T6G(SCH_1):PAGE430
 R1485    2      B Q_RES_0201LF-4.7K,5%,1/20W,EMPTY,CS24701JE04   I119 @T6G_MB_LIB.T6G(SCH_1):PAGE430

JTAG_TCK_RT_CPU1_P0 @T6G_MB_LIB.T6G(SCH_1):JTAG_TCK_RT_CPU1_P0
 U6014   B3 JTAG_TCK PT5161LRS-PT5161LRS,SMLF,IC,AJ051610U03     I1 @T6G_MB_LIB.T6G(SCH_1):PAGE401
 R1381    1      A Q_RES_0201LF-4.7K,5%,1/20W,CHIP,CS24701JE04   I144 @T6G_MB_LIB.T6G(SCH_1):PAGE401
 R1467    2      B Q_RES_0201LF-4.7K,5%,1/20W,EMPTY,CS24701JE04   I147 @T6G_MB_LIB.T6G(SCH_1):PAGE401

JTAG_TCK_RT_CPU1_P1 @T6G_MB_LIB.T6G(SCH_1):JTAG_TCK_RT_CPU1_P1
 U6015   B3 JTAG_TCK PT5161LRS-PT5161LRS,SMLF,IC,AJ051610U03    I47 @T6G_MB_LIB.T6G(SCH_1):PAGE392
 R1373    1      A Q_RES_0201LF-4.7K,5%,1/20W,CHIP,CS24701JE04   I150 @T6G_MB_LIB.T6G(SCH_1):PAGE392
 R1461    2      B Q_RES_0201LF-4.7K,5%,1/20W,EMPTY,CS24701JE04   I151 @T6G_MB_LIB.T6G(SCH_1):PAGE392

JTAG_TCK_RT_CPU1_P2 @T6G_MB_LIB.T6G(SCH_1):JTAG_TCK_RT_CPU1_P2
 U6016   B3 JTAG_TCK PT5161LRS-PT5161LRS,SMLF,IC,AJ051610U03    I97 @T6G_MB_LIB.T6G(SCH_1):PAGE451
 R1417    1      A Q_RES_0201LF-4.7K,5%,1/20W,CHIP,CS24701JE04   I136 @T6G_MB_LIB.T6G(SCH_1):PAGE451
 R1499    2      B Q_RES_0201LF-4.7K,5%,1/20W,EMPTY,CS24701JE04   I137 @T6G_MB_LIB.T6G(SCH_1):PAGE451

JTAG_TCK_RT_CPU1_P3 @T6G_MB_LIB.T6G(SCH_1):JTAG_TCK_RT_CPU1_P3
 U6017   B3 JTAG_TCK PT5161LRS-PT5161LRS,SMLF,IC,AJ051610U03    I97 @T6G_MB_LIB.T6G(SCH_1):PAGE462
 R1430    1      A Q_RES_0201LF-4.7K,5%,1/20W,CHIP,CS24701JE04   I136 @T6G_MB_LIB.T6G(SCH_1):PAGE462
 R1513    2      B Q_RES_0201LF-4.7K,5%,1/20W,EMPTY,CS24701JE04   I137 @T6G_MB_LIB.T6G(SCH_1):PAGE462

JTAG_TDI @T6G_MB_LIB.T6G(SCH_1):JTAG_TDI
 R1625    2      B Q_RES_0402LF-0,5%,1/16W,CHIP,CS00002JB13    I53 @T6G_MB_LIB.T6G(SCH_1):PAGE149
  U152    8     A1 SN74AVC2T245RSWR-SN74AVC2T245RSWR,SMLF,IC,AL02T245A    I60 @T6G_MB_LIB.T6G(SCH_1):PAGE150
   C86    1      A Q_CAP_C0402-0.01UF,50V,10%,EMPTY,CH31006KB18   I161 @T6G_MB_LIB.T6G(SCH_1):PAGE149

JTAG_TDI_R @T6G_MB_LIB.T6G(SCH_1):JTAG_TDI_R
  U147    5     B1 SN74AVC2T245RSWR-SN74AVC2T245RSWR,SMLF,IC,AL02T245A     I1 @T6G_MB_LIB.T6G(SCH_1):PAGE149
 R1625    1      A Q_RES_0402LF-0,5%,1/16W,CHIP,CS00002JB13    I53 @T6G_MB_LIB.T6G(SCH_1):PAGE149
  U146    5     B1 SN74AVC2T245RSWR-SN74AVC2T245RSWR,SMLF,IC,AL02T245A    I76 @T6G_MB_LIB.T6G(SCH_1):PAGE149

JTAG_TDI_RT_CPU0_P0 @T6G_MB_LIB.T6G(SCH_1):JTAG_TDI_RT_CPU0_P0
 U6010   B6 JTAG_TDI PT5161LRS-PT5161LRS,SMLF,IC,AJ051610U03    I53 @T6G_MB_LIB.T6G(SCH_1):PAGE385
 R1438    2      B Q_RES_0201LF-4.7K,5%,1/20W,EMPTY,CS24701JE04   I147 @T6G_MB_LIB.T6G(SCH_1):PAGE385

JTAG_TDI_RT_CPU0_P1 @T6G_MB_LIB.T6G(SCH_1):JTAG_TDI_RT_CPU0_P1
 U6011   B6 JTAG_TDI PT5161LRS-PT5161LRS,SMLF,IC,AJ051610U03    I83 @T6G_MB_LIB.T6G(SCH_1):PAGE408
 R1470    2      B Q_RES_0201LF-4.7K,5%,1/20W,EMPTY,CS24701JE04   I115 @T6G_MB_LIB.T6G(SCH_1):PAGE408

JTAG_TDI_RT_CPU0_P2 @T6G_MB_LIB.T6G(SCH_1):JTAG_TDI_RT_CPU0_P2
 U6012   B6 JTAG_TDI PT5161LRS-PT5161LRS,SMLF,IC,AJ051610U03    I83 @T6G_MB_LIB.T6G(SCH_1):PAGE419
 R1476    2      B Q_RES_0201LF-4.7K,5%,1/20W,EMPTY,CS24701JE04   I116 @T6G_MB_LIB.T6G(SCH_1):PAGE419

JTAG_TDI_RT_CPU0_P3 @T6G_MB_LIB.T6G(SCH_1):JTAG_TDI_RT_CPU0_P3
 U6013   B6 JTAG_TDI PT5161LRS-PT5161LRS,SMLF,IC,AJ051610U03    I83 @T6G_MB_LIB.T6G(SCH_1):PAGE430
 R1482    2      B Q_RES_0201LF-4.7K,5%,1/20W,EMPTY,CS24701JE04   I112 @T6G_MB_LIB.T6G(SCH_1):PAGE430

JTAG_TDI_RT_CPU1_P0 @T6G_MB_LIB.T6G(SCH_1):JTAG_TDI_RT_CPU1_P0
 U6014   B6 JTAG_TDI PT5161LRS-PT5161LRS,SMLF,IC,AJ051610U03     I1 @T6G_MB_LIB.T6G(SCH_1):PAGE401
 R1464    2      B Q_RES_0201LF-4.7K,5%,1/20W,EMPTY,CS24701JE04   I149 @T6G_MB_LIB.T6G(SCH_1):PAGE401

JTAG_TDI_RT_CPU1_P1 @T6G_MB_LIB.T6G(SCH_1):JTAG_TDI_RT_CPU1_P1
 U6015   B6 JTAG_TDI PT5161LRS-PT5161LRS,SMLF,IC,AJ051610U03    I47 @T6G_MB_LIB.T6G(SCH_1):PAGE392
 R1454    2      B Q_RES_0201LF-4.7K,5%,1/20W,EMPTY,CS24701JE04   I145 @T6G_MB_LIB.T6G(SCH_1):PAGE392

JTAG_TDI_RT_CPU1_P2 @T6G_MB_LIB.T6G(SCH_1):JTAG_TDI_RT_CPU1_P2
 U6016   B6 JTAG_TDI PT5161LRS-PT5161LRS,SMLF,IC,AJ051610U03    I97 @T6G_MB_LIB.T6G(SCH_1):PAGE451
 R1488    2      B Q_RES_0201LF-4.7K,5%,1/20W,EMPTY,CS24701JE04   I132 @T6G_MB_LIB.T6G(SCH_1):PAGE451

JTAG_TDI_RT_CPU1_P3 @T6G_MB_LIB.T6G(SCH_1):JTAG_TDI_RT_CPU1_P3
 U6017   B6 JTAG_TDI PT5161LRS-PT5161LRS,SMLF,IC,AJ051610U03    I97 @T6G_MB_LIB.T6G(SCH_1):PAGE462
 R1510    2      B Q_RES_0201LF-4.7K,5%,1/20W,EMPTY,CS24701JE04   I139 @T6G_MB_LIB.T6G(SCH_1):PAGE462

JTAG_TDO @T6G_MB_LIB.T6G(SCH_1):JTAG_TDO
 R6109    1      A Q_RES_0402LF-0,5%,1/16W,CHIP,CS00002JB13    I78 @T6G_MB_LIB.T6G(SCH_1):PAGE150
 R6111    2      B Q_RES_0402LF-0,5%,1/16W,CHIP,CS00002JB13   I160 @T6G_MB_LIB.T6G(SCH_1):PAGE149

JTAG_TDO_R @T6G_MB_LIB.T6G(SCH_1):JTAG_TDO_R
  U152    9     A2 SN74AVC2T245RSWR-SN74AVC2T245RSWR,SMLF,IC,AL02T245A    I60 @T6G_MB_LIB.T6G(SCH_1):PAGE150
 R6109    2      B Q_RES_0402LF-0,5%,1/16W,CHIP,CS00002JB13    I78 @T6G_MB_LIB.T6G(SCH_1):PAGE150

JTAG_TDO_R1 @T6G_MB_LIB.T6G(SCH_1):JTAG_TDO_R1
  U147    4     B2 SN74AVC2T245RSWR-SN74AVC2T245RSWR,SMLF,IC,AL02T245A     I1 @T6G_MB_LIB.T6G(SCH_1):PAGE149
  U146    4     B2 SN74AVC2T245RSWR-SN74AVC2T245RSWR,SMLF,IC,AL02T245A    I76 @T6G_MB_LIB.T6G(SCH_1):PAGE149
 R6111    1      A Q_RES_0402LF-0,5%,1/16W,CHIP,CS00002JB13   I160 @T6G_MB_LIB.T6G(SCH_1):PAGE149

JTAG_TDO_RT_CPU0_P0 @T6G_MB_LIB.T6G(SCH_1):JTAG_TDO_RT_CPU0_P0
 U6010   B9 JTAG_TDO PT5161LRS-PT5161LRS,SMLF,IC,AJ051610U03    I53 @T6G_MB_LIB.T6G(SCH_1):PAGE385
 R1445    2      B Q_RES_0201LF-1K,1%,1/20W,EMPTY,CS21001FE07   I145 @T6G_MB_LIB.T6G(SCH_1):PAGE385

JTAG_TDO_RT_CPU0_P1 @T6G_MB_LIB.T6G(SCH_1):JTAG_TDO_RT_CPU0_P1
 U6011   B9 JTAG_TDO PT5161LRS-PT5161LRS,SMLF,IC,AJ051610U03    I83 @T6G_MB_LIB.T6G(SCH_1):PAGE408
 R1472    2      B Q_RES_0201LF-1K,1%,1/20W,EMPTY,CS21001FE07   I121 @T6G_MB_LIB.T6G(SCH_1):PAGE408

JTAG_TDO_RT_CPU0_P2 @T6G_MB_LIB.T6G(SCH_1):JTAG_TDO_RT_CPU0_P2
 U6012   B9 JTAG_TDO PT5161LRS-PT5161LRS,SMLF,IC,AJ051610U03    I83 @T6G_MB_LIB.T6G(SCH_1):PAGE419
 R1478    2      B Q_RES_0201LF-1K,1%,1/20W,EMPTY,CS21001FE07   I118 @T6G_MB_LIB.T6G(SCH_1):PAGE419

JTAG_TDO_RT_CPU0_P3 @T6G_MB_LIB.T6G(SCH_1):JTAG_TDO_RT_CPU0_P3
 U6013   B9 JTAG_TDO PT5161LRS-PT5161LRS,SMLF,IC,AJ051610U03    I83 @T6G_MB_LIB.T6G(SCH_1):PAGE430
 R1484    2      B Q_RES_0201LF-1K,1%,1/20W,EMPTY,CS21001FE07   I118 @T6G_MB_LIB.T6G(SCH_1):PAGE430

JTAG_TDO_RT_CPU1_P0 @T6G_MB_LIB.T6G(SCH_1):JTAG_TDO_RT_CPU1_P0
 U6014   B9 JTAG_TDO PT5161LRS-PT5161LRS,SMLF,IC,AJ051610U03     I1 @T6G_MB_LIB.T6G(SCH_1):PAGE401
 R1466    2      B Q_RES_0201LF-1K,1%,1/20W,EMPTY,CS21001FE07   I146 @T6G_MB_LIB.T6G(SCH_1):PAGE401

JTAG_TDO_RT_CPU1_P1 @T6G_MB_LIB.T6G(SCH_1):JTAG_TDO_RT_CPU1_P1
 U6015   B9 JTAG_TDO PT5161LRS-PT5161LRS,SMLF,IC,AJ051610U03    I47 @T6G_MB_LIB.T6G(SCH_1):PAGE392
 R1456    2      B Q_RES_0201LF-1K,1%,1/20W,EMPTY,CS21001FE07   I153 @T6G_MB_LIB.T6G(SCH_1):PAGE392

JTAG_TDO_RT_CPU1_P2 @T6G_MB_LIB.T6G(SCH_1):JTAG_TDO_RT_CPU1_P2
 U6016   B9 JTAG_TDO PT5161LRS-PT5161LRS,SMLF,IC,AJ051610U03    I97 @T6G_MB_LIB.T6G(SCH_1):PAGE451
 R1490    2      B Q_RES_0201LF-1K,1%,1/20W,EMPTY,CS21001FE07   I139 @T6G_MB_LIB.T6G(SCH_1):PAGE451

JTAG_TDO_RT_CPU1_P3 @T6G_MB_LIB.T6G(SCH_1):JTAG_TDO_RT_CPU1_P3
 U6017   B9 JTAG_TDO PT5161LRS-PT5161LRS,SMLF,IC,AJ051610U03    I97 @T6G_MB_LIB.T6G(SCH_1):PAGE462
 R1512    2      B Q_RES_0201LF-1K,1%,1/20W,EMPTY,CS21001FE07   I140 @T6G_MB_LIB.T6G(SCH_1):PAGE462

JTAG_TEST_MODE_RT_CPU0_P0 @T6G_MB_LIB.T6G(SCH_1):JTAG_TEST_MODE_RT_CPU0_P0
 U6010  FF8 JTAG_TEST_MODE PT5161LRS-PT5161LRS,SMLF,IC,AJ051610U03    I53 @T6G_MB_LIB.T6G(SCH_1):PAGE385
  R997    1      A Q_RES_0201LF-4.7K,5%,1/20W,CHIP,CS24701JE04    I60 @T6G_MB_LIB.T6G(SCH_1):PAGE385
  R975    2      B Q_RES_0201LF-4.7K,5%,1/20W,EMPTY,CS24701JE04    I63 @T6G_MB_LIB.T6G(SCH_1):PAGE385

JTAG_TEST_MODE_RT_CPU0_P1 @T6G_MB_LIB.T6G(SCH_1):JTAG_TEST_MODE_RT_CPU0_P1
 R1037    1      A Q_RES_0201LF-4.7K,5%,1/20W,CHIP,CS24701JE04    I39 @T6G_MB_LIB.T6G(SCH_1):PAGE408
 R1024    2      B Q_RES_0201LF-4.7K,5%,1/20W,EMPTY,CS24701JE04    I42 @T6G_MB_LIB.T6G(SCH_1):PAGE408
 U6011  FF8 JTAG_TEST_MODE PT5161LRS-PT5161LRS,SMLF,IC,AJ051610U03    I83 @T6G_MB_LIB.T6G(SCH_1):PAGE408

JTAG_TEST_MODE_RT_CPU0_P2 @T6G_MB_LIB.T6G(SCH_1):JTAG_TEST_MODE_RT_CPU0_P2
 R1079    1      A Q_RES_0201LF-4.7K,5%,1/20W,CHIP,CS24701JE04    I39 @T6G_MB_LIB.T6G(SCH_1):PAGE419
 R1066    2      B Q_RES_0201LF-4.7K,5%,1/20W,EMPTY,CS24701JE04    I42 @T6G_MB_LIB.T6G(SCH_1):PAGE419
 U6012  FF8 JTAG_TEST_MODE PT5161LRS-PT5161LRS,SMLF,IC,AJ051610U03    I83 @T6G_MB_LIB.T6G(SCH_1):PAGE419

JTAG_TEST_MODE_RT_CPU0_P3 @T6G_MB_LIB.T6G(SCH_1):JTAG_TEST_MODE_RT_CPU0_P3
 R1121    1      A Q_RES_0201LF-4.7K,5%,1/20W,CHIP,CS24701JE04    I39 @T6G_MB_LIB.T6G(SCH_1):PAGE430
 R1108    2      B Q_RES_0201LF-4.7K,5%,1/20W,EMPTY,CS24701JE04    I42 @T6G_MB_LIB.T6G(SCH_1):PAGE430
 U6013  FF8 JTAG_TEST_MODE PT5161LRS-PT5161LRS,SMLF,IC,AJ051610U03    I83 @T6G_MB_LIB.T6G(SCH_1):PAGE430

JTAG_TEST_MODE_RT_CPU1_P0 @T6G_MB_LIB.T6G(SCH_1):JTAG_TEST_MODE_RT_CPU1_P0
 U6014  FF8 JTAG_TEST_MODE PT5161LRS-PT5161LRS,SMLF,IC,AJ051610U03     I1 @T6G_MB_LIB.T6G(SCH_1):PAGE401
  R726    1      A Q_RES_0201LF-4.7K,5%,1/20W,CHIP,CS24701JE04    I90 @T6G_MB_LIB.T6G(SCH_1):PAGE401
 R6725    2      B Q_RES_0201LF-4.7K,5%,1/20W,EMPTY,CS24701JE04    I91 @T6G_MB_LIB.T6G(SCH_1):PAGE401

JTAG_TEST_MODE_RT_CPU1_P1 @T6G_MB_LIB.T6G(SCH_1):JTAG_TEST_MODE_RT_CPU1_P1
 U6015  FF8 JTAG_TEST_MODE PT5161LRS-PT5161LRS,SMLF,IC,AJ051610U03    I47 @T6G_MB_LIB.T6G(SCH_1):PAGE392
  R792    1      A Q_RES_0201LF-4.7K,5%,1/20W,CHIP,CS24701JE04    I54 @T6G_MB_LIB.T6G(SCH_1):PAGE392
  R759    2      B Q_RES_0201LF-4.7K,5%,1/20W,EMPTY,CS24701JE04    I57 @T6G_MB_LIB.T6G(SCH_1):PAGE392

JTAG_TEST_MODE_RT_CPU1_P2 @T6G_MB_LIB.T6G(SCH_1):JTAG_TEST_MODE_RT_CPU1_P2
  R884    1      A Q_RES_0201LF-4.7K,5%,1/20W,CHIP,CS24701JE04    I46 @T6G_MB_LIB.T6G(SCH_1):PAGE451
  R871    2      B Q_RES_0201LF-4.7K,5%,1/20W,EMPTY,CS24701JE04    I50 @T6G_MB_LIB.T6G(SCH_1):PAGE451
 U6016  FF8 JTAG_TEST_MODE PT5161LRS-PT5161LRS,SMLF,IC,AJ051610U03    I97 @T6G_MB_LIB.T6G(SCH_1):PAGE451

JTAG_TEST_MODE_RT_CPU1_P3 @T6G_MB_LIB.T6G(SCH_1):JTAG_TEST_MODE_RT_CPU1_P3
  R924    1      A Q_RES_0201LF-4.7K,5%,1/20W,CHIP,CS24701JE04    I53 @T6G_MB_LIB.T6G(SCH_1):PAGE462
  R912    2      B Q_RES_0201LF-4.7K,5%,1/20W,EMPTY,CS24701JE04    I56 @T6G_MB_LIB.T6G(SCH_1):PAGE462
 U6017  FF8 JTAG_TEST_MODE PT5161LRS-PT5161LRS,SMLF,IC,AJ051610U03    I97 @T6G_MB_LIB.T6G(SCH_1):PAGE462

JTAG_TMS @T6G_MB_LIB.T6G(SCH_1):JTAG_TMS
 R1634    2      B Q_RES_0402LF-0,5%,1/16W,CHIP,CS00002JB13    I96 @T6G_MB_LIB.T6G(SCH_1):PAGE149
  U150    4     A2 SN74AVC4T774PWR-SN74AVC4T774PWR,SMLF,IC,AL04T774K00     I8 @T6G_MB_LIB.T6G(SCH_1):PAGE150
  U151    4     A2 SN74AVC4T774PWR-SN74AVC4T774PWR,SMLF,IC,AL04T774K00    I28 @T6G_MB_LIB.T6G(SCH_1):PAGE150

JTAG_TMS_R @T6G_MB_LIB.T6G(SCH_1):JTAG_TMS_R
  U149   13     B2 SN74AVC4T774PWR-SN74AVC4T774PWR,SMLF,IC,AL04T774K00    I31 @T6G_MB_LIB.T6G(SCH_1):PAGE149
  U148   13     B2 SN74AVC4T774PWR-SN74AVC4T774PWR,SMLF,IC,AL04T774K00    I34 @T6G_MB_LIB.T6G(SCH_1):PAGE149
 R1634    1      A Q_RES_0402LF-0,5%,1/16W,CHIP,CS00002JB13    I96 @T6G_MB_LIB.T6G(SCH_1):PAGE149

JTAG_TMS_RT_CPU0_P0 @T6G_MB_LIB.T6G(SCH_1):JTAG_TMS_RT_CPU0_P0
 U6010  B12 JTAG_TMS PT5161LRS-PT5161LRS,SMLF,IC,AJ051610U03    I53 @T6G_MB_LIB.T6G(SCH_1):PAGE385
 R1439    2      B Q_RES_0201LF-4.7K,5%,1/20W,EMPTY,CS24701JE04   I146 @T6G_MB_LIB.T6G(SCH_1):PAGE385

JTAG_TMS_RT_CPU0_P1 @T6G_MB_LIB.T6G(SCH_1):JTAG_TMS_RT_CPU0_P1
 U6011  B12 JTAG_TMS PT5161LRS-PT5161LRS,SMLF,IC,AJ051610U03    I83 @T6G_MB_LIB.T6G(SCH_1):PAGE408
 R1471    2      B Q_RES_0201LF-4.7K,5%,1/20W,EMPTY,CS24701JE04   I116 @T6G_MB_LIB.T6G(SCH_1):PAGE408

JTAG_TMS_RT_CPU0_P2 @T6G_MB_LIB.T6G(SCH_1):JTAG_TMS_RT_CPU0_P2
 U6012  B12 JTAG_TMS PT5161LRS-PT5161LRS,SMLF,IC,AJ051610U03    I83 @T6G_MB_LIB.T6G(SCH_1):PAGE419
 R1477    2      B Q_RES_0201LF-4.7K,5%,1/20W,EMPTY,CS24701JE04   I117 @T6G_MB_LIB.T6G(SCH_1):PAGE419

JTAG_TMS_RT_CPU0_P3 @T6G_MB_LIB.T6G(SCH_1):JTAG_TMS_RT_CPU0_P3
 U6013  B12 JTAG_TMS PT5161LRS-PT5161LRS,SMLF,IC,AJ051610U03    I83 @T6G_MB_LIB.T6G(SCH_1):PAGE430
 R1483    2      B Q_RES_0201LF-4.7K,5%,1/20W,EMPTY,CS24701JE04   I113 @T6G_MB_LIB.T6G(SCH_1):PAGE430

JTAG_TMS_RT_CPU1_P0 @T6G_MB_LIB.T6G(SCH_1):JTAG_TMS_RT_CPU1_P0
 U6014  B12 JTAG_TMS PT5161LRS-PT5161LRS,SMLF,IC,AJ051610U03     I1 @T6G_MB_LIB.T6G(SCH_1):PAGE401
 R1465    2      B Q_RES_0201LF-4.7K,5%,1/20W,EMPTY,CS24701JE04   I145 @T6G_MB_LIB.T6G(SCH_1):PAGE401

JTAG_TMS_RT_CPU1_P1 @T6G_MB_LIB.T6G(SCH_1):JTAG_TMS_RT_CPU1_P1
 U6015  B12 JTAG_TMS PT5161LRS-PT5161LRS,SMLF,IC,AJ051610U03    I47 @T6G_MB_LIB.T6G(SCH_1):PAGE392
 R1455    2      B Q_RES_0201LF-4.7K,5%,1/20W,EMPTY,CS24701JE04   I146 @T6G_MB_LIB.T6G(SCH_1):PAGE392

JTAG_TMS_RT_CPU1_P2 @T6G_MB_LIB.T6G(SCH_1):JTAG_TMS_RT_CPU1_P2
 U6016  B12 JTAG_TMS PT5161LRS-PT5161LRS,SMLF,IC,AJ051610U03    I97 @T6G_MB_LIB.T6G(SCH_1):PAGE451
 R1489    2      B Q_RES_0201LF-4.7K,5%,1/20W,EMPTY,CS24701JE04   I140 @T6G_MB_LIB.T6G(SCH_1):PAGE451

JTAG_TMS_RT_CPU1_P3 @T6G_MB_LIB.T6G(SCH_1):JTAG_TMS_RT_CPU1_P3
 U6017  B12 JTAG_TMS PT5161LRS-PT5161LRS,SMLF,IC,AJ051610U03    I97 @T6G_MB_LIB.T6G(SCH_1):PAGE462
 R1511    2      B Q_RES_0201LF-4.7K,5%,1/20W,EMPTY,CS24701JE04   I132 @T6G_MB_LIB.T6G(SCH_1):PAGE462

JTAG_TRST_N @T6G_MB_LIB.T6G(SCH_1):JTAG_TRST_N
 R1635    2      B Q_RES_0402LF-22,1%,1/16W,CHIP,CS02202FB02     I8 @T6G_MB_LIB.T6G(SCH_1):PAGE149
 C1511    1      A Q_CAP_0402-33PF,50V,5%,NPO,TMP_QCH03306JB04    I23 @T6G_MB_LIB.T6G(SCH_1):PAGE149
  U150    5     A3 SN74AVC4T774PWR-SN74AVC4T774PWR,SMLF,IC,AL04T774K00     I8 @T6G_MB_LIB.T6G(SCH_1):PAGE150
  U151    5     A3 SN74AVC4T774PWR-SN74AVC4T774PWR,SMLF,IC,AL04T774K00    I28 @T6G_MB_LIB.T6G(SCH_1):PAGE150

JTAG_TRST_RT_CPU0_P0_N @T6G_MB_LIB.T6G(SCH_1):JTAG_TRST_RT_CPU0_P0_N
 U6010   E8 JTAG_TRST_N PT5161LRS-PT5161LRS,SMLF,IC,AJ051610U03    I53 @T6G_MB_LIB.T6G(SCH_1):PAGE385
 R1364    1      A Q_RES_0201LF-1K,1%,1/20W,CHIP,CS21001FE07   I111 @T6G_MB_LIB.T6G(SCH_1):PAGE385

JTAG_TRST_RT_CPU0_P1_N @T6G_MB_LIB.T6G(SCH_1):JTAG_TRST_RT_CPU0_P1_N
 U6011   E8 JTAG_TRST_N PT5161LRS-PT5161LRS,SMLF,IC,AJ051610U03    I83 @T6G_MB_LIB.T6G(SCH_1):PAGE408
 R1391    1      A Q_RES_0201LF-1K,1%,1/20W,CHIP,CS21001FE07    I84 @T6G_MB_LIB.T6G(SCH_1):PAGE408

JTAG_TRST_RT_CPU0_P2_N @T6G_MB_LIB.T6G(SCH_1):JTAG_TRST_RT_CPU0_P2_N
 U6012   E8 JTAG_TRST_N PT5161LRS-PT5161LRS,SMLF,IC,AJ051610U03    I83 @T6G_MB_LIB.T6G(SCH_1):PAGE419
 R1400    1      A Q_RES_0201LF-1K,1%,1/20W,CHIP,CS21001FE07    I84 @T6G_MB_LIB.T6G(SCH_1):PAGE419

JTAG_TRST_RT_CPU0_P3_N @T6G_MB_LIB.T6G(SCH_1):JTAG_TRST_RT_CPU0_P3_N
 U6013   E8 JTAG_TRST_N PT5161LRS-PT5161LRS,SMLF,IC,AJ051610U03    I83 @T6G_MB_LIB.T6G(SCH_1):PAGE430
 R1408    1      A Q_RES_0201LF-1K,1%,1/20W,CHIP,CS21001FE07    I85 @T6G_MB_LIB.T6G(SCH_1):PAGE430

JTAG_TRST_RT_CPU1_P0_N @T6G_MB_LIB.T6G(SCH_1):JTAG_TRST_RT_CPU1_P0_N
 U6014   E8 JTAG_TRST_N PT5161LRS-PT5161LRS,SMLF,IC,AJ051610U03     I1 @T6G_MB_LIB.T6G(SCH_1):PAGE401
 R1380    1      A Q_RES_0201LF-1K,1%,1/20W,CHIP,CS21001FE07   I112 @T6G_MB_LIB.T6G(SCH_1):PAGE401

JTAG_TRST_RT_CPU1_P1_N @T6G_MB_LIB.T6G(SCH_1):JTAG_TRST_RT_CPU1_P1_N
 U6015   E8 JTAG_TRST_N PT5161LRS-PT5161LRS,SMLF,IC,AJ051610U03    I47 @T6G_MB_LIB.T6G(SCH_1):PAGE392
 R1372    1      A Q_RES_0201LF-1K,1%,1/20W,CHIP,CS21001FE07   I115 @T6G_MB_LIB.T6G(SCH_1):PAGE392

JTAG_TRST_RT_CPU1_P2_N @T6G_MB_LIB.T6G(SCH_1):JTAG_TRST_RT_CPU1_P2_N
 U6016   E8 JTAG_TRST_N PT5161LRS-PT5161LRS,SMLF,IC,AJ051610U03    I97 @T6G_MB_LIB.T6G(SCH_1):PAGE451
 R1416    1      A Q_RES_0201LF-1K,1%,1/20W,CHIP,CS21001FE07   I102 @T6G_MB_LIB.T6G(SCH_1):PAGE451

JTAG_TRST_RT_CPU1_P3_N @T6G_MB_LIB.T6G(SCH_1):JTAG_TRST_RT_CPU1_P3_N
 U6017   E8 JTAG_TRST_N PT5161LRS-PT5161LRS,SMLF,IC,AJ051610U03    I97 @T6G_MB_LIB.T6G(SCH_1):PAGE462
 R1429    1      A Q_RES_0201LF-1K,1%,1/20W,CHIP,CS21001FE07   I103 @T6G_MB_LIB.T6G(SCH_1):PAGE462

JTAG_TRST_R_N @T6G_MB_LIB.T6G(SCH_1):JTAG_TRST_R_N
 R1635    1      A Q_RES_0402LF-22,1%,1/16W,CHIP,CS02202FB02     I8 @T6G_MB_LIB.T6G(SCH_1):PAGE149
  U149   12     B3 SN74AVC4T774PWR-SN74AVC4T774PWR,SMLF,IC,AL04T774K00    I31 @T6G_MB_LIB.T6G(SCH_1):PAGE149
  U148   12     B3 SN74AVC4T774PWR-SN74AVC4T774PWR,SMLF,IC,AL04T774K00    I34 @T6G_MB_LIB.T6G(SCH_1):PAGE149

LED_BIOS_DBG_MODE @T6G_MB_LIB.T6G(SCH_1):LED_BIOS_DBG_MODE
    D9    C      C Q_LED_SMLF-LED_BLUE,LTST-C281TBKT-5A,IC,BEBL0172Z00    I79 @T6G_MB_LIB.T6G(SCH_1):PAGE142
   Q29    D  DRAIN MOSFET_N_GSD-NX138BK,SMLF,IC,BAM01380023    I80 @T6G_MB_LIB.T6G(SCH_1):PAGE142

LED_BIOS_DBG_MODE_N @T6G_MB_LIB.T6G(SCH_1):LED_BIOS_DBG_MODE_N
   Q29    G   GATE MOSFET_N_GSD-NX138BK,SMLF,IC,BAM01380023    I80 @T6G_MB_LIB.T6G(SCH_1):PAGE142
   Q30    D  DRAIN MOSFET_N_GSD-NX138BK,SMLF,IC,BAM01380023    I81 @T6G_MB_LIB.T6G(SCH_1):PAGE142
 R1507    2      B Q_RES_0402LF-1K,1%,1/16W,CHIP,CS21002FB06    I87 @T6G_MB_LIB.T6G(SCH_1):PAGE142

LED_BIOS_DBG_MODE_R @T6G_MB_LIB.T6G(SCH_1):LED_BIOS_DBG_MODE_R
    D9    A      A Q_LED_SMLF-LED_BLUE,LTST-C281TBKT-5A,IC,BEBL0172Z00    I79 @T6G_MB_LIB.T6G(SCH_1):PAGE142
 R1444    2      B Q_RES_0402LF-130,1%,1/16W,CHIP,CS11302FB03    I82 @T6G_MB_LIB.T6G(SCH_1):PAGE142

LED_HDD_ACTIVITY_B_N @T6G_MB_LIB.T6G(SCH_1):LED_HDD_ACTIVITY_B_N
 R3254    2      B Q_RES_0402LF-0,5%,1/16W,EMPTY,CS00002JB13    I50 @T6G_MB_LIB.T6G(SCH_1):PAGE348
  U239    4      Y 74LVC1G126SE7-74LVC1G126SE-7,SMLF,IC,AL1G0126009    I53 @T6G_MB_LIB.T6G(SCH_1):PAGE345
 R3297    1      A Q_RES_0402LF-10K,1%,1/16W,CHIP,CS31002FB08    I60 @T6G_MB_LIB.T6G(SCH_1):PAGE345
 R6075    1      A Q_RES_0402LF-0,5%,1/16W,CHIP,CS00002JB13    I57 @T6G_MB_LIB.T6G(SCH_1):PAGE84

LED_HDD_ACTIVITY_B_PLD_N @T6G_MB_LIB.T6G(SCH_1):LED_HDD_ACTIVITY_B_PLD_N
   U18   L1 PL16A||PCLKT4_0 LCMXO3LF9400C5BG484C-LCMXO3LF-9400C-5BG484C,SMLF,IA   I143 @T6G_MB_LIB.T6G(SCH_1):PAGE81
 R6075    2      B Q_RES_0402LF-0,5%,1/16W,CHIP,CS00002JB13    I57 @T6G_MB_LIB.T6G(SCH_1):PAGE84

LED_HDD_ACTIVITY_N @T6G_MB_LIB.T6G(SCH_1):LED_HDD_ACTIVITY_N
 R3294    2      B Q_RES_0402LF-0,5%,1/16W,CHIP,CS00002JB13    I19 @T6G_MB_LIB.T6G(SCH_1):PAGE345
 R3295    2      B Q_RES_0402LF-4.7K,1%,1/16W,CHIP,CS24702FB06    I21 @T6G_MB_LIB.T6G(SCH_1):PAGE345
  U239    2      A 74LVC1G126SE7-74LVC1G126SE-7,SMLF,IC,AL1G0126009    I53 @T6G_MB_LIB.T6G(SCH_1):PAGE345

LED_M2_SSD_0_ACT_N @T6G_MB_LIB.T6G(SCH_1):LED_M2_SSD_0_ACT_N
   J59   10 DAS_DSS#||LED1# SCONN75K_APCI0155P004A-SCONN75K_APCI0155-P004A,SMLA    I88 @T6G_MB_LIB.T6G(SCH_1):PAGE345
 R3294    1      A Q_RES_0402LF-0,5%,1/16W,CHIP,CS00002JB13    I19 @T6G_MB_LIB.T6G(SCH_1):PAGE345

LED_P12V_AUX_R1 @T6G_MB_LIB.T6G(SCH_1):LED_P12V_AUX_R1
 D8000    A      A Q_LED_SMLF-LED_BLUE,LTST-C281TBKT-5A,IC,BEBL0172Z00    I42 @T6G_MB_LIB.T6G(SCH_1):PAGE375
 R8022    1      A Q_RES_0402LF-560,1%,1/16W,CHIP,CS15602FB03    I44 @T6G_MB_LIB.T6G(SCH_1):PAGE375

LED_P12V_AUX_R2 @T6G_MB_LIB.T6G(SCH_1):LED_P12V_AUX_R2
 R8022    2      B Q_RES_0402LF-560,1%,1/16W,CHIP,CS15602FB03    I44 @T6G_MB_LIB.T6G(SCH_1):PAGE375
 R8023    1      A Q_RES_0402LF-560,1%,1/16W,CHIP,CS15602FB03    I45 @T6G_MB_LIB.T6G(SCH_1):PAGE375

LED_P12V_AUX_R3 @T6G_MB_LIB.T6G(SCH_1):LED_P12V_AUX_R3
 R8023    2      B Q_RES_0402LF-560,1%,1/16W,CHIP,CS15602FB03    I45 @T6G_MB_LIB.T6G(SCH_1):PAGE375
 R8024    1      A Q_RES_0402LF-560,1%,1/16W,CHIP,CS15602FB03    I46 @T6G_MB_LIB.T6G(SCH_1):PAGE375

LED_P12V_PSU_R1 @T6G_MB_LIB.T6G(SCH_1):LED_P12V_PSU_R1
 R8025    1      A Q_RES_0402LF-560,1%,1/16W,CHIP,CS15602FB03    I51 @T6G_MB_LIB.T6G(SCH_1):PAGE375
 D8001    A      A Q_LED_SMLF-LED_BLUE,LTST-C281TBKT-5A,IC,BEBL0172Z00    I52 @T6G_MB_LIB.T6G(SCH_1):PAGE375

LED_P12V_PSU_R2 @T6G_MB_LIB.T6G(SCH_1):LED_P12V_PSU_R2
 R8026    1      A Q_RES_0402LF-560,1%,1/16W,CHIP,CS15602FB03    I50 @T6G_MB_LIB.T6G(SCH_1):PAGE375
 R8025    2      B Q_RES_0402LF-560,1%,1/16W,CHIP,CS15602FB03    I51 @T6G_MB_LIB.T6G(SCH_1):PAGE375

LED_P12V_PSU_R3 @T6G_MB_LIB.T6G(SCH_1):LED_P12V_PSU_R3
 R8027    1      A Q_RES_0402LF-560,1%,1/16W,CHIP,CS15602FB03    I49 @T6G_MB_LIB.T6G(SCH_1):PAGE375
 R8026    2      B Q_RES_0402LF-560,1%,1/16W,CHIP,CS15602FB03    I50 @T6G_MB_LIB.T6G(SCH_1):PAGE375

LED_P12V_SCM_FAULT @T6G_MB_LIB.T6G(SCH_1):LED_P12V_SCM_FAULT
 R8029    1      A Q_RES_0402LF-249,1%,1/16W,CHIP,CS12492FB02    I55 @T6G_MB_LIB.T6G(SCH_1):PAGE375
 D8002    A      A Q_LED_SMLF-LED_YELLOW,LTST-C190KSKT-P,IC,BEYL0159ZA    I56 @T6G_MB_LIB.T6G(SCH_1):PAGE375

LED_P12V_SCM_FAULT_D1 @T6G_MB_LIB.T6G(SCH_1):LED_P12V_SCM_FAULT_D1
 Q8001    6     D1 MOSFET_NCH_DUAL-PJT138K,SMLF,IC,BAM138K0003    I57 @T6G_MB_LIB.T6G(SCH_1):PAGE375
 Q8001    5     G2 MOSFET_NCH_DUAL-PJT138K,SMLF,IC,BAM138K0003    I58 @T6G_MB_LIB.T6G(SCH_1):PAGE375
 R8028    2      B Q_RES_0402LF-4.7K,5%,1/16W,CHIP,CS24702JB10    I62 @T6G_MB_LIB.T6G(SCH_1):PAGE375

LED_P12V_SCM_FAULT_D2 @T6G_MB_LIB.T6G(SCH_1):LED_P12V_SCM_FAULT_D2
 D8002    C      C Q_LED_SMLF-LED_YELLOW,LTST-C190KSKT-P,IC,BEYL0159ZA    I56 @T6G_MB_LIB.T6G(SCH_1):PAGE375
 Q8001    3     D2 MOSFET_NCH_DUAL-PJT138K,SMLF,IC,BAM138K0003    I58 @T6G_MB_LIB.T6G(SCH_1):PAGE375

LED_P3V3 @T6G_MB_LIB.T6G(SCH_1):LED_P3V3
   D99    A      A Q_LED_SMLF-LED_BLUE,LTST-C281TBKT-5A,IC,BEBL0172Z00     I3 @T6G_MB_LIB.T6G(SCH_1):PAGE254
 R3100    1      A Q_RES_0402LF-130,1%,1/16W,CHIP,CS11302FB03     I8 @T6G_MB_LIB.T6G(SCH_1):PAGE254

LED_P5V @T6G_MB_LIB.T6G(SCH_1):LED_P5V
 R3102    1      A Q_RES_0402LF-470,1%,1/16W,CHIP,CS14702FB04     I9 @T6G_MB_LIB.T6G(SCH_1):PAGE254
   D98    A      A Q_LED_SMLF-LED_BLUE,LTST-C281TBKT-5A,IC,BEBL0172Z00    I17 @T6G_MB_LIB.T6G(SCH_1):PAGE254

LED_PWRGD_P1V2_AUX @T6G_MB_LIB.T6G(SCH_1):LED_PWRGD_P1V2_AUX
 D6000    A      A Q_LED_SMLF-LED_BLUE,LTST-C281TBKT-5A,IC,BEBL0172Z00    I43 @T6G_MB_LIB.T6G(SCH_1):PAGE254
 R6246    1      A Q_RES_0402LF-130,1%,1/16W,CHIP,CS11302FB03    I45 @T6G_MB_LIB.T6G(SCH_1):PAGE254

LED_PWRGD_P1V2_AUX_D @T6G_MB_LIB.T6G(SCH_1):LED_PWRGD_P1V2_AUX_D
 D6000    C      C Q_LED_SMLF-LED_BLUE,LTST-C281TBKT-5A,IC,BEBL0172Z00    I43 @T6G_MB_LIB.T6G(SCH_1):PAGE254
 Q6000    6     D1 MOSFET_NCH_DUAL-PJT138K,SMLF,IC,BAM138K0003    I47 @T6G_MB_LIB.T6G(SCH_1):PAGE254

LED_PWRGD_P1V8_AUX @T6G_MB_LIB.T6G(SCH_1):LED_PWRGD_P1V8_AUX
 R3071    1      A Q_RES_0402LF-130,1%,1/16W,CHIP,CS11302FB03    I21 @T6G_MB_LIB.T6G(SCH_1):PAGE254
   D91    A      A Q_LED_SMLF-LED_BLUE,LTST-C281TBKT-5A,IC,BEBL0172Z00    I23 @T6G_MB_LIB.T6G(SCH_1):PAGE254

LED_PWRGD_P1V8_AUX_D @T6G_MB_LIB.T6G(SCH_1):LED_PWRGD_P1V8_AUX_D
   D91    C      C Q_LED_SMLF-LED_BLUE,LTST-C281TBKT-5A,IC,BEBL0172Z00    I23 @T6G_MB_LIB.T6G(SCH_1):PAGE254
   Q78    6     D1 MOSFET_NCH_DUAL-PJT138K,SMLF,IC,BAM138K0003    I24 @T6G_MB_LIB.T6G(SCH_1):PAGE254

LED_PWRGD_PS_PWROK_PLD @T6G_MB_LIB.T6G(SCH_1):LED_PWRGD_PS_PWROK_PLD
   D96    A      A Q_LED_SMLF-LED_BLUE,LTST-C281TBKT-5A,IC,BEBL0172Z00    I14 @T6G_MB_LIB.T6G(SCH_1):PAGE254
 R3075    1      A Q_RES_0402LF-130,1%,1/16W,CHIP,CS11302FB03    I15 @T6G_MB_LIB.T6G(SCH_1):PAGE254

LED_PWRGD_PS_PWROK_PLD_D @T6G_MB_LIB.T6G(SCH_1):LED_PWRGD_PS_PWROK_PLD_D
   D96    C      C Q_LED_SMLF-LED_BLUE,LTST-C281TBKT-5A,IC,BEBL0172Z00    I14 @T6G_MB_LIB.T6G(SCH_1):PAGE254
   Q78    3     D2 MOSFET_NCH_DUAL-PJT138K,SMLF,IC,BAM138K0003    I18 @T6G_MB_LIB.T6G(SCH_1):PAGE254

LED_PWRGD_PVDD11_S3_P0_D @T6G_MB_LIB.T6G(SCH_1):LED_PWRGD_PVDD11_S3_P0_D
   Q81    3     D2 MOSFET_NCH_DUAL-PJT138K,SMLF,IC,BAM138K0003    I27 @T6G_MB_LIB.T6G(SCH_1):PAGE374
   D78    C      C Q_LED_SMLF-LED_BLUE,LTST-C281TBKT-5A,IC,BEBL0172Z00    I32 @T6G_MB_LIB.T6G(SCH_1):PAGE374

LED_PWRGD_PVDD11_S3_P0_R @T6G_MB_LIB.T6G(SCH_1):LED_PWRGD_PVDD11_S3_P0_R
   D78    A      A Q_LED_SMLF-LED_BLUE,LTST-C281TBKT-5A,IC,BEBL0172Z00    I32 @T6G_MB_LIB.T6G(SCH_1):PAGE374
 R3090    1      A Q_RES_0402LF-130,1%,1/16W,CHIP,CS11302FB03    I38 @T6G_MB_LIB.T6G(SCH_1):PAGE374

LED_PWRGD_PVDD11_S3_P1_D @T6G_MB_LIB.T6G(SCH_1):LED_PWRGD_PVDD11_S3_P1_D
   Q86    6     D1 MOSFET_NCH_DUAL-PJT138K,SMLF,IC,BAM138K0003    I30 @T6G_MB_LIB.T6G(SCH_1):PAGE375
   D84    C      C Q_LED_SMLF-LED_BLUE,LTST-C281TBKT-5A,IC,BEBL0172Z00    I35 @T6G_MB_LIB.T6G(SCH_1):PAGE375

LED_PWRGD_PVDD11_S3_P1_R @T6G_MB_LIB.T6G(SCH_1):LED_PWRGD_PVDD11_S3_P1_R
   D84    A      A Q_LED_SMLF-LED_BLUE,LTST-C281TBKT-5A,IC,BEBL0172Z00    I35 @T6G_MB_LIB.T6G(SCH_1):PAGE375
 R3099    1      A Q_RES_0402LF-130,1%,1/16W,CHIP,CS11302FB03    I40 @T6G_MB_LIB.T6G(SCH_1):PAGE375

LED_PWRGD_PVDD18_S5_P0_D @T6G_MB_LIB.T6G(SCH_1):LED_PWRGD_PVDD18_S5_P0_D
   Q83    6     D1 MOSFET_NCH_DUAL-PJT138K,SMLF,IC,BAM138K0003    I23 @T6G_MB_LIB.T6G(SCH_1):PAGE374
   D79    C      C Q_LED_SMLF-LED_BLUE,LTST-C281TBKT-5A,IC,BEBL0172Z00    I30 @T6G_MB_LIB.T6G(SCH_1):PAGE374

LED_PWRGD_PVDD18_S5_P0_R @T6G_MB_LIB.T6G(SCH_1):LED_PWRGD_PVDD18_S5_P0_R
   D79    A      A Q_LED_SMLF-LED_BLUE,LTST-C281TBKT-5A,IC,BEBL0172Z00    I30 @T6G_MB_LIB.T6G(SCH_1):PAGE374
 R3091    1      A Q_RES_0402LF-130,1%,1/16W,CHIP,CS11302FB03    I37 @T6G_MB_LIB.T6G(SCH_1):PAGE374

LED_PWRGD_PVDD18_S5_P1_D @T6G_MB_LIB.T6G(SCH_1):LED_PWRGD_PVDD18_S5_P1_D
   Q86    3     D2 MOSFET_NCH_DUAL-PJT138K,SMLF,IC,BAM138K0003    I29 @T6G_MB_LIB.T6G(SCH_1):PAGE375
   D85    C      C Q_LED_SMLF-LED_BLUE,LTST-C281TBKT-5A,IC,BEBL0172Z00    I33 @T6G_MB_LIB.T6G(SCH_1):PAGE375

LED_PWRGD_PVDD18_S5_P1_R @T6G_MB_LIB.T6G(SCH_1):LED_PWRGD_PVDD18_S5_P1_R
   D85    A      A Q_LED_SMLF-LED_BLUE,LTST-C281TBKT-5A,IC,BEBL0172Z00    I33 @T6G_MB_LIB.T6G(SCH_1):PAGE375
 R3097    1      A Q_RES_0402LF-130,1%,1/16W,CHIP,CS11302FB03    I38 @T6G_MB_LIB.T6G(SCH_1):PAGE375

LED_PWRGD_PVDD33_S5_D @T6G_MB_LIB.T6G(SCH_1):LED_PWRGD_PVDD33_S5_D
   Q79    6     D1 MOSFET_NCH_DUAL-PJT138K,SMLF,IC,BAM138K0003    I18 @T6G_MB_LIB.T6G(SCH_1):PAGE374
   D73    C      C Q_LED_SMLF-LED_BLUE,LTST-C281TBKT-5A,IC,BEBL0172Z00    I19 @T6G_MB_LIB.T6G(SCH_1):PAGE374

LED_PWRGD_PVDD33_S5_R @T6G_MB_LIB.T6G(SCH_1):LED_PWRGD_PVDD33_S5_R
   D73    A      A Q_LED_SMLF-LED_BLUE,LTST-C281TBKT-5A,IC,BEBL0172Z00    I19 @T6G_MB_LIB.T6G(SCH_1):PAGE374
 R3086    1      A Q_RES_0402LF-130,1%,1/16W,CHIP,CS11302FB03    I20 @T6G_MB_LIB.T6G(SCH_1):PAGE374

LED_PWRGD_PVDDCR_CPU0_P0_D @T6G_MB_LIB.T6G(SCH_1):LED_PWRGD_PVDDCR_CPU0_P0_D
   Q79    3     D2 MOSFET_NCH_DUAL-PJT138K,SMLF,IC,BAM138K0003     I8 @T6G_MB_LIB.T6G(SCH_1):PAGE374
   D74    C      C Q_LED_SMLF-LED_BLUE,LTST-C281TBKT-5A,IC,BEBL0172Z00    I14 @T6G_MB_LIB.T6G(SCH_1):PAGE374

LED_PWRGD_PVDDCR_CPU0_P0_R @T6G_MB_LIB.T6G(SCH_1):LED_PWRGD_PVDDCR_CPU0_P0_R
   D74    A      A Q_LED_SMLF-LED_BLUE,LTST-C281TBKT-5A,IC,BEBL0172Z00    I14 @T6G_MB_LIB.T6G(SCH_1):PAGE374
 R3087    1      A Q_RES_0402LF-130,1%,1/16W,CHIP,CS11302FB03    I16 @T6G_MB_LIB.T6G(SCH_1):PAGE374

LED_PWRGD_PVDDCR_CPU0_P1_D @T6G_MB_LIB.T6G(SCH_1):LED_PWRGD_PVDDCR_CPU0_P1_D
   Q84    6     D1 MOSFET_NCH_DUAL-PJT138K,SMLF,IC,BAM138K0003    I11 @T6G_MB_LIB.T6G(SCH_1):PAGE375
   D80    C      C Q_LED_SMLF-LED_BLUE,LTST-C281TBKT-5A,IC,BEBL0172Z00    I19 @T6G_MB_LIB.T6G(SCH_1):PAGE375

LED_PWRGD_PVDDCR_CPU0_P1_R @T6G_MB_LIB.T6G(SCH_1):LED_PWRGD_PVDDCR_CPU0_P1_R
   D80    A      A Q_LED_SMLF-LED_BLUE,LTST-C281TBKT-5A,IC,BEBL0172Z00    I19 @T6G_MB_LIB.T6G(SCH_1):PAGE375
 R3093    1      A Q_RES_0402LF-130,1%,1/16W,CHIP,CS11302FB03    I20 @T6G_MB_LIB.T6G(SCH_1):PAGE375

LED_PWRGD_PVDDCR_CPU1_P0_D @T6G_MB_LIB.T6G(SCH_1):LED_PWRGD_PVDDCR_CPU1_P0_D
   Q80    3     D2 MOSFET_NCH_DUAL-PJT138K,SMLF,IC,BAM138K0003     I3 @T6G_MB_LIB.T6G(SCH_1):PAGE374
   D76    C      C Q_LED_SMLF-LED_BLUE,LTST-C281TBKT-5A,IC,BEBL0172Z00    I11 @T6G_MB_LIB.T6G(SCH_1):PAGE374

LED_PWRGD_PVDDCR_CPU1_P0_R @T6G_MB_LIB.T6G(SCH_1):LED_PWRGD_PVDDCR_CPU1_P0_R
   D76    A      A Q_LED_SMLF-LED_BLUE,LTST-C281TBKT-5A,IC,BEBL0172Z00    I11 @T6G_MB_LIB.T6G(SCH_1):PAGE374
 R3088    1      A Q_RES_0402LF-130,1%,1/16W,CHIP,CS11302FB03    I12 @T6G_MB_LIB.T6G(SCH_1):PAGE374

LED_PWRGD_PVDDCR_CPU1_P1_D @T6G_MB_LIB.T6G(SCH_1):LED_PWRGD_PVDDCR_CPU1_P1_D
   Q85    6     D1 MOSFET_NCH_DUAL-PJT138K,SMLF,IC,BAM138K0003     I7 @T6G_MB_LIB.T6G(SCH_1):PAGE375
   D82    C      C Q_LED_SMLF-LED_BLUE,LTST-C281TBKT-5A,IC,BEBL0172Z00    I14 @T6G_MB_LIB.T6G(SCH_1):PAGE375

LED_PWRGD_PVDDCR_CPU1_P1_R @T6G_MB_LIB.T6G(SCH_1):LED_PWRGD_PVDDCR_CPU1_P1_R
   D82    A      A Q_LED_SMLF-LED_BLUE,LTST-C281TBKT-5A,IC,BEBL0172Z00    I14 @T6G_MB_LIB.T6G(SCH_1):PAGE375
 R3096    1      A Q_RES_0402LF-130,1%,1/16W,CHIP,CS11302FB03    I16 @T6G_MB_LIB.T6G(SCH_1):PAGE375

LED_PWRGD_PVDDCR_SOC_P0_D @T6G_MB_LIB.T6G(SCH_1):LED_PWRGD_PVDDCR_SOC_P0_D
   Q80    6     D1 MOSFET_NCH_DUAL-PJT138K,SMLF,IC,BAM138K0003     I6 @T6G_MB_LIB.T6G(SCH_1):PAGE374
   D75    C      C Q_LED_SMLF-LED_BLUE,LTST-C281TBKT-5A,IC,BEBL0172Z00    I13 @T6G_MB_LIB.T6G(SCH_1):PAGE374

LED_PWRGD_PVDDCR_SOC_P0_R @T6G_MB_LIB.T6G(SCH_1):LED_PWRGD_PVDDCR_SOC_P0_R
   D75    A      A Q_LED_SMLF-LED_BLUE,LTST-C281TBKT-5A,IC,BEBL0172Z00    I13 @T6G_MB_LIB.T6G(SCH_1):PAGE374
 R3089    1      A Q_RES_0402LF-130,1%,1/16W,CHIP,CS11302FB03    I15 @T6G_MB_LIB.T6G(SCH_1):PAGE374

LED_PWRGD_PVDDCR_SOC_P1_D @T6G_MB_LIB.T6G(SCH_1):LED_PWRGD_PVDDCR_SOC_P1_D
   Q84    3     D2 MOSFET_NCH_DUAL-PJT138K,SMLF,IC,BAM138K0003    I10 @T6G_MB_LIB.T6G(SCH_1):PAGE375
   D81    C      C Q_LED_SMLF-LED_BLUE,LTST-C281TBKT-5A,IC,BEBL0172Z00    I17 @T6G_MB_LIB.T6G(SCH_1):PAGE375

LED_PWRGD_PVDDCR_SOC_P1_R @T6G_MB_LIB.T6G(SCH_1):LED_PWRGD_PVDDCR_SOC_P1_R
   D81    A      A Q_LED_SMLF-LED_BLUE,LTST-C281TBKT-5A,IC,BEBL0172Z00    I17 @T6G_MB_LIB.T6G(SCH_1):PAGE375
 R3094    1      A Q_RES_0402LF-130,1%,1/16W,CHIP,CS11302FB03    I18 @T6G_MB_LIB.T6G(SCH_1):PAGE375

LED_PWRGD_PVDDIO_P0_D @T6G_MB_LIB.T6G(SCH_1):LED_PWRGD_PVDDIO_P0_D
   Q81    6     D1 MOSFET_NCH_DUAL-PJT138K,SMLF,IC,BAM138K0003    I35 @T6G_MB_LIB.T6G(SCH_1):PAGE374
   D77    C      C Q_LED_SMLF-LED_BLUE,LTST-C281TBKT-5A,IC,BEBL0172Z00    I36 @T6G_MB_LIB.T6G(SCH_1):PAGE374

LED_PWRGD_PVDDIO_P0_R @T6G_MB_LIB.T6G(SCH_1):LED_PWRGD_PVDDIO_P0_R
   D77    A      A Q_LED_SMLF-LED_BLUE,LTST-C281TBKT-5A,IC,BEBL0172Z00    I36 @T6G_MB_LIB.T6G(SCH_1):PAGE374
 R3092    1      A Q_RES_0402LF-130,1%,1/16W,CHIP,CS11302FB03    I41 @T6G_MB_LIB.T6G(SCH_1):PAGE374

LED_PWRGD_PVDDIO_P1_D @T6G_MB_LIB.T6G(SCH_1):LED_PWRGD_PVDDIO_P1_D
   Q85    3     D2 MOSFET_NCH_DUAL-PJT138K,SMLF,IC,BAM138K0003     I2 @T6G_MB_LIB.T6G(SCH_1):PAGE375
   D83    C      C Q_LED_SMLF-LED_BLUE,LTST-C281TBKT-5A,IC,BEBL0172Z00    I13 @T6G_MB_LIB.T6G(SCH_1):PAGE375

LED_PWRGD_PVDDIO_P1_R @T6G_MB_LIB.T6G(SCH_1):LED_PWRGD_PVDDIO_P1_R
   D83    A      A Q_LED_SMLF-LED_BLUE,LTST-C281TBKT-5A,IC,BEBL0172Z00    I13 @T6G_MB_LIB.T6G(SCH_1):PAGE375
 R3095    1      A Q_RES_0402LF-130,1%,1/16W,CHIP,CS11302FB03    I15 @T6G_MB_LIB.T6G(SCH_1):PAGE375

LED_PWRGD_SYS_PWROK_R @T6G_MB_LIB.T6G(SCH_1):LED_PWRGD_SYS_PWROK_R
 R3069    1      A Q_RES_0402LF-130,1%,1/16W,CHIP,CS11302FB03    I32 @T6G_MB_LIB.T6G(SCH_1):PAGE254
   D88    A      A Q_LED_SMLF-LED_BLUE,LTST-C281TBKT-5A,IC,BEBL0172Z00    I33 @T6G_MB_LIB.T6G(SCH_1):PAGE254

LED_PWRGD_SYS_PWROK_R_D @T6G_MB_LIB.T6G(SCH_1):LED_PWRGD_SYS_PWROK_R_D
   D88    C      C Q_LED_SMLF-LED_BLUE,LTST-C281TBKT-5A,IC,BEBL0172Z00    I33 @T6G_MB_LIB.T6G(SCH_1):PAGE254
   Q87    3     D2 MOSFET_NCH_DUAL-PJT138K,SMLF,IC,BAM138K0003    I35 @T6G_MB_LIB.T6G(SCH_1):PAGE254

LED_RST_RSMRST_PLD_R_N @T6G_MB_LIB.T6G(SCH_1):LED_RST_RSMRST_PLD_R_N
   D93    A      A Q_LED_SMLF-LED_BLUE,LTST-C281TBKT-5A,IC,BEBL0172Z00    I40 @T6G_MB_LIB.T6G(SCH_1):PAGE254
 R3074    1      A Q_RES_0402LF-130,1%,1/16W,CHIP,CS11302FB03    I41 @T6G_MB_LIB.T6G(SCH_1):PAGE254

LED_RST_RSMRST_PLD_R_N_D @T6G_MB_LIB.T6G(SCH_1):LED_RST_RSMRST_PLD_R_N_D
   Q87    6     D1 MOSFET_NCH_DUAL-PJT138K,SMLF,IC,BAM138K0003    I38 @T6G_MB_LIB.T6G(SCH_1):PAGE254
   D93    C      C Q_LED_SMLF-LED_BLUE,LTST-C281TBKT-5A,IC,BEBL0172Z00    I40 @T6G_MB_LIB.T6G(SCH_1):PAGE254

M2_0_P3V3_ADC_ALERT @T6G_MB_LIB.T6G(SCH_1):M2_0_P3V3_ADC_ALERT
 R3560    2      B Q_RES_0402LF-0,5%,1/16W,CHIP,CS00002JB13    I41 @T6G_MB_LIB.T6G(SCH_1):PAGE360
   U18   M1  PL17A LCMXO3LF9400C5BG484C-LCMXO3LF-9400C-5BG484C,SMLF,IA   I143 @T6G_MB_LIB.T6G(SCH_1):PAGE81

M2_0_P3V3_ADC_ALERT_R @T6G_MB_LIB.T6G(SCH_1):M2_0_P3V3_ADC_ALERT_R
 R3560    1      A Q_RES_0402LF-0,5%,1/16W,CHIP,CS00002JB13    I41 @T6G_MB_LIB.T6G(SCH_1):PAGE360
  U264    3 EXT_CLK||INT ISL28022FRZT-ISL28022FRZ-T,SMLF,IC,AL028022003    I46 @T6G_MB_LIB.T6G(SCH_1):PAGE360
 R4090    2      B Q_RES_0402LF-1K,1%,1/16W,CHIP,CS21002FB06   I124 @T6G_MB_LIB.T6G(SCH_1):PAGE360

M2_0_PEWAKE_N @T6G_MB_LIB.T6G(SCH_1):M2_0_PEWAKE_N
   J59   54 PEWAKE# SCONN75K_APCI0155P004A-SCONN75K_APCI0155-P004A,SMLA    I88 @T6G_MB_LIB.T6G(SCH_1):PAGE345
 R3301    2      B Q_RES_0402LF-33.2,1%,1/16W,CHIP,CS03322FB03    I30 @T6G_MB_LIB.T6G(SCH_1):PAGE345

M2_0_PEWAKE_R_N @T6G_MB_LIB.T6G(SCH_1):M2_0_PEWAKE_R_N
 R3301    1      A Q_RES_0402LF-33.2,1%,1/16W,CHIP,CS03322FB03    I30 @T6G_MB_LIB.T6G(SCH_1):PAGE345
 R1005    1      A Q_RES_0402LF-33,5%,1/16W,CHIP,CS03302JB10     I4 @T6G_MB_LIB.T6G(SCH_1):PAGE132

M2_SSD0_CLKREQ_EN_N @T6G_MB_LIB.T6G(SCH_1):M2_SSD0_CLKREQ_EN_N
  U259    1     1A SN74LVC2G07DCKR_SMLF-SN74LVC2G07DCKR,IC,AL002G07006     I5 @T6G_MB_LIB.T6G(SCH_1):PAGE345
  R138    1      A Q_RES_0402LF-4.7K,1%,1/16W,EMPTY,CS24702FB06    I15 @T6G_MB_LIB.T6G(SCH_1):PAGE345
  R153    1      A Q_RES_0402LF-0,5%,1/16W,CHIP,CS00002JB13    I27 @T6G_MB_LIB.T6G(SCH_1):PAGE345
 R6053    1      A Q_RES_0402LF-0,5%,1/16W,CHIP,CS00002JB13    I85 @T6G_MB_LIB.T6G(SCH_1):PAGE81

M2_SSD0_CLKREQ_EN_N_BUF @T6G_MB_LIB.T6G(SCH_1):M2_SSD0_CLKREQ_EN_N_BUF
   J59   52 CLKREQ# SCONN75K_APCI0155P004A-SCONN75K_APCI0155-P004A,SMLA    I88 @T6G_MB_LIB.T6G(SCH_1):PAGE345
  R153    2      B Q_RES_0402LF-0,5%,1/16W,CHIP,CS00002JB13    I27 @T6G_MB_LIB.T6G(SCH_1):PAGE345
  R155    2      B Q_RES_0402LF-1K,1%,1/16W,EMPTY,CS21002FB06    I32 @T6G_MB_LIB.T6G(SCH_1):PAGE345

MAX11617_2_VREF @T6G_MB_LIB.T6G(SCH_1):MAX11617_2_VREF
 C1074    1      A Q_CAP_0402-0.1UF,25V,10%,X7R,CH4104K1B00   I115 @T6G_MB_LIB.T6G(SCH_1):PAGE263
 C1076    1      A Q_CAP_C0805-10UF,16V,10%,X6S,CH6103KEA00   I152 @T6G_MB_LIB.T6G(SCH_1):PAGE263
 R1230    1      A Q_RES_0402LF-2K,1%,1/16W,CHIP,CS22002FB07   I154 @T6G_MB_LIB.T6G(SCH_1):PAGE263

MAX11617_2_VREF_R @T6G_MB_LIB.T6G(SCH_1):MAX11617_2_VREF_R
 R1230    2      B Q_RES_0402LF-2K,1%,1/16W,CHIP,CS22002FB07   I154 @T6G_MB_LIB.T6G(SCH_1):PAGE263
   U50    1 AIN11||REF MAX11617EEET-MAX11617EEE+T,SMLF,EMPTY,AL011617W00   I156 @T6G_MB_LIB.T6G(SCH_1):PAGE263

MAX11617_VREF @T6G_MB_LIB.T6G(SCH_1):MAX11617_VREF
 C1347    1      A Q_CAP_0402-0.1UF,25V,10%,X7R,CH4104K1B00   I119 @T6G_MB_LIB.T6G(SCH_1):PAGE369
 C1767    1      A Q_CAP_C0805-10UF,16V,10%,X6S,CH6103KEA00   I121 @T6G_MB_LIB.T6G(SCH_1):PAGE369
 R2900    1      A Q_RES_0402LF-2K,1%,1/16W,CHIP,CS22002FB07   I160 @T6G_MB_LIB.T6G(SCH_1):PAGE369

MAX11617_VREF_R @T6G_MB_LIB.T6G(SCH_1):MAX11617_VREF_R
 R2900    2      B Q_RES_0402LF-2K,1%,1/16W,CHIP,CS22002FB07   I160 @T6G_MB_LIB.T6G(SCH_1):PAGE369
  U193    1 AIN11||REF MAX11617EEET-MAX11617EEE+T,SMLF,EMPTY,AL011617W00   I169 @T6G_MB_LIB.T6G(SCH_1):PAGE369

MB0_CM_GATE_G0 @T6G_MB_LIB.T6G(SCH_1):MB0_CM_GATE_G0
PR2538    1      A Q_RES_0402LF-10,1%,1/16W,CHIP,CS01002FB07    I74 @T6G_MB_LIB.T6G(SCH_1):PAGE302
  PPQ9    4      4 MOSFET_NCH_1D3S-PSMNR58-30YLH,SMLF,IC,BAMNR580000    I75 @T6G_MB_LIB.T6G(SCH_1):PAGE302

MB0_P12V_STBY_PWRGD @T6G_MB_LIB.T6G(SCH_1):MB0_P12V_STBY_PWRGD
 R2531    1      A Q_RES_0402LF-0,5%,1/16W,CHIP,CS00002JB13     I3 @T6G_MB_LIB.T6G(SCH_1):PAGE365
 R3048    1      A Q_RES_0402LF-0,5%,1/16W,CHIP,CS00002JB13     I7 @T6G_MB_LIB.T6G(SCH_1):PAGE368
 R3047    1      A Q_RES_0402LF-0,5%,1/16W,CHIP,CS00002JB13     I8 @T6G_MB_LIB.T6G(SCH_1):PAGE368
 R6097    1      A Q_RES_0402LF-0,5%,1/16W,CHIP,CS00002JB13    I40 @T6G_MB_LIB.T6G(SCH_1):PAGE244
 R1117    1      A Q_RES_0402LF-6.19K,1%,1/16W,CHIP,CS26192FB03    I22 @T6G_MB_LIB.T6G(SCH_1):PAGE267
 PU289   13 PG||OCW# MP5990GMA1111Z-MP5990GMA-1111-Z,SMLF,IC,AR0F0TP4023    I58 @T6G_MB_LIB.T6G(SCH_1):PAGE267
 R3933    2      B Q_RES_0402LF-16.9K,1%,1/16W,CHIP,CS31692FB03    I63 @T6G_MB_LIB.T6G(SCH_1):PAGE267
  PJ38   15     15 SCONN21_9193031121LF-SCONN21_91930-31121LF,SMLF,IOA    I42 @T6G_MB_LIB.T6G(SCH_1):PAGE371

MB_FRU_ADDR0 @T6G_MB_LIB.T6G(SCH_1):MB_FRU_ADDR0
   U64    1     E0 M24128BWMN6TP-M24128-BWMN6TP,SMLF,IC,AKE30Z00613    I35 @T6G_MB_LIB.T6G(SCH_1):PAGE361
  R722    1      A Q_RES_0402LF-1K,1%,1/16W,EMPTY,CS21002FB06    I61 @T6G_MB_LIB.T6G(SCH_1):PAGE361
  R721    2      B Q_RES_0402LF-10K,1%,1/16W,CHIP,CS31002FB08    I62 @T6G_MB_LIB.T6G(SCH_1):PAGE361

MB_FRU_ADDR1 @T6G_MB_LIB.T6G(SCH_1):MB_FRU_ADDR1
   U64    2     E1 M24128BWMN6TP-M24128-BWMN6TP,SMLF,IC,AKE30Z00613    I35 @T6G_MB_LIB.T6G(SCH_1):PAGE361
  R717    2      B Q_RES_0402LF-10K,1%,1/16W,EMPTY,CS31002FB08    I45 @T6G_MB_LIB.T6G(SCH_1):PAGE361
  R718    1      A Q_RES_0402LF-1K,1%,1/16W,CHIP,CS21002FB06    I50 @T6G_MB_LIB.T6G(SCH_1):PAGE361

MB_FRU_ADDR2 @T6G_MB_LIB.T6G(SCH_1):MB_FRU_ADDR2
   U64    3     E2 M24128BWMN6TP-M24128-BWMN6TP,SMLF,IC,AKE30Z00613    I35 @T6G_MB_LIB.T6G(SCH_1):PAGE361
  R713    2      B Q_RES_0402LF-10K,1%,1/16W,EMPTY,CS31002FB08    I47 @T6G_MB_LIB.T6G(SCH_1):PAGE361
  R714    1      A Q_RES_0402LF-1K,1%,1/16W,CHIP,CS21002FB06    I52 @T6G_MB_LIB.T6G(SCH_1):PAGE361

MB_PDB_SMB9_R_EN @T6G_MB_LIB.T6G(SCH_1):MB_PDB_SMB9_R_EN
  U192    1 ENABLE LTC4307CMS8-LTC4307CMS8,SMLF,IC,AL004307000   I398 @T6G_MB_LIB.T6G(SCH_1):PAGE363
 R2796    2      B Q_RES_0402LF-0,5%,1/16W,CHIP,CS00002JB13   I420 @T6G_MB_LIB.T6G(SCH_1):PAGE363

MODE_RT_CPU0_P0 @T6G_MB_LIB.T6G(SCH_1):MODE_RT_CPU0_P0
 U6010  FJ9   MODE PT5161LRS-PT5161LRS,SMLF,IC,AJ051610U03    I53 @T6G_MB_LIB.T6G(SCH_1):PAGE385
 R1001    1      A Q_RES_0201LF-4.7K,5%,1/20W,EMPTY,CS24701JE04    I71 @T6G_MB_LIB.T6G(SCH_1):PAGE385
  R998    2      B Q_RES_0201LF-4.7K,5%,1/20W,CHIP,CS24701JE04    I72 @T6G_MB_LIB.T6G(SCH_1):PAGE385

MODE_RT_CPU0_P1 @T6G_MB_LIB.T6G(SCH_1):MODE_RT_CPU0_P1
 R1006    1      A Q_RES_0201LF-4.7K,5%,1/20W,EMPTY,CS24701JE04    I50 @T6G_MB_LIB.T6G(SCH_1):PAGE408
 R1039    2      B Q_RES_0201LF-4.7K,5%,1/20W,CHIP,CS24701JE04    I51 @T6G_MB_LIB.T6G(SCH_1):PAGE408
 U6011  FJ9   MODE PT5161LRS-PT5161LRS,SMLF,IC,AJ051610U03    I83 @T6G_MB_LIB.T6G(SCH_1):PAGE408

MODE_RT_CPU0_P2 @T6G_MB_LIB.T6G(SCH_1):MODE_RT_CPU0_P2
 R1048    1      A Q_RES_0201LF-4.7K,5%,1/20W,EMPTY,CS24701JE04    I50 @T6G_MB_LIB.T6G(SCH_1):PAGE419
 R1080    2      B Q_RES_0201LF-4.7K,5%,1/20W,CHIP,CS24701JE04    I51 @T6G_MB_LIB.T6G(SCH_1):PAGE419
 U6012  FJ9   MODE PT5161LRS-PT5161LRS,SMLF,IC,AJ051610U03    I83 @T6G_MB_LIB.T6G(SCH_1):PAGE419

MODE_RT_CPU0_P3 @T6G_MB_LIB.T6G(SCH_1):MODE_RT_CPU0_P3
 R1091    1      A Q_RES_0201LF-4.7K,5%,1/20W,EMPTY,CS24701JE04    I50 @T6G_MB_LIB.T6G(SCH_1):PAGE430
 R1122    2      B Q_RES_0201LF-4.7K,5%,1/20W,CHIP,CS24701JE04    I51 @T6G_MB_LIB.T6G(SCH_1):PAGE430
 U6013  FJ9   MODE PT5161LRS-PT5161LRS,SMLF,IC,AJ051610U03    I83 @T6G_MB_LIB.T6G(SCH_1):PAGE430

MODE_RT_CPU1_P0 @T6G_MB_LIB.T6G(SCH_1):MODE_RT_CPU1_P0
 U6014  FJ9   MODE PT5161LRS-PT5161LRS,SMLF,IC,AJ051610U03     I1 @T6G_MB_LIB.T6G(SCH_1):PAGE401
  R727    2      B Q_RES_0201LF-4.7K,5%,1/20W,CHIP,CS24701JE04    I54 @T6G_MB_LIB.T6G(SCH_1):PAGE401
  R728    1      A Q_RES_0201LF-4.7K,5%,1/20W,EMPTY,CS24701JE04    I55 @T6G_MB_LIB.T6G(SCH_1):PAGE401

MODE_RT_CPU1_P1 @T6G_MB_LIB.T6G(SCH_1):MODE_RT_CPU1_P1
 U6015  FJ9   MODE PT5161LRS-PT5161LRS,SMLF,IC,AJ051610U03    I47 @T6G_MB_LIB.T6G(SCH_1):PAGE392
  R794    1      A Q_RES_0201LF-4.7K,5%,1/20W,EMPTY,CS24701JE04    I65 @T6G_MB_LIB.T6G(SCH_1):PAGE392
  R793    2      B Q_RES_0201LF-4.7K,5%,1/20W,CHIP,CS24701JE04    I66 @T6G_MB_LIB.T6G(SCH_1):PAGE392

MODE_RT_CPU1_P2 @T6G_MB_LIB.T6G(SCH_1):MODE_RT_CPU1_P2
  R886    1      A Q_RES_0201LF-4.7K,5%,1/20W,EMPTY,CS24701JE04    I58 @T6G_MB_LIB.T6G(SCH_1):PAGE451
  R885    2      B Q_RES_0201LF-4.7K,5%,1/20W,CHIP,CS24701JE04    I59 @T6G_MB_LIB.T6G(SCH_1):PAGE451
 U6016  FJ9   MODE PT5161LRS-PT5161LRS,SMLF,IC,AJ051610U03    I97 @T6G_MB_LIB.T6G(SCH_1):PAGE451

MODE_RT_CPU1_P3 @T6G_MB_LIB.T6G(SCH_1):MODE_RT_CPU1_P3
  R926    1      A Q_RES_0201LF-4.7K,5%,1/20W,EMPTY,CS24701JE04    I64 @T6G_MB_LIB.T6G(SCH_1):PAGE462
  R925    2      B Q_RES_0201LF-4.7K,5%,1/20W,CHIP,CS24701JE04    I65 @T6G_MB_LIB.T6G(SCH_1):PAGE462
 U6017  FJ9   MODE PT5161LRS-PT5161LRS,SMLF,IC,AJ051610U03    I97 @T6G_MB_LIB.T6G(SCH_1):PAGE462

M_A_CPU0_ALERT_N @T6G_MB_LIB.T6G(SCH_1):M_A_CPU0_ALERT_N
  R375    1      A Q_RES_0402LF-15,1%,1/16W,CHIP,CS01502FB03   I837 @T6G_MB_LIB.T6G(SCH_1):PAGE10
    J1   62 ALERT_N SCONN288_DDR506112002KQ-SCONN288_DDR506112002KQ,SMA   I536 @T6G_MB_LIB.T6G(SCH_1):PAGE85

M_A_CPU0_ALERT_R_N @T6G_MB_LIB.T6G(SCH_1):M_A_CPU0_ALERT_R_N
   U25 AR74 MA_ALERT_L GENOA_SP5-SOCKET6096_13568-001,SMLF,IO,DGA^6000030   I200 @T6G_MB_LIB.T6G(SCH_1):PAGE10
  R375    2      B Q_RES_0402LF-15,1%,1/16W,CHIP,CS01502FB03   I837 @T6G_MB_LIB.T6G(SCH_1):PAGE10

M_A_CPU0_CLK_DN<0> @T6G_MB_LIB.T6G(SCH_1):M_A_CPU0_CLK_DN(0)
   U25 BD74 MA0_CLK_L GENOA_SP5-SOCKET6096_13568-001,SMLF,IO,DGA^6000030   I200 @T6G_MB_LIB.T6G(SCH_1):PAGE10
    J1  218   CK_C SCONN288_DDR506112002KQ-SCONN288_DDR506112002KQ,SMA   I536 @T6G_MB_LIB.T6G(SCH_1):PAGE85

M_A_CPU0_CLK_DP<0> @T6G_MB_LIB.T6G(SCH_1):M_A_CPU0_CLK_DP(0)
   U25 BC74 MA0_CLK_H GENOA_SP5-SOCKET6096_13568-001,SMLF,IO,DGA^6000030   I200 @T6G_MB_LIB.T6G(SCH_1):PAGE10
    J1  217   CK_T SCONN288_DDR506112002KQ-SCONN288_DDR506112002KQ,SMA   I536 @T6G_MB_LIB.T6G(SCH_1):PAGE85

M_A_CPU0_RESET_N @T6G_MB_LIB.T6G(SCH_1):M_A_CPU0_RESET_N
   U25 AT74 MA_RESET_L GENOA_SP5-SOCKET6096_13568-001,SMLF,IO,DGA^6000030   I200 @T6G_MB_LIB.T6G(SCH_1):PAGE10
    J1  207 RESET_N SCONN288_DDR506112002KQ-SCONN288_DDR506112002KQ,SMA   I536 @T6G_MB_LIB.T6G(SCH_1):PAGE85

M_A_CPU0_SA_CA<0> @T6G_MB_LIB.T6G(SCH_1):M_A_CPU0_SA_CA(0)
   U25 AW74 MAA_CA0 GENOA_SP5-SOCKET6096_13568-001,SMLF,IO,DGA^6000030   I200 @T6G_MB_LIB.T6G(SCH_1):PAGE10
    J1   66  CA0_A SCONN288_DDR506112002KQ-SCONN288_DDR506112002KQ,SMA   I536 @T6G_MB_LIB.T6G(SCH_1):PAGE85

M_A_CPU0_SA_CA<1> @T6G_MB_LIB.T6G(SCH_1):M_A_CPU0_SA_CA(1)
   U25 AY74 MAA_CA1 GENOA_SP5-SOCKET6096_13568-001,SMLF,IO,DGA^6000030   I200 @T6G_MB_LIB.T6G(SCH_1):PAGE10
    J1  211  CA1_A SCONN288_DDR506112002KQ-SCONN288_DDR506112002KQ,SMA   I536 @T6G_MB_LIB.T6G(SCH_1):PAGE85

M_A_CPU0_SA_CA<2> @T6G_MB_LIB.T6G(SCH_1):M_A_CPU0_SA_CA(2)
   U25 AY72 MAA_CA2 GENOA_SP5-SOCKET6096_13568-001,SMLF,IO,DGA^6000030   I200 @T6G_MB_LIB.T6G(SCH_1):PAGE10
    J1   68  CA2_A SCONN288_DDR506112002KQ-SCONN288_DDR506112002KQ,SMA   I536 @T6G_MB_LIB.T6G(SCH_1):PAGE85

M_A_CPU0_SA_CA<3> @T6G_MB_LIB.T6G(SCH_1):M_A_CPU0_SA_CA(3)
   U25 BA73 MAA_CA3 GENOA_SP5-SOCKET6096_13568-001,SMLF,IO,DGA^6000030   I200 @T6G_MB_LIB.T6G(SCH_1):PAGE10
    J1  213  CA3_A SCONN288_DDR506112002KQ-SCONN288_DDR506112002KQ,SMA   I536 @T6G_MB_LIB.T6G(SCH_1):PAGE85

M_A_CPU0_SA_CA<4> @T6G_MB_LIB.T6G(SCH_1):M_A_CPU0_SA_CA(4)
   U25 BA74 MAA_CA4 GENOA_SP5-SOCKET6096_13568-001,SMLF,IO,DGA^6000030   I200 @T6G_MB_LIB.T6G(SCH_1):PAGE10
    J1   70  CA4_A SCONN288_DDR506112002KQ-SCONN288_DDR506112002KQ,SMA   I536 @T6G_MB_LIB.T6G(SCH_1):PAGE85

M_A_CPU0_SA_CA<5> @T6G_MB_LIB.T6G(SCH_1):M_A_CPU0_SA_CA(5)
   U25 BB74 MAA_CA5 GENOA_SP5-SOCKET6096_13568-001,SMLF,IO,DGA^6000030   I200 @T6G_MB_LIB.T6G(SCH_1):PAGE10
    J1  215  CA5_A SCONN288_DDR506112002KQ-SCONN288_DDR506112002KQ,SMA   I536 @T6G_MB_LIB.T6G(SCH_1):PAGE85

M_A_CPU0_SA_CA<6> @T6G_MB_LIB.T6G(SCH_1):M_A_CPU0_SA_CA(6)
   U25 BB72 MAA_CA6 GENOA_SP5-SOCKET6096_13568-001,SMLF,IO,DGA^6000030   I200 @T6G_MB_LIB.T6G(SCH_1):PAGE10
    J1   72  CA6_A SCONN288_DDR506112002KQ-SCONN288_DDR506112002KQ,SMA   I536 @T6G_MB_LIB.T6G(SCH_1):PAGE85

M_A_CPU0_SA_CB<0> @T6G_MB_LIB.T6G(SCH_1):M_A_CPU0_SA_CB(0)
   U25 AJ74 MAA_CHECK0 GENOA_SP5-SOCKET6096_13568-001,SMLF,IO,DGA^6000030   I200 @T6G_MB_LIB.T6G(SCH_1):PAGE10
    J1   51  CB0_A SCONN288_DDR506112002KQ-SCONN288_DDR506112002KQ,SMA   I536 @T6G_MB_LIB.T6G(SCH_1):PAGE85

M_A_CPU0_SA_CB<1> @T6G_MB_LIB.T6G(SCH_1):M_A_CPU0_SA_CB(1)
   U25 AK72 MAA_CHECK1 GENOA_SP5-SOCKET6096_13568-001,SMLF,IO,DGA^6000030   I200 @T6G_MB_LIB.T6G(SCH_1):PAGE10
    J1   53  CB1_A SCONN288_DDR506112002KQ-SCONN288_DDR506112002KQ,SMA   I536 @T6G_MB_LIB.T6G(SCH_1):PAGE85

M_A_CPU0_SA_CB<2> @T6G_MB_LIB.T6G(SCH_1):M_A_CPU0_SA_CB(2)
   U25 AK74 MAA_CHECK2 GENOA_SP5-SOCKET6096_13568-001,SMLF,IO,DGA^6000030   I200 @T6G_MB_LIB.T6G(SCH_1):PAGE10
    J1  196  CB2_A SCONN288_DDR506112002KQ-SCONN288_DDR506112002KQ,SMA   I536 @T6G_MB_LIB.T6G(SCH_1):PAGE85

M_A_CPU0_SA_CB<3> @T6G_MB_LIB.T6G(SCH_1):M_A_CPU0_SA_CB(3)
   U25 AL73 MAA_CHECK3 GENOA_SP5-SOCKET6096_13568-001,SMLF,IO,DGA^6000030   I200 @T6G_MB_LIB.T6G(SCH_1):PAGE10
    J1  198  CB3_A SCONN288_DDR506112002KQ-SCONN288_DDR506112002KQ,SMA   I536 @T6G_MB_LIB.T6G(SCH_1):PAGE85

M_A_CPU0_SA_CB<4> @T6G_MB_LIB.T6G(SCH_1):M_A_CPU0_SA_CB(4)
   U25 AN74 MAA_CHECK4 GENOA_SP5-SOCKET6096_13568-001,SMLF,IO,DGA^6000030   I200 @T6G_MB_LIB.T6G(SCH_1):PAGE10
    J1   58  CB4_A SCONN288_DDR506112002KQ-SCONN288_DDR506112002KQ,SMA   I536 @T6G_MB_LIB.T6G(SCH_1):PAGE85

M_A_CPU0_SA_CB<5> @T6G_MB_LIB.T6G(SCH_1):M_A_CPU0_SA_CB(5)
   U25 AP72 MAA_CHECK5 GENOA_SP5-SOCKET6096_13568-001,SMLF,IO,DGA^6000030   I200 @T6G_MB_LIB.T6G(SCH_1):PAGE10
    J1   60  CB5_A SCONN288_DDR506112002KQ-SCONN288_DDR506112002KQ,SMA   I536 @T6G_MB_LIB.T6G(SCH_1):PAGE85

M_A_CPU0_SA_CB<6> @T6G_MB_LIB.T6G(SCH_1):M_A_CPU0_SA_CB(6)
   U25 AP74 MAA_CHECK6 GENOA_SP5-SOCKET6096_13568-001,SMLF,IO,DGA^6000030   I200 @T6G_MB_LIB.T6G(SCH_1):PAGE10
    J1  203  CB6_A SCONN288_DDR506112002KQ-SCONN288_DDR506112002KQ,SMA   I536 @T6G_MB_LIB.T6G(SCH_1):PAGE85

M_A_CPU0_SA_CB<7> @T6G_MB_LIB.T6G(SCH_1):M_A_CPU0_SA_CB(7)
   U25 AR73 MAA_CHECK7 GENOA_SP5-SOCKET6096_13568-001,SMLF,IO,DGA^6000030   I200 @T6G_MB_LIB.T6G(SCH_1):PAGE10
    J1  205  CB7_A SCONN288_DDR506112002KQ-SCONN288_DDR506112002KQ,SMA   I536 @T6G_MB_LIB.T6G(SCH_1):PAGE85

M_A_CPU0_SA_CS_N<0> @T6G_MB_LIB.T6G(SCH_1):M_A_CPU0_SA_CS_N(0)
   U25 AV74 MAA0_CS_L0 GENOA_SP5-SOCKET6096_13568-001,SMLF,IO,DGA^6000030   I200 @T6G_MB_LIB.T6G(SCH_1):PAGE10
    J1   64 CS0_A_N SCONN288_DDR506112002KQ-SCONN288_DDR506112002KQ,SMA   I536 @T6G_MB_LIB.T6G(SCH_1):PAGE85

M_A_CPU0_SA_CS_N<1> @T6G_MB_LIB.T6G(SCH_1):M_A_CPU0_SA_CS_N(1)
   U25 AW73 MAA0_CS_L1 GENOA_SP5-SOCKET6096_13568-001,SMLF,IO,DGA^6000030   I200 @T6G_MB_LIB.T6G(SCH_1):PAGE10
    J1  209 CS1_A_N SCONN288_DDR506112002KQ-SCONN288_DDR506112002KQ,SMA   I536 @T6G_MB_LIB.T6G(SCH_1):PAGE85

M_A_CPU0_SA_DQ<0> @T6G_MB_LIB.T6G(SCH_1):M_A_CPU0_SA_DQ(0)
   U25  E74 MAA_DATA0 GENOA_SP5-SOCKET6096_13568-001,SMLF,IO,DGA^6000030   I200 @T6G_MB_LIB.T6G(SCH_1):PAGE10
    J1    7  DQ0_A SCONN288_DDR506112002KQ-SCONN288_DDR506112002KQ,SMA   I536 @T6G_MB_LIB.T6G(SCH_1):PAGE85

M_A_CPU0_SA_DQ<10> @T6G_MB_LIB.T6G(SCH_1):M_A_CPU0_SA_DQ(10)
   U25  M74 MAA_DATA10 GENOA_SP5-SOCKET6096_13568-001,SMLF,IO,DGA^6000030   I200 @T6G_MB_LIB.T6G(SCH_1):PAGE10
    J1  163 DQ10_A SCONN288_DDR506112002KQ-SCONN288_DDR506112002KQ,SMA   I536 @T6G_MB_LIB.T6G(SCH_1):PAGE85

M_A_CPU0_SA_DQ<11> @T6G_MB_LIB.T6G(SCH_1):M_A_CPU0_SA_DQ(11)
   U25  N73 MAA_DATA11 GENOA_SP5-SOCKET6096_13568-001,SMLF,IO,DGA^6000030   I200 @T6G_MB_LIB.T6G(SCH_1):PAGE10
    J1  165 DQ11_A SCONN288_DDR506112002KQ-SCONN288_DDR506112002KQ,SMA   I536 @T6G_MB_LIB.T6G(SCH_1):PAGE85

M_A_CPU0_SA_DQ<12> @T6G_MB_LIB.T6G(SCH_1):M_A_CPU0_SA_DQ(12)
   U25  R74 MAA_DATA12 GENOA_SP5-SOCKET6096_13568-001,SMLF,IO,DGA^6000030   I200 @T6G_MB_LIB.T6G(SCH_1):PAGE10
    J1   25 DQ12_A SCONN288_DDR506112002KQ-SCONN288_DDR506112002KQ,SMA   I536 @T6G_MB_LIB.T6G(SCH_1):PAGE85

M_A_CPU0_SA_DQ<13> @T6G_MB_LIB.T6G(SCH_1):M_A_CPU0_SA_DQ(13)
   U25  T72 MAA_DATA13 GENOA_SP5-SOCKET6096_13568-001,SMLF,IO,DGA^6000030   I200 @T6G_MB_LIB.T6G(SCH_1):PAGE10
    J1   27 DQ13_A SCONN288_DDR506112002KQ-SCONN288_DDR506112002KQ,SMA   I536 @T6G_MB_LIB.T6G(SCH_1):PAGE85

M_A_CPU0_SA_DQ<14> @T6G_MB_LIB.T6G(SCH_1):M_A_CPU0_SA_DQ(14)
   U25  T74 MAA_DATA14 GENOA_SP5-SOCKET6096_13568-001,SMLF,IO,DGA^6000030   I200 @T6G_MB_LIB.T6G(SCH_1):PAGE10
    J1  170 DQ14_A SCONN288_DDR506112002KQ-SCONN288_DDR506112002KQ,SMA   I536 @T6G_MB_LIB.T6G(SCH_1):PAGE85

M_A_CPU0_SA_DQ<15> @T6G_MB_LIB.T6G(SCH_1):M_A_CPU0_SA_DQ(15)
   U25  U73 MAA_DATA15 GENOA_SP5-SOCKET6096_13568-001,SMLF,IO,DGA^6000030   I200 @T6G_MB_LIB.T6G(SCH_1):PAGE10
    J1  172 DQ15_A SCONN288_DDR506112002KQ-SCONN288_DDR506112002KQ,SMA   I536 @T6G_MB_LIB.T6G(SCH_1):PAGE85

M_A_CPU0_SA_DQ<16> @T6G_MB_LIB.T6G(SCH_1):M_A_CPU0_SA_DQ(16)
   U25  U74 MAA_DATA16 GENOA_SP5-SOCKET6096_13568-001,SMLF,IO,DGA^6000030   I200 @T6G_MB_LIB.T6G(SCH_1):PAGE10
    J1   29 DQ16_A SCONN288_DDR506112002KQ-SCONN288_DDR506112002KQ,SMA   I536 @T6G_MB_LIB.T6G(SCH_1):PAGE85

M_A_CPU0_SA_DQ<17> @T6G_MB_LIB.T6G(SCH_1):M_A_CPU0_SA_DQ(17)
   U25  V72 MAA_DATA17 GENOA_SP5-SOCKET6096_13568-001,SMLF,IO,DGA^6000030   I200 @T6G_MB_LIB.T6G(SCH_1):PAGE10
    J1   31 DQ17_A SCONN288_DDR506112002KQ-SCONN288_DDR506112002KQ,SMA   I536 @T6G_MB_LIB.T6G(SCH_1):PAGE85

M_A_CPU0_SA_DQ<18> @T6G_MB_LIB.T6G(SCH_1):M_A_CPU0_SA_DQ(18)
   U25  V74 MAA_DATA18 GENOA_SP5-SOCKET6096_13568-001,SMLF,IO,DGA^6000030   I200 @T6G_MB_LIB.T6G(SCH_1):PAGE10
    J1  174 DQ18_A SCONN288_DDR506112002KQ-SCONN288_DDR506112002KQ,SMA   I536 @T6G_MB_LIB.T6G(SCH_1):PAGE85

M_A_CPU0_SA_DQ<19> @T6G_MB_LIB.T6G(SCH_1):M_A_CPU0_SA_DQ(19)
   U25  W73 MAA_DATA19 GENOA_SP5-SOCKET6096_13568-001,SMLF,IO,DGA^6000030   I200 @T6G_MB_LIB.T6G(SCH_1):PAGE10
    J1  176 DQ19_A SCONN288_DDR506112002KQ-SCONN288_DDR506112002KQ,SMA   I536 @T6G_MB_LIB.T6G(SCH_1):PAGE85

M_A_CPU0_SA_DQ<1> @T6G_MB_LIB.T6G(SCH_1):M_A_CPU0_SA_DQ(1)
   U25  F72 MAA_DATA1 GENOA_SP5-SOCKET6096_13568-001,SMLF,IO,DGA^6000030   I200 @T6G_MB_LIB.T6G(SCH_1):PAGE10
    J1    9  DQ1_A SCONN288_DDR506112002KQ-SCONN288_DDR506112002KQ,SMA   I536 @T6G_MB_LIB.T6G(SCH_1):PAGE85

M_A_CPU0_SA_DQ<20> @T6G_MB_LIB.T6G(SCH_1):M_A_CPU0_SA_DQ(20)
   U25 AA74 MAA_DATA20 GENOA_SP5-SOCKET6096_13568-001,SMLF,IO,DGA^6000030   I200 @T6G_MB_LIB.T6G(SCH_1):PAGE10
    J1   36 DQ20_A SCONN288_DDR506112002KQ-SCONN288_DDR506112002KQ,SMA   I536 @T6G_MB_LIB.T6G(SCH_1):PAGE85

M_A_CPU0_SA_DQ<21> @T6G_MB_LIB.T6G(SCH_1):M_A_CPU0_SA_DQ(21)
   U25 AB72 MAA_DATA21 GENOA_SP5-SOCKET6096_13568-001,SMLF,IO,DGA^6000030   I200 @T6G_MB_LIB.T6G(SCH_1):PAGE10
    J1   38 DQ21_A SCONN288_DDR506112002KQ-SCONN288_DDR506112002KQ,SMA   I536 @T6G_MB_LIB.T6G(SCH_1):PAGE85

M_A_CPU0_SA_DQ<22> @T6G_MB_LIB.T6G(SCH_1):M_A_CPU0_SA_DQ(22)
   U25 AB74 MAA_DATA22 GENOA_SP5-SOCKET6096_13568-001,SMLF,IO,DGA^6000030   I200 @T6G_MB_LIB.T6G(SCH_1):PAGE10
    J1  181 DQ22_A SCONN288_DDR506112002KQ-SCONN288_DDR506112002KQ,SMA   I536 @T6G_MB_LIB.T6G(SCH_1):PAGE85

M_A_CPU0_SA_DQ<23> @T6G_MB_LIB.T6G(SCH_1):M_A_CPU0_SA_DQ(23)
   U25 AC73 MAA_DATA23 GENOA_SP5-SOCKET6096_13568-001,SMLF,IO,DGA^6000030   I200 @T6G_MB_LIB.T6G(SCH_1):PAGE10
    J1  183 DQ23_A SCONN288_DDR506112002KQ-SCONN288_DDR506112002KQ,SMA   I536 @T6G_MB_LIB.T6G(SCH_1):PAGE85

M_A_CPU0_SA_DQ<24> @T6G_MB_LIB.T6G(SCH_1):M_A_CPU0_SA_DQ(24)
   U25 AC74 MAA_DATA24 GENOA_SP5-SOCKET6096_13568-001,SMLF,IO,DGA^6000030   I200 @T6G_MB_LIB.T6G(SCH_1):PAGE10
    J1   40 DQ24_A SCONN288_DDR506112002KQ-SCONN288_DDR506112002KQ,SMA   I536 @T6G_MB_LIB.T6G(SCH_1):PAGE85

M_A_CPU0_SA_DQ<25> @T6G_MB_LIB.T6G(SCH_1):M_A_CPU0_SA_DQ(25)
   U25 AD72 MAA_DATA25 GENOA_SP5-SOCKET6096_13568-001,SMLF,IO,DGA^6000030   I200 @T6G_MB_LIB.T6G(SCH_1):PAGE10
    J1   42 DQ25_A SCONN288_DDR506112002KQ-SCONN288_DDR506112002KQ,SMA   I536 @T6G_MB_LIB.T6G(SCH_1):PAGE85

M_A_CPU0_SA_DQ<26> @T6G_MB_LIB.T6G(SCH_1):M_A_CPU0_SA_DQ(26)
   U25 AD74 MAA_DATA26 GENOA_SP5-SOCKET6096_13568-001,SMLF,IO,DGA^6000030   I200 @T6G_MB_LIB.T6G(SCH_1):PAGE10
    J1  185 DQ26_A SCONN288_DDR506112002KQ-SCONN288_DDR506112002KQ,SMA   I536 @T6G_MB_LIB.T6G(SCH_1):PAGE85

M_A_CPU0_SA_DQ<27> @T6G_MB_LIB.T6G(SCH_1):M_A_CPU0_SA_DQ(27)
   U25 AE73 MAA_DATA27 GENOA_SP5-SOCKET6096_13568-001,SMLF,IO,DGA^6000030   I200 @T6G_MB_LIB.T6G(SCH_1):PAGE10
    J1  187 DQ27_A SCONN288_DDR506112002KQ-SCONN288_DDR506112002KQ,SMA   I536 @T6G_MB_LIB.T6G(SCH_1):PAGE85

M_A_CPU0_SA_DQ<28> @T6G_MB_LIB.T6G(SCH_1):M_A_CPU0_SA_DQ(28)
   U25 AG74 MAA_DATA28 GENOA_SP5-SOCKET6096_13568-001,SMLF,IO,DGA^6000030   I200 @T6G_MB_LIB.T6G(SCH_1):PAGE10
    J1   47 DQ28_A SCONN288_DDR506112002KQ-SCONN288_DDR506112002KQ,SMA   I536 @T6G_MB_LIB.T6G(SCH_1):PAGE85

M_A_CPU0_SA_DQ<29> @T6G_MB_LIB.T6G(SCH_1):M_A_CPU0_SA_DQ(29)
   U25 AH72 MAA_DATA29 GENOA_SP5-SOCKET6096_13568-001,SMLF,IO,DGA^6000030   I200 @T6G_MB_LIB.T6G(SCH_1):PAGE10
    J1   49 DQ29_A SCONN288_DDR506112002KQ-SCONN288_DDR506112002KQ,SMA   I536 @T6G_MB_LIB.T6G(SCH_1):PAGE85

M_A_CPU0_SA_DQ<2> @T6G_MB_LIB.T6G(SCH_1):M_A_CPU0_SA_DQ(2)
   U25  F74 MAA_DATA2 GENOA_SP5-SOCKET6096_13568-001,SMLF,IO,DGA^6000030   I200 @T6G_MB_LIB.T6G(SCH_1):PAGE10
    J1  152  DQ2_A SCONN288_DDR506112002KQ-SCONN288_DDR506112002KQ,SMA   I536 @T6G_MB_LIB.T6G(SCH_1):PAGE85

M_A_CPU0_SA_DQ<30> @T6G_MB_LIB.T6G(SCH_1):M_A_CPU0_SA_DQ(30)
   U25 AH74 MAA_DATA30 GENOA_SP5-SOCKET6096_13568-001,SMLF,IO,DGA^6000030   I200 @T6G_MB_LIB.T6G(SCH_1):PAGE10
    J1  192 DQ30_A SCONN288_DDR506112002KQ-SCONN288_DDR506112002KQ,SMA   I536 @T6G_MB_LIB.T6G(SCH_1):PAGE85

M_A_CPU0_SA_DQ<31> @T6G_MB_LIB.T6G(SCH_1):M_A_CPU0_SA_DQ(31)
   U25 AJ73 MAA_DATA31 GENOA_SP5-SOCKET6096_13568-001,SMLF,IO,DGA^6000030   I200 @T6G_MB_LIB.T6G(SCH_1):PAGE10
    J1  194 DQ31_A SCONN288_DDR506112002KQ-SCONN288_DDR506112002KQ,SMA   I536 @T6G_MB_LIB.T6G(SCH_1):PAGE85

M_A_CPU0_SA_DQ<3> @T6G_MB_LIB.T6G(SCH_1):M_A_CPU0_SA_DQ(3)
   U25  G73 MAA_DATA3 GENOA_SP5-SOCKET6096_13568-001,SMLF,IO,DGA^6000030   I200 @T6G_MB_LIB.T6G(SCH_1):PAGE10
    J1  154  DQ3_A SCONN288_DDR506112002KQ-SCONN288_DDR506112002KQ,SMA   I536 @T6G_MB_LIB.T6G(SCH_1):PAGE85

M_A_CPU0_SA_DQ<4> @T6G_MB_LIB.T6G(SCH_1):M_A_CPU0_SA_DQ(4)
   U25  J74 MAA_DATA4 GENOA_SP5-SOCKET6096_13568-001,SMLF,IO,DGA^6000030   I200 @T6G_MB_LIB.T6G(SCH_1):PAGE10
    J1   14  DQ4_A SCONN288_DDR506112002KQ-SCONN288_DDR506112002KQ,SMA   I536 @T6G_MB_LIB.T6G(SCH_1):PAGE85

M_A_CPU0_SA_DQ<5> @T6G_MB_LIB.T6G(SCH_1):M_A_CPU0_SA_DQ(5)
   U25  K72 MAA_DATA5 GENOA_SP5-SOCKET6096_13568-001,SMLF,IO,DGA^6000030   I200 @T6G_MB_LIB.T6G(SCH_1):PAGE10
    J1   16  DQ5_A SCONN288_DDR506112002KQ-SCONN288_DDR506112002KQ,SMA   I536 @T6G_MB_LIB.T6G(SCH_1):PAGE85

M_A_CPU0_SA_DQ<6> @T6G_MB_LIB.T6G(SCH_1):M_A_CPU0_SA_DQ(6)
   U25  K74 MAA_DATA6 GENOA_SP5-SOCKET6096_13568-001,SMLF,IO,DGA^6000030   I200 @T6G_MB_LIB.T6G(SCH_1):PAGE10
    J1  159  DQ6_A SCONN288_DDR506112002KQ-SCONN288_DDR506112002KQ,SMA   I536 @T6G_MB_LIB.T6G(SCH_1):PAGE85

M_A_CPU0_SA_DQ<7> @T6G_MB_LIB.T6G(SCH_1):M_A_CPU0_SA_DQ(7)
   U25  L73 MAA_DATA7 GENOA_SP5-SOCKET6096_13568-001,SMLF,IO,DGA^6000030   I200 @T6G_MB_LIB.T6G(SCH_1):PAGE10
    J1  161  DQ7_A SCONN288_DDR506112002KQ-SCONN288_DDR506112002KQ,SMA   I536 @T6G_MB_LIB.T6G(SCH_1):PAGE85

M_A_CPU0_SA_DQ<8> @T6G_MB_LIB.T6G(SCH_1):M_A_CPU0_SA_DQ(8)
   U25  L74 MAA_DATA8 GENOA_SP5-SOCKET6096_13568-001,SMLF,IO,DGA^6000030   I200 @T6G_MB_LIB.T6G(SCH_1):PAGE10
    J1   18  DQ8_A SCONN288_DDR506112002KQ-SCONN288_DDR506112002KQ,SMA   I536 @T6G_MB_LIB.T6G(SCH_1):PAGE85

M_A_CPU0_SA_DQ<9> @T6G_MB_LIB.T6G(SCH_1):M_A_CPU0_SA_DQ(9)
   U25  M72 MAA_DATA9 GENOA_SP5-SOCKET6096_13568-001,SMLF,IO,DGA^6000030   I200 @T6G_MB_LIB.T6G(SCH_1):PAGE10
    J1   20  DQ9_A SCONN288_DDR506112002KQ-SCONN288_DDR506112002KQ,SMA   I536 @T6G_MB_LIB.T6G(SCH_1):PAGE85

M_A_CPU0_SA_DQS_DN<0> @T6G_MB_LIB.T6G(SCH_1):M_A_CPU0_SA_DQS_DN(0)
   U25  H74 MAA_DQS_L0 GENOA_SP5-SOCKET6096_13568-001,SMLF,IO,DGA^6000030   I200 @T6G_MB_LIB.T6G(SCH_1):PAGE10
    J1   12 DQS0_A_C SCONN288_DDR506112002KQ-SCONN288_DDR506112002KQ,SMA   I537 @T6G_MB_LIB.T6G(SCH_1):PAGE85

M_A_CPU0_SA_DQS_DN<1> @T6G_MB_LIB.T6G(SCH_1):M_A_CPU0_SA_DQS_DN(1)
   U25  P74 MAA_DQS_L1 GENOA_SP5-SOCKET6096_13568-001,SMLF,IO,DGA^6000030   I200 @T6G_MB_LIB.T6G(SCH_1):PAGE10
    J1   23 DQS1_A_C SCONN288_DDR506112002KQ-SCONN288_DDR506112002KQ,SMA   I537 @T6G_MB_LIB.T6G(SCH_1):PAGE85

M_A_CPU0_SA_DQS_DN<2> @T6G_MB_LIB.T6G(SCH_1):M_A_CPU0_SA_DQS_DN(2)
   U25  Y74 MAA_DQS_L2 GENOA_SP5-SOCKET6096_13568-001,SMLF,IO,DGA^6000030   I200 @T6G_MB_LIB.T6G(SCH_1):PAGE10
    J1   34 DQS2_A_C SCONN288_DDR506112002KQ-SCONN288_DDR506112002KQ,SMA   I537 @T6G_MB_LIB.T6G(SCH_1):PAGE85

M_A_CPU0_SA_DQS_DN<3> @T6G_MB_LIB.T6G(SCH_1):M_A_CPU0_SA_DQS_DN(3)
   U25 AF74 MAA_DQS_L3 GENOA_SP5-SOCKET6096_13568-001,SMLF,IO,DGA^6000030   I200 @T6G_MB_LIB.T6G(SCH_1):PAGE10
    J1   45 DQS3_A_C SCONN288_DDR506112002KQ-SCONN288_DDR506112002KQ,SMA   I537 @T6G_MB_LIB.T6G(SCH_1):PAGE85

M_A_CPU0_SA_DQS_DN<4> @T6G_MB_LIB.T6G(SCH_1):M_A_CPU0_SA_DQS_DN(4)
   U25 AM74 MAA_DQS_L4 GENOA_SP5-SOCKET6096_13568-001,SMLF,IO,DGA^6000030   I200 @T6G_MB_LIB.T6G(SCH_1):PAGE10
    J1   56 DQS4_A_C SCONN288_DDR506112002KQ-SCONN288_DDR506112002KQ,SMA   I537 @T6G_MB_LIB.T6G(SCH_1):PAGE85

M_A_CPU0_SA_DQS_DN<5> @T6G_MB_LIB.T6G(SCH_1):M_A_CPU0_SA_DQS_DN(5)
   U25  H72 MAA_DQS_L5 GENOA_SP5-SOCKET6096_13568-001,SMLF,IO,DGA^6000030   I200 @T6G_MB_LIB.T6G(SCH_1):PAGE10
    J1  156 DQS5_A_C||TDQS5_A_C||DQS5_A_T||TDQS5_A_T SCONN288_DDR506112002KQ-SCONN288_DDR506112002KQ,SMA   I537 @T6G_MB_LIB.T6G(SCH_1):PAGE85

M_A_CPU0_SA_DQS_DN<6> @T6G_MB_LIB.T6G(SCH_1):M_A_CPU0_SA_DQS_DN(6)
   U25  P72 MAA_DQS_L6 GENOA_SP5-SOCKET6096_13568-001,SMLF,IO,DGA^6000030   I200 @T6G_MB_LIB.T6G(SCH_1):PAGE10
    J1  167 DQS6_A_C||TDQS6_A_C||DQS6_A_T||TDQS6_A_T SCONN288_DDR506112002KQ-SCONN288_DDR506112002KQ,SMA   I537 @T6G_MB_LIB.T6G(SCH_1):PAGE85

M_A_CPU0_SA_DQS_DN<7> @T6G_MB_LIB.T6G(SCH_1):M_A_CPU0_SA_DQS_DN(7)
   U25  Y72 MAA_DQS_L7 GENOA_SP5-SOCKET6096_13568-001,SMLF,IO,DGA^6000030   I200 @T6G_MB_LIB.T6G(SCH_1):PAGE10
    J1  178 DQS7_A_C||TDQS7_A_C SCONN288_DDR506112002KQ-SCONN288_DDR506112002KQ,SMA   I537 @T6G_MB_LIB.T6G(SCH_1):PAGE85

M_A_CPU0_SA_DQS_DN<8> @T6G_MB_LIB.T6G(SCH_1):M_A_CPU0_SA_DQS_DN(8)
   U25 AF72 MAA_DQS_L8 GENOA_SP5-SOCKET6096_13568-001,SMLF,IO,DGA^6000030   I200 @T6G_MB_LIB.T6G(SCH_1):PAGE10
    J1  189 DQS8_A_C||TDQS8_A_C SCONN288_DDR506112002KQ-SCONN288_DDR506112002KQ,SMA   I537 @T6G_MB_LIB.T6G(SCH_1):PAGE85

M_A_CPU0_SA_DQS_DN<9> @T6G_MB_LIB.T6G(SCH_1):M_A_CPU0_SA_DQS_DN(9)
   U25 AM72 MAA_DQS_L9 GENOA_SP5-SOCKET6096_13568-001,SMLF,IO,DGA^6000030   I200 @T6G_MB_LIB.T6G(SCH_1):PAGE10
    J1  200 DQS9_A_C||TDQS9_A_C SCONN288_DDR506112002KQ-SCONN288_DDR506112002KQ,SMA   I537 @T6G_MB_LIB.T6G(SCH_1):PAGE85

M_A_CPU0_SA_DQS_DP<0> @T6G_MB_LIB.T6G(SCH_1):M_A_CPU0_SA_DQS_DP(0)
   U25  G74 MAA_DQS_H0 GENOA_SP5-SOCKET6096_13568-001,SMLF,IO,DGA^6000030   I200 @T6G_MB_LIB.T6G(SCH_1):PAGE10
    J1   11 DQS0_A_T SCONN288_DDR506112002KQ-SCONN288_DDR506112002KQ,SMA   I537 @T6G_MB_LIB.T6G(SCH_1):PAGE85

M_A_CPU0_SA_DQS_DP<1> @T6G_MB_LIB.T6G(SCH_1):M_A_CPU0_SA_DQS_DP(1)
   U25  N74 MAA_DQS_H1 GENOA_SP5-SOCKET6096_13568-001,SMLF,IO,DGA^6000030   I200 @T6G_MB_LIB.T6G(SCH_1):PAGE10
    J1   22 DQS1_A_T SCONN288_DDR506112002KQ-SCONN288_DDR506112002KQ,SMA   I537 @T6G_MB_LIB.T6G(SCH_1):PAGE85

M_A_CPU0_SA_DQS_DP<2> @T6G_MB_LIB.T6G(SCH_1):M_A_CPU0_SA_DQS_DP(2)
   U25  W74 MAA_DQS_H2 GENOA_SP5-SOCKET6096_13568-001,SMLF,IO,DGA^6000030   I200 @T6G_MB_LIB.T6G(SCH_1):PAGE10
    J1   33 DQS2_A_T SCONN288_DDR506112002KQ-SCONN288_DDR506112002KQ,SMA   I537 @T6G_MB_LIB.T6G(SCH_1):PAGE85

M_A_CPU0_SA_DQS_DP<3> @T6G_MB_LIB.T6G(SCH_1):M_A_CPU0_SA_DQS_DP(3)
   U25 AE74 MAA_DQS_H3 GENOA_SP5-SOCKET6096_13568-001,SMLF,IO,DGA^6000030   I200 @T6G_MB_LIB.T6G(SCH_1):PAGE10
    J1   44 DQS3_A_T SCONN288_DDR506112002KQ-SCONN288_DDR506112002KQ,SMA   I537 @T6G_MB_LIB.T6G(SCH_1):PAGE85

M_A_CPU0_SA_DQS_DP<4> @T6G_MB_LIB.T6G(SCH_1):M_A_CPU0_SA_DQS_DP(4)
   U25 AL74 MAA_DQS_H4 GENOA_SP5-SOCKET6096_13568-001,SMLF,IO,DGA^6000030   I200 @T6G_MB_LIB.T6G(SCH_1):PAGE10
    J1   55 DQS4_A_T SCONN288_DDR506112002KQ-SCONN288_DDR506112002KQ,SMA   I537 @T6G_MB_LIB.T6G(SCH_1):PAGE85

M_A_CPU0_SA_DQS_DP<5> @T6G_MB_LIB.T6G(SCH_1):M_A_CPU0_SA_DQS_DP(5)
   U25  J73 MAA_DQS_H5 GENOA_SP5-SOCKET6096_13568-001,SMLF,IO,DGA^6000030   I200 @T6G_MB_LIB.T6G(SCH_1):PAGE10
    J1  157 DQS5_A_T||TDQS5_A_T SCONN288_DDR506112002KQ-SCONN288_DDR506112002KQ,SMA   I537 @T6G_MB_LIB.T6G(SCH_1):PAGE85

M_A_CPU0_SA_DQS_DP<6> @T6G_MB_LIB.T6G(SCH_1):M_A_CPU0_SA_DQS_DP(6)
   U25  R73 MAA_DQS_H6 GENOA_SP5-SOCKET6096_13568-001,SMLF,IO,DGA^6000030   I200 @T6G_MB_LIB.T6G(SCH_1):PAGE10
    J1  168 DQS6_A_T||TDQS6_A_T SCONN288_DDR506112002KQ-SCONN288_DDR506112002KQ,SMA   I537 @T6G_MB_LIB.T6G(SCH_1):PAGE85

M_A_CPU0_SA_DQS_DP<7> @T6G_MB_LIB.T6G(SCH_1):M_A_CPU0_SA_DQS_DP(7)
   U25 AA73 MAA_DQS_H7 GENOA_SP5-SOCKET6096_13568-001,SMLF,IO,DGA^6000030   I200 @T6G_MB_LIB.T6G(SCH_1):PAGE10
    J1  179 DQS7_A_T||TDQS7_A_T SCONN288_DDR506112002KQ-SCONN288_DDR506112002KQ,SMA   I537 @T6G_MB_LIB.T6G(SCH_1):PAGE85

M_A_CPU0_SA_DQS_DP<8> @T6G_MB_LIB.T6G(SCH_1):M_A_CPU0_SA_DQS_DP(8)
   U25 AG73 MAA_DQS_H8 GENOA_SP5-SOCKET6096_13568-001,SMLF,IO,DGA^6000030   I200 @T6G_MB_LIB.T6G(SCH_1):PAGE10
    J1  190 DQS8_A_T||TDQS8_A_T SCONN288_DDR506112002KQ-SCONN288_DDR506112002KQ,SMA   I537 @T6G_MB_LIB.T6G(SCH_1):PAGE85

M_A_CPU0_SA_DQS_DP<9> @T6G_MB_LIB.T6G(SCH_1):M_A_CPU0_SA_DQS_DP(9)
   U25 AN73 MAA_DQS_H9 GENOA_SP5-SOCKET6096_13568-001,SMLF,IO,DGA^6000030   I200 @T6G_MB_LIB.T6G(SCH_1):PAGE10
    J1  201 DQS9_A_T||TDQS9_A_T SCONN288_DDR506112002KQ-SCONN288_DDR506112002KQ,SMA   I537 @T6G_MB_LIB.T6G(SCH_1):PAGE85

M_A_CPU0_SA_PAR @T6G_MB_LIB.T6G(SCH_1):M_A_CPU0_SA_PAR
   U25 BC73 MAA_PAR GENOA_SP5-SOCKET6096_13568-001,SMLF,IO,DGA^6000030   I200 @T6G_MB_LIB.T6G(SCH_1):PAGE10
    J1   74  PAR_A SCONN288_DDR506112002KQ-SCONN288_DDR506112002KQ,SMA   I536 @T6G_MB_LIB.T6G(SCH_1):PAGE85

M_A_CPU0_SA_RSP<0> @T6G_MB_LIB.T6G(SCH_1):M_A_CPU0_SA_RSP(0)
   U25 BN73 MAA0_RSP_L GENOA_SP5-SOCKET6096_13568-001,SMLF,IO,DGA^6000030   I200 @T6G_MB_LIB.T6G(SCH_1):PAGE10
    J1   86 LBD||RSP_A_N SCONN288_DDR506112002KQ-SCONN288_DDR506112002KQ,SMA   I536 @T6G_MB_LIB.T6G(SCH_1):PAGE85

M_A_CPU0_SB_CA<0> @T6G_MB_LIB.T6G(SCH_1):M_A_CPU0_SB_CA(0)
   U25 BG73 MAB_CA0 GENOA_SP5-SOCKET6096_13568-001,SMLF,IO,DGA^6000030   I200 @T6G_MB_LIB.T6G(SCH_1):PAGE10
    J1   76  CA0_B SCONN288_DDR506112002KQ-SCONN288_DDR506112002KQ,SMA   I536 @T6G_MB_LIB.T6G(SCH_1):PAGE85

M_A_CPU0_SB_CA<1> @T6G_MB_LIB.T6G(SCH_1):M_A_CPU0_SB_CA(1)
   U25 BH72 MAB_CA1 GENOA_SP5-SOCKET6096_13568-001,SMLF,IO,DGA^6000030   I200 @T6G_MB_LIB.T6G(SCH_1):PAGE10
    J1  221  CA1_B SCONN288_DDR506112002KQ-SCONN288_DDR506112002KQ,SMA   I536 @T6G_MB_LIB.T6G(SCH_1):PAGE85

M_A_CPU0_SB_CA<2> @T6G_MB_LIB.T6G(SCH_1):M_A_CPU0_SB_CA(2)
   U25 BH74 MAB_CA2 GENOA_SP5-SOCKET6096_13568-001,SMLF,IO,DGA^6000030   I200 @T6G_MB_LIB.T6G(SCH_1):PAGE10
    J1   78  CA2_B SCONN288_DDR506112002KQ-SCONN288_DDR506112002KQ,SMA   I536 @T6G_MB_LIB.T6G(SCH_1):PAGE85

M_A_CPU0_SB_CA<3> @T6G_MB_LIB.T6G(SCH_1):M_A_CPU0_SB_CA(3)
   U25 BJ74 MAB_CA3 GENOA_SP5-SOCKET6096_13568-001,SMLF,IO,DGA^6000030   I200 @T6G_MB_LIB.T6G(SCH_1):PAGE10
    J1  223  CA3_B SCONN288_DDR506112002KQ-SCONN288_DDR506112002KQ,SMA   I536 @T6G_MB_LIB.T6G(SCH_1):PAGE85

M_A_CPU0_SB_CA<4> @T6G_MB_LIB.T6G(SCH_1):M_A_CPU0_SB_CA(4)
   U25 BJ73 MAB_CA4 GENOA_SP5-SOCKET6096_13568-001,SMLF,IO,DGA^6000030   I200 @T6G_MB_LIB.T6G(SCH_1):PAGE10
    J1   80  CA4_B SCONN288_DDR506112002KQ-SCONN288_DDR506112002KQ,SMA   I536 @T6G_MB_LIB.T6G(SCH_1):PAGE85

M_A_CPU0_SB_CA<5> @T6G_MB_LIB.T6G(SCH_1):M_A_CPU0_SB_CA(5)
   U25 BK72 MAB_CA5 GENOA_SP5-SOCKET6096_13568-001,SMLF,IO,DGA^6000030   I200 @T6G_MB_LIB.T6G(SCH_1):PAGE10
    J1  225  CA5_B SCONN288_DDR506112002KQ-SCONN288_DDR506112002KQ,SMA   I536 @T6G_MB_LIB.T6G(SCH_1):PAGE85

M_A_CPU0_SB_CA<6> @T6G_MB_LIB.T6G(SCH_1):M_A_CPU0_SB_CA(6)
   U25 BK74 MAB_CA6 GENOA_SP5-SOCKET6096_13568-001,SMLF,IO,DGA^6000030   I200 @T6G_MB_LIB.T6G(SCH_1):PAGE10
    J1   82  CA6_B SCONN288_DDR506112002KQ-SCONN288_DDR506112002KQ,SMA   I536 @T6G_MB_LIB.T6G(SCH_1):PAGE85

M_A_CPU0_SB_CB<0> @T6G_MB_LIB.T6G(SCH_1):M_A_CPU0_SB_CB(0)
   U25 BY74 MAB_CHECK0 GENOA_SP5-SOCKET6096_13568-001,SMLF,IO,DGA^6000030   I200 @T6G_MB_LIB.T6G(SCH_1):PAGE10
    J1   96  CB0_B SCONN288_DDR506112002KQ-SCONN288_DDR506112002KQ,SMA   I536 @T6G_MB_LIB.T6G(SCH_1):PAGE85

M_A_CPU0_SB_CB<1> @T6G_MB_LIB.T6G(SCH_1):M_A_CPU0_SB_CB(1)
   U25 CA73 MAB_CHECK1 GENOA_SP5-SOCKET6096_13568-001,SMLF,IO,DGA^6000030   I200 @T6G_MB_LIB.T6G(SCH_1):PAGE10
    J1   98  CB1_B SCONN288_DDR506112002KQ-SCONN288_DDR506112002KQ,SMA   I536 @T6G_MB_LIB.T6G(SCH_1):PAGE85

M_A_CPU0_SB_CB<2> @T6G_MB_LIB.T6G(SCH_1):M_A_CPU0_SB_CB(2)
   U25 CA74 MAB_CHECK2 GENOA_SP5-SOCKET6096_13568-001,SMLF,IO,DGA^6000030   I200 @T6G_MB_LIB.T6G(SCH_1):PAGE10
    J1  241  CB2_B SCONN288_DDR506112002KQ-SCONN288_DDR506112002KQ,SMA   I536 @T6G_MB_LIB.T6G(SCH_1):PAGE85

M_A_CPU0_SB_CB<3> @T6G_MB_LIB.T6G(SCH_1):M_A_CPU0_SB_CB(3)
   U25 CB72 MAB_CHECK3 GENOA_SP5-SOCKET6096_13568-001,SMLF,IO,DGA^6000030   I200 @T6G_MB_LIB.T6G(SCH_1):PAGE10
    J1  243  CB3_B SCONN288_DDR506112002KQ-SCONN288_DDR506112002KQ,SMA   I536 @T6G_MB_LIB.T6G(SCH_1):PAGE85

M_A_CPU0_SB_CB<4> @T6G_MB_LIB.T6G(SCH_1):M_A_CPU0_SB_CB(4)
   U25 BT74 MAB_CHECK4 GENOA_SP5-SOCKET6096_13568-001,SMLF,IO,DGA^6000030   I200 @T6G_MB_LIB.T6G(SCH_1):PAGE10
    J1   89  CB4_B SCONN288_DDR506112002KQ-SCONN288_DDR506112002KQ,SMA   I536 @T6G_MB_LIB.T6G(SCH_1):PAGE85

M_A_CPU0_SB_CB<5> @T6G_MB_LIB.T6G(SCH_1):M_A_CPU0_SB_CB(5)
   U25 BU73 MAB_CHECK5 GENOA_SP5-SOCKET6096_13568-001,SMLF,IO,DGA^6000030   I200 @T6G_MB_LIB.T6G(SCH_1):PAGE10
    J1   91  CB5_B SCONN288_DDR506112002KQ-SCONN288_DDR506112002KQ,SMA   I536 @T6G_MB_LIB.T6G(SCH_1):PAGE85

M_A_CPU0_SB_CB<6> @T6G_MB_LIB.T6G(SCH_1):M_A_CPU0_SB_CB(6)
   U25 BU74 MAB_CHECK6 GENOA_SP5-SOCKET6096_13568-001,SMLF,IO,DGA^6000030   I200 @T6G_MB_LIB.T6G(SCH_1):PAGE10
    J1  234  CB6_B SCONN288_DDR506112002KQ-SCONN288_DDR506112002KQ,SMA   I536 @T6G_MB_LIB.T6G(SCH_1):PAGE85

M_A_CPU0_SB_CB<7> @T6G_MB_LIB.T6G(SCH_1):M_A_CPU0_SB_CB(7)
   U25 BV72 MAB_CHECK7 GENOA_SP5-SOCKET6096_13568-001,SMLF,IO,DGA^6000030   I200 @T6G_MB_LIB.T6G(SCH_1):PAGE10
    J1  236  CB7_B SCONN288_DDR506112002KQ-SCONN288_DDR506112002KQ,SMA   I536 @T6G_MB_LIB.T6G(SCH_1):PAGE85

M_A_CPU0_SB_CS_N<0> @T6G_MB_LIB.T6G(SCH_1):M_A_CPU0_SB_CS_N(0)
   U25 BM72 MAB0_CS_L0 GENOA_SP5-SOCKET6096_13568-001,SMLF,IO,DGA^6000030   I200 @T6G_MB_LIB.T6G(SCH_1):PAGE10
    J1   84 CS0_B_N SCONN288_DDR506112002KQ-SCONN288_DDR506112002KQ,SMA   I536 @T6G_MB_LIB.T6G(SCH_1):PAGE85

M_A_CPU0_SB_CS_N<1> @T6G_MB_LIB.T6G(SCH_1):M_A_CPU0_SB_CS_N(1)
   U25 BN74 MAB0_CS_L1 GENOA_SP5-SOCKET6096_13568-001,SMLF,IO,DGA^6000030   I200 @T6G_MB_LIB.T6G(SCH_1):PAGE10
    J1  229 CS1_B_N SCONN288_DDR506112002KQ-SCONN288_DDR506112002KQ,SMA   I536 @T6G_MB_LIB.T6G(SCH_1):PAGE85

M_A_CPU0_SB_DQ<0> @T6G_MB_LIB.T6G(SCH_1):M_A_CPU0_SB_DQ(0)
   U25 CB74 MAB_DATA0 GENOA_SP5-SOCKET6096_13568-001,SMLF,IO,DGA^6000030   I200 @T6G_MB_LIB.T6G(SCH_1):PAGE10
    J1  100  DQ0_B SCONN288_DDR506112002KQ-SCONN288_DDR506112002KQ,SMA   I536 @T6G_MB_LIB.T6G(SCH_1):PAGE85

M_A_CPU0_SB_DQ<10> @T6G_MB_LIB.T6G(SCH_1):M_A_CPU0_SB_DQ(10)
   U25 CJ74 MAB_DATA10 GENOA_SP5-SOCKET6096_13568-001,SMLF,IO,DGA^6000030   I200 @T6G_MB_LIB.T6G(SCH_1):PAGE10
    J1  256 DQ10_B SCONN288_DDR506112002KQ-SCONN288_DDR506112002KQ,SMA   I536 @T6G_MB_LIB.T6G(SCH_1):PAGE85

M_A_CPU0_SB_DQ<11> @T6G_MB_LIB.T6G(SCH_1):M_A_CPU0_SB_DQ(11)
   U25 CK72 MAB_DATA11 GENOA_SP5-SOCKET6096_13568-001,SMLF,IO,DGA^6000030   I200 @T6G_MB_LIB.T6G(SCH_1):PAGE10
    J1  258 DQ11_B SCONN288_DDR506112002KQ-SCONN288_DDR506112002KQ,SMA   I536 @T6G_MB_LIB.T6G(SCH_1):PAGE85

M_A_CPU0_SB_DQ<12> @T6G_MB_LIB.T6G(SCH_1):M_A_CPU0_SB_DQ(12)
   U25 CM74 MAB_DATA12 GENOA_SP5-SOCKET6096_13568-001,SMLF,IO,DGA^6000030   I200 @T6G_MB_LIB.T6G(SCH_1):PAGE10
    J1  118 DQ12_B SCONN288_DDR506112002KQ-SCONN288_DDR506112002KQ,SMA   I536 @T6G_MB_LIB.T6G(SCH_1):PAGE85

M_A_CPU0_SB_DQ<13> @T6G_MB_LIB.T6G(SCH_1):M_A_CPU0_SB_DQ(13)
   U25 CN73 MAB_DATA13 GENOA_SP5-SOCKET6096_13568-001,SMLF,IO,DGA^6000030   I200 @T6G_MB_LIB.T6G(SCH_1):PAGE10
    J1  120 DQ13_B SCONN288_DDR506112002KQ-SCONN288_DDR506112002KQ,SMA   I536 @T6G_MB_LIB.T6G(SCH_1):PAGE85

M_A_CPU0_SB_DQ<14> @T6G_MB_LIB.T6G(SCH_1):M_A_CPU0_SB_DQ(14)
   U25 CN74 MAB_DATA14 GENOA_SP5-SOCKET6096_13568-001,SMLF,IO,DGA^6000030   I200 @T6G_MB_LIB.T6G(SCH_1):PAGE10
    J1  263 DQ14_B SCONN288_DDR506112002KQ-SCONN288_DDR506112002KQ,SMA   I536 @T6G_MB_LIB.T6G(SCH_1):PAGE85

M_A_CPU0_SB_DQ<15> @T6G_MB_LIB.T6G(SCH_1):M_A_CPU0_SB_DQ(15)
   U25 CP72 MAB_DATA15 GENOA_SP5-SOCKET6096_13568-001,SMLF,IO,DGA^6000030   I200 @T6G_MB_LIB.T6G(SCH_1):PAGE10
    J1  265 DQ15_B SCONN288_DDR506112002KQ-SCONN288_DDR506112002KQ,SMA   I536 @T6G_MB_LIB.T6G(SCH_1):PAGE85

M_A_CPU0_SB_DQ<16> @T6G_MB_LIB.T6G(SCH_1):M_A_CPU0_SB_DQ(16)
   U25 CP74 MAB_DATA16 GENOA_SP5-SOCKET6096_13568-001,SMLF,IO,DGA^6000030   I200 @T6G_MB_LIB.T6G(SCH_1):PAGE10
    J1  122 DQ16_B SCONN288_DDR506112002KQ-SCONN288_DDR506112002KQ,SMA   I536 @T6G_MB_LIB.T6G(SCH_1):PAGE85

M_A_CPU0_SB_DQ<17> @T6G_MB_LIB.T6G(SCH_1):M_A_CPU0_SB_DQ(17)
   U25 CR73 MAB_DATA17 GENOA_SP5-SOCKET6096_13568-001,SMLF,IO,DGA^6000030   I200 @T6G_MB_LIB.T6G(SCH_1):PAGE10
    J1  124 DQ17_B SCONN288_DDR506112002KQ-SCONN288_DDR506112002KQ,SMA   I536 @T6G_MB_LIB.T6G(SCH_1):PAGE85

M_A_CPU0_SB_DQ<18> @T6G_MB_LIB.T6G(SCH_1):M_A_CPU0_SB_DQ(18)
   U25 CR74 MAB_DATA18 GENOA_SP5-SOCKET6096_13568-001,SMLF,IO,DGA^6000030   I200 @T6G_MB_LIB.T6G(SCH_1):PAGE10
    J1  267 DQ18_B SCONN288_DDR506112002KQ-SCONN288_DDR506112002KQ,SMA   I536 @T6G_MB_LIB.T6G(SCH_1):PAGE85

M_A_CPU0_SB_DQ<19> @T6G_MB_LIB.T6G(SCH_1):M_A_CPU0_SB_DQ(19)
   U25 CT72 MAB_DATA19 GENOA_SP5-SOCKET6096_13568-001,SMLF,IO,DGA^6000030   I200 @T6G_MB_LIB.T6G(SCH_1):PAGE10
    J1  269 DQ19_B SCONN288_DDR506112002KQ-SCONN288_DDR506112002KQ,SMA   I536 @T6G_MB_LIB.T6G(SCH_1):PAGE85

M_A_CPU0_SB_DQ<1> @T6G_MB_LIB.T6G(SCH_1):M_A_CPU0_SB_DQ(1)
   U25 CC73 MAB_DATA1 GENOA_SP5-SOCKET6096_13568-001,SMLF,IO,DGA^6000030   I200 @T6G_MB_LIB.T6G(SCH_1):PAGE10
    J1  102  DQ1_B SCONN288_DDR506112002KQ-SCONN288_DDR506112002KQ,SMA   I536 @T6G_MB_LIB.T6G(SCH_1):PAGE85

M_A_CPU0_SB_DQ<20> @T6G_MB_LIB.T6G(SCH_1):M_A_CPU0_SB_DQ(20)
   U25 CV74 MAB_DATA20 GENOA_SP5-SOCKET6096_13568-001,SMLF,IO,DGA^6000030   I200 @T6G_MB_LIB.T6G(SCH_1):PAGE10
    J1  129 DQ20_B SCONN288_DDR506112002KQ-SCONN288_DDR506112002KQ,SMA   I536 @T6G_MB_LIB.T6G(SCH_1):PAGE85

M_A_CPU0_SB_DQ<21> @T6G_MB_LIB.T6G(SCH_1):M_A_CPU0_SB_DQ(21)
   U25 CW73 MAB_DATA21 GENOA_SP5-SOCKET6096_13568-001,SMLF,IO,DGA^6000030   I200 @T6G_MB_LIB.T6G(SCH_1):PAGE10
    J1  131 DQ21_B SCONN288_DDR506112002KQ-SCONN288_DDR506112002KQ,SMA   I536 @T6G_MB_LIB.T6G(SCH_1):PAGE85

M_A_CPU0_SB_DQ<22> @T6G_MB_LIB.T6G(SCH_1):M_A_CPU0_SB_DQ(22)
   U25 CW74 MAB_DATA22 GENOA_SP5-SOCKET6096_13568-001,SMLF,IO,DGA^6000030   I200 @T6G_MB_LIB.T6G(SCH_1):PAGE10
    J1  274 DQ22_B SCONN288_DDR506112002KQ-SCONN288_DDR506112002KQ,SMA   I536 @T6G_MB_LIB.T6G(SCH_1):PAGE85

M_A_CPU0_SB_DQ<23> @T6G_MB_LIB.T6G(SCH_1):M_A_CPU0_SB_DQ(23)
   U25 CY72 MAB_DATA23 GENOA_SP5-SOCKET6096_13568-001,SMLF,IO,DGA^6000030   I200 @T6G_MB_LIB.T6G(SCH_1):PAGE10
    J1  276 DQ23_B SCONN288_DDR506112002KQ-SCONN288_DDR506112002KQ,SMA   I536 @T6G_MB_LIB.T6G(SCH_1):PAGE85

M_A_CPU0_SB_DQ<24> @T6G_MB_LIB.T6G(SCH_1):M_A_CPU0_SB_DQ(24)
   U25 CY74 MAB_DATA24 GENOA_SP5-SOCKET6096_13568-001,SMLF,IO,DGA^6000030   I200 @T6G_MB_LIB.T6G(SCH_1):PAGE10
    J1  133 DQ24_B SCONN288_DDR506112002KQ-SCONN288_DDR506112002KQ,SMA   I536 @T6G_MB_LIB.T6G(SCH_1):PAGE85

M_A_CPU0_SB_DQ<25> @T6G_MB_LIB.T6G(SCH_1):M_A_CPU0_SB_DQ(25)
   U25 DA73 MAB_DATA25 GENOA_SP5-SOCKET6096_13568-001,SMLF,IO,DGA^6000030   I200 @T6G_MB_LIB.T6G(SCH_1):PAGE10
    J1  135 DQ25_B SCONN288_DDR506112002KQ-SCONN288_DDR506112002KQ,SMA   I536 @T6G_MB_LIB.T6G(SCH_1):PAGE85

M_A_CPU0_SB_DQ<26> @T6G_MB_LIB.T6G(SCH_1):M_A_CPU0_SB_DQ(26)
   U25 DA74 MAB_DATA26 GENOA_SP5-SOCKET6096_13568-001,SMLF,IO,DGA^6000030   I200 @T6G_MB_LIB.T6G(SCH_1):PAGE10
    J1  278 DQ26_B SCONN288_DDR506112002KQ-SCONN288_DDR506112002KQ,SMA   I536 @T6G_MB_LIB.T6G(SCH_1):PAGE85

M_A_CPU0_SB_DQ<27> @T6G_MB_LIB.T6G(SCH_1):M_A_CPU0_SB_DQ(27)
   U25 DB72 MAB_DATA27 GENOA_SP5-SOCKET6096_13568-001,SMLF,IO,DGA^6000030   I200 @T6G_MB_LIB.T6G(SCH_1):PAGE10
    J1  280 DQ27_B SCONN288_DDR506112002KQ-SCONN288_DDR506112002KQ,SMA   I536 @T6G_MB_LIB.T6G(SCH_1):PAGE85

M_A_CPU0_SB_DQ<28> @T6G_MB_LIB.T6G(SCH_1):M_A_CPU0_SB_DQ(28)
   U25 DD74 MAB_DATA28 GENOA_SP5-SOCKET6096_13568-001,SMLF,IO,DGA^6000030   I200 @T6G_MB_LIB.T6G(SCH_1):PAGE10
    J1  140 DQ28_B SCONN288_DDR506112002KQ-SCONN288_DDR506112002KQ,SMA   I536 @T6G_MB_LIB.T6G(SCH_1):PAGE85

M_A_CPU0_SB_DQ<29> @T6G_MB_LIB.T6G(SCH_1):M_A_CPU0_SB_DQ(29)
   U25 DE73 MAB_DATA29 GENOA_SP5-SOCKET6096_13568-001,SMLF,IO,DGA^6000030   I200 @T6G_MB_LIB.T6G(SCH_1):PAGE10
    J1  142 DQ29_B SCONN288_DDR506112002KQ-SCONN288_DDR506112002KQ,SMA   I536 @T6G_MB_LIB.T6G(SCH_1):PAGE85

M_A_CPU0_SB_DQ<2> @T6G_MB_LIB.T6G(SCH_1):M_A_CPU0_SB_DQ(2)
   U25 CC74 MAB_DATA2 GENOA_SP5-SOCKET6096_13568-001,SMLF,IO,DGA^6000030   I200 @T6G_MB_LIB.T6G(SCH_1):PAGE10
    J1  245  DQ2_B SCONN288_DDR506112002KQ-SCONN288_DDR506112002KQ,SMA   I536 @T6G_MB_LIB.T6G(SCH_1):PAGE85

M_A_CPU0_SB_DQ<30> @T6G_MB_LIB.T6G(SCH_1):M_A_CPU0_SB_DQ(30)
   U25 DE74 MAB_DATA30 GENOA_SP5-SOCKET6096_13568-001,SMLF,IO,DGA^6000030   I200 @T6G_MB_LIB.T6G(SCH_1):PAGE10
    J1  285 DQ30_B SCONN288_DDR506112002KQ-SCONN288_DDR506112002KQ,SMA   I536 @T6G_MB_LIB.T6G(SCH_1):PAGE85

M_A_CPU0_SB_DQ<31> @T6G_MB_LIB.T6G(SCH_1):M_A_CPU0_SB_DQ(31)
   U25 DF74 MAB_DATA31 GENOA_SP5-SOCKET6096_13568-001,SMLF,IO,DGA^6000030   I200 @T6G_MB_LIB.T6G(SCH_1):PAGE10
    J1  287 DQ31_B SCONN288_DDR506112002KQ-SCONN288_DDR506112002KQ,SMA   I536 @T6G_MB_LIB.T6G(SCH_1):PAGE85

M_A_CPU0_SB_DQ<3> @T6G_MB_LIB.T6G(SCH_1):M_A_CPU0_SB_DQ(3)
   U25 CD72 MAB_DATA3 GENOA_SP5-SOCKET6096_13568-001,SMLF,IO,DGA^6000030   I200 @T6G_MB_LIB.T6G(SCH_1):PAGE10
    J1  247  DQ3_B SCONN288_DDR506112002KQ-SCONN288_DDR506112002KQ,SMA   I536 @T6G_MB_LIB.T6G(SCH_1):PAGE85

M_A_CPU0_SB_DQ<4> @T6G_MB_LIB.T6G(SCH_1):M_A_CPU0_SB_DQ(4)
   U25 CF74 MAB_DATA4 GENOA_SP5-SOCKET6096_13568-001,SMLF,IO,DGA^6000030   I200 @T6G_MB_LIB.T6G(SCH_1):PAGE10
    J1  107  DQ4_B SCONN288_DDR506112002KQ-SCONN288_DDR506112002KQ,SMA   I536 @T6G_MB_LIB.T6G(SCH_1):PAGE85

M_A_CPU0_SB_DQ<5> @T6G_MB_LIB.T6G(SCH_1):M_A_CPU0_SB_DQ(5)
   U25 CG73 MAB_DATA5 GENOA_SP5-SOCKET6096_13568-001,SMLF,IO,DGA^6000030   I200 @T6G_MB_LIB.T6G(SCH_1):PAGE10
    J1  109  DQ5_B SCONN288_DDR506112002KQ-SCONN288_DDR506112002KQ,SMA   I536 @T6G_MB_LIB.T6G(SCH_1):PAGE85

M_A_CPU0_SB_DQ<6> @T6G_MB_LIB.T6G(SCH_1):M_A_CPU0_SB_DQ(6)
   U25 CG74 MAB_DATA6 GENOA_SP5-SOCKET6096_13568-001,SMLF,IO,DGA^6000030   I200 @T6G_MB_LIB.T6G(SCH_1):PAGE10
    J1  252  DQ6_B SCONN288_DDR506112002KQ-SCONN288_DDR506112002KQ,SMA   I536 @T6G_MB_LIB.T6G(SCH_1):PAGE85

M_A_CPU0_SB_DQ<7> @T6G_MB_LIB.T6G(SCH_1):M_A_CPU0_SB_DQ(7)
   U25 CH72 MAB_DATA7 GENOA_SP5-SOCKET6096_13568-001,SMLF,IO,DGA^6000030   I200 @T6G_MB_LIB.T6G(SCH_1):PAGE10
    J1  254  DQ7_B SCONN288_DDR506112002KQ-SCONN288_DDR506112002KQ,SMA   I536 @T6G_MB_LIB.T6G(SCH_1):PAGE85

M_A_CPU0_SB_DQ<8> @T6G_MB_LIB.T6G(SCH_1):M_A_CPU0_SB_DQ(8)
   U25 CH74 MAB_DATA8 GENOA_SP5-SOCKET6096_13568-001,SMLF,IO,DGA^6000030   I200 @T6G_MB_LIB.T6G(SCH_1):PAGE10
    J1  111  DQ8_B SCONN288_DDR506112002KQ-SCONN288_DDR506112002KQ,SMA   I536 @T6G_MB_LIB.T6G(SCH_1):PAGE85

M_A_CPU0_SB_DQ<9> @T6G_MB_LIB.T6G(SCH_1):M_A_CPU0_SB_DQ(9)
   U25 CJ73 MAB_DATA9 GENOA_SP5-SOCKET6096_13568-001,SMLF,IO,DGA^6000030   I200 @T6G_MB_LIB.T6G(SCH_1):PAGE10
    J1  113  DQ9_B SCONN288_DDR506112002KQ-SCONN288_DDR506112002KQ,SMA   I536 @T6G_MB_LIB.T6G(SCH_1):PAGE85

M_A_CPU0_SB_DQS_DN<0> @T6G_MB_LIB.T6G(SCH_1):M_A_CPU0_SB_DQS_DN(0)
   U25 CE74 MAB_DQS_L0 GENOA_SP5-SOCKET6096_13568-001,SMLF,IO,DGA^6000030   I200 @T6G_MB_LIB.T6G(SCH_1):PAGE10
    J1  105 DQS0_B_C SCONN288_DDR506112002KQ-SCONN288_DDR506112002KQ,SMA   I537 @T6G_MB_LIB.T6G(SCH_1):PAGE85

M_A_CPU0_SB_DQS_DN<1> @T6G_MB_LIB.T6G(SCH_1):M_A_CPU0_SB_DQS_DN(1)
   U25 CL74 MAB_DQS_L1 GENOA_SP5-SOCKET6096_13568-001,SMLF,IO,DGA^6000030   I200 @T6G_MB_LIB.T6G(SCH_1):PAGE10
    J1  116 DQS1_B_C SCONN288_DDR506112002KQ-SCONN288_DDR506112002KQ,SMA   I537 @T6G_MB_LIB.T6G(SCH_1):PAGE85

M_A_CPU0_SB_DQS_DN<2> @T6G_MB_LIB.T6G(SCH_1):M_A_CPU0_SB_DQS_DN(2)
   U25 CU74 MAB_DQS_L2 GENOA_SP5-SOCKET6096_13568-001,SMLF,IO,DGA^6000030   I200 @T6G_MB_LIB.T6G(SCH_1):PAGE10
    J1  127 DQS2_B_C SCONN288_DDR506112002KQ-SCONN288_DDR506112002KQ,SMA   I537 @T6G_MB_LIB.T6G(SCH_1):PAGE85

M_A_CPU0_SB_DQS_DN<3> @T6G_MB_LIB.T6G(SCH_1):M_A_CPU0_SB_DQS_DN(3)
   U25 DC74 MAB_DQS_L3 GENOA_SP5-SOCKET6096_13568-001,SMLF,IO,DGA^6000030   I200 @T6G_MB_LIB.T6G(SCH_1):PAGE10
    J1  138 DQS3_B_C SCONN288_DDR506112002KQ-SCONN288_DDR506112002KQ,SMA   I537 @T6G_MB_LIB.T6G(SCH_1):PAGE85

M_A_CPU0_SB_DQS_DN<4> @T6G_MB_LIB.T6G(SCH_1):M_A_CPU0_SB_DQS_DN(4)
   U25 BW73 MAB_DQS_L4 GENOA_SP5-SOCKET6096_13568-001,SMLF,IO,DGA^6000030   I200 @T6G_MB_LIB.T6G(SCH_1):PAGE10
    J1  238 DQS4_B_C SCONN288_DDR506112002KQ-SCONN288_DDR506112002KQ,SMA   I537 @T6G_MB_LIB.T6G(SCH_1):PAGE85

M_A_CPU0_SB_DQS_DN<5> @T6G_MB_LIB.T6G(SCH_1):M_A_CPU0_SB_DQS_DN(5)
   U25 CE73 MAB_DQS_L5 GENOA_SP5-SOCKET6096_13568-001,SMLF,IO,DGA^6000030   I200 @T6G_MB_LIB.T6G(SCH_1):PAGE10
    J1  249 DQS5_B_C||TDQS5_B_C SCONN288_DDR506112002KQ-SCONN288_DDR506112002KQ,SMA   I537 @T6G_MB_LIB.T6G(SCH_1):PAGE85

M_A_CPU0_SB_DQS_DN<6> @T6G_MB_LIB.T6G(SCH_1):M_A_CPU0_SB_DQS_DN(6)
   U25 CL73 MAB_DQS_L6 GENOA_SP5-SOCKET6096_13568-001,SMLF,IO,DGA^6000030   I200 @T6G_MB_LIB.T6G(SCH_1):PAGE10
    J1  260 DQS6_B_C||TDQS6_B_C SCONN288_DDR506112002KQ-SCONN288_DDR506112002KQ,SMA   I537 @T6G_MB_LIB.T6G(SCH_1):PAGE85

M_A_CPU0_SB_DQS_DN<7> @T6G_MB_LIB.T6G(SCH_1):M_A_CPU0_SB_DQS_DN(7)
   U25 CU73 MAB_DQS_L7 GENOA_SP5-SOCKET6096_13568-001,SMLF,IO,DGA^6000030   I200 @T6G_MB_LIB.T6G(SCH_1):PAGE10
    J1  271 DQS7_B_C||TDQS7_B_C SCONN288_DDR506112002KQ-SCONN288_DDR506112002KQ,SMA   I537 @T6G_MB_LIB.T6G(SCH_1):PAGE85

M_A_CPU0_SB_DQS_DN<8> @T6G_MB_LIB.T6G(SCH_1):M_A_CPU0_SB_DQS_DN(8)
   U25 DC73 MAB_DQS_L8 GENOA_SP5-SOCKET6096_13568-001,SMLF,IO,DGA^6000030   I200 @T6G_MB_LIB.T6G(SCH_1):PAGE10
    J1  282 DQS8_B_C||TDQS8_B_C SCONN288_DDR506112002KQ-SCONN288_DDR506112002KQ,SMA   I537 @T6G_MB_LIB.T6G(SCH_1):PAGE85

M_A_CPU0_SB_DQS_DN<9> @T6G_MB_LIB.T6G(SCH_1):M_A_CPU0_SB_DQS_DN(9)
   U25 BW74 MAB_DQS_L9 GENOA_SP5-SOCKET6096_13568-001,SMLF,IO,DGA^6000030   I200 @T6G_MB_LIB.T6G(SCH_1):PAGE10
    J1   94 DQS9_B_C||TDQS9_B_C SCONN288_DDR506112002KQ-SCONN288_DDR506112002KQ,SMA   I537 @T6G_MB_LIB.T6G(SCH_1):PAGE85

M_A_CPU0_SB_DQS_DP<0> @T6G_MB_LIB.T6G(SCH_1):M_A_CPU0_SB_DQS_DP(0)
   U25 CD74 MAB_DQS_H0 GENOA_SP5-SOCKET6096_13568-001,SMLF,IO,DGA^6000030   I200 @T6G_MB_LIB.T6G(SCH_1):PAGE10
    J1  104 DQS0_B_T SCONN288_DDR506112002KQ-SCONN288_DDR506112002KQ,SMA   I537 @T6G_MB_LIB.T6G(SCH_1):PAGE85

M_A_CPU0_SB_DQS_DP<1> @T6G_MB_LIB.T6G(SCH_1):M_A_CPU0_SB_DQS_DP(1)
   U25 CK74 MAB_DQS_H1 GENOA_SP5-SOCKET6096_13568-001,SMLF,IO,DGA^6000030   I200 @T6G_MB_LIB.T6G(SCH_1):PAGE10
    J1  115 DQS1_B_T SCONN288_DDR506112002KQ-SCONN288_DDR506112002KQ,SMA   I537 @T6G_MB_LIB.T6G(SCH_1):PAGE85

M_A_CPU0_SB_DQS_DP<2> @T6G_MB_LIB.T6G(SCH_1):M_A_CPU0_SB_DQS_DP(2)
   U25 CT74 MAB_DQS_H2 GENOA_SP5-SOCKET6096_13568-001,SMLF,IO,DGA^6000030   I200 @T6G_MB_LIB.T6G(SCH_1):PAGE10
    J1  126 DQS2_B_T SCONN288_DDR506112002KQ-SCONN288_DDR506112002KQ,SMA   I537 @T6G_MB_LIB.T6G(SCH_1):PAGE85

M_A_CPU0_SB_DQS_DP<3> @T6G_MB_LIB.T6G(SCH_1):M_A_CPU0_SB_DQS_DP(3)
   U25 DB74 MAB_DQS_H3 GENOA_SP5-SOCKET6096_13568-001,SMLF,IO,DGA^6000030   I200 @T6G_MB_LIB.T6G(SCH_1):PAGE10
    J1  137 DQS3_B_T SCONN288_DDR506112002KQ-SCONN288_DDR506112002KQ,SMA   I537 @T6G_MB_LIB.T6G(SCH_1):PAGE85

M_A_CPU0_SB_DQS_DP<4> @T6G_MB_LIB.T6G(SCH_1):M_A_CPU0_SB_DQS_DP(4)
   U25 BY72 MAB_DQS_H4 GENOA_SP5-SOCKET6096_13568-001,SMLF,IO,DGA^6000030   I200 @T6G_MB_LIB.T6G(SCH_1):PAGE10
    J1  239 DQS4_B_T SCONN288_DDR506112002KQ-SCONN288_DDR506112002KQ,SMA   I537 @T6G_MB_LIB.T6G(SCH_1):PAGE85

M_A_CPU0_SB_DQS_DP<5> @T6G_MB_LIB.T6G(SCH_1):M_A_CPU0_SB_DQS_DP(5)
   U25 CF72 MAB_DQS_H5 GENOA_SP5-SOCKET6096_13568-001,SMLF,IO,DGA^6000030   I200 @T6G_MB_LIB.T6G(SCH_1):PAGE10
    J1  250 DQS5_B_T||TDQS5_B_T SCONN288_DDR506112002KQ-SCONN288_DDR506112002KQ,SMA   I537 @T6G_MB_LIB.T6G(SCH_1):PAGE85

M_A_CPU0_SB_DQS_DP<6> @T6G_MB_LIB.T6G(SCH_1):M_A_CPU0_SB_DQS_DP(6)
   U25 CM72 MAB_DQS_H6 GENOA_SP5-SOCKET6096_13568-001,SMLF,IO,DGA^6000030   I200 @T6G_MB_LIB.T6G(SCH_1):PAGE10
    J1  261 DQS6_B_T||TDQS6_B_T SCONN288_DDR506112002KQ-SCONN288_DDR506112002KQ,SMA   I537 @T6G_MB_LIB.T6G(SCH_1):PAGE85

M_A_CPU0_SB_DQS_DP<7> @T6G_MB_LIB.T6G(SCH_1):M_A_CPU0_SB_DQS_DP(7)
   U25 CV72 MAB_DQS_H7 GENOA_SP5-SOCKET6096_13568-001,SMLF,IO,DGA^6000030   I200 @T6G_MB_LIB.T6G(SCH_1):PAGE10
    J1  272 DQS7_B_T||TDQS7_B_T SCONN288_DDR506112002KQ-SCONN288_DDR506112002KQ,SMA   I537 @T6G_MB_LIB.T6G(SCH_1):PAGE85

M_A_CPU0_SB_DQS_DP<8> @T6G_MB_LIB.T6G(SCH_1):M_A_CPU0_SB_DQS_DP(8)
   U25 DD72 MAB_DQS_H8 GENOA_SP5-SOCKET6096_13568-001,SMLF,IO,DGA^6000030   I200 @T6G_MB_LIB.T6G(SCH_1):PAGE10
    J1  283 DQS8_B_T||TDQS8_B_T SCONN288_DDR506112002KQ-SCONN288_DDR506112002KQ,SMA   I537 @T6G_MB_LIB.T6G(SCH_1):PAGE85

M_A_CPU0_SB_DQS_DP<9> @T6G_MB_LIB.T6G(SCH_1):M_A_CPU0_SB_DQS_DP(9)
   U25 BV74 MAB_DQS_H9 GENOA_SP5-SOCKET6096_13568-001,SMLF,IO,DGA^6000030   I200 @T6G_MB_LIB.T6G(SCH_1):PAGE10
    J1   93 DQS9_B_T||TDQS9_B_T||DBI4_B_N SCONN288_DDR506112002KQ-SCONN288_DDR506112002KQ,SMA   I537 @T6G_MB_LIB.T6G(SCH_1):PAGE85

M_A_CPU0_SB_PAR @T6G_MB_LIB.T6G(SCH_1):M_A_CPU0_SB_PAR
   U25 BL74 MAB_PAR GENOA_SP5-SOCKET6096_13568-001,SMLF,IO,DGA^6000030   I200 @T6G_MB_LIB.T6G(SCH_1):PAGE10
    J1  227  PAR_B SCONN288_DDR506112002KQ-SCONN288_DDR506112002KQ,SMA   I536 @T6G_MB_LIB.T6G(SCH_1):PAGE85

M_A_CPU0_SB_RSP<0> @T6G_MB_LIB.T6G(SCH_1):M_A_CPU0_SB_RSP(0)
   U25 BP74 MAB0_RSP_L GENOA_SP5-SOCKET6096_13568-001,SMLF,IO,DGA^6000030   I200 @T6G_MB_LIB.T6G(SCH_1):PAGE10
    J1   87 LBS||RSP_B_N SCONN288_DDR506112002KQ-SCONN288_DDR506112002KQ,SMA   I536 @T6G_MB_LIB.T6G(SCH_1):PAGE85

M_A_CPU1_ALERT_N @T6G_MB_LIB.T6G(SCH_1):M_A_CPU1_ALERT_N
  R500    1      A Q_RES_0402LF-15,1%,1/16W,CHIP,CS01502FB03   I322 @T6G_MB_LIB.T6G(SCH_1):PAGE37
   J24   62 ALERT_N SCONN288_DDR506112002KQ-SCONN288_DDR506112002KQ,SMA    I22 @T6G_MB_LIB.T6G(SCH_1):PAGE97

M_A_CPU1_ALERT_R_N @T6G_MB_LIB.T6G(SCH_1):M_A_CPU1_ALERT_R_N
   U26 AR74 MA_ALERT_L GENOA_SP5-SOCKET6096_13568-001,SMLF,IO,DGA^6000030   I167 @T6G_MB_LIB.T6G(SCH_1):PAGE37
  R500    2      B Q_RES_0402LF-15,1%,1/16W,CHIP,CS01502FB03   I322 @T6G_MB_LIB.T6G(SCH_1):PAGE37

M_A_CPU1_CLK_DN<0> @T6G_MB_LIB.T6G(SCH_1):M_A_CPU1_CLK_DN(0)
   U26 BD74 MA0_CLK_L GENOA_SP5-SOCKET6096_13568-001,SMLF,IO,DGA^6000030   I167 @T6G_MB_LIB.T6G(SCH_1):PAGE37
   J24  218   CK_C SCONN288_DDR506112002KQ-SCONN288_DDR506112002KQ,SMA    I22 @T6G_MB_LIB.T6G(SCH_1):PAGE97

M_A_CPU1_CLK_DP<0> @T6G_MB_LIB.T6G(SCH_1):M_A_CPU1_CLK_DP(0)
   U26 BC74 MA0_CLK_H GENOA_SP5-SOCKET6096_13568-001,SMLF,IO,DGA^6000030   I167 @T6G_MB_LIB.T6G(SCH_1):PAGE37
   J24  217   CK_T SCONN288_DDR506112002KQ-SCONN288_DDR506112002KQ,SMA    I22 @T6G_MB_LIB.T6G(SCH_1):PAGE97

M_A_CPU1_RESET_N @T6G_MB_LIB.T6G(SCH_1):M_A_CPU1_RESET_N
   U26 AT74 MA_RESET_L GENOA_SP5-SOCKET6096_13568-001,SMLF,IO,DGA^6000030   I167 @T6G_MB_LIB.T6G(SCH_1):PAGE37
   J24  207 RESET_N SCONN288_DDR506112002KQ-SCONN288_DDR506112002KQ,SMA    I22 @T6G_MB_LIB.T6G(SCH_1):PAGE97

M_A_CPU1_SA_CA<0> @T6G_MB_LIB.T6G(SCH_1):M_A_CPU1_SA_CA(0)
   U26 AW74 MAA_CA0 GENOA_SP5-SOCKET6096_13568-001,SMLF,IO,DGA^6000030   I167 @T6G_MB_LIB.T6G(SCH_1):PAGE37
   J24   66  CA0_A SCONN288_DDR506112002KQ-SCONN288_DDR506112002KQ,SMA    I22 @T6G_MB_LIB.T6G(SCH_1):PAGE97

M_A_CPU1_SA_CA<1> @T6G_MB_LIB.T6G(SCH_1):M_A_CPU1_SA_CA(1)
   U26 AY74 MAA_CA1 GENOA_SP5-SOCKET6096_13568-001,SMLF,IO,DGA^6000030   I167 @T6G_MB_LIB.T6G(SCH_1):PAGE37
   J24  211  CA1_A SCONN288_DDR506112002KQ-SCONN288_DDR506112002KQ,SMA    I22 @T6G_MB_LIB.T6G(SCH_1):PAGE97

M_A_CPU1_SA_CA<2> @T6G_MB_LIB.T6G(SCH_1):M_A_CPU1_SA_CA(2)
   U26 AY72 MAA_CA2 GENOA_SP5-SOCKET6096_13568-001,SMLF,IO,DGA^6000030   I167 @T6G_MB_LIB.T6G(SCH_1):PAGE37
   J24   68  CA2_A SCONN288_DDR506112002KQ-SCONN288_DDR506112002KQ,SMA    I22 @T6G_MB_LIB.T6G(SCH_1):PAGE97

M_A_CPU1_SA_CA<3> @T6G_MB_LIB.T6G(SCH_1):M_A_CPU1_SA_CA(3)
   U26 BA73 MAA_CA3 GENOA_SP5-SOCKET6096_13568-001,SMLF,IO,DGA^6000030   I167 @T6G_MB_LIB.T6G(SCH_1):PAGE37
   J24  213  CA3_A SCONN288_DDR506112002KQ-SCONN288_DDR506112002KQ,SMA    I22 @T6G_MB_LIB.T6G(SCH_1):PAGE97

M_A_CPU1_SA_CA<4> @T6G_MB_LIB.T6G(SCH_1):M_A_CPU1_SA_CA(4)
   U26 BA74 MAA_CA4 GENOA_SP5-SOCKET6096_13568-001,SMLF,IO,DGA^6000030   I167 @T6G_MB_LIB.T6G(SCH_1):PAGE37
   J24   70  CA4_A SCONN288_DDR506112002KQ-SCONN288_DDR506112002KQ,SMA    I22 @T6G_MB_LIB.T6G(SCH_1):PAGE97

M_A_CPU1_SA_CA<5> @T6G_MB_LIB.T6G(SCH_1):M_A_CPU1_SA_CA(5)
   U26 BB74 MAA_CA5 GENOA_SP5-SOCKET6096_13568-001,SMLF,IO,DGA^6000030   I167 @T6G_MB_LIB.T6G(SCH_1):PAGE37
   J24  215  CA5_A SCONN288_DDR506112002KQ-SCONN288_DDR506112002KQ,SMA    I22 @T6G_MB_LIB.T6G(SCH_1):PAGE97

M_A_CPU1_SA_CA<6> @T6G_MB_LIB.T6G(SCH_1):M_A_CPU1_SA_CA(6)
   U26 BB72 MAA_CA6 GENOA_SP5-SOCKET6096_13568-001,SMLF,IO,DGA^6000030   I167 @T6G_MB_LIB.T6G(SCH_1):PAGE37
   J24   72  CA6_A SCONN288_DDR506112002KQ-SCONN288_DDR506112002KQ,SMA    I22 @T6G_MB_LIB.T6G(SCH_1):PAGE97

M_A_CPU1_SA_CB<0> @T6G_MB_LIB.T6G(SCH_1):M_A_CPU1_SA_CB(0)
   U26 AJ74 MAA_CHECK0 GENOA_SP5-SOCKET6096_13568-001,SMLF,IO,DGA^6000030   I167 @T6G_MB_LIB.T6G(SCH_1):PAGE37
   J24   51  CB0_A SCONN288_DDR506112002KQ-SCONN288_DDR506112002KQ,SMA    I22 @T6G_MB_LIB.T6G(SCH_1):PAGE97

M_A_CPU1_SA_CB<1> @T6G_MB_LIB.T6G(SCH_1):M_A_CPU1_SA_CB(1)
   U26 AK72 MAA_CHECK1 GENOA_SP5-SOCKET6096_13568-001,SMLF,IO,DGA^6000030   I167 @T6G_MB_LIB.T6G(SCH_1):PAGE37
   J24   53  CB1_A SCONN288_DDR506112002KQ-SCONN288_DDR506112002KQ,SMA    I22 @T6G_MB_LIB.T6G(SCH_1):PAGE97

M_A_CPU1_SA_CB<2> @T6G_MB_LIB.T6G(SCH_1):M_A_CPU1_SA_CB(2)
   U26 AK74 MAA_CHECK2 GENOA_SP5-SOCKET6096_13568-001,SMLF,IO,DGA^6000030   I167 @T6G_MB_LIB.T6G(SCH_1):PAGE37
   J24  196  CB2_A SCONN288_DDR506112002KQ-SCONN288_DDR506112002KQ,SMA    I22 @T6G_MB_LIB.T6G(SCH_1):PAGE97

M_A_CPU1_SA_CB<3> @T6G_MB_LIB.T6G(SCH_1):M_A_CPU1_SA_CB(3)
   U26 AL73 MAA_CHECK3 GENOA_SP5-SOCKET6096_13568-001,SMLF,IO,DGA^6000030   I167 @T6G_MB_LIB.T6G(SCH_1):PAGE37
   J24  198  CB3_A SCONN288_DDR506112002KQ-SCONN288_DDR506112002KQ,SMA    I22 @T6G_MB_LIB.T6G(SCH_1):PAGE97

M_A_CPU1_SA_CB<4> @T6G_MB_LIB.T6G(SCH_1):M_A_CPU1_SA_CB(4)
   U26 AN74 MAA_CHECK4 GENOA_SP5-SOCKET6096_13568-001,SMLF,IO,DGA^6000030   I167 @T6G_MB_LIB.T6G(SCH_1):PAGE37
   J24   58  CB4_A SCONN288_DDR506112002KQ-SCONN288_DDR506112002KQ,SMA    I22 @T6G_MB_LIB.T6G(SCH_1):PAGE97

M_A_CPU1_SA_CB<5> @T6G_MB_LIB.T6G(SCH_1):M_A_CPU1_SA_CB(5)
   U26 AP72 MAA_CHECK5 GENOA_SP5-SOCKET6096_13568-001,SMLF,IO,DGA^6000030   I167 @T6G_MB_LIB.T6G(SCH_1):PAGE37
   J24   60  CB5_A SCONN288_DDR506112002KQ-SCONN288_DDR506112002KQ,SMA    I22 @T6G_MB_LIB.T6G(SCH_1):PAGE97

M_A_CPU1_SA_CB<6> @T6G_MB_LIB.T6G(SCH_1):M_A_CPU1_SA_CB(6)
   U26 AP74 MAA_CHECK6 GENOA_SP5-SOCKET6096_13568-001,SMLF,IO,DGA^6000030   I167 @T6G_MB_LIB.T6G(SCH_1):PAGE37
   J24  203  CB6_A SCONN288_DDR506112002KQ-SCONN288_DDR506112002KQ,SMA    I22 @T6G_MB_LIB.T6G(SCH_1):PAGE97

M_A_CPU1_SA_CB<7> @T6G_MB_LIB.T6G(SCH_1):M_A_CPU1_SA_CB(7)
   U26 AR73 MAA_CHECK7 GENOA_SP5-SOCKET6096_13568-001,SMLF,IO,DGA^6000030   I167 @T6G_MB_LIB.T6G(SCH_1):PAGE37
   J24  205  CB7_A SCONN288_DDR506112002KQ-SCONN288_DDR506112002KQ,SMA    I22 @T6G_MB_LIB.T6G(SCH_1):PAGE97

M_A_CPU1_SA_CS_N<0> @T6G_MB_LIB.T6G(SCH_1):M_A_CPU1_SA_CS_N(0)
   U26 AV74 MAA0_CS_L0 GENOA_SP5-SOCKET6096_13568-001,SMLF,IO,DGA^6000030   I167 @T6G_MB_LIB.T6G(SCH_1):PAGE37
   J24   64 CS0_A_N SCONN288_DDR506112002KQ-SCONN288_DDR506112002KQ,SMA    I22 @T6G_MB_LIB.T6G(SCH_1):PAGE97

M_A_CPU1_SA_CS_N<1> @T6G_MB_LIB.T6G(SCH_1):M_A_CPU1_SA_CS_N(1)
   U26 AW73 MAA0_CS_L1 GENOA_SP5-SOCKET6096_13568-001,SMLF,IO,DGA^6000030   I167 @T6G_MB_LIB.T6G(SCH_1):PAGE37
   J24  209 CS1_A_N SCONN288_DDR506112002KQ-SCONN288_DDR506112002KQ,SMA    I22 @T6G_MB_LIB.T6G(SCH_1):PAGE97

M_A_CPU1_SA_DQ<0> @T6G_MB_LIB.T6G(SCH_1):M_A_CPU1_SA_DQ(0)
   U26  E74 MAA_DATA0 GENOA_SP5-SOCKET6096_13568-001,SMLF,IO,DGA^6000030   I167 @T6G_MB_LIB.T6G(SCH_1):PAGE37
   J24    7  DQ0_A SCONN288_DDR506112002KQ-SCONN288_DDR506112002KQ,SMA    I22 @T6G_MB_LIB.T6G(SCH_1):PAGE97

M_A_CPU1_SA_DQ<10> @T6G_MB_LIB.T6G(SCH_1):M_A_CPU1_SA_DQ(10)
   U26  M74 MAA_DATA10 GENOA_SP5-SOCKET6096_13568-001,SMLF,IO,DGA^6000030   I167 @T6G_MB_LIB.T6G(SCH_1):PAGE37
   J24  163 DQ10_A SCONN288_DDR506112002KQ-SCONN288_DDR506112002KQ,SMA    I22 @T6G_MB_LIB.T6G(SCH_1):PAGE97

M_A_CPU1_SA_DQ<11> @T6G_MB_LIB.T6G(SCH_1):M_A_CPU1_SA_DQ(11)
   U26  N73 MAA_DATA11 GENOA_SP5-SOCKET6096_13568-001,SMLF,IO,DGA^6000030   I167 @T6G_MB_LIB.T6G(SCH_1):PAGE37
   J24  165 DQ11_A SCONN288_DDR506112002KQ-SCONN288_DDR506112002KQ,SMA    I22 @T6G_MB_LIB.T6G(SCH_1):PAGE97

M_A_CPU1_SA_DQ<12> @T6G_MB_LIB.T6G(SCH_1):M_A_CPU1_SA_DQ(12)
   U26  R74 MAA_DATA12 GENOA_SP5-SOCKET6096_13568-001,SMLF,IO,DGA^6000030   I167 @T6G_MB_LIB.T6G(SCH_1):PAGE37
   J24   25 DQ12_A SCONN288_DDR506112002KQ-SCONN288_DDR506112002KQ,SMA    I22 @T6G_MB_LIB.T6G(SCH_1):PAGE97

M_A_CPU1_SA_DQ<13> @T6G_MB_LIB.T6G(SCH_1):M_A_CPU1_SA_DQ(13)
   U26  T72 MAA_DATA13 GENOA_SP5-SOCKET6096_13568-001,SMLF,IO,DGA^6000030   I167 @T6G_MB_LIB.T6G(SCH_1):PAGE37
   J24   27 DQ13_A SCONN288_DDR506112002KQ-SCONN288_DDR506112002KQ,SMA    I22 @T6G_MB_LIB.T6G(SCH_1):PAGE97

M_A_CPU1_SA_DQ<14> @T6G_MB_LIB.T6G(SCH_1):M_A_CPU1_SA_DQ(14)
   U26  T74 MAA_DATA14 GENOA_SP5-SOCKET6096_13568-001,SMLF,IO,DGA^6000030   I167 @T6G_MB_LIB.T6G(SCH_1):PAGE37
   J24  170 DQ14_A SCONN288_DDR506112002KQ-SCONN288_DDR506112002KQ,SMA    I22 @T6G_MB_LIB.T6G(SCH_1):PAGE97

M_A_CPU1_SA_DQ<15> @T6G_MB_LIB.T6G(SCH_1):M_A_CPU1_SA_DQ(15)
   U26  U73 MAA_DATA15 GENOA_SP5-SOCKET6096_13568-001,SMLF,IO,DGA^6000030   I167 @T6G_MB_LIB.T6G(SCH_1):PAGE37
   J24  172 DQ15_A SCONN288_DDR506112002KQ-SCONN288_DDR506112002KQ,SMA    I22 @T6G_MB_LIB.T6G(SCH_1):PAGE97

M_A_CPU1_SA_DQ<16> @T6G_MB_LIB.T6G(SCH_1):M_A_CPU1_SA_DQ(16)
   U26  U74 MAA_DATA16 GENOA_SP5-SOCKET6096_13568-001,SMLF,IO,DGA^6000030   I167 @T6G_MB_LIB.T6G(SCH_1):PAGE37
   J24   29 DQ16_A SCONN288_DDR506112002KQ-SCONN288_DDR506112002KQ,SMA    I22 @T6G_MB_LIB.T6G(SCH_1):PAGE97

M_A_CPU1_SA_DQ<17> @T6G_MB_LIB.T6G(SCH_1):M_A_CPU1_SA_DQ(17)
   U26  V72 MAA_DATA17 GENOA_SP5-SOCKET6096_13568-001,SMLF,IO,DGA^6000030   I167 @T6G_MB_LIB.T6G(SCH_1):PAGE37
   J24   31 DQ17_A SCONN288_DDR506112002KQ-SCONN288_DDR506112002KQ,SMA    I22 @T6G_MB_LIB.T6G(SCH_1):PAGE97

M_A_CPU1_SA_DQ<18> @T6G_MB_LIB.T6G(SCH_1):M_A_CPU1_SA_DQ(18)
   U26  V74 MAA_DATA18 GENOA_SP5-SOCKET6096_13568-001,SMLF,IO,DGA^6000030   I167 @T6G_MB_LIB.T6G(SCH_1):PAGE37
   J24  174 DQ18_A SCONN288_DDR506112002KQ-SCONN288_DDR506112002KQ,SMA    I22 @T6G_MB_LIB.T6G(SCH_1):PAGE97

M_A_CPU1_SA_DQ<19> @T6G_MB_LIB.T6G(SCH_1):M_A_CPU1_SA_DQ(19)
   U26  W73 MAA_DATA19 GENOA_SP5-SOCKET6096_13568-001,SMLF,IO,DGA^6000030   I167 @T6G_MB_LIB.T6G(SCH_1):PAGE37
   J24  176 DQ19_A SCONN288_DDR506112002KQ-SCONN288_DDR506112002KQ,SMA    I22 @T6G_MB_LIB.T6G(SCH_1):PAGE97

M_A_CPU1_SA_DQ<1> @T6G_MB_LIB.T6G(SCH_1):M_A_CPU1_SA_DQ(1)
   U26  F72 MAA_DATA1 GENOA_SP5-SOCKET6096_13568-001,SMLF,IO,DGA^6000030   I167 @T6G_MB_LIB.T6G(SCH_1):PAGE37
   J24    9  DQ1_A SCONN288_DDR506112002KQ-SCONN288_DDR506112002KQ,SMA    I22 @T6G_MB_LIB.T6G(SCH_1):PAGE97

M_A_CPU1_SA_DQ<20> @T6G_MB_LIB.T6G(SCH_1):M_A_CPU1_SA_DQ(20)
   U26 AA74 MAA_DATA20 GENOA_SP5-SOCKET6096_13568-001,SMLF,IO,DGA^6000030   I167 @T6G_MB_LIB.T6G(SCH_1):PAGE37
   J24   36 DQ20_A SCONN288_DDR506112002KQ-SCONN288_DDR506112002KQ,SMA    I22 @T6G_MB_LIB.T6G(SCH_1):PAGE97

M_A_CPU1_SA_DQ<21> @T6G_MB_LIB.T6G(SCH_1):M_A_CPU1_SA_DQ(21)
   U26 AB72 MAA_DATA21 GENOA_SP5-SOCKET6096_13568-001,SMLF,IO,DGA^6000030   I167 @T6G_MB_LIB.T6G(SCH_1):PAGE37
   J24   38 DQ21_A SCONN288_DDR506112002KQ-SCONN288_DDR506112002KQ,SMA    I22 @T6G_MB_LIB.T6G(SCH_1):PAGE97

M_A_CPU1_SA_DQ<22> @T6G_MB_LIB.T6G(SCH_1):M_A_CPU1_SA_DQ(22)
   U26 AB74 MAA_DATA22 GENOA_SP5-SOCKET6096_13568-001,SMLF,IO,DGA^6000030   I167 @T6G_MB_LIB.T6G(SCH_1):PAGE37
   J24  181 DQ22_A SCONN288_DDR506112002KQ-SCONN288_DDR506112002KQ,SMA    I22 @T6G_MB_LIB.T6G(SCH_1):PAGE97

M_A_CPU1_SA_DQ<23> @T6G_MB_LIB.T6G(SCH_1):M_A_CPU1_SA_DQ(23)
   U26 AC73 MAA_DATA23 GENOA_SP5-SOCKET6096_13568-001,SMLF,IO,DGA^6000030   I167 @T6G_MB_LIB.T6G(SCH_1):PAGE37
   J24  183 DQ23_A SCONN288_DDR506112002KQ-SCONN288_DDR506112002KQ,SMA    I22 @T6G_MB_LIB.T6G(SCH_1):PAGE97

M_A_CPU1_SA_DQ<24> @T6G_MB_LIB.T6G(SCH_1):M_A_CPU1_SA_DQ(24)
   U26 AC74 MAA_DATA24 GENOA_SP5-SOCKET6096_13568-001,SMLF,IO,DGA^6000030   I167 @T6G_MB_LIB.T6G(SCH_1):PAGE37
   J24   40 DQ24_A SCONN288_DDR506112002KQ-SCONN288_DDR506112002KQ,SMA    I22 @T6G_MB_LIB.T6G(SCH_1):PAGE97

M_A_CPU1_SA_DQ<25> @T6G_MB_LIB.T6G(SCH_1):M_A_CPU1_SA_DQ(25)
   U26 AD72 MAA_DATA25 GENOA_SP5-SOCKET6096_13568-001,SMLF,IO,DGA^6000030   I167 @T6G_MB_LIB.T6G(SCH_1):PAGE37
   J24   42 DQ25_A SCONN288_DDR506112002KQ-SCONN288_DDR506112002KQ,SMA    I22 @T6G_MB_LIB.T6G(SCH_1):PAGE97

M_A_CPU1_SA_DQ<26> @T6G_MB_LIB.T6G(SCH_1):M_A_CPU1_SA_DQ(26)
   U26 AD74 MAA_DATA26 GENOA_SP5-SOCKET6096_13568-001,SMLF,IO,DGA^6000030   I167 @T6G_MB_LIB.T6G(SCH_1):PAGE37
   J24  185 DQ26_A SCONN288_DDR506112002KQ-SCONN288_DDR506112002KQ,SMA    I22 @T6G_MB_LIB.T6G(SCH_1):PAGE97

M_A_CPU1_SA_DQ<27> @T6G_MB_LIB.T6G(SCH_1):M_A_CPU1_SA_DQ(27)
   U26 AE73 MAA_DATA27 GENOA_SP5-SOCKET6096_13568-001,SMLF,IO,DGA^6000030   I167 @T6G_MB_LIB.T6G(SCH_1):PAGE37
   J24  187 DQ27_A SCONN288_DDR506112002KQ-SCONN288_DDR506112002KQ,SMA    I22 @T6G_MB_LIB.T6G(SCH_1):PAGE97

M_A_CPU1_SA_DQ<28> @T6G_MB_LIB.T6G(SCH_1):M_A_CPU1_SA_DQ(28)
   U26 AG74 MAA_DATA28 GENOA_SP5-SOCKET6096_13568-001,SMLF,IO,DGA^6000030   I167 @T6G_MB_LIB.T6G(SCH_1):PAGE37
   J24   47 DQ28_A SCONN288_DDR506112002KQ-SCONN288_DDR506112002KQ,SMA    I22 @T6G_MB_LIB.T6G(SCH_1):PAGE97

M_A_CPU1_SA_DQ<29> @T6G_MB_LIB.T6G(SCH_1):M_A_CPU1_SA_DQ(29)
   U26 AH72 MAA_DATA29 GENOA_SP5-SOCKET6096_13568-001,SMLF,IO,DGA^6000030   I167 @T6G_MB_LIB.T6G(SCH_1):PAGE37
   J24   49 DQ29_A SCONN288_DDR506112002KQ-SCONN288_DDR506112002KQ,SMA    I22 @T6G_MB_LIB.T6G(SCH_1):PAGE97

M_A_CPU1_SA_DQ<2> @T6G_MB_LIB.T6G(SCH_1):M_A_CPU1_SA_DQ(2)
   U26  F74 MAA_DATA2 GENOA_SP5-SOCKET6096_13568-001,SMLF,IO,DGA^6000030   I167 @T6G_MB_LIB.T6G(SCH_1):PAGE37
   J24  152  DQ2_A SCONN288_DDR506112002KQ-SCONN288_DDR506112002KQ,SMA    I22 @T6G_MB_LIB.T6G(SCH_1):PAGE97

M_A_CPU1_SA_DQ<30> @T6G_MB_LIB.T6G(SCH_1):M_A_CPU1_SA_DQ(30)
   U26 AH74 MAA_DATA30 GENOA_SP5-SOCKET6096_13568-001,SMLF,IO,DGA^6000030   I167 @T6G_MB_LIB.T6G(SCH_1):PAGE37
   J24  192 DQ30_A SCONN288_DDR506112002KQ-SCONN288_DDR506112002KQ,SMA    I22 @T6G_MB_LIB.T6G(SCH_1):PAGE97

M_A_CPU1_SA_DQ<31> @T6G_MB_LIB.T6G(SCH_1):M_A_CPU1_SA_DQ(31)
   U26 AJ73 MAA_DATA31 GENOA_SP5-SOCKET6096_13568-001,SMLF,IO,DGA^6000030   I167 @T6G_MB_LIB.T6G(SCH_1):PAGE37
   J24  194 DQ31_A SCONN288_DDR506112002KQ-SCONN288_DDR506112002KQ,SMA    I22 @T6G_MB_LIB.T6G(SCH_1):PAGE97

M_A_CPU1_SA_DQ<3> @T6G_MB_LIB.T6G(SCH_1):M_A_CPU1_SA_DQ(3)
   U26  G73 MAA_DATA3 GENOA_SP5-SOCKET6096_13568-001,SMLF,IO,DGA^6000030   I167 @T6G_MB_LIB.T6G(SCH_1):PAGE37
   J24  154  DQ3_A SCONN288_DDR506112002KQ-SCONN288_DDR506112002KQ,SMA    I22 @T6G_MB_LIB.T6G(SCH_1):PAGE97

M_A_CPU1_SA_DQ<4> @T6G_MB_LIB.T6G(SCH_1):M_A_CPU1_SA_DQ(4)
   U26  J74 MAA_DATA4 GENOA_SP5-SOCKET6096_13568-001,SMLF,IO,DGA^6000030   I167 @T6G_MB_LIB.T6G(SCH_1):PAGE37
   J24   14  DQ4_A SCONN288_DDR506112002KQ-SCONN288_DDR506112002KQ,SMA    I22 @T6G_MB_LIB.T6G(SCH_1):PAGE97

M_A_CPU1_SA_DQ<5> @T6G_MB_LIB.T6G(SCH_1):M_A_CPU1_SA_DQ(5)
   U26  K72 MAA_DATA5 GENOA_SP5-SOCKET6096_13568-001,SMLF,IO,DGA^6000030   I167 @T6G_MB_LIB.T6G(SCH_1):PAGE37
   J24   16  DQ5_A SCONN288_DDR506112002KQ-SCONN288_DDR506112002KQ,SMA    I22 @T6G_MB_LIB.T6G(SCH_1):PAGE97

M_A_CPU1_SA_DQ<6> @T6G_MB_LIB.T6G(SCH_1):M_A_CPU1_SA_DQ(6)
   U26  K74 MAA_DATA6 GENOA_SP5-SOCKET6096_13568-001,SMLF,IO,DGA^6000030   I167 @T6G_MB_LIB.T6G(SCH_1):PAGE37
   J24  159  DQ6_A SCONN288_DDR506112002KQ-SCONN288_DDR506112002KQ,SMA    I22 @T6G_MB_LIB.T6G(SCH_1):PAGE97

M_A_CPU1_SA_DQ<7> @T6G_MB_LIB.T6G(SCH_1):M_A_CPU1_SA_DQ(7)
   U26  L73 MAA_DATA7 GENOA_SP5-SOCKET6096_13568-001,SMLF,IO,DGA^6000030   I167 @T6G_MB_LIB.T6G(SCH_1):PAGE37
   J24  161  DQ7_A SCONN288_DDR506112002KQ-SCONN288_DDR506112002KQ,SMA    I22 @T6G_MB_LIB.T6G(SCH_1):PAGE97

M_A_CPU1_SA_DQ<8> @T6G_MB_LIB.T6G(SCH_1):M_A_CPU1_SA_DQ(8)
   U26  L74 MAA_DATA8 GENOA_SP5-SOCKET6096_13568-001,SMLF,IO,DGA^6000030   I167 @T6G_MB_LIB.T6G(SCH_1):PAGE37
   J24   18  DQ8_A SCONN288_DDR506112002KQ-SCONN288_DDR506112002KQ,SMA    I22 @T6G_MB_LIB.T6G(SCH_1):PAGE97

M_A_CPU1_SA_DQ<9> @T6G_MB_LIB.T6G(SCH_1):M_A_CPU1_SA_DQ(9)
   U26  M72 MAA_DATA9 GENOA_SP5-SOCKET6096_13568-001,SMLF,IO,DGA^6000030   I167 @T6G_MB_LIB.T6G(SCH_1):PAGE37
   J24   20  DQ9_A SCONN288_DDR506112002KQ-SCONN288_DDR506112002KQ,SMA    I22 @T6G_MB_LIB.T6G(SCH_1):PAGE97

M_A_CPU1_SA_DQS_DN<0> @T6G_MB_LIB.T6G(SCH_1):M_A_CPU1_SA_DQS_DN(0)
   U26  H74 MAA_DQS_L0 GENOA_SP5-SOCKET6096_13568-001,SMLF,IO,DGA^6000030   I167 @T6G_MB_LIB.T6G(SCH_1):PAGE37
   J24   12 DQS0_A_C SCONN288_DDR506112002KQ-SCONN288_DDR506112002KQ,SMA   I238 @T6G_MB_LIB.T6G(SCH_1):PAGE97

M_A_CPU1_SA_DQS_DN<1> @T6G_MB_LIB.T6G(SCH_1):M_A_CPU1_SA_DQS_DN(1)
   U26  P74 MAA_DQS_L1 GENOA_SP5-SOCKET6096_13568-001,SMLF,IO,DGA^6000030   I167 @T6G_MB_LIB.T6G(SCH_1):PAGE37
   J24   23 DQS1_A_C SCONN288_DDR506112002KQ-SCONN288_DDR506112002KQ,SMA   I238 @T6G_MB_LIB.T6G(SCH_1):PAGE97

M_A_CPU1_SA_DQS_DN<2> @T6G_MB_LIB.T6G(SCH_1):M_A_CPU1_SA_DQS_DN(2)
   U26  Y74 MAA_DQS_L2 GENOA_SP5-SOCKET6096_13568-001,SMLF,IO,DGA^6000030   I167 @T6G_MB_LIB.T6G(SCH_1):PAGE37
   J24   34 DQS2_A_C SCONN288_DDR506112002KQ-SCONN288_DDR506112002KQ,SMA   I238 @T6G_MB_LIB.T6G(SCH_1):PAGE97

M_A_CPU1_SA_DQS_DN<3> @T6G_MB_LIB.T6G(SCH_1):M_A_CPU1_SA_DQS_DN(3)
   U26 AF74 MAA_DQS_L3 GENOA_SP5-SOCKET6096_13568-001,SMLF,IO,DGA^6000030   I167 @T6G_MB_LIB.T6G(SCH_1):PAGE37
   J24   45 DQS3_A_C SCONN288_DDR506112002KQ-SCONN288_DDR506112002KQ,SMA   I238 @T6G_MB_LIB.T6G(SCH_1):PAGE97

M_A_CPU1_SA_DQS_DN<4> @T6G_MB_LIB.T6G(SCH_1):M_A_CPU1_SA_DQS_DN(4)
   U26 AM74 MAA_DQS_L4 GENOA_SP5-SOCKET6096_13568-001,SMLF,IO,DGA^6000030   I167 @T6G_MB_LIB.T6G(SCH_1):PAGE37
   J24   56 DQS4_A_C SCONN288_DDR506112002KQ-SCONN288_DDR506112002KQ,SMA   I238 @T6G_MB_LIB.T6G(SCH_1):PAGE97

M_A_CPU1_SA_DQS_DN<5> @T6G_MB_LIB.T6G(SCH_1):M_A_CPU1_SA_DQS_DN(5)
   U26  H72 MAA_DQS_L5 GENOA_SP5-SOCKET6096_13568-001,SMLF,IO,DGA^6000030   I167 @T6G_MB_LIB.T6G(SCH_1):PAGE37
   J24  156 DQS5_A_C||TDQS5_A_C||DQS5_A_T||TDQS5_A_T SCONN288_DDR506112002KQ-SCONN288_DDR506112002KQ,SMA   I238 @T6G_MB_LIB.T6G(SCH_1):PAGE97

M_A_CPU1_SA_DQS_DN<6> @T6G_MB_LIB.T6G(SCH_1):M_A_CPU1_SA_DQS_DN(6)
   U26  P72 MAA_DQS_L6 GENOA_SP5-SOCKET6096_13568-001,SMLF,IO,DGA^6000030   I167 @T6G_MB_LIB.T6G(SCH_1):PAGE37
   J24  167 DQS6_A_C||TDQS6_A_C||DQS6_A_T||TDQS6_A_T SCONN288_DDR506112002KQ-SCONN288_DDR506112002KQ,SMA   I238 @T6G_MB_LIB.T6G(SCH_1):PAGE97

M_A_CPU1_SA_DQS_DN<7> @T6G_MB_LIB.T6G(SCH_1):M_A_CPU1_SA_DQS_DN(7)
   U26  Y72 MAA_DQS_L7 GENOA_SP5-SOCKET6096_13568-001,SMLF,IO,DGA^6000030   I167 @T6G_MB_LIB.T6G(SCH_1):PAGE37
   J24  178 DQS7_A_C||TDQS7_A_C SCONN288_DDR506112002KQ-SCONN288_DDR506112002KQ,SMA   I238 @T6G_MB_LIB.T6G(SCH_1):PAGE97

M_A_CPU1_SA_DQS_DN<8> @T6G_MB_LIB.T6G(SCH_1):M_A_CPU1_SA_DQS_DN(8)
   U26 AF72 MAA_DQS_L8 GENOA_SP5-SOCKET6096_13568-001,SMLF,IO,DGA^6000030   I167 @T6G_MB_LIB.T6G(SCH_1):PAGE37
   J24  189 DQS8_A_C||TDQS8_A_C SCONN288_DDR506112002KQ-SCONN288_DDR506112002KQ,SMA   I238 @T6G_MB_LIB.T6G(SCH_1):PAGE97

M_A_CPU1_SA_DQS_DN<9> @T6G_MB_LIB.T6G(SCH_1):M_A_CPU1_SA_DQS_DN(9)
   U26 AM72 MAA_DQS_L9 GENOA_SP5-SOCKET6096_13568-001,SMLF,IO,DGA^6000030   I167 @T6G_MB_LIB.T6G(SCH_1):PAGE37
   J24  200 DQS9_A_C||TDQS9_A_C SCONN288_DDR506112002KQ-SCONN288_DDR506112002KQ,SMA   I238 @T6G_MB_LIB.T6G(SCH_1):PAGE97

M_A_CPU1_SA_DQS_DP<0> @T6G_MB_LIB.T6G(SCH_1):M_A_CPU1_SA_DQS_DP(0)
   U26  G74 MAA_DQS_H0 GENOA_SP5-SOCKET6096_13568-001,SMLF,IO,DGA^6000030   I167 @T6G_MB_LIB.T6G(SCH_1):PAGE37
   J24   11 DQS0_A_T SCONN288_DDR506112002KQ-SCONN288_DDR506112002KQ,SMA   I238 @T6G_MB_LIB.T6G(SCH_1):PAGE97

M_A_CPU1_SA_DQS_DP<1> @T6G_MB_LIB.T6G(SCH_1):M_A_CPU1_SA_DQS_DP(1)
   U26  N74 MAA_DQS_H1 GENOA_SP5-SOCKET6096_13568-001,SMLF,IO,DGA^6000030   I167 @T6G_MB_LIB.T6G(SCH_1):PAGE37
   J24   22 DQS1_A_T SCONN288_DDR506112002KQ-SCONN288_DDR506112002KQ,SMA   I238 @T6G_MB_LIB.T6G(SCH_1):PAGE97

M_A_CPU1_SA_DQS_DP<2> @T6G_MB_LIB.T6G(SCH_1):M_A_CPU1_SA_DQS_DP(2)
   U26  W74 MAA_DQS_H2 GENOA_SP5-SOCKET6096_13568-001,SMLF,IO,DGA^6000030   I167 @T6G_MB_LIB.T6G(SCH_1):PAGE37
   J24   33 DQS2_A_T SCONN288_DDR506112002KQ-SCONN288_DDR506112002KQ,SMA   I238 @T6G_MB_LIB.T6G(SCH_1):PAGE97

M_A_CPU1_SA_DQS_DP<3> @T6G_MB_LIB.T6G(SCH_1):M_A_CPU1_SA_DQS_DP(3)
   U26 AE74 MAA_DQS_H3 GENOA_SP5-SOCKET6096_13568-001,SMLF,IO,DGA^6000030   I167 @T6G_MB_LIB.T6G(SCH_1):PAGE37
   J24   44 DQS3_A_T SCONN288_DDR506112002KQ-SCONN288_DDR506112002KQ,SMA   I238 @T6G_MB_LIB.T6G(SCH_1):PAGE97

M_A_CPU1_SA_DQS_DP<4> @T6G_MB_LIB.T6G(SCH_1):M_A_CPU1_SA_DQS_DP(4)
   U26 AL74 MAA_DQS_H4 GENOA_SP5-SOCKET6096_13568-001,SMLF,IO,DGA^6000030   I167 @T6G_MB_LIB.T6G(SCH_1):PAGE37
   J24   55 DQS4_A_T SCONN288_DDR506112002KQ-SCONN288_DDR506112002KQ,SMA   I238 @T6G_MB_LIB.T6G(SCH_1):PAGE97

M_A_CPU1_SA_DQS_DP<5> @T6G_MB_LIB.T6G(SCH_1):M_A_CPU1_SA_DQS_DP(5)
   U26  J73 MAA_DQS_H5 GENOA_SP5-SOCKET6096_13568-001,SMLF,IO,DGA^6000030   I167 @T6G_MB_LIB.T6G(SCH_1):PAGE37
   J24  157 DQS5_A_T||TDQS5_A_T SCONN288_DDR506112002KQ-SCONN288_DDR506112002KQ,SMA   I238 @T6G_MB_LIB.T6G(SCH_1):PAGE97

M_A_CPU1_SA_DQS_DP<6> @T6G_MB_LIB.T6G(SCH_1):M_A_CPU1_SA_DQS_DP(6)
   U26  R73 MAA_DQS_H6 GENOA_SP5-SOCKET6096_13568-001,SMLF,IO,DGA^6000030   I167 @T6G_MB_LIB.T6G(SCH_1):PAGE37
   J24  168 DQS6_A_T||TDQS6_A_T SCONN288_DDR506112002KQ-SCONN288_DDR506112002KQ,SMA   I238 @T6G_MB_LIB.T6G(SCH_1):PAGE97

M_A_CPU1_SA_DQS_DP<7> @T6G_MB_LIB.T6G(SCH_1):M_A_CPU1_SA_DQS_DP(7)
   U26 AA73 MAA_DQS_H7 GENOA_SP5-SOCKET6096_13568-001,SMLF,IO,DGA^6000030   I167 @T6G_MB_LIB.T6G(SCH_1):PAGE37
   J24  179 DQS7_A_T||TDQS7_A_T SCONN288_DDR506112002KQ-SCONN288_DDR506112002KQ,SMA   I238 @T6G_MB_LIB.T6G(SCH_1):PAGE97

M_A_CPU1_SA_DQS_DP<8> @T6G_MB_LIB.T6G(SCH_1):M_A_CPU1_SA_DQS_DP(8)
   U26 AG73 MAA_DQS_H8 GENOA_SP5-SOCKET6096_13568-001,SMLF,IO,DGA^6000030   I167 @T6G_MB_LIB.T6G(SCH_1):PAGE37
   J24  190 DQS8_A_T||TDQS8_A_T SCONN288_DDR506112002KQ-SCONN288_DDR506112002KQ,SMA   I238 @T6G_MB_LIB.T6G(SCH_1):PAGE97

M_A_CPU1_SA_DQS_DP<9> @T6G_MB_LIB.T6G(SCH_1):M_A_CPU1_SA_DQS_DP(9)
   U26 AN73 MAA_DQS_H9 GENOA_SP5-SOCKET6096_13568-001,SMLF,IO,DGA^6000030   I167 @T6G_MB_LIB.T6G(SCH_1):PAGE37
   J24  201 DQS9_A_T||TDQS9_A_T SCONN288_DDR506112002KQ-SCONN288_DDR506112002KQ,SMA   I238 @T6G_MB_LIB.T6G(SCH_1):PAGE97

M_A_CPU1_SA_PAR @T6G_MB_LIB.T6G(SCH_1):M_A_CPU1_SA_PAR
   U26 BC73 MAA_PAR GENOA_SP5-SOCKET6096_13568-001,SMLF,IO,DGA^6000030   I167 @T6G_MB_LIB.T6G(SCH_1):PAGE37
   J24   74  PAR_A SCONN288_DDR506112002KQ-SCONN288_DDR506112002KQ,SMA    I22 @T6G_MB_LIB.T6G(SCH_1):PAGE97

M_A_CPU1_SA_RSP<0> @T6G_MB_LIB.T6G(SCH_1):M_A_CPU1_SA_RSP(0)
   U26 BN73 MAA0_RSP_L GENOA_SP5-SOCKET6096_13568-001,SMLF,IO,DGA^6000030   I167 @T6G_MB_LIB.T6G(SCH_1):PAGE37
   J24   86 LBD||RSP_A_N SCONN288_DDR506112002KQ-SCONN288_DDR506112002KQ,SMA    I22 @T6G_MB_LIB.T6G(SCH_1):PAGE97

M_A_CPU1_SB_CA<0> @T6G_MB_LIB.T6G(SCH_1):M_A_CPU1_SB_CA(0)
   U26 BG73 MAB_CA0 GENOA_SP5-SOCKET6096_13568-001,SMLF,IO,DGA^6000030   I167 @T6G_MB_LIB.T6G(SCH_1):PAGE37
   J24   76  CA0_B SCONN288_DDR506112002KQ-SCONN288_DDR506112002KQ,SMA    I22 @T6G_MB_LIB.T6G(SCH_1):PAGE97

M_A_CPU1_SB_CA<1> @T6G_MB_LIB.T6G(SCH_1):M_A_CPU1_SB_CA(1)
   U26 BH72 MAB_CA1 GENOA_SP5-SOCKET6096_13568-001,SMLF,IO,DGA^6000030   I167 @T6G_MB_LIB.T6G(SCH_1):PAGE37
   J24  221  CA1_B SCONN288_DDR506112002KQ-SCONN288_DDR506112002KQ,SMA    I22 @T6G_MB_LIB.T6G(SCH_1):PAGE97

M_A_CPU1_SB_CA<2> @T6G_MB_LIB.T6G(SCH_1):M_A_CPU1_SB_CA(2)
   U26 BH74 MAB_CA2 GENOA_SP5-SOCKET6096_13568-001,SMLF,IO,DGA^6000030   I167 @T6G_MB_LIB.T6G(SCH_1):PAGE37
   J24   78  CA2_B SCONN288_DDR506112002KQ-SCONN288_DDR506112002KQ,SMA    I22 @T6G_MB_LIB.T6G(SCH_1):PAGE97

M_A_CPU1_SB_CA<3> @T6G_MB_LIB.T6G(SCH_1):M_A_CPU1_SB_CA(3)
   U26 BJ74 MAB_CA3 GENOA_SP5-SOCKET6096_13568-001,SMLF,IO,DGA^6000030   I167 @T6G_MB_LIB.T6G(SCH_1):PAGE37
   J24  223  CA3_B SCONN288_DDR506112002KQ-SCONN288_DDR506112002KQ,SMA    I22 @T6G_MB_LIB.T6G(SCH_1):PAGE97

M_A_CPU1_SB_CA<4> @T6G_MB_LIB.T6G(SCH_1):M_A_CPU1_SB_CA(4)
   U26 BJ73 MAB_CA4 GENOA_SP5-SOCKET6096_13568-001,SMLF,IO,DGA^6000030   I167 @T6G_MB_LIB.T6G(SCH_1):PAGE37
   J24   80  CA4_B SCONN288_DDR506112002KQ-SCONN288_DDR506112002KQ,SMA    I22 @T6G_MB_LIB.T6G(SCH_1):PAGE97

M_A_CPU1_SB_CA<5> @T6G_MB_LIB.T6G(SCH_1):M_A_CPU1_SB_CA(5)
   U26 BK72 MAB_CA5 GENOA_SP5-SOCKET6096_13568-001,SMLF,IO,DGA^6000030   I167 @T6G_MB_LIB.T6G(SCH_1):PAGE37
   J24  225  CA5_B SCONN288_DDR506112002KQ-SCONN288_DDR506112002KQ,SMA    I22 @T6G_MB_LIB.T6G(SCH_1):PAGE97

M_A_CPU1_SB_CA<6> @T6G_MB_LIB.T6G(SCH_1):M_A_CPU1_SB_CA(6)
   U26 BK74 MAB_CA6 GENOA_SP5-SOCKET6096_13568-001,SMLF,IO,DGA^6000030   I167 @T6G_MB_LIB.T6G(SCH_1):PAGE37
   J24   82  CA6_B SCONN288_DDR506112002KQ-SCONN288_DDR506112002KQ,SMA    I22 @T6G_MB_LIB.T6G(SCH_1):PAGE97

M_A_CPU1_SB_CB<0> @T6G_MB_LIB.T6G(SCH_1):M_A_CPU1_SB_CB(0)
   U26 BY74 MAB_CHECK0 GENOA_SP5-SOCKET6096_13568-001,SMLF,IO,DGA^6000030   I167 @T6G_MB_LIB.T6G(SCH_1):PAGE37
   J24   96  CB0_B SCONN288_DDR506112002KQ-SCONN288_DDR506112002KQ,SMA    I22 @T6G_MB_LIB.T6G(SCH_1):PAGE97

M_A_CPU1_SB_CB<1> @T6G_MB_LIB.T6G(SCH_1):M_A_CPU1_SB_CB(1)
   U26 CA73 MAB_CHECK1 GENOA_SP5-SOCKET6096_13568-001,SMLF,IO,DGA^6000030   I167 @T6G_MB_LIB.T6G(SCH_1):PAGE37
   J24   98  CB1_B SCONN288_DDR506112002KQ-SCONN288_DDR506112002KQ,SMA    I22 @T6G_MB_LIB.T6G(SCH_1):PAGE97

M_A_CPU1_SB_CB<2> @T6G_MB_LIB.T6G(SCH_1):M_A_CPU1_SB_CB(2)
   U26 CA74 MAB_CHECK2 GENOA_SP5-SOCKET6096_13568-001,SMLF,IO,DGA^6000030   I167 @T6G_MB_LIB.T6G(SCH_1):PAGE37
   J24  241  CB2_B SCONN288_DDR506112002KQ-SCONN288_DDR506112002KQ,SMA    I22 @T6G_MB_LIB.T6G(SCH_1):PAGE97

M_A_CPU1_SB_CB<3> @T6G_MB_LIB.T6G(SCH_1):M_A_CPU1_SB_CB(3)
   U26 CB72 MAB_CHECK3 GENOA_SP5-SOCKET6096_13568-001,SMLF,IO,DGA^6000030   I167 @T6G_MB_LIB.T6G(SCH_1):PAGE37
   J24  243  CB3_B SCONN288_DDR506112002KQ-SCONN288_DDR506112002KQ,SMA    I22 @T6G_MB_LIB.T6G(SCH_1):PAGE97

M_A_CPU1_SB_CB<4> @T6G_MB_LIB.T6G(SCH_1):M_A_CPU1_SB_CB(4)
   U26 BT74 MAB_CHECK4 GENOA_SP5-SOCKET6096_13568-001,SMLF,IO,DGA^6000030   I167 @T6G_MB_LIB.T6G(SCH_1):PAGE37
   J24   89  CB4_B SCONN288_DDR506112002KQ-SCONN288_DDR506112002KQ,SMA    I22 @T6G_MB_LIB.T6G(SCH_1):PAGE97

M_A_CPU1_SB_CB<5> @T6G_MB_LIB.T6G(SCH_1):M_A_CPU1_SB_CB(5)
   U26 BU73 MAB_CHECK5 GENOA_SP5-SOCKET6096_13568-001,SMLF,IO,DGA^6000030   I167 @T6G_MB_LIB.T6G(SCH_1):PAGE37
   J24   91  CB5_B SCONN288_DDR506112002KQ-SCONN288_DDR506112002KQ,SMA    I22 @T6G_MB_LIB.T6G(SCH_1):PAGE97

M_A_CPU1_SB_CB<6> @T6G_MB_LIB.T6G(SCH_1):M_A_CPU1_SB_CB(6)
   U26 BU74 MAB_CHECK6 GENOA_SP5-SOCKET6096_13568-001,SMLF,IO,DGA^6000030   I167 @T6G_MB_LIB.T6G(SCH_1):PAGE37
   J24  234  CB6_B SCONN288_DDR506112002KQ-SCONN288_DDR506112002KQ,SMA    I22 @T6G_MB_LIB.T6G(SCH_1):PAGE97

M_A_CPU1_SB_CB<7> @T6G_MB_LIB.T6G(SCH_1):M_A_CPU1_SB_CB(7)
   U26 BV72 MAB_CHECK7 GENOA_SP5-SOCKET6096_13568-001,SMLF,IO,DGA^6000030   I167 @T6G_MB_LIB.T6G(SCH_1):PAGE37
   J24  236  CB7_B SCONN288_DDR506112002KQ-SCONN288_DDR506112002KQ,SMA    I22 @T6G_MB_LIB.T6G(SCH_1):PAGE97

M_A_CPU1_SB_CS_N<0> @T6G_MB_LIB.T6G(SCH_1):M_A_CPU1_SB_CS_N(0)
   U26 BM72 MAB0_CS_L0 GENOA_SP5-SOCKET6096_13568-001,SMLF,IO,DGA^6000030   I167 @T6G_MB_LIB.T6G(SCH_1):PAGE37
   J24   84 CS0_B_N SCONN288_DDR506112002KQ-SCONN288_DDR506112002KQ,SMA    I22 @T6G_MB_LIB.T6G(SCH_1):PAGE97

M_A_CPU1_SB_CS_N<1> @T6G_MB_LIB.T6G(SCH_1):M_A_CPU1_SB_CS_N(1)
   U26 BN74 MAB0_CS_L1 GENOA_SP5-SOCKET6096_13568-001,SMLF,IO,DGA^6000030   I167 @T6G_MB_LIB.T6G(SCH_1):PAGE37
   J24  229 CS1_B_N SCONN288_DDR506112002KQ-SCONN288_DDR506112002KQ,SMA    I22 @T6G_MB_LIB.T6G(SCH_1):PAGE97

M_A_CPU1_SB_DQ<0> @T6G_MB_LIB.T6G(SCH_1):M_A_CPU1_SB_DQ(0)
   U26 CB74 MAB_DATA0 GENOA_SP5-SOCKET6096_13568-001,SMLF,IO,DGA^6000030   I167 @T6G_MB_LIB.T6G(SCH_1):PAGE37
   J24  100  DQ0_B SCONN288_DDR506112002KQ-SCONN288_DDR506112002KQ,SMA    I22 @T6G_MB_LIB.T6G(SCH_1):PAGE97

M_A_CPU1_SB_DQ<10> @T6G_MB_LIB.T6G(SCH_1):M_A_CPU1_SB_DQ(10)
   U26 CJ74 MAB_DATA10 GENOA_SP5-SOCKET6096_13568-001,SMLF,IO,DGA^6000030   I167 @T6G_MB_LIB.T6G(SCH_1):PAGE37
   J24  256 DQ10_B SCONN288_DDR506112002KQ-SCONN288_DDR506112002KQ,SMA    I22 @T6G_MB_LIB.T6G(SCH_1):PAGE97

M_A_CPU1_SB_DQ<11> @T6G_MB_LIB.T6G(SCH_1):M_A_CPU1_SB_DQ(11)
   U26 CK72 MAB_DATA11 GENOA_SP5-SOCKET6096_13568-001,SMLF,IO,DGA^6000030   I167 @T6G_MB_LIB.T6G(SCH_1):PAGE37
   J24  258 DQ11_B SCONN288_DDR506112002KQ-SCONN288_DDR506112002KQ,SMA    I22 @T6G_MB_LIB.T6G(SCH_1):PAGE97

M_A_CPU1_SB_DQ<12> @T6G_MB_LIB.T6G(SCH_1):M_A_CPU1_SB_DQ(12)
   U26 CM74 MAB_DATA12 GENOA_SP5-SOCKET6096_13568-001,SMLF,IO,DGA^6000030   I167 @T6G_MB_LIB.T6G(SCH_1):PAGE37
   J24  118 DQ12_B SCONN288_DDR506112002KQ-SCONN288_DDR506112002KQ,SMA    I22 @T6G_MB_LIB.T6G(SCH_1):PAGE97

M_A_CPU1_SB_DQ<13> @T6G_MB_LIB.T6G(SCH_1):M_A_CPU1_SB_DQ(13)
   U26 CN73 MAB_DATA13 GENOA_SP5-SOCKET6096_13568-001,SMLF,IO,DGA^6000030   I167 @T6G_MB_LIB.T6G(SCH_1):PAGE37
   J24  120 DQ13_B SCONN288_DDR506112002KQ-SCONN288_DDR506112002KQ,SMA    I22 @T6G_MB_LIB.T6G(SCH_1):PAGE97

M_A_CPU1_SB_DQ<14> @T6G_MB_LIB.T6G(SCH_1):M_A_CPU1_SB_DQ(14)
   U26 CN74 MAB_DATA14 GENOA_SP5-SOCKET6096_13568-001,SMLF,IO,DGA^6000030   I167 @T6G_MB_LIB.T6G(SCH_1):PAGE37
   J24  263 DQ14_B SCONN288_DDR506112002KQ-SCONN288_DDR506112002KQ,SMA    I22 @T6G_MB_LIB.T6G(SCH_1):PAGE97

M_A_CPU1_SB_DQ<15> @T6G_MB_LIB.T6G(SCH_1):M_A_CPU1_SB_DQ(15)
   U26 CP72 MAB_DATA15 GENOA_SP5-SOCKET6096_13568-001,SMLF,IO,DGA^6000030   I167 @T6G_MB_LIB.T6G(SCH_1):PAGE37
   J24  265 DQ15_B SCONN288_DDR506112002KQ-SCONN288_DDR506112002KQ,SMA    I22 @T6G_MB_LIB.T6G(SCH_1):PAGE97

M_A_CPU1_SB_DQ<16> @T6G_MB_LIB.T6G(SCH_1):M_A_CPU1_SB_DQ(16)
   U26 CP74 MAB_DATA16 GENOA_SP5-SOCKET6096_13568-001,SMLF,IO,DGA^6000030   I167 @T6G_MB_LIB.T6G(SCH_1):PAGE37
   J24  122 DQ16_B SCONN288_DDR506112002KQ-SCONN288_DDR506112002KQ,SMA    I22 @T6G_MB_LIB.T6G(SCH_1):PAGE97

M_A_CPU1_SB_DQ<17> @T6G_MB_LIB.T6G(SCH_1):M_A_CPU1_SB_DQ(17)
   U26 CR73 MAB_DATA17 GENOA_SP5-SOCKET6096_13568-001,SMLF,IO,DGA^6000030   I167 @T6G_MB_LIB.T6G(SCH_1):PAGE37
   J24  124 DQ17_B SCONN288_DDR506112002KQ-SCONN288_DDR506112002KQ,SMA    I22 @T6G_MB_LIB.T6G(SCH_1):PAGE97

M_A_CPU1_SB_DQ<18> @T6G_MB_LIB.T6G(SCH_1):M_A_CPU1_SB_DQ(18)
   U26 CR74 MAB_DATA18 GENOA_SP5-SOCKET6096_13568-001,SMLF,IO,DGA^6000030   I167 @T6G_MB_LIB.T6G(SCH_1):PAGE37
   J24  267 DQ18_B SCONN288_DDR506112002KQ-SCONN288_DDR506112002KQ,SMA    I22 @T6G_MB_LIB.T6G(SCH_1):PAGE97

M_A_CPU1_SB_DQ<19> @T6G_MB_LIB.T6G(SCH_1):M_A_CPU1_SB_DQ(19)
   U26 CT72 MAB_DATA19 GENOA_SP5-SOCKET6096_13568-001,SMLF,IO,DGA^6000030   I167 @T6G_MB_LIB.T6G(SCH_1):PAGE37
   J24  269 DQ19_B SCONN288_DDR506112002KQ-SCONN288_DDR506112002KQ,SMA    I22 @T6G_MB_LIB.T6G(SCH_1):PAGE97

M_A_CPU1_SB_DQ<1> @T6G_MB_LIB.T6G(SCH_1):M_A_CPU1_SB_DQ(1)
   U26 CC73 MAB_DATA1 GENOA_SP5-SOCKET6096_13568-001,SMLF,IO,DGA^6000030   I167 @T6G_MB_LIB.T6G(SCH_1):PAGE37
   J24  102  DQ1_B SCONN288_DDR506112002KQ-SCONN288_DDR506112002KQ,SMA    I22 @T6G_MB_LIB.T6G(SCH_1):PAGE97

M_A_CPU1_SB_DQ<20> @T6G_MB_LIB.T6G(SCH_1):M_A_CPU1_SB_DQ(20)
   U26 CV74 MAB_DATA20 GENOA_SP5-SOCKET6096_13568-001,SMLF,IO,DGA^6000030   I167 @T6G_MB_LIB.T6G(SCH_1):PAGE37
   J24  129 DQ20_B SCONN288_DDR506112002KQ-SCONN288_DDR506112002KQ,SMA    I22 @T6G_MB_LIB.T6G(SCH_1):PAGE97

M_A_CPU1_SB_DQ<21> @T6G_MB_LIB.T6G(SCH_1):M_A_CPU1_SB_DQ(21)
   U26 CW73 MAB_DATA21 GENOA_SP5-SOCKET6096_13568-001,SMLF,IO,DGA^6000030   I167 @T6G_MB_LIB.T6G(SCH_1):PAGE37
   J24  131 DQ21_B SCONN288_DDR506112002KQ-SCONN288_DDR506112002KQ,SMA    I22 @T6G_MB_LIB.T6G(SCH_1):PAGE97

M_A_CPU1_SB_DQ<22> @T6G_MB_LIB.T6G(SCH_1):M_A_CPU1_SB_DQ(22)
   U26 CW74 MAB_DATA22 GENOA_SP5-SOCKET6096_13568-001,SMLF,IO,DGA^6000030   I167 @T6G_MB_LIB.T6G(SCH_1):PAGE37
   J24  274 DQ22_B SCONN288_DDR506112002KQ-SCONN288_DDR506112002KQ,SMA    I22 @T6G_MB_LIB.T6G(SCH_1):PAGE97

M_A_CPU1_SB_DQ<23> @T6G_MB_LIB.T6G(SCH_1):M_A_CPU1_SB_DQ(23)
   U26 CY72 MAB_DATA23 GENOA_SP5-SOCKET6096_13568-001,SMLF,IO,DGA^6000030   I167 @T6G_MB_LIB.T6G(SCH_1):PAGE37
   J24  276 DQ23_B SCONN288_DDR506112002KQ-SCONN288_DDR506112002KQ,SMA    I22 @T6G_MB_LIB.T6G(SCH_1):PAGE97

M_A_CPU1_SB_DQ<24> @T6G_MB_LIB.T6G(SCH_1):M_A_CPU1_SB_DQ(24)
   U26 CY74 MAB_DATA24 GENOA_SP5-SOCKET6096_13568-001,SMLF,IO,DGA^6000030   I167 @T6G_MB_LIB.T6G(SCH_1):PAGE37
   J24  133 DQ24_B SCONN288_DDR506112002KQ-SCONN288_DDR506112002KQ,SMA    I22 @T6G_MB_LIB.T6G(SCH_1):PAGE97

M_A_CPU1_SB_DQ<25> @T6G_MB_LIB.T6G(SCH_1):M_A_CPU1_SB_DQ(25)
   U26 DA73 MAB_DATA25 GENOA_SP5-SOCKET6096_13568-001,SMLF,IO,DGA^6000030   I167 @T6G_MB_LIB.T6G(SCH_1):PAGE37
   J24  135 DQ25_B SCONN288_DDR506112002KQ-SCONN288_DDR506112002KQ,SMA    I22 @T6G_MB_LIB.T6G(SCH_1):PAGE97

M_A_CPU1_SB_DQ<26> @T6G_MB_LIB.T6G(SCH_1):M_A_CPU1_SB_DQ(26)
   U26 DA74 MAB_DATA26 GENOA_SP5-SOCKET6096_13568-001,SMLF,IO,DGA^6000030   I167 @T6G_MB_LIB.T6G(SCH_1):PAGE37
   J24  278 DQ26_B SCONN288_DDR506112002KQ-SCONN288_DDR506112002KQ,SMA    I22 @T6G_MB_LIB.T6G(SCH_1):PAGE97

M_A_CPU1_SB_DQ<27> @T6G_MB_LIB.T6G(SCH_1):M_A_CPU1_SB_DQ(27)
   U26 DB72 MAB_DATA27 GENOA_SP5-SOCKET6096_13568-001,SMLF,IO,DGA^6000030   I167 @T6G_MB_LIB.T6G(SCH_1):PAGE37
   J24  280 DQ27_B SCONN288_DDR506112002KQ-SCONN288_DDR506112002KQ,SMA    I22 @T6G_MB_LIB.T6G(SCH_1):PAGE97

M_A_CPU1_SB_DQ<28> @T6G_MB_LIB.T6G(SCH_1):M_A_CPU1_SB_DQ(28)
   U26 DD74 MAB_DATA28 GENOA_SP5-SOCKET6096_13568-001,SMLF,IO,DGA^6000030   I167 @T6G_MB_LIB.T6G(SCH_1):PAGE37
   J24  140 DQ28_B SCONN288_DDR506112002KQ-SCONN288_DDR506112002KQ,SMA    I22 @T6G_MB_LIB.T6G(SCH_1):PAGE97

M_A_CPU1_SB_DQ<29> @T6G_MB_LIB.T6G(SCH_1):M_A_CPU1_SB_DQ(29)
   U26 DE73 MAB_DATA29 GENOA_SP5-SOCKET6096_13568-001,SMLF,IO,DGA^6000030   I167 @T6G_MB_LIB.T6G(SCH_1):PAGE37
   J24  142 DQ29_B SCONN288_DDR506112002KQ-SCONN288_DDR506112002KQ,SMA    I22 @T6G_MB_LIB.T6G(SCH_1):PAGE97

M_A_CPU1_SB_DQ<2> @T6G_MB_LIB.T6G(SCH_1):M_A_CPU1_SB_DQ(2)
   U26 CC74 MAB_DATA2 GENOA_SP5-SOCKET6096_13568-001,SMLF,IO,DGA^6000030   I167 @T6G_MB_LIB.T6G(SCH_1):PAGE37
   J24  245  DQ2_B SCONN288_DDR506112002KQ-SCONN288_DDR506112002KQ,SMA    I22 @T6G_MB_LIB.T6G(SCH_1):PAGE97

M_A_CPU1_SB_DQ<30> @T6G_MB_LIB.T6G(SCH_1):M_A_CPU1_SB_DQ(30)
   U26 DE74 MAB_DATA30 GENOA_SP5-SOCKET6096_13568-001,SMLF,IO,DGA^6000030   I167 @T6G_MB_LIB.T6G(SCH_1):PAGE37
   J24  285 DQ30_B SCONN288_DDR506112002KQ-SCONN288_DDR506112002KQ,SMA    I22 @T6G_MB_LIB.T6G(SCH_1):PAGE97

M_A_CPU1_SB_DQ<31> @T6G_MB_LIB.T6G(SCH_1):M_A_CPU1_SB_DQ(31)
   U26 DF74 MAB_DATA31 GENOA_SP5-SOCKET6096_13568-001,SMLF,IO,DGA^6000030   I167 @T6G_MB_LIB.T6G(SCH_1):PAGE37
   J24  287 DQ31_B SCONN288_DDR506112002KQ-SCONN288_DDR506112002KQ,SMA    I22 @T6G_MB_LIB.T6G(SCH_1):PAGE97

M_A_CPU1_SB_DQ<3> @T6G_MB_LIB.T6G(SCH_1):M_A_CPU1_SB_DQ(3)
   U26 CD72 MAB_DATA3 GENOA_SP5-SOCKET6096_13568-001,SMLF,IO,DGA^6000030   I167 @T6G_MB_LIB.T6G(SCH_1):PAGE37
   J24  247  DQ3_B SCONN288_DDR506112002KQ-SCONN288_DDR506112002KQ,SMA    I22 @T6G_MB_LIB.T6G(SCH_1):PAGE97

M_A_CPU1_SB_DQ<4> @T6G_MB_LIB.T6G(SCH_1):M_A_CPU1_SB_DQ(4)
   U26 CF74 MAB_DATA4 GENOA_SP5-SOCKET6096_13568-001,SMLF,IO,DGA^6000030   I167 @T6G_MB_LIB.T6G(SCH_1):PAGE37
   J24  107  DQ4_B SCONN288_DDR506112002KQ-SCONN288_DDR506112002KQ,SMA    I22 @T6G_MB_LIB.T6G(SCH_1):PAGE97

M_A_CPU1_SB_DQ<5> @T6G_MB_LIB.T6G(SCH_1):M_A_CPU1_SB_DQ(5)
   U26 CG73 MAB_DATA5 GENOA_SP5-SOCKET6096_13568-001,SMLF,IO,DGA^6000030   I167 @T6G_MB_LIB.T6G(SCH_1):PAGE37
   J24  109  DQ5_B SCONN288_DDR506112002KQ-SCONN288_DDR506112002KQ,SMA    I22 @T6G_MB_LIB.T6G(SCH_1):PAGE97

M_A_CPU1_SB_DQ<6> @T6G_MB_LIB.T6G(SCH_1):M_A_CPU1_SB_DQ(6)
   U26 CG74 MAB_DATA6 GENOA_SP5-SOCKET6096_13568-001,SMLF,IO,DGA^6000030   I167 @T6G_MB_LIB.T6G(SCH_1):PAGE37
   J24  252  DQ6_B SCONN288_DDR506112002KQ-SCONN288_DDR506112002KQ,SMA    I22 @T6G_MB_LIB.T6G(SCH_1):PAGE97

M_A_CPU1_SB_DQ<7> @T6G_MB_LIB.T6G(SCH_1):M_A_CPU1_SB_DQ(7)
   U26 CH72 MAB_DATA7 GENOA_SP5-SOCKET6096_13568-001,SMLF,IO,DGA^6000030   I167 @T6G_MB_LIB.T6G(SCH_1):PAGE37
   J24  254  DQ7_B SCONN288_DDR506112002KQ-SCONN288_DDR506112002KQ,SMA    I22 @T6G_MB_LIB.T6G(SCH_1):PAGE97

M_A_CPU1_SB_DQ<8> @T6G_MB_LIB.T6G(SCH_1):M_A_CPU1_SB_DQ(8)
   U26 CH74 MAB_DATA8 GENOA_SP5-SOCKET6096_13568-001,SMLF,IO,DGA^6000030   I167 @T6G_MB_LIB.T6G(SCH_1):PAGE37
   J24  111  DQ8_B SCONN288_DDR506112002KQ-SCONN288_DDR506112002KQ,SMA    I22 @T6G_MB_LIB.T6G(SCH_1):PAGE97

M_A_CPU1_SB_DQ<9> @T6G_MB_LIB.T6G(SCH_1):M_A_CPU1_SB_DQ(9)
   U26 CJ73 MAB_DATA9 GENOA_SP5-SOCKET6096_13568-001,SMLF,IO,DGA^6000030   I167 @T6G_MB_LIB.T6G(SCH_1):PAGE37
   J24  113  DQ9_B SCONN288_DDR506112002KQ-SCONN288_DDR506112002KQ,SMA    I22 @T6G_MB_LIB.T6G(SCH_1):PAGE97

M_A_CPU1_SB_DQS_DN<0> @T6G_MB_LIB.T6G(SCH_1):M_A_CPU1_SB_DQS_DN(0)
   U26 CE74 MAB_DQS_L0 GENOA_SP5-SOCKET6096_13568-001,SMLF,IO,DGA^6000030   I167 @T6G_MB_LIB.T6G(SCH_1):PAGE37
   J24  105 DQS0_B_C SCONN288_DDR506112002KQ-SCONN288_DDR506112002KQ,SMA   I238 @T6G_MB_LIB.T6G(SCH_1):PAGE97

M_A_CPU1_SB_DQS_DN<1> @T6G_MB_LIB.T6G(SCH_1):M_A_CPU1_SB_DQS_DN(1)
   U26 CL74 MAB_DQS_L1 GENOA_SP5-SOCKET6096_13568-001,SMLF,IO,DGA^6000030   I167 @T6G_MB_LIB.T6G(SCH_1):PAGE37
   J24  116 DQS1_B_C SCONN288_DDR506112002KQ-SCONN288_DDR506112002KQ,SMA   I238 @T6G_MB_LIB.T6G(SCH_1):PAGE97

M_A_CPU1_SB_DQS_DN<2> @T6G_MB_LIB.T6G(SCH_1):M_A_CPU1_SB_DQS_DN(2)
   U26 CU74 MAB_DQS_L2 GENOA_SP5-SOCKET6096_13568-001,SMLF,IO,DGA^6000030   I167 @T6G_MB_LIB.T6G(SCH_1):PAGE37
   J24  127 DQS2_B_C SCONN288_DDR506112002KQ-SCONN288_DDR506112002KQ,SMA   I238 @T6G_MB_LIB.T6G(SCH_1):PAGE97

M_A_CPU1_SB_DQS_DN<3> @T6G_MB_LIB.T6G(SCH_1):M_A_CPU1_SB_DQS_DN(3)
   U26 DC74 MAB_DQS_L3 GENOA_SP5-SOCKET6096_13568-001,SMLF,IO,DGA^6000030   I167 @T6G_MB_LIB.T6G(SCH_1):PAGE37
   J24  138 DQS3_B_C SCONN288_DDR506112002KQ-SCONN288_DDR506112002KQ,SMA   I238 @T6G_MB_LIB.T6G(SCH_1):PAGE97

M_A_CPU1_SB_DQS_DN<4> @T6G_MB_LIB.T6G(SCH_1):M_A_CPU1_SB_DQS_DN(4)
   U26 BW73 MAB_DQS_L4 GENOA_SP5-SOCKET6096_13568-001,SMLF,IO,DGA^6000030   I167 @T6G_MB_LIB.T6G(SCH_1):PAGE37
   J24  238 DQS4_B_C SCONN288_DDR506112002KQ-SCONN288_DDR506112002KQ,SMA   I238 @T6G_MB_LIB.T6G(SCH_1):PAGE97

M_A_CPU1_SB_DQS_DN<5> @T6G_MB_LIB.T6G(SCH_1):M_A_CPU1_SB_DQS_DN(5)
   U26 CE73 MAB_DQS_L5 GENOA_SP5-SOCKET6096_13568-001,SMLF,IO,DGA^6000030   I167 @T6G_MB_LIB.T6G(SCH_1):PAGE37
   J24  249 DQS5_B_C||TDQS5_B_C SCONN288_DDR506112002KQ-SCONN288_DDR506112002KQ,SMA   I238 @T6G_MB_LIB.T6G(SCH_1):PAGE97

M_A_CPU1_SB_DQS_DN<6> @T6G_MB_LIB.T6G(SCH_1):M_A_CPU1_SB_DQS_DN(6)
   U26 CL73 MAB_DQS_L6 GENOA_SP5-SOCKET6096_13568-001,SMLF,IO,DGA^6000030   I167 @T6G_MB_LIB.T6G(SCH_1):PAGE37
   J24  260 DQS6_B_C||TDQS6_B_C SCONN288_DDR506112002KQ-SCONN288_DDR506112002KQ,SMA   I238 @T6G_MB_LIB.T6G(SCH_1):PAGE97

M_A_CPU1_SB_DQS_DN<7> @T6G_MB_LIB.T6G(SCH_1):M_A_CPU1_SB_DQS_DN(7)
   U26 CU73 MAB_DQS_L7 GENOA_SP5-SOCKET6096_13568-001,SMLF,IO,DGA^6000030   I167 @T6G_MB_LIB.T6G(SCH_1):PAGE37
   J24  271 DQS7_B_C||TDQS7_B_C SCONN288_DDR506112002KQ-SCONN288_DDR506112002KQ,SMA   I238 @T6G_MB_LIB.T6G(SCH_1):PAGE97

M_A_CPU1_SB_DQS_DN<8> @T6G_MB_LIB.T6G(SCH_1):M_A_CPU1_SB_DQS_DN(8)
   U26 DC73 MAB_DQS_L8 GENOA_SP5-SOCKET6096_13568-001,SMLF,IO,DGA^6000030   I167 @T6G_MB_LIB.T6G(SCH_1):PAGE37
   J24  282 DQS8_B_C||TDQS8_B_C SCONN288_DDR506112002KQ-SCONN288_DDR506112002KQ,SMA   I238 @T6G_MB_LIB.T6G(SCH_1):PAGE97

M_A_CPU1_SB_DQS_DN<9> @T6G_MB_LIB.T6G(SCH_1):M_A_CPU1_SB_DQS_DN(9)
   U26 BW74 MAB_DQS_L9 GENOA_SP5-SOCKET6096_13568-001,SMLF,IO,DGA^6000030   I167 @T6G_MB_LIB.T6G(SCH_1):PAGE37
   J24   94 DQS9_B_C||TDQS9_B_C SCONN288_DDR506112002KQ-SCONN288_DDR506112002KQ,SMA   I238 @T6G_MB_LIB.T6G(SCH_1):PAGE97

M_A_CPU1_SB_DQS_DP<0> @T6G_MB_LIB.T6G(SCH_1):M_A_CPU1_SB_DQS_DP(0)
   U26 CD74 MAB_DQS_H0 GENOA_SP5-SOCKET6096_13568-001,SMLF,IO,DGA^6000030   I167 @T6G_MB_LIB.T6G(SCH_1):PAGE37
   J24  104 DQS0_B_T SCONN288_DDR506112002KQ-SCONN288_DDR506112002KQ,SMA   I238 @T6G_MB_LIB.T6G(SCH_1):PAGE97

M_A_CPU1_SB_DQS_DP<1> @T6G_MB_LIB.T6G(SCH_1):M_A_CPU1_SB_DQS_DP(1)
   U26 CK74 MAB_DQS_H1 GENOA_SP5-SOCKET6096_13568-001,SMLF,IO,DGA^6000030   I167 @T6G_MB_LIB.T6G(SCH_1):PAGE37
   J24  115 DQS1_B_T SCONN288_DDR506112002KQ-SCONN288_DDR506112002KQ,SMA   I238 @T6G_MB_LIB.T6G(SCH_1):PAGE97

M_A_CPU1_SB_DQS_DP<2> @T6G_MB_LIB.T6G(SCH_1):M_A_CPU1_SB_DQS_DP(2)
   U26 CT74 MAB_DQS_H2 GENOA_SP5-SOCKET6096_13568-001,SMLF,IO,DGA^6000030   I167 @T6G_MB_LIB.T6G(SCH_1):PAGE37
   J24  126 DQS2_B_T SCONN288_DDR506112002KQ-SCONN288_DDR506112002KQ,SMA   I238 @T6G_MB_LIB.T6G(SCH_1):PAGE97

M_A_CPU1_SB_DQS_DP<3> @T6G_MB_LIB.T6G(SCH_1):M_A_CPU1_SB_DQS_DP(3)
   U26 DB74 MAB_DQS_H3 GENOA_SP5-SOCKET6096_13568-001,SMLF,IO,DGA^6000030   I167 @T6G_MB_LIB.T6G(SCH_1):PAGE37
   J24  137 DQS3_B_T SCONN288_DDR506112002KQ-SCONN288_DDR506112002KQ,SMA   I238 @T6G_MB_LIB.T6G(SCH_1):PAGE97

M_A_CPU1_SB_DQS_DP<4> @T6G_MB_LIB.T6G(SCH_1):M_A_CPU1_SB_DQS_DP(4)
   U26 BY72 MAB_DQS_H4 GENOA_SP5-SOCKET6096_13568-001,SMLF,IO,DGA^6000030   I167 @T6G_MB_LIB.T6G(SCH_1):PAGE37
   J24  239 DQS4_B_T SCONN288_DDR506112002KQ-SCONN288_DDR506112002KQ,SMA   I238 @T6G_MB_LIB.T6G(SCH_1):PAGE97

M_A_CPU1_SB_DQS_DP<5> @T6G_MB_LIB.T6G(SCH_1):M_A_CPU1_SB_DQS_DP(5)
   U26 CF72 MAB_DQS_H5 GENOA_SP5-SOCKET6096_13568-001,SMLF,IO,DGA^6000030   I167 @T6G_MB_LIB.T6G(SCH_1):PAGE37
   J24  250 DQS5_B_T||TDQS5_B_T SCONN288_DDR506112002KQ-SCONN288_DDR506112002KQ,SMA   I238 @T6G_MB_LIB.T6G(SCH_1):PAGE97

M_A_CPU1_SB_DQS_DP<6> @T6G_MB_LIB.T6G(SCH_1):M_A_CPU1_SB_DQS_DP(6)
   U26 CM72 MAB_DQS_H6 GENOA_SP5-SOCKET6096_13568-001,SMLF,IO,DGA^6000030   I167 @T6G_MB_LIB.T6G(SCH_1):PAGE37
   J24  261 DQS6_B_T||TDQS6_B_T SCONN288_DDR506112002KQ-SCONN288_DDR506112002KQ,SMA   I238 @T6G_MB_LIB.T6G(SCH_1):PAGE97

M_A_CPU1_SB_DQS_DP<7> @T6G_MB_LIB.T6G(SCH_1):M_A_CPU1_SB_DQS_DP(7)
   U26 CV72 MAB_DQS_H7 GENOA_SP5-SOCKET6096_13568-001,SMLF,IO,DGA^6000030   I167 @T6G_MB_LIB.T6G(SCH_1):PAGE37
   J24  272 DQS7_B_T||TDQS7_B_T SCONN288_DDR506112002KQ-SCONN288_DDR506112002KQ,SMA   I238 @T6G_MB_LIB.T6G(SCH_1):PAGE97

M_A_CPU1_SB_DQS_DP<8> @T6G_MB_LIB.T6G(SCH_1):M_A_CPU1_SB_DQS_DP(8)
   U26 DD72 MAB_DQS_H8 GENOA_SP5-SOCKET6096_13568-001,SMLF,IO,DGA^6000030   I167 @T6G_MB_LIB.T6G(SCH_1):PAGE37
   J24  283 DQS8_B_T||TDQS8_B_T SCONN288_DDR506112002KQ-SCONN288_DDR506112002KQ,SMA   I238 @T6G_MB_LIB.T6G(SCH_1):PAGE97

M_A_CPU1_SB_DQS_DP<9> @T6G_MB_LIB.T6G(SCH_1):M_A_CPU1_SB_DQS_DP(9)
   U26 BV74 MAB_DQS_H9 GENOA_SP5-SOCKET6096_13568-001,SMLF,IO,DGA^6000030   I167 @T6G_MB_LIB.T6G(SCH_1):PAGE37
   J24   93 DQS9_B_T||TDQS9_B_T||DBI4_B_N SCONN288_DDR506112002KQ-SCONN288_DDR506112002KQ,SMA   I238 @T6G_MB_LIB.T6G(SCH_1):PAGE97

M_A_CPU1_SB_PAR @T6G_MB_LIB.T6G(SCH_1):M_A_CPU1_SB_PAR
   U26 BL74 MAB_PAR GENOA_SP5-SOCKET6096_13568-001,SMLF,IO,DGA^6000030   I167 @T6G_MB_LIB.T6G(SCH_1):PAGE37
   J24  227  PAR_B SCONN288_DDR506112002KQ-SCONN288_DDR506112002KQ,SMA    I22 @T6G_MB_LIB.T6G(SCH_1):PAGE97

M_A_CPU1_SB_RSP<0> @T6G_MB_LIB.T6G(SCH_1):M_A_CPU1_SB_RSP(0)
   U26 BP74 MAB0_RSP_L GENOA_SP5-SOCKET6096_13568-001,SMLF,IO,DGA^6000030   I167 @T6G_MB_LIB.T6G(SCH_1):PAGE37
   J24   87 LBS||RSP_B_N SCONN288_DDR506112002KQ-SCONN288_DDR506112002KQ,SMA    I22 @T6G_MB_LIB.T6G(SCH_1):PAGE97

M_B_CPU0_ALERT_N @T6G_MB_LIB.T6G(SCH_1):M_B_CPU0_ALERT_N
  R376    1      A Q_RES_0402LF-15,1%,1/16W,CHIP,CS01502FB03   I327 @T6G_MB_LIB.T6G(SCH_1):PAGE11
   J15   62 ALERT_N SCONN288_DDR506112002KQ-SCONN288_DDR506112002KQ,SMA   I350 @T6G_MB_LIB.T6G(SCH_1):PAGE86

M_B_CPU0_ALERT_R_N @T6G_MB_LIB.T6G(SCH_1):M_B_CPU0_ALERT_R_N
   U25 AT62 MB_ALERT_L GENOA_SP5-SOCKET6096_13568-001,SMLF,IO,DGA^6000030   I171 @T6G_MB_LIB.T6G(SCH_1):PAGE11
  R376    2      B Q_RES_0402LF-15,1%,1/16W,CHIP,CS01502FB03   I327 @T6G_MB_LIB.T6G(SCH_1):PAGE11

M_B_CPU0_CLK_DN<0> @T6G_MB_LIB.T6G(SCH_1):M_B_CPU0_CLK_DN(0)
   U25 BD63 MB0_CLK_L GENOA_SP5-SOCKET6096_13568-001,SMLF,IO,DGA^6000030   I171 @T6G_MB_LIB.T6G(SCH_1):PAGE11
   J15  218   CK_C SCONN288_DDR506112002KQ-SCONN288_DDR506112002KQ,SMA   I350 @T6G_MB_LIB.T6G(SCH_1):PAGE86

M_B_CPU0_CLK_DP<0> @T6G_MB_LIB.T6G(SCH_1):M_B_CPU0_CLK_DP(0)
   U25 BC64 MB0_CLK_H GENOA_SP5-SOCKET6096_13568-001,SMLF,IO,DGA^6000030   I171 @T6G_MB_LIB.T6G(SCH_1):PAGE11
   J15  217   CK_T SCONN288_DDR506112002KQ-SCONN288_DDR506112002KQ,SMA   I350 @T6G_MB_LIB.T6G(SCH_1):PAGE86

M_B_CPU0_RESET_N @T6G_MB_LIB.T6G(SCH_1):M_B_CPU0_RESET_N
   U25 AU62 MB_RESET_L GENOA_SP5-SOCKET6096_13568-001,SMLF,IO,DGA^6000030   I171 @T6G_MB_LIB.T6G(SCH_1):PAGE11
   J15  207 RESET_N SCONN288_DDR506112002KQ-SCONN288_DDR506112002KQ,SMA   I350 @T6G_MB_LIB.T6G(SCH_1):PAGE86

M_B_CPU0_SA_CA<0> @T6G_MB_LIB.T6G(SCH_1):M_B_CPU0_SA_CA(0)
   U25 AW64 MBA_CA0 GENOA_SP5-SOCKET6096_13568-001,SMLF,IO,DGA^6000030   I171 @T6G_MB_LIB.T6G(SCH_1):PAGE11
   J15   66  CA0_A SCONN288_DDR506112002KQ-SCONN288_DDR506112002KQ,SMA   I350 @T6G_MB_LIB.T6G(SCH_1):PAGE86

M_B_CPU0_SA_CA<1> @T6G_MB_LIB.T6G(SCH_1):M_B_CPU0_SA_CA(1)
   U25 AY63 MBA_CA1 GENOA_SP5-SOCKET6096_13568-001,SMLF,IO,DGA^6000030   I171 @T6G_MB_LIB.T6G(SCH_1):PAGE11
   J15  211  CA1_A SCONN288_DDR506112002KQ-SCONN288_DDR506112002KQ,SMA   I350 @T6G_MB_LIB.T6G(SCH_1):PAGE86

M_B_CPU0_SA_CA<2> @T6G_MB_LIB.T6G(SCH_1):M_B_CPU0_SA_CA(2)
   U25 AY62 MBA_CA2 GENOA_SP5-SOCKET6096_13568-001,SMLF,IO,DGA^6000030   I171 @T6G_MB_LIB.T6G(SCH_1):PAGE11
   J15   68  CA2_A SCONN288_DDR506112002KQ-SCONN288_DDR506112002KQ,SMA   I350 @T6G_MB_LIB.T6G(SCH_1):PAGE86

M_B_CPU0_SA_CA<3> @T6G_MB_LIB.T6G(SCH_1):M_B_CPU0_SA_CA(3)
   U25 BA62 MBA_CA3 GENOA_SP5-SOCKET6096_13568-001,SMLF,IO,DGA^6000030   I171 @T6G_MB_LIB.T6G(SCH_1):PAGE11
   J15  213  CA3_A SCONN288_DDR506112002KQ-SCONN288_DDR506112002KQ,SMA   I350 @T6G_MB_LIB.T6G(SCH_1):PAGE86

M_B_CPU0_SA_CA<4> @T6G_MB_LIB.T6G(SCH_1):M_B_CPU0_SA_CA(4)
   U25 BA64 MBA_CA4 GENOA_SP5-SOCKET6096_13568-001,SMLF,IO,DGA^6000030   I171 @T6G_MB_LIB.T6G(SCH_1):PAGE11
   J15   70  CA4_A SCONN288_DDR506112002KQ-SCONN288_DDR506112002KQ,SMA   I350 @T6G_MB_LIB.T6G(SCH_1):PAGE86

M_B_CPU0_SA_CA<5> @T6G_MB_LIB.T6G(SCH_1):M_B_CPU0_SA_CA(5)
   U25 BB63 MBA_CA5 GENOA_SP5-SOCKET6096_13568-001,SMLF,IO,DGA^6000030   I171 @T6G_MB_LIB.T6G(SCH_1):PAGE11
   J15  215  CA5_A SCONN288_DDR506112002KQ-SCONN288_DDR506112002KQ,SMA   I350 @T6G_MB_LIB.T6G(SCH_1):PAGE86

M_B_CPU0_SA_CA<6> @T6G_MB_LIB.T6G(SCH_1):M_B_CPU0_SA_CA(6)
   U25 BB62 MBA_CA6 GENOA_SP5-SOCKET6096_13568-001,SMLF,IO,DGA^6000030   I171 @T6G_MB_LIB.T6G(SCH_1):PAGE11
   J15   72  CA6_A SCONN288_DDR506112002KQ-SCONN288_DDR506112002KQ,SMA   I350 @T6G_MB_LIB.T6G(SCH_1):PAGE86

M_B_CPU0_SA_CB<0> @T6G_MB_LIB.T6G(SCH_1):M_B_CPU0_SA_CB(0)
   U25 AJ64 MBA_CHECK0 GENOA_SP5-SOCKET6096_13568-001,SMLF,IO,DGA^6000030   I171 @T6G_MB_LIB.T6G(SCH_1):PAGE11
   J15   51  CB0_A SCONN288_DDR506112002KQ-SCONN288_DDR506112002KQ,SMA   I350 @T6G_MB_LIB.T6G(SCH_1):PAGE86

M_B_CPU0_SA_CB<1> @T6G_MB_LIB.T6G(SCH_1):M_B_CPU0_SA_CB(1)
   U25 AK62 MBA_CHECK1 GENOA_SP5-SOCKET6096_13568-001,SMLF,IO,DGA^6000030   I171 @T6G_MB_LIB.T6G(SCH_1):PAGE11
   J15   53  CB1_A SCONN288_DDR506112002KQ-SCONN288_DDR506112002KQ,SMA   I350 @T6G_MB_LIB.T6G(SCH_1):PAGE86

M_B_CPU0_SA_CB<2> @T6G_MB_LIB.T6G(SCH_1):M_B_CPU0_SA_CB(2)
   U25 AK63 MBA_CHECK2 GENOA_SP5-SOCKET6096_13568-001,SMLF,IO,DGA^6000030   I171 @T6G_MB_LIB.T6G(SCH_1):PAGE11
   J15  196  CB2_A SCONN288_DDR506112002KQ-SCONN288_DDR506112002KQ,SMA   I350 @T6G_MB_LIB.T6G(SCH_1):PAGE86

M_B_CPU0_SA_CB<3> @T6G_MB_LIB.T6G(SCH_1):M_B_CPU0_SA_CB(3)
   U25 AL62 MBA_CHECK3 GENOA_SP5-SOCKET6096_13568-001,SMLF,IO,DGA^6000030   I171 @T6G_MB_LIB.T6G(SCH_1):PAGE11
   J15  198  CB3_A SCONN288_DDR506112002KQ-SCONN288_DDR506112002KQ,SMA   I350 @T6G_MB_LIB.T6G(SCH_1):PAGE86

M_B_CPU0_SA_CB<4> @T6G_MB_LIB.T6G(SCH_1):M_B_CPU0_SA_CB(4)
   U25 AN64 MBA_CHECK4 GENOA_SP5-SOCKET6096_13568-001,SMLF,IO,DGA^6000030   I171 @T6G_MB_LIB.T6G(SCH_1):PAGE11
   J15   58  CB4_A SCONN288_DDR506112002KQ-SCONN288_DDR506112002KQ,SMA   I350 @T6G_MB_LIB.T6G(SCH_1):PAGE86

M_B_CPU0_SA_CB<5> @T6G_MB_LIB.T6G(SCH_1):M_B_CPU0_SA_CB(5)
   U25 AP62 MBA_CHECK5 GENOA_SP5-SOCKET6096_13568-001,SMLF,IO,DGA^6000030   I171 @T6G_MB_LIB.T6G(SCH_1):PAGE11
   J15   60  CB5_A SCONN288_DDR506112002KQ-SCONN288_DDR506112002KQ,SMA   I350 @T6G_MB_LIB.T6G(SCH_1):PAGE86

M_B_CPU0_SA_CB<6> @T6G_MB_LIB.T6G(SCH_1):M_B_CPU0_SA_CB(6)
   U25 AP63 MBA_CHECK6 GENOA_SP5-SOCKET6096_13568-001,SMLF,IO,DGA^6000030   I171 @T6G_MB_LIB.T6G(SCH_1):PAGE11
   J15  203  CB6_A SCONN288_DDR506112002KQ-SCONN288_DDR506112002KQ,SMA   I350 @T6G_MB_LIB.T6G(SCH_1):PAGE86

M_B_CPU0_SA_CB<7> @T6G_MB_LIB.T6G(SCH_1):M_B_CPU0_SA_CB(7)
   U25 AR62 MBA_CHECK7 GENOA_SP5-SOCKET6096_13568-001,SMLF,IO,DGA^6000030   I171 @T6G_MB_LIB.T6G(SCH_1):PAGE11
   J15  205  CB7_A SCONN288_DDR506112002KQ-SCONN288_DDR506112002KQ,SMA   I350 @T6G_MB_LIB.T6G(SCH_1):PAGE86

M_B_CPU0_SA_CS_N<0> @T6G_MB_LIB.T6G(SCH_1):M_B_CPU0_SA_CS_N(0)
   U25 AV63 MBA0_CS_L0 GENOA_SP5-SOCKET6096_13568-001,SMLF,IO,DGA^6000030   I171 @T6G_MB_LIB.T6G(SCH_1):PAGE11
   J15   64 CS0_A_N SCONN288_DDR506112002KQ-SCONN288_DDR506112002KQ,SMA   I350 @T6G_MB_LIB.T6G(SCH_1):PAGE86

M_B_CPU0_SA_CS_N<1> @T6G_MB_LIB.T6G(SCH_1):M_B_CPU0_SA_CS_N(1)
   U25 AW62 MBA0_CS_L1 GENOA_SP5-SOCKET6096_13568-001,SMLF,IO,DGA^6000030   I171 @T6G_MB_LIB.T6G(SCH_1):PAGE11
   J15  209 CS1_A_N SCONN288_DDR506112002KQ-SCONN288_DDR506112002KQ,SMA   I350 @T6G_MB_LIB.T6G(SCH_1):PAGE86

M_B_CPU0_SA_DQ<0> @T6G_MB_LIB.T6G(SCH_1):M_B_CPU0_SA_DQ(0)
   U25  E64 MBA_DATA0 GENOA_SP5-SOCKET6096_13568-001,SMLF,IO,DGA^6000030   I171 @T6G_MB_LIB.T6G(SCH_1):PAGE11
   J15    7  DQ0_A SCONN288_DDR506112002KQ-SCONN288_DDR506112002KQ,SMA   I350 @T6G_MB_LIB.T6G(SCH_1):PAGE86

M_B_CPU0_SA_DQ<10> @T6G_MB_LIB.T6G(SCH_1):M_B_CPU0_SA_DQ(10)
   U25  M63 MBA_DATA10 GENOA_SP5-SOCKET6096_13568-001,SMLF,IO,DGA^6000030   I171 @T6G_MB_LIB.T6G(SCH_1):PAGE11
   J15  163 DQ10_A SCONN288_DDR506112002KQ-SCONN288_DDR506112002KQ,SMA   I350 @T6G_MB_LIB.T6G(SCH_1):PAGE86

M_B_CPU0_SA_DQ<11> @T6G_MB_LIB.T6G(SCH_1):M_B_CPU0_SA_DQ(11)
   U25  N62 MBA_DATA11 GENOA_SP5-SOCKET6096_13568-001,SMLF,IO,DGA^6000030   I171 @T6G_MB_LIB.T6G(SCH_1):PAGE11
   J15  165 DQ11_A SCONN288_DDR506112002KQ-SCONN288_DDR506112002KQ,SMA   I350 @T6G_MB_LIB.T6G(SCH_1):PAGE86

M_B_CPU0_SA_DQ<12> @T6G_MB_LIB.T6G(SCH_1):M_B_CPU0_SA_DQ(12)
   U25  R64 MBA_DATA12 GENOA_SP5-SOCKET6096_13568-001,SMLF,IO,DGA^6000030   I171 @T6G_MB_LIB.T6G(SCH_1):PAGE11
   J15   25 DQ12_A SCONN288_DDR506112002KQ-SCONN288_DDR506112002KQ,SMA   I350 @T6G_MB_LIB.T6G(SCH_1):PAGE86

M_B_CPU0_SA_DQ<13> @T6G_MB_LIB.T6G(SCH_1):M_B_CPU0_SA_DQ(13)
   U25  T62 MBA_DATA13 GENOA_SP5-SOCKET6096_13568-001,SMLF,IO,DGA^6000030   I171 @T6G_MB_LIB.T6G(SCH_1):PAGE11
   J15   27 DQ13_A SCONN288_DDR506112002KQ-SCONN288_DDR506112002KQ,SMA   I350 @T6G_MB_LIB.T6G(SCH_1):PAGE86

M_B_CPU0_SA_DQ<14> @T6G_MB_LIB.T6G(SCH_1):M_B_CPU0_SA_DQ(14)
   U25  T63 MBA_DATA14 GENOA_SP5-SOCKET6096_13568-001,SMLF,IO,DGA^6000030   I171 @T6G_MB_LIB.T6G(SCH_1):PAGE11
   J15  170 DQ14_A SCONN288_DDR506112002KQ-SCONN288_DDR506112002KQ,SMA   I350 @T6G_MB_LIB.T6G(SCH_1):PAGE86

M_B_CPU0_SA_DQ<15> @T6G_MB_LIB.T6G(SCH_1):M_B_CPU0_SA_DQ(15)
   U25  U62 MBA_DATA15 GENOA_SP5-SOCKET6096_13568-001,SMLF,IO,DGA^6000030   I171 @T6G_MB_LIB.T6G(SCH_1):PAGE11
   J15  172 DQ15_A SCONN288_DDR506112002KQ-SCONN288_DDR506112002KQ,SMA   I350 @T6G_MB_LIB.T6G(SCH_1):PAGE86

M_B_CPU0_SA_DQ<16> @T6G_MB_LIB.T6G(SCH_1):M_B_CPU0_SA_DQ(16)
   U25  U64 MBA_DATA16 GENOA_SP5-SOCKET6096_13568-001,SMLF,IO,DGA^6000030   I171 @T6G_MB_LIB.T6G(SCH_1):PAGE11
   J15   29 DQ16_A SCONN288_DDR506112002KQ-SCONN288_DDR506112002KQ,SMA   I350 @T6G_MB_LIB.T6G(SCH_1):PAGE86

M_B_CPU0_SA_DQ<17> @T6G_MB_LIB.T6G(SCH_1):M_B_CPU0_SA_DQ(17)
   U25  V62 MBA_DATA17 GENOA_SP5-SOCKET6096_13568-001,SMLF,IO,DGA^6000030   I171 @T6G_MB_LIB.T6G(SCH_1):PAGE11
   J15   31 DQ17_A SCONN288_DDR506112002KQ-SCONN288_DDR506112002KQ,SMA   I350 @T6G_MB_LIB.T6G(SCH_1):PAGE86

M_B_CPU0_SA_DQ<18> @T6G_MB_LIB.T6G(SCH_1):M_B_CPU0_SA_DQ(18)
   U25  V63 MBA_DATA18 GENOA_SP5-SOCKET6096_13568-001,SMLF,IO,DGA^6000030   I171 @T6G_MB_LIB.T6G(SCH_1):PAGE11
   J15  174 DQ18_A SCONN288_DDR506112002KQ-SCONN288_DDR506112002KQ,SMA   I350 @T6G_MB_LIB.T6G(SCH_1):PAGE86

M_B_CPU0_SA_DQ<19> @T6G_MB_LIB.T6G(SCH_1):M_B_CPU0_SA_DQ(19)
   U25  W62 MBA_DATA19 GENOA_SP5-SOCKET6096_13568-001,SMLF,IO,DGA^6000030   I171 @T6G_MB_LIB.T6G(SCH_1):PAGE11
   J15  176 DQ19_A SCONN288_DDR506112002KQ-SCONN288_DDR506112002KQ,SMA   I350 @T6G_MB_LIB.T6G(SCH_1):PAGE86

M_B_CPU0_SA_DQ<1> @T6G_MB_LIB.T6G(SCH_1):M_B_CPU0_SA_DQ(1)
   U25  F62 MBA_DATA1 GENOA_SP5-SOCKET6096_13568-001,SMLF,IO,DGA^6000030   I171 @T6G_MB_LIB.T6G(SCH_1):PAGE11
   J15    9  DQ1_A SCONN288_DDR506112002KQ-SCONN288_DDR506112002KQ,SMA   I350 @T6G_MB_LIB.T6G(SCH_1):PAGE86

M_B_CPU0_SA_DQ<20> @T6G_MB_LIB.T6G(SCH_1):M_B_CPU0_SA_DQ(20)
   U25 AA64 MBA_DATA20 GENOA_SP5-SOCKET6096_13568-001,SMLF,IO,DGA^6000030   I171 @T6G_MB_LIB.T6G(SCH_1):PAGE11
   J15   36 DQ20_A SCONN288_DDR506112002KQ-SCONN288_DDR506112002KQ,SMA   I350 @T6G_MB_LIB.T6G(SCH_1):PAGE86

M_B_CPU0_SA_DQ<21> @T6G_MB_LIB.T6G(SCH_1):M_B_CPU0_SA_DQ(21)
   U25 AB62 MBA_DATA21 GENOA_SP5-SOCKET6096_13568-001,SMLF,IO,DGA^6000030   I171 @T6G_MB_LIB.T6G(SCH_1):PAGE11
   J15   38 DQ21_A SCONN288_DDR506112002KQ-SCONN288_DDR506112002KQ,SMA   I350 @T6G_MB_LIB.T6G(SCH_1):PAGE86

M_B_CPU0_SA_DQ<22> @T6G_MB_LIB.T6G(SCH_1):M_B_CPU0_SA_DQ(22)
   U25 AB63 MBA_DATA22 GENOA_SP5-SOCKET6096_13568-001,SMLF,IO,DGA^6000030   I171 @T6G_MB_LIB.T6G(SCH_1):PAGE11
   J15  181 DQ22_A SCONN288_DDR506112002KQ-SCONN288_DDR506112002KQ,SMA   I350 @T6G_MB_LIB.T6G(SCH_1):PAGE86

M_B_CPU0_SA_DQ<23> @T6G_MB_LIB.T6G(SCH_1):M_B_CPU0_SA_DQ(23)
   U25 AC62 MBA_DATA23 GENOA_SP5-SOCKET6096_13568-001,SMLF,IO,DGA^6000030   I171 @T6G_MB_LIB.T6G(SCH_1):PAGE11
   J15  183 DQ23_A SCONN288_DDR506112002KQ-SCONN288_DDR506112002KQ,SMA   I350 @T6G_MB_LIB.T6G(SCH_1):PAGE86

M_B_CPU0_SA_DQ<24> @T6G_MB_LIB.T6G(SCH_1):M_B_CPU0_SA_DQ(24)
   U25 AC64 MBA_DATA24 GENOA_SP5-SOCKET6096_13568-001,SMLF,IO,DGA^6000030   I171 @T6G_MB_LIB.T6G(SCH_1):PAGE11
   J15   40 DQ24_A SCONN288_DDR506112002KQ-SCONN288_DDR506112002KQ,SMA   I350 @T6G_MB_LIB.T6G(SCH_1):PAGE86

M_B_CPU0_SA_DQ<25> @T6G_MB_LIB.T6G(SCH_1):M_B_CPU0_SA_DQ(25)
   U25 AD62 MBA_DATA25 GENOA_SP5-SOCKET6096_13568-001,SMLF,IO,DGA^6000030   I171 @T6G_MB_LIB.T6G(SCH_1):PAGE11
   J15   42 DQ25_A SCONN288_DDR506112002KQ-SCONN288_DDR506112002KQ,SMA   I350 @T6G_MB_LIB.T6G(SCH_1):PAGE86

M_B_CPU0_SA_DQ<26> @T6G_MB_LIB.T6G(SCH_1):M_B_CPU0_SA_DQ(26)
   U25 AD63 MBA_DATA26 GENOA_SP5-SOCKET6096_13568-001,SMLF,IO,DGA^6000030   I171 @T6G_MB_LIB.T6G(SCH_1):PAGE11
   J15  185 DQ26_A SCONN288_DDR506112002KQ-SCONN288_DDR506112002KQ,SMA   I350 @T6G_MB_LIB.T6G(SCH_1):PAGE86

M_B_CPU0_SA_DQ<27> @T6G_MB_LIB.T6G(SCH_1):M_B_CPU0_SA_DQ(27)
   U25 AE62 MBA_DATA27 GENOA_SP5-SOCKET6096_13568-001,SMLF,IO,DGA^6000030   I171 @T6G_MB_LIB.T6G(SCH_1):PAGE11
   J15  187 DQ27_A SCONN288_DDR506112002KQ-SCONN288_DDR506112002KQ,SMA   I350 @T6G_MB_LIB.T6G(SCH_1):PAGE86

M_B_CPU0_SA_DQ<28> @T6G_MB_LIB.T6G(SCH_1):M_B_CPU0_SA_DQ(28)
   U25 AG64 MBA_DATA28 GENOA_SP5-SOCKET6096_13568-001,SMLF,IO,DGA^6000030   I171 @T6G_MB_LIB.T6G(SCH_1):PAGE11
   J15   47 DQ28_A SCONN288_DDR506112002KQ-SCONN288_DDR506112002KQ,SMA   I350 @T6G_MB_LIB.T6G(SCH_1):PAGE86

M_B_CPU0_SA_DQ<29> @T6G_MB_LIB.T6G(SCH_1):M_B_CPU0_SA_DQ(29)
   U25 AH62 MBA_DATA29 GENOA_SP5-SOCKET6096_13568-001,SMLF,IO,DGA^6000030   I171 @T6G_MB_LIB.T6G(SCH_1):PAGE11
   J15   49 DQ29_A SCONN288_DDR506112002KQ-SCONN288_DDR506112002KQ,SMA   I350 @T6G_MB_LIB.T6G(SCH_1):PAGE86

M_B_CPU0_SA_DQ<2> @T6G_MB_LIB.T6G(SCH_1):M_B_CPU0_SA_DQ(2)
   U25  F63 MBA_DATA2 GENOA_SP5-SOCKET6096_13568-001,SMLF,IO,DGA^6000030   I171 @T6G_MB_LIB.T6G(SCH_1):PAGE11
   J15  152  DQ2_A SCONN288_DDR506112002KQ-SCONN288_DDR506112002KQ,SMA   I350 @T6G_MB_LIB.T6G(SCH_1):PAGE86

M_B_CPU0_SA_DQ<30> @T6G_MB_LIB.T6G(SCH_1):M_B_CPU0_SA_DQ(30)
   U25 AH63 MBA_DATA30 GENOA_SP5-SOCKET6096_13568-001,SMLF,IO,DGA^6000030   I171 @T6G_MB_LIB.T6G(SCH_1):PAGE11
   J15  192 DQ30_A SCONN288_DDR506112002KQ-SCONN288_DDR506112002KQ,SMA   I350 @T6G_MB_LIB.T6G(SCH_1):PAGE86

M_B_CPU0_SA_DQ<31> @T6G_MB_LIB.T6G(SCH_1):M_B_CPU0_SA_DQ(31)
   U25 AJ62 MBA_DATA31 GENOA_SP5-SOCKET6096_13568-001,SMLF,IO,DGA^6000030   I171 @T6G_MB_LIB.T6G(SCH_1):PAGE11
   J15  194 DQ31_A SCONN288_DDR506112002KQ-SCONN288_DDR506112002KQ,SMA   I350 @T6G_MB_LIB.T6G(SCH_1):PAGE86

M_B_CPU0_SA_DQ<3> @T6G_MB_LIB.T6G(SCH_1):M_B_CPU0_SA_DQ(3)
   U25  G62 MBA_DATA3 GENOA_SP5-SOCKET6096_13568-001,SMLF,IO,DGA^6000030   I171 @T6G_MB_LIB.T6G(SCH_1):PAGE11
   J15  154  DQ3_A SCONN288_DDR506112002KQ-SCONN288_DDR506112002KQ,SMA   I350 @T6G_MB_LIB.T6G(SCH_1):PAGE86

M_B_CPU0_SA_DQ<4> @T6G_MB_LIB.T6G(SCH_1):M_B_CPU0_SA_DQ(4)
   U25  J64 MBA_DATA4 GENOA_SP5-SOCKET6096_13568-001,SMLF,IO,DGA^6000030   I171 @T6G_MB_LIB.T6G(SCH_1):PAGE11
   J15   14  DQ4_A SCONN288_DDR506112002KQ-SCONN288_DDR506112002KQ,SMA   I350 @T6G_MB_LIB.T6G(SCH_1):PAGE86

M_B_CPU0_SA_DQ<5> @T6G_MB_LIB.T6G(SCH_1):M_B_CPU0_SA_DQ(5)
   U25  K62 MBA_DATA5 GENOA_SP5-SOCKET6096_13568-001,SMLF,IO,DGA^6000030   I171 @T6G_MB_LIB.T6G(SCH_1):PAGE11
   J15   16  DQ5_A SCONN288_DDR506112002KQ-SCONN288_DDR506112002KQ,SMA   I350 @T6G_MB_LIB.T6G(SCH_1):PAGE86

M_B_CPU0_SA_DQ<6> @T6G_MB_LIB.T6G(SCH_1):M_B_CPU0_SA_DQ(6)
   U25  K63 MBA_DATA6 GENOA_SP5-SOCKET6096_13568-001,SMLF,IO,DGA^6000030   I171 @T6G_MB_LIB.T6G(SCH_1):PAGE11
   J15  159  DQ6_A SCONN288_DDR506112002KQ-SCONN288_DDR506112002KQ,SMA   I350 @T6G_MB_LIB.T6G(SCH_1):PAGE86

M_B_CPU0_SA_DQ<7> @T6G_MB_LIB.T6G(SCH_1):M_B_CPU0_SA_DQ(7)
   U25  L62 MBA_DATA7 GENOA_SP5-SOCKET6096_13568-001,SMLF,IO,DGA^6000030   I171 @T6G_MB_LIB.T6G(SCH_1):PAGE11
   J15  161  DQ7_A SCONN288_DDR506112002KQ-SCONN288_DDR506112002KQ,SMA   I350 @T6G_MB_LIB.T6G(SCH_1):PAGE86

M_B_CPU0_SA_DQ<8> @T6G_MB_LIB.T6G(SCH_1):M_B_CPU0_SA_DQ(8)
   U25  L64 MBA_DATA8 GENOA_SP5-SOCKET6096_13568-001,SMLF,IO,DGA^6000030   I171 @T6G_MB_LIB.T6G(SCH_1):PAGE11
   J15   18  DQ8_A SCONN288_DDR506112002KQ-SCONN288_DDR506112002KQ,SMA   I350 @T6G_MB_LIB.T6G(SCH_1):PAGE86

M_B_CPU0_SA_DQ<9> @T6G_MB_LIB.T6G(SCH_1):M_B_CPU0_SA_DQ(9)
   U25  M62 MBA_DATA9 GENOA_SP5-SOCKET6096_13568-001,SMLF,IO,DGA^6000030   I171 @T6G_MB_LIB.T6G(SCH_1):PAGE11
   J15   20  DQ9_A SCONN288_DDR506112002KQ-SCONN288_DDR506112002KQ,SMA   I350 @T6G_MB_LIB.T6G(SCH_1):PAGE86

M_B_CPU0_SA_DQS_DN<0> @T6G_MB_LIB.T6G(SCH_1):M_B_CPU0_SA_DQS_DN(0)
   U25  H63 MBA_DQS_L0 GENOA_SP5-SOCKET6096_13568-001,SMLF,IO,DGA^6000030   I171 @T6G_MB_LIB.T6G(SCH_1):PAGE11
   J15   12 DQS0_A_C SCONN288_DDR506112002KQ-SCONN288_DDR506112002KQ,SMA   I367 @T6G_MB_LIB.T6G(SCH_1):PAGE86

M_B_CPU0_SA_DQS_DN<1> @T6G_MB_LIB.T6G(SCH_1):M_B_CPU0_SA_DQS_DN(1)
   U25  P63 MBA_DQS_L1 GENOA_SP5-SOCKET6096_13568-001,SMLF,IO,DGA^6000030   I171 @T6G_MB_LIB.T6G(SCH_1):PAGE11
   J15   23 DQS1_A_C SCONN288_DDR506112002KQ-SCONN288_DDR506112002KQ,SMA   I367 @T6G_MB_LIB.T6G(SCH_1):PAGE86

M_B_CPU0_SA_DQS_DN<2> @T6G_MB_LIB.T6G(SCH_1):M_B_CPU0_SA_DQS_DN(2)
   U25  Y63 MBA_DQS_L2 GENOA_SP5-SOCKET6096_13568-001,SMLF,IO,DGA^6000030   I171 @T6G_MB_LIB.T6G(SCH_1):PAGE11
   J15   34 DQS2_A_C SCONN288_DDR506112002KQ-SCONN288_DDR506112002KQ,SMA   I367 @T6G_MB_LIB.T6G(SCH_1):PAGE86

M_B_CPU0_SA_DQS_DN<3> @T6G_MB_LIB.T6G(SCH_1):M_B_CPU0_SA_DQS_DN(3)
   U25 AF63 MBA_DQS_L3 GENOA_SP5-SOCKET6096_13568-001,SMLF,IO,DGA^6000030   I171 @T6G_MB_LIB.T6G(SCH_1):PAGE11
   J15   45 DQS3_A_C SCONN288_DDR506112002KQ-SCONN288_DDR506112002KQ,SMA   I367 @T6G_MB_LIB.T6G(SCH_1):PAGE86

M_B_CPU0_SA_DQS_DN<4> @T6G_MB_LIB.T6G(SCH_1):M_B_CPU0_SA_DQS_DN(4)
   U25 AM63 MBA_DQS_L4 GENOA_SP5-SOCKET6096_13568-001,SMLF,IO,DGA^6000030   I171 @T6G_MB_LIB.T6G(SCH_1):PAGE11
   J15   56 DQS4_A_C SCONN288_DDR506112002KQ-SCONN288_DDR506112002KQ,SMA   I367 @T6G_MB_LIB.T6G(SCH_1):PAGE86

M_B_CPU0_SA_DQS_DN<5> @T6G_MB_LIB.T6G(SCH_1):M_B_CPU0_SA_DQS_DN(5)
   U25  H62 MBA_DQS_L5 GENOA_SP5-SOCKET6096_13568-001,SMLF,IO,DGA^6000030   I171 @T6G_MB_LIB.T6G(SCH_1):PAGE11
   J15  156 DQS5_A_C||TDQS5_A_C||DQS5_A_T||TDQS5_A_T SCONN288_DDR506112002KQ-SCONN288_DDR506112002KQ,SMA   I367 @T6G_MB_LIB.T6G(SCH_1):PAGE86

M_B_CPU0_SA_DQS_DN<6> @T6G_MB_LIB.T6G(SCH_1):M_B_CPU0_SA_DQS_DN(6)
   U25  P62 MBA_DQS_L6 GENOA_SP5-SOCKET6096_13568-001,SMLF,IO,DGA^6000030   I171 @T6G_MB_LIB.T6G(SCH_1):PAGE11
   J15  167 DQS6_A_C||TDQS6_A_C||DQS6_A_T||TDQS6_A_T SCONN288_DDR506112002KQ-SCONN288_DDR506112002KQ,SMA   I367 @T6G_MB_LIB.T6G(SCH_1):PAGE86

M_B_CPU0_SA_DQS_DN<7> @T6G_MB_LIB.T6G(SCH_1):M_B_CPU0_SA_DQS_DN(7)
   U25  Y62 MBA_DQS_L7 GENOA_SP5-SOCKET6096_13568-001,SMLF,IO,DGA^6000030   I171 @T6G_MB_LIB.T6G(SCH_1):PAGE11
   J15  178 DQS7_A_C||TDQS7_A_C SCONN288_DDR506112002KQ-SCONN288_DDR506112002KQ,SMA   I367 @T6G_MB_LIB.T6G(SCH_1):PAGE86

M_B_CPU0_SA_DQS_DN<8> @T6G_MB_LIB.T6G(SCH_1):M_B_CPU0_SA_DQS_DN(8)
   U25 AF62 MBA_DQS_L8 GENOA_SP5-SOCKET6096_13568-001,SMLF,IO,DGA^6000030   I171 @T6G_MB_LIB.T6G(SCH_1):PAGE11
   J15  189 DQS8_A_C||TDQS8_A_C SCONN288_DDR506112002KQ-SCONN288_DDR506112002KQ,SMA   I367 @T6G_MB_LIB.T6G(SCH_1):PAGE86

M_B_CPU0_SA_DQS_DN<9> @T6G_MB_LIB.T6G(SCH_1):M_B_CPU0_SA_DQS_DN(9)
   U25 AM62 MBA_DQS_L9 GENOA_SP5-SOCKET6096_13568-001,SMLF,IO,DGA^6000030   I171 @T6G_MB_LIB.T6G(SCH_1):PAGE11
   J15  200 DQS9_A_C||TDQS9_A_C SCONN288_DDR506112002KQ-SCONN288_DDR506112002KQ,SMA   I367 @T6G_MB_LIB.T6G(SCH_1):PAGE86

M_B_CPU0_SA_DQS_DP<0> @T6G_MB_LIB.T6G(SCH_1):M_B_CPU0_SA_DQS_DP(0)
   U25  G64 MBA_DQS_H0 GENOA_SP5-SOCKET6096_13568-001,SMLF,IO,DGA^6000030   I171 @T6G_MB_LIB.T6G(SCH_1):PAGE11
   J15   11 DQS0_A_T SCONN288_DDR506112002KQ-SCONN288_DDR506112002KQ,SMA   I367 @T6G_MB_LIB.T6G(SCH_1):PAGE86

M_B_CPU0_SA_DQS_DP<1> @T6G_MB_LIB.T6G(SCH_1):M_B_CPU0_SA_DQS_DP(1)
   U25  N64 MBA_DQS_H1 GENOA_SP5-SOCKET6096_13568-001,SMLF,IO,DGA^6000030   I171 @T6G_MB_LIB.T6G(SCH_1):PAGE11
   J15   22 DQS1_A_T SCONN288_DDR506112002KQ-SCONN288_DDR506112002KQ,SMA   I367 @T6G_MB_LIB.T6G(SCH_1):PAGE86

M_B_CPU0_SA_DQS_DP<2> @T6G_MB_LIB.T6G(SCH_1):M_B_CPU0_SA_DQS_DP(2)
   U25  W64 MBA_DQS_H2 GENOA_SP5-SOCKET6096_13568-001,SMLF,IO,DGA^6000030   I171 @T6G_MB_LIB.T6G(SCH_1):PAGE11
   J15   33 DQS2_A_T SCONN288_DDR506112002KQ-SCONN288_DDR506112002KQ,SMA   I367 @T6G_MB_LIB.T6G(SCH_1):PAGE86

M_B_CPU0_SA_DQS_DP<3> @T6G_MB_LIB.T6G(SCH_1):M_B_CPU0_SA_DQS_DP(3)
   U25 AE64 MBA_DQS_H3 GENOA_SP5-SOCKET6096_13568-001,SMLF,IO,DGA^6000030   I171 @T6G_MB_LIB.T6G(SCH_1):PAGE11
   J15   44 DQS3_A_T SCONN288_DDR506112002KQ-SCONN288_DDR506112002KQ,SMA   I367 @T6G_MB_LIB.T6G(SCH_1):PAGE86

M_B_CPU0_SA_DQS_DP<4> @T6G_MB_LIB.T6G(SCH_1):M_B_CPU0_SA_DQS_DP(4)
   U25 AL64 MBA_DQS_H4 GENOA_SP5-SOCKET6096_13568-001,SMLF,IO,DGA^6000030   I171 @T6G_MB_LIB.T6G(SCH_1):PAGE11
   J15   55 DQS4_A_T SCONN288_DDR506112002KQ-SCONN288_DDR506112002KQ,SMA   I367 @T6G_MB_LIB.T6G(SCH_1):PAGE86

M_B_CPU0_SA_DQS_DP<5> @T6G_MB_LIB.T6G(SCH_1):M_B_CPU0_SA_DQS_DP(5)
   U25  J62 MBA_DQS_H5 GENOA_SP5-SOCKET6096_13568-001,SMLF,IO,DGA^6000030   I171 @T6G_MB_LIB.T6G(SCH_1):PAGE11
   J15  157 DQS5_A_T||TDQS5_A_T SCONN288_DDR506112002KQ-SCONN288_DDR506112002KQ,SMA   I367 @T6G_MB_LIB.T6G(SCH_1):PAGE86

M_B_CPU0_SA_DQS_DP<6> @T6G_MB_LIB.T6G(SCH_1):M_B_CPU0_SA_DQS_DP(6)
   U25  R62 MBA_DQS_H6 GENOA_SP5-SOCKET6096_13568-001,SMLF,IO,DGA^6000030   I171 @T6G_MB_LIB.T6G(SCH_1):PAGE11
   J15  168 DQS6_A_T||TDQS6_A_T SCONN288_DDR506112002KQ-SCONN288_DDR506112002KQ,SMA   I367 @T6G_MB_LIB.T6G(SCH_1):PAGE86

M_B_CPU0_SA_DQS_DP<7> @T6G_MB_LIB.T6G(SCH_1):M_B_CPU0_SA_DQS_DP(7)
   U25 AA62 MBA_DQS_H7 GENOA_SP5-SOCKET6096_13568-001,SMLF,IO,DGA^6000030   I171 @T6G_MB_LIB.T6G(SCH_1):PAGE11
   J15  179 DQS7_A_T||TDQS7_A_T SCONN288_DDR506112002KQ-SCONN288_DDR506112002KQ,SMA   I367 @T6G_MB_LIB.T6G(SCH_1):PAGE86

M_B_CPU0_SA_DQS_DP<8> @T6G_MB_LIB.T6G(SCH_1):M_B_CPU0_SA_DQS_DP(8)
   U25 AG62 MBA_DQS_H8 GENOA_SP5-SOCKET6096_13568-001,SMLF,IO,DGA^6000030   I171 @T6G_MB_LIB.T6G(SCH_1):PAGE11
   J15  190 DQS8_A_T||TDQS8_A_T SCONN288_DDR506112002KQ-SCONN288_DDR506112002KQ,SMA   I367 @T6G_MB_LIB.T6G(SCH_1):PAGE86

M_B_CPU0_SA_DQS_DP<9> @T6G_MB_LIB.T6G(SCH_1):M_B_CPU0_SA_DQS_DP(9)
   U25 AN62 MBA_DQS_H9 GENOA_SP5-SOCKET6096_13568-001,SMLF,IO,DGA^6000030   I171 @T6G_MB_LIB.T6G(SCH_1):PAGE11
   J15  201 DQS9_A_T||TDQS9_A_T SCONN288_DDR506112002KQ-SCONN288_DDR506112002KQ,SMA   I367 @T6G_MB_LIB.T6G(SCH_1):PAGE86

M_B_CPU0_SA_PAR @T6G_MB_LIB.T6G(SCH_1):M_B_CPU0_SA_PAR
   U25 BC62 MBA_PAR GENOA_SP5-SOCKET6096_13568-001,SMLF,IO,DGA^6000030   I171 @T6G_MB_LIB.T6G(SCH_1):PAGE11
   J15   74  PAR_A SCONN288_DDR506112002KQ-SCONN288_DDR506112002KQ,SMA   I350 @T6G_MB_LIB.T6G(SCH_1):PAGE86

M_B_CPU0_SA_RSP<0> @T6G_MB_LIB.T6G(SCH_1):M_B_CPU0_SA_RSP(0)
   U25 BN62 MBA0_RSP_L GENOA_SP5-SOCKET6096_13568-001,SMLF,IO,DGA^6000030   I171 @T6G_MB_LIB.T6G(SCH_1):PAGE11
   J15   86 LBD||RSP_A_N SCONN288_DDR506112002KQ-SCONN288_DDR506112002KQ,SMA   I350 @T6G_MB_LIB.T6G(SCH_1):PAGE86

M_B_CPU0_SB_CA<0> @T6G_MB_LIB.T6G(SCH_1):M_B_CPU0_SB_CA(0)
   U25 BG62 MBB_CA0 GENOA_SP5-SOCKET6096_13568-001,SMLF,IO,DGA^6000030   I171 @T6G_MB_LIB.T6G(SCH_1):PAGE11
   J15   76  CA0_B SCONN288_DDR506112002KQ-SCONN288_DDR506112002KQ,SMA   I350 @T6G_MB_LIB.T6G(SCH_1):PAGE86

M_B_CPU0_SB_CA<1> @T6G_MB_LIB.T6G(SCH_1):M_B_CPU0_SB_CA(1)
   U25 BH62 MBB_CA1 GENOA_SP5-SOCKET6096_13568-001,SMLF,IO,DGA^6000030   I171 @T6G_MB_LIB.T6G(SCH_1):PAGE11
   J15  221  CA1_B SCONN288_DDR506112002KQ-SCONN288_DDR506112002KQ,SMA   I350 @T6G_MB_LIB.T6G(SCH_1):PAGE86

M_B_CPU0_SB_CA<2> @T6G_MB_LIB.T6G(SCH_1):M_B_CPU0_SB_CA(2)
   U25 BH63 MBB_CA2 GENOA_SP5-SOCKET6096_13568-001,SMLF,IO,DGA^6000030   I171 @T6G_MB_LIB.T6G(SCH_1):PAGE11
   J15   78  CA2_B SCONN288_DDR506112002KQ-SCONN288_DDR506112002KQ,SMA   I350 @T6G_MB_LIB.T6G(SCH_1):PAGE86

M_B_CPU0_SB_CA<3> @T6G_MB_LIB.T6G(SCH_1):M_B_CPU0_SB_CA(3)
   U25 BJ64 MBB_CA3 GENOA_SP5-SOCKET6096_13568-001,SMLF,IO,DGA^6000030   I171 @T6G_MB_LIB.T6G(SCH_1):PAGE11
   J15  223  CA3_B SCONN288_DDR506112002KQ-SCONN288_DDR506112002KQ,SMA   I350 @T6G_MB_LIB.T6G(SCH_1):PAGE86

M_B_CPU0_SB_CA<4> @T6G_MB_LIB.T6G(SCH_1):M_B_CPU0_SB_CA(4)
   U25 BJ62 MBB_CA4 GENOA_SP5-SOCKET6096_13568-001,SMLF,IO,DGA^6000030   I171 @T6G_MB_LIB.T6G(SCH_1):PAGE11
   J15   80  CA4_B SCONN288_DDR506112002KQ-SCONN288_DDR506112002KQ,SMA   I350 @T6G_MB_LIB.T6G(SCH_1):PAGE86

M_B_CPU0_SB_CA<5> @T6G_MB_LIB.T6G(SCH_1):M_B_CPU0_SB_CA(5)
   U25 BK62 MBB_CA5 GENOA_SP5-SOCKET6096_13568-001,SMLF,IO,DGA^6000030   I171 @T6G_MB_LIB.T6G(SCH_1):PAGE11
   J15  225  CA5_B SCONN288_DDR506112002KQ-SCONN288_DDR506112002KQ,SMA   I350 @T6G_MB_LIB.T6G(SCH_1):PAGE86

M_B_CPU0_SB_CA<6> @T6G_MB_LIB.T6G(SCH_1):M_B_CPU0_SB_CA(6)
   U25 BK63 MBB_CA6 GENOA_SP5-SOCKET6096_13568-001,SMLF,IO,DGA^6000030   I171 @T6G_MB_LIB.T6G(SCH_1):PAGE11
   J15   82  CA6_B SCONN288_DDR506112002KQ-SCONN288_DDR506112002KQ,SMA   I350 @T6G_MB_LIB.T6G(SCH_1):PAGE86

M_B_CPU0_SB_CB<0> @T6G_MB_LIB.T6G(SCH_1):M_B_CPU0_SB_CB(0)
   U25 BY63 MBB_CHECK0 GENOA_SP5-SOCKET6096_13568-001,SMLF,IO,DGA^6000030   I171 @T6G_MB_LIB.T6G(SCH_1):PAGE11
   J15   96  CB0_B SCONN288_DDR506112002KQ-SCONN288_DDR506112002KQ,SMA   I350 @T6G_MB_LIB.T6G(SCH_1):PAGE86

M_B_CPU0_SB_CB<1> @T6G_MB_LIB.T6G(SCH_1):M_B_CPU0_SB_CB(1)
   U25 CA62 MBB_CHECK1 GENOA_SP5-SOCKET6096_13568-001,SMLF,IO,DGA^6000030   I171 @T6G_MB_LIB.T6G(SCH_1):PAGE11
   J15   98  CB1_B SCONN288_DDR506112002KQ-SCONN288_DDR506112002KQ,SMA   I350 @T6G_MB_LIB.T6G(SCH_1):PAGE86

M_B_CPU0_SB_CB<2> @T6G_MB_LIB.T6G(SCH_1):M_B_CPU0_SB_CB(2)
   U25 CA64 MBB_CHECK2 GENOA_SP5-SOCKET6096_13568-001,SMLF,IO,DGA^6000030   I171 @T6G_MB_LIB.T6G(SCH_1):PAGE11
   J15  241  CB2_B SCONN288_DDR506112002KQ-SCONN288_DDR506112002KQ,SMA   I350 @T6G_MB_LIB.T6G(SCH_1):PAGE86

M_B_CPU0_SB_CB<3> @T6G_MB_LIB.T6G(SCH_1):M_B_CPU0_SB_CB(3)
   U25 CB62 MBB_CHECK3 GENOA_SP5-SOCKET6096_13568-001,SMLF,IO,DGA^6000030   I171 @T6G_MB_LIB.T6G(SCH_1):PAGE11
   J15  243  CB3_B SCONN288_DDR506112002KQ-SCONN288_DDR506112002KQ,SMA   I350 @T6G_MB_LIB.T6G(SCH_1):PAGE86

M_B_CPU0_SB_CB<4> @T6G_MB_LIB.T6G(SCH_1):M_B_CPU0_SB_CB(4)
   U25 BT63 MBB_CHECK4 GENOA_SP5-SOCKET6096_13568-001,SMLF,IO,DGA^6000030   I171 @T6G_MB_LIB.T6G(SCH_1):PAGE11
   J15   89  CB4_B SCONN288_DDR506112002KQ-SCONN288_DDR506112002KQ,SMA   I350 @T6G_MB_LIB.T6G(SCH_1):PAGE86

M_B_CPU0_SB_CB<5> @T6G_MB_LIB.T6G(SCH_1):M_B_CPU0_SB_CB(5)
   U25 BU62 MBB_CHECK5 GENOA_SP5-SOCKET6096_13568-001,SMLF,IO,DGA^6000030   I171 @T6G_MB_LIB.T6G(SCH_1):PAGE11
   J15   91  CB5_B SCONN288_DDR506112002KQ-SCONN288_DDR506112002KQ,SMA   I350 @T6G_MB_LIB.T6G(SCH_1):PAGE86

M_B_CPU0_SB_CB<6> @T6G_MB_LIB.T6G(SCH_1):M_B_CPU0_SB_CB(6)
   U25 BU64 MBB_CHECK6 GENOA_SP5-SOCKET6096_13568-001,SMLF,IO,DGA^6000030   I171 @T6G_MB_LIB.T6G(SCH_1):PAGE11
   J15  234  CB6_B SCONN288_DDR506112002KQ-SCONN288_DDR506112002KQ,SMA   I350 @T6G_MB_LIB.T6G(SCH_1):PAGE86

M_B_CPU0_SB_CB<7> @T6G_MB_LIB.T6G(SCH_1):M_B_CPU0_SB_CB(7)
   U25 BV62 MBB_CHECK7 GENOA_SP5-SOCKET6096_13568-001,SMLF,IO,DGA^6000030   I171 @T6G_MB_LIB.T6G(SCH_1):PAGE11
   J15  236  CB7_B SCONN288_DDR506112002KQ-SCONN288_DDR506112002KQ,SMA   I350 @T6G_MB_LIB.T6G(SCH_1):PAGE86

M_B_CPU0_SB_CS_N<0> @T6G_MB_LIB.T6G(SCH_1):M_B_CPU0_SB_CS_N(0)
   U25 BM62 MBB0_CS_L0 GENOA_SP5-SOCKET6096_13568-001,SMLF,IO,DGA^6000030   I171 @T6G_MB_LIB.T6G(SCH_1):PAGE11
   J15   84 CS0_B_N SCONN288_DDR506112002KQ-SCONN288_DDR506112002KQ,SMA   I350 @T6G_MB_LIB.T6G(SCH_1):PAGE86

M_B_CPU0_SB_CS_N<1> @T6G_MB_LIB.T6G(SCH_1):M_B_CPU0_SB_CS_N(1)
   U25 BN64 MBB0_CS_L1 GENOA_SP5-SOCKET6096_13568-001,SMLF,IO,DGA^6000030   I171 @T6G_MB_LIB.T6G(SCH_1):PAGE11
   J15  229 CS1_B_N SCONN288_DDR506112002KQ-SCONN288_DDR506112002KQ,SMA   I350 @T6G_MB_LIB.T6G(SCH_1):PAGE86

M_B_CPU0_SB_DQ<0> @T6G_MB_LIB.T6G(SCH_1):M_B_CPU0_SB_DQ(0)
   U25 CB63 MBB_DATA0 GENOA_SP5-SOCKET6096_13568-001,SMLF,IO,DGA^6000030   I171 @T6G_MB_LIB.T6G(SCH_1):PAGE11
   J15  100  DQ0_B SCONN288_DDR506112002KQ-SCONN288_DDR506112002KQ,SMA   I350 @T6G_MB_LIB.T6G(SCH_1):PAGE86

M_B_CPU0_SB_DQ<10> @T6G_MB_LIB.T6G(SCH_1):M_B_CPU0_SB_DQ(10)
   U25 CJ64 MBB_DATA10 GENOA_SP5-SOCKET6096_13568-001,SMLF,IO,DGA^6000030   I171 @T6G_MB_LIB.T6G(SCH_1):PAGE11
   J15  256 DQ10_B SCONN288_DDR506112002KQ-SCONN288_DDR506112002KQ,SMA   I350 @T6G_MB_LIB.T6G(SCH_1):PAGE86

M_B_CPU0_SB_DQ<11> @T6G_MB_LIB.T6G(SCH_1):M_B_CPU0_SB_DQ(11)
   U25 CK62 MBB_DATA11 GENOA_SP5-SOCKET6096_13568-001,SMLF,IO,DGA^6000030   I171 @T6G_MB_LIB.T6G(SCH_1):PAGE11
   J15  258 DQ11_B SCONN288_DDR506112002KQ-SCONN288_DDR506112002KQ,SMA   I350 @T6G_MB_LIB.T6G(SCH_1):PAGE86

M_B_CPU0_SB_DQ<12> @T6G_MB_LIB.T6G(SCH_1):M_B_CPU0_SB_DQ(12)
   U25 CM63 MBB_DATA12 GENOA_SP5-SOCKET6096_13568-001,SMLF,IO,DGA^6000030   I171 @T6G_MB_LIB.T6G(SCH_1):PAGE11
   J15  118 DQ12_B SCONN288_DDR506112002KQ-SCONN288_DDR506112002KQ,SMA   I350 @T6G_MB_LIB.T6G(SCH_1):PAGE86

M_B_CPU0_SB_DQ<13> @T6G_MB_LIB.T6G(SCH_1):M_B_CPU0_SB_DQ(13)
   U25 CN62 MBB_DATA13 GENOA_SP5-SOCKET6096_13568-001,SMLF,IO,DGA^6000030   I171 @T6G_MB_LIB.T6G(SCH_1):PAGE11
   J15  120 DQ13_B SCONN288_DDR506112002KQ-SCONN288_DDR506112002KQ,SMA   I350 @T6G_MB_LIB.T6G(SCH_1):PAGE86

M_B_CPU0_SB_DQ<14> @T6G_MB_LIB.T6G(SCH_1):M_B_CPU0_SB_DQ(14)
   U25 CN64 MBB_DATA14 GENOA_SP5-SOCKET6096_13568-001,SMLF,IO,DGA^6000030   I171 @T6G_MB_LIB.T6G(SCH_1):PAGE11
   J15  263 DQ14_B SCONN288_DDR506112002KQ-SCONN288_DDR506112002KQ,SMA   I350 @T6G_MB_LIB.T6G(SCH_1):PAGE86

M_B_CPU0_SB_DQ<15> @T6G_MB_LIB.T6G(SCH_1):M_B_CPU0_SB_DQ(15)
   U25 CP62 MBB_DATA15 GENOA_SP5-SOCKET6096_13568-001,SMLF,IO,DGA^6000030   I171 @T6G_MB_LIB.T6G(SCH_1):PAGE11
   J15  265 DQ15_B SCONN288_DDR506112002KQ-SCONN288_DDR506112002KQ,SMA   I350 @T6G_MB_LIB.T6G(SCH_1):PAGE86

M_B_CPU0_SB_DQ<16> @T6G_MB_LIB.T6G(SCH_1):M_B_CPU0_SB_DQ(16)
   U25 CP63 MBB_DATA16 GENOA_SP5-SOCKET6096_13568-001,SMLF,IO,DGA^6000030   I171 @T6G_MB_LIB.T6G(SCH_1):PAGE11
   J15  122 DQ16_B SCONN288_DDR506112002KQ-SCONN288_DDR506112002KQ,SMA   I350 @T6G_MB_LIB.T6G(SCH_1):PAGE86

M_B_CPU0_SB_DQ<17> @T6G_MB_LIB.T6G(SCH_1):M_B_CPU0_SB_DQ(17)
   U25 CR62 MBB_DATA17 GENOA_SP5-SOCKET6096_13568-001,SMLF,IO,DGA^6000030   I171 @T6G_MB_LIB.T6G(SCH_1):PAGE11
   J15  124 DQ17_B SCONN288_DDR506112002KQ-SCONN288_DDR506112002KQ,SMA   I350 @T6G_MB_LIB.T6G(SCH_1):PAGE86

M_B_CPU0_SB_DQ<18> @T6G_MB_LIB.T6G(SCH_1):M_B_CPU0_SB_DQ(18)
   U25 CR64 MBB_DATA18 GENOA_SP5-SOCKET6096_13568-001,SMLF,IO,DGA^6000030   I171 @T6G_MB_LIB.T6G(SCH_1):PAGE11
   J15  267 DQ18_B SCONN288_DDR506112002KQ-SCONN288_DDR506112002KQ,SMA   I350 @T6G_MB_LIB.T6G(SCH_1):PAGE86

M_B_CPU0_SB_DQ<19> @T6G_MB_LIB.T6G(SCH_1):M_B_CPU0_SB_DQ(19)
   U25 CT62 MBB_DATA19 GENOA_SP5-SOCKET6096_13568-001,SMLF,IO,DGA^6000030   I171 @T6G_MB_LIB.T6G(SCH_1):PAGE11
   J15  269 DQ19_B SCONN288_DDR506112002KQ-SCONN288_DDR506112002KQ,SMA   I350 @T6G_MB_LIB.T6G(SCH_1):PAGE86

M_B_CPU0_SB_DQ<1> @T6G_MB_LIB.T6G(SCH_1):M_B_CPU0_SB_DQ(1)
   U25 CC62 MBB_DATA1 GENOA_SP5-SOCKET6096_13568-001,SMLF,IO,DGA^6000030   I171 @T6G_MB_LIB.T6G(SCH_1):PAGE11
   J15  102  DQ1_B SCONN288_DDR506112002KQ-SCONN288_DDR506112002KQ,SMA   I350 @T6G_MB_LIB.T6G(SCH_1):PAGE86

M_B_CPU0_SB_DQ<20> @T6G_MB_LIB.T6G(SCH_1):M_B_CPU0_SB_DQ(20)
   U25 CV63 MBB_DATA20 GENOA_SP5-SOCKET6096_13568-001,SMLF,IO,DGA^6000030   I171 @T6G_MB_LIB.T6G(SCH_1):PAGE11
   J15  129 DQ20_B SCONN288_DDR506112002KQ-SCONN288_DDR506112002KQ,SMA   I350 @T6G_MB_LIB.T6G(SCH_1):PAGE86

M_B_CPU0_SB_DQ<21> @T6G_MB_LIB.T6G(SCH_1):M_B_CPU0_SB_DQ(21)
   U25 CW62 MBB_DATA21 GENOA_SP5-SOCKET6096_13568-001,SMLF,IO,DGA^6000030   I171 @T6G_MB_LIB.T6G(SCH_1):PAGE11
   J15  131 DQ21_B SCONN288_DDR506112002KQ-SCONN288_DDR506112002KQ,SMA   I350 @T6G_MB_LIB.T6G(SCH_1):PAGE86

M_B_CPU0_SB_DQ<22> @T6G_MB_LIB.T6G(SCH_1):M_B_CPU0_SB_DQ(22)
   U25 CW64 MBB_DATA22 GENOA_SP5-SOCKET6096_13568-001,SMLF,IO,DGA^6000030   I171 @T6G_MB_LIB.T6G(SCH_1):PAGE11
   J15  274 DQ22_B SCONN288_DDR506112002KQ-SCONN288_DDR506112002KQ,SMA   I350 @T6G_MB_LIB.T6G(SCH_1):PAGE86

M_B_CPU0_SB_DQ<23> @T6G_MB_LIB.T6G(SCH_1):M_B_CPU0_SB_DQ(23)
   U25 CY62 MBB_DATA23 GENOA_SP5-SOCKET6096_13568-001,SMLF,IO,DGA^6000030   I171 @T6G_MB_LIB.T6G(SCH_1):PAGE11
   J15  276 DQ23_B SCONN288_DDR506112002KQ-SCONN288_DDR506112002KQ,SMA   I350 @T6G_MB_LIB.T6G(SCH_1):PAGE86

M_B_CPU0_SB_DQ<24> @T6G_MB_LIB.T6G(SCH_1):M_B_CPU0_SB_DQ(24)
   U25 CY63 MBB_DATA24 GENOA_SP5-SOCKET6096_13568-001,SMLF,IO,DGA^6000030   I171 @T6G_MB_LIB.T6G(SCH_1):PAGE11
   J15  133 DQ24_B SCONN288_DDR506112002KQ-SCONN288_DDR506112002KQ,SMA   I350 @T6G_MB_LIB.T6G(SCH_1):PAGE86

M_B_CPU0_SB_DQ<25> @T6G_MB_LIB.T6G(SCH_1):M_B_CPU0_SB_DQ(25)
   U25 DA62 MBB_DATA25 GENOA_SP5-SOCKET6096_13568-001,SMLF,IO,DGA^6000030   I171 @T6G_MB_LIB.T6G(SCH_1):PAGE11
   J15  135 DQ25_B SCONN288_DDR506112002KQ-SCONN288_DDR506112002KQ,SMA   I350 @T6G_MB_LIB.T6G(SCH_1):PAGE86

M_B_CPU0_SB_DQ<26> @T6G_MB_LIB.T6G(SCH_1):M_B_CPU0_SB_DQ(26)
   U25 DA64 MBB_DATA26 GENOA_SP5-SOCKET6096_13568-001,SMLF,IO,DGA^6000030   I171 @T6G_MB_LIB.T6G(SCH_1):PAGE11
   J15  278 DQ26_B SCONN288_DDR506112002KQ-SCONN288_DDR506112002KQ,SMA   I350 @T6G_MB_LIB.T6G(SCH_1):PAGE86

M_B_CPU0_SB_DQ<27> @T6G_MB_LIB.T6G(SCH_1):M_B_CPU0_SB_DQ(27)
   U25 DB62 MBB_DATA27 GENOA_SP5-SOCKET6096_13568-001,SMLF,IO,DGA^6000030   I171 @T6G_MB_LIB.T6G(SCH_1):PAGE11
   J15  280 DQ27_B SCONN288_DDR506112002KQ-SCONN288_DDR506112002KQ,SMA   I350 @T6G_MB_LIB.T6G(SCH_1):PAGE86

M_B_CPU0_SB_DQ<28> @T6G_MB_LIB.T6G(SCH_1):M_B_CPU0_SB_DQ(28)
   U25 DD63 MBB_DATA28 GENOA_SP5-SOCKET6096_13568-001,SMLF,IO,DGA^6000030   I171 @T6G_MB_LIB.T6G(SCH_1):PAGE11
   J15  140 DQ28_B SCONN288_DDR506112002KQ-SCONN288_DDR506112002KQ,SMA   I350 @T6G_MB_LIB.T6G(SCH_1):PAGE86

M_B_CPU0_SB_DQ<29> @T6G_MB_LIB.T6G(SCH_1):M_B_CPU0_SB_DQ(29)
   U25 DE62 MBB_DATA29 GENOA_SP5-SOCKET6096_13568-001,SMLF,IO,DGA^6000030   I171 @T6G_MB_LIB.T6G(SCH_1):PAGE11
   J15  142 DQ29_B SCONN288_DDR506112002KQ-SCONN288_DDR506112002KQ,SMA   I350 @T6G_MB_LIB.T6G(SCH_1):PAGE86

M_B_CPU0_SB_DQ<2> @T6G_MB_LIB.T6G(SCH_1):M_B_CPU0_SB_DQ(2)
   U25 CC64 MBB_DATA2 GENOA_SP5-SOCKET6096_13568-001,SMLF,IO,DGA^6000030   I171 @T6G_MB_LIB.T6G(SCH_1):PAGE11
   J15  245  DQ2_B SCONN288_DDR506112002KQ-SCONN288_DDR506112002KQ,SMA   I350 @T6G_MB_LIB.T6G(SCH_1):PAGE86

M_B_CPU0_SB_DQ<30> @T6G_MB_LIB.T6G(SCH_1):M_B_CPU0_SB_DQ(30)
   U25 DE64 MBB_DATA30 GENOA_SP5-SOCKET6096_13568-001,SMLF,IO,DGA^6000030   I171 @T6G_MB_LIB.T6G(SCH_1):PAGE11
   J15  285 DQ30_B SCONN288_DDR506112002KQ-SCONN288_DDR506112002KQ,SMA   I350 @T6G_MB_LIB.T6G(SCH_1):PAGE86

M_B_CPU0_SB_DQ<31> @T6G_MB_LIB.T6G(SCH_1):M_B_CPU0_SB_DQ(31)
   U25 DF62 MBB_DATA31 GENOA_SP5-SOCKET6096_13568-001,SMLF,IO,DGA^6000030   I171 @T6G_MB_LIB.T6G(SCH_1):PAGE11
   J15  287 DQ31_B SCONN288_DDR506112002KQ-SCONN288_DDR506112002KQ,SMA   I350 @T6G_MB_LIB.T6G(SCH_1):PAGE86

M_B_CPU0_SB_DQ<3> @T6G_MB_LIB.T6G(SCH_1):M_B_CPU0_SB_DQ(3)
   U25 CD62 MBB_DATA3 GENOA_SP5-SOCKET6096_13568-001,SMLF,IO,DGA^6000030   I171 @T6G_MB_LIB.T6G(SCH_1):PAGE11
   J15  247  DQ3_B SCONN288_DDR506112002KQ-SCONN288_DDR506112002KQ,SMA   I350 @T6G_MB_LIB.T6G(SCH_1):PAGE86

M_B_CPU0_SB_DQ<4> @T6G_MB_LIB.T6G(SCH_1):M_B_CPU0_SB_DQ(4)
   U25 CF63 MBB_DATA4 GENOA_SP5-SOCKET6096_13568-001,SMLF,IO,DGA^6000030   I171 @T6G_MB_LIB.T6G(SCH_1):PAGE11
   J15  107  DQ4_B SCONN288_DDR506112002KQ-SCONN288_DDR506112002KQ,SMA   I350 @T6G_MB_LIB.T6G(SCH_1):PAGE86

M_B_CPU0_SB_DQ<5> @T6G_MB_LIB.T6G(SCH_1):M_B_CPU0_SB_DQ(5)
   U25 CG62 MBB_DATA5 GENOA_SP5-SOCKET6096_13568-001,SMLF,IO,DGA^6000030   I171 @T6G_MB_LIB.T6G(SCH_1):PAGE11
   J15  109  DQ5_B SCONN288_DDR506112002KQ-SCONN288_DDR506112002KQ,SMA   I350 @T6G_MB_LIB.T6G(SCH_1):PAGE86

M_B_CPU0_SB_DQ<6> @T6G_MB_LIB.T6G(SCH_1):M_B_CPU0_SB_DQ(6)
   U25 CG64 MBB_DATA6 GENOA_SP5-SOCKET6096_13568-001,SMLF,IO,DGA^6000030   I171 @T6G_MB_LIB.T6G(SCH_1):PAGE11
   J15  252  DQ6_B SCONN288_DDR506112002KQ-SCONN288_DDR506112002KQ,SMA   I350 @T6G_MB_LIB.T6G(SCH_1):PAGE86

M_B_CPU0_SB_DQ<7> @T6G_MB_LIB.T6G(SCH_1):M_B_CPU0_SB_DQ(7)
   U25 CH62 MBB_DATA7 GENOA_SP5-SOCKET6096_13568-001,SMLF,IO,DGA^6000030   I171 @T6G_MB_LIB.T6G(SCH_1):PAGE11
   J15  254  DQ7_B SCONN288_DDR506112002KQ-SCONN288_DDR506112002KQ,SMA   I350 @T6G_MB_LIB.T6G(SCH_1):PAGE86

M_B_CPU0_SB_DQ<8> @T6G_MB_LIB.T6G(SCH_1):M_B_CPU0_SB_DQ(8)
   U25 CH63 MBB_DATA8 GENOA_SP5-SOCKET6096_13568-001,SMLF,IO,DGA^6000030   I171 @T6G_MB_LIB.T6G(SCH_1):PAGE11
   J15  111  DQ8_B SCONN288_DDR506112002KQ-SCONN288_DDR506112002KQ,SMA   I350 @T6G_MB_LIB.T6G(SCH_1):PAGE86

M_B_CPU0_SB_DQ<9> @T6G_MB_LIB.T6G(SCH_1):M_B_CPU0_SB_DQ(9)
   U25 CJ62 MBB_DATA9 GENOA_SP5-SOCKET6096_13568-001,SMLF,IO,DGA^6000030   I171 @T6G_MB_LIB.T6G(SCH_1):PAGE11
   J15  113  DQ9_B SCONN288_DDR506112002KQ-SCONN288_DDR506112002KQ,SMA   I350 @T6G_MB_LIB.T6G(SCH_1):PAGE86

M_B_CPU0_SB_DQS_DN<0> @T6G_MB_LIB.T6G(SCH_1):M_B_CPU0_SB_DQS_DN(0)
   U25 CE64 MBB_DQS_L0 GENOA_SP5-SOCKET6096_13568-001,SMLF,IO,DGA^6000030   I171 @T6G_MB_LIB.T6G(SCH_1):PAGE11
   J15  105 DQS0_B_C SCONN288_DDR506112002KQ-SCONN288_DDR506112002KQ,SMA   I367 @T6G_MB_LIB.T6G(SCH_1):PAGE86

M_B_CPU0_SB_DQS_DN<1> @T6G_MB_LIB.T6G(SCH_1):M_B_CPU0_SB_DQS_DN(1)
   U25 CL64 MBB_DQS_L1 GENOA_SP5-SOCKET6096_13568-001,SMLF,IO,DGA^6000030   I171 @T6G_MB_LIB.T6G(SCH_1):PAGE11
   J15  116 DQS1_B_C SCONN288_DDR506112002KQ-SCONN288_DDR506112002KQ,SMA   I367 @T6G_MB_LIB.T6G(SCH_1):PAGE86

M_B_CPU0_SB_DQS_DN<2> @T6G_MB_LIB.T6G(SCH_1):M_B_CPU0_SB_DQS_DN(2)
   U25 CU64 MBB_DQS_L2 GENOA_SP5-SOCKET6096_13568-001,SMLF,IO,DGA^6000030   I171 @T6G_MB_LIB.T6G(SCH_1):PAGE11
   J15  127 DQS2_B_C SCONN288_DDR506112002KQ-SCONN288_DDR506112002KQ,SMA   I367 @T6G_MB_LIB.T6G(SCH_1):PAGE86

M_B_CPU0_SB_DQS_DN<3> @T6G_MB_LIB.T6G(SCH_1):M_B_CPU0_SB_DQS_DN(3)
   U25 DC64 MBB_DQS_L3 GENOA_SP5-SOCKET6096_13568-001,SMLF,IO,DGA^6000030   I171 @T6G_MB_LIB.T6G(SCH_1):PAGE11
   J15  138 DQS3_B_C SCONN288_DDR506112002KQ-SCONN288_DDR506112002KQ,SMA   I367 @T6G_MB_LIB.T6G(SCH_1):PAGE86

M_B_CPU0_SB_DQS_DN<4> @T6G_MB_LIB.T6G(SCH_1):M_B_CPU0_SB_DQS_DN(4)
   U25 BW62 MBB_DQS_L4 GENOA_SP5-SOCKET6096_13568-001,SMLF,IO,DGA^6000030   I171 @T6G_MB_LIB.T6G(SCH_1):PAGE11
   J15  238 DQS4_B_C SCONN288_DDR506112002KQ-SCONN288_DDR506112002KQ,SMA   I367 @T6G_MB_LIB.T6G(SCH_1):PAGE86

M_B_CPU0_SB_DQS_DN<5> @T6G_MB_LIB.T6G(SCH_1):M_B_CPU0_SB_DQS_DN(5)
   U25 CE62 MBB_DQS_L5 GENOA_SP5-SOCKET6096_13568-001,SMLF,IO,DGA^6000030   I171 @T6G_MB_LIB.T6G(SCH_1):PAGE11
   J15  249 DQS5_B_C||TDQS5_B_C SCONN288_DDR506112002KQ-SCONN288_DDR506112002KQ,SMA   I367 @T6G_MB_LIB.T6G(SCH_1):PAGE86

M_B_CPU0_SB_DQS_DN<6> @T6G_MB_LIB.T6G(SCH_1):M_B_CPU0_SB_DQS_DN(6)
   U25 CL62 MBB_DQS_L6 GENOA_SP5-SOCKET6096_13568-001,SMLF,IO,DGA^6000030   I171 @T6G_MB_LIB.T6G(SCH_1):PAGE11
   J15  260 DQS6_B_C||TDQS6_B_C SCONN288_DDR506112002KQ-SCONN288_DDR506112002KQ,SMA   I367 @T6G_MB_LIB.T6G(SCH_1):PAGE86

M_B_CPU0_SB_DQS_DN<7> @T6G_MB_LIB.T6G(SCH_1):M_B_CPU0_SB_DQS_DN(7)
   U25 CU62 MBB_DQS_L7 GENOA_SP5-SOCKET6096_13568-001,SMLF,IO,DGA^6000030   I171 @T6G_MB_LIB.T6G(SCH_1):PAGE11
   J15  271 DQS7_B_C||TDQS7_B_C SCONN288_DDR506112002KQ-SCONN288_DDR506112002KQ,SMA   I367 @T6G_MB_LIB.T6G(SCH_1):PAGE86

M_B_CPU0_SB_DQS_DN<8> @T6G_MB_LIB.T6G(SCH_1):M_B_CPU0_SB_DQS_DN(8)
   U25 DC62 MBB_DQS_L8 GENOA_SP5-SOCKET6096_13568-001,SMLF,IO,DGA^6000030   I171 @T6G_MB_LIB.T6G(SCH_1):PAGE11
   J15  282 DQS8_B_C||TDQS8_B_C SCONN288_DDR506112002KQ-SCONN288_DDR506112002KQ,SMA   I367 @T6G_MB_LIB.T6G(SCH_1):PAGE86

M_B_CPU0_SB_DQS_DN<9> @T6G_MB_LIB.T6G(SCH_1):M_B_CPU0_SB_DQS_DN(9)
   U25 BW64 MBB_DQS_L9 GENOA_SP5-SOCKET6096_13568-001,SMLF,IO,DGA^6000030   I171 @T6G_MB_LIB.T6G(SCH_1):PAGE11
   J15   94 DQS9_B_C||TDQS9_B_C SCONN288_DDR506112002KQ-SCONN288_DDR506112002KQ,SMA   I367 @T6G_MB_LIB.T6G(SCH_1):PAGE86

M_B_CPU0_SB_DQS_DP<0> @T6G_MB_LIB.T6G(SCH_1):M_B_CPU0_SB_DQS_DP(0)
   U25 CD63 MBB_DQS_H0 GENOA_SP5-SOCKET6096_13568-001,SMLF,IO,DGA^6000030   I171 @T6G_MB_LIB.T6G(SCH_1):PAGE11
   J15  104 DQS0_B_T SCONN288_DDR506112002KQ-SCONN288_DDR506112002KQ,SMA   I367 @T6G_MB_LIB.T6G(SCH_1):PAGE86

M_B_CPU0_SB_DQS_DP<1> @T6G_MB_LIB.T6G(SCH_1):M_B_CPU0_SB_DQS_DP(1)
   U25 CK63 MBB_DQS_H1 GENOA_SP5-SOCKET6096_13568-001,SMLF,IO,DGA^6000030   I171 @T6G_MB_LIB.T6G(SCH_1):PAGE11
   J15  115 DQS1_B_T SCONN288_DDR506112002KQ-SCONN288_DDR506112002KQ,SMA   I367 @T6G_MB_LIB.T6G(SCH_1):PAGE86

M_B_CPU0_SB_DQS_DP<2> @T6G_MB_LIB.T6G(SCH_1):M_B_CPU0_SB_DQS_DP(2)
   U25 CT63 MBB_DQS_H2 GENOA_SP5-SOCKET6096_13568-001,SMLF,IO,DGA^6000030   I171 @T6G_MB_LIB.T6G(SCH_1):PAGE11
   J15  126 DQS2_B_T SCONN288_DDR506112002KQ-SCONN288_DDR506112002KQ,SMA   I367 @T6G_MB_LIB.T6G(SCH_1):PAGE86

M_B_CPU0_SB_DQS_DP<3> @T6G_MB_LIB.T6G(SCH_1):M_B_CPU0_SB_DQS_DP(3)
   U25 DB63 MBB_DQS_H3 GENOA_SP5-SOCKET6096_13568-001,SMLF,IO,DGA^6000030   I171 @T6G_MB_LIB.T6G(SCH_1):PAGE11
   J15  137 DQS3_B_T SCONN288_DDR506112002KQ-SCONN288_DDR506112002KQ,SMA   I367 @T6G_MB_LIB.T6G(SCH_1):PAGE86

M_B_CPU0_SB_DQS_DP<4> @T6G_MB_LIB.T6G(SCH_1):M_B_CPU0_SB_DQS_DP(4)
   U25 BY62 MBB_DQS_H4 GENOA_SP5-SOCKET6096_13568-001,SMLF,IO,DGA^6000030   I171 @T6G_MB_LIB.T6G(SCH_1):PAGE11
   J15  239 DQS4_B_T SCONN288_DDR506112002KQ-SCONN288_DDR506112002KQ,SMA   I367 @T6G_MB_LIB.T6G(SCH_1):PAGE86

M_B_CPU0_SB_DQS_DP<5> @T6G_MB_LIB.T6G(SCH_1):M_B_CPU0_SB_DQS_DP(5)
   U25 CF62 MBB_DQS_H5 GENOA_SP5-SOCKET6096_13568-001,SMLF,IO,DGA^6000030   I171 @T6G_MB_LIB.T6G(SCH_1):PAGE11
   J15  250 DQS5_B_T||TDQS5_B_T SCONN288_DDR506112002KQ-SCONN288_DDR506112002KQ,SMA   I367 @T6G_MB_LIB.T6G(SCH_1):PAGE86

M_B_CPU0_SB_DQS_DP<6> @T6G_MB_LIB.T6G(SCH_1):M_B_CPU0_SB_DQS_DP(6)
   U25 CM62 MBB_DQS_H6 GENOA_SP5-SOCKET6096_13568-001,SMLF,IO,DGA^6000030   I171 @T6G_MB_LIB.T6G(SCH_1):PAGE11
   J15  261 DQS6_B_T||TDQS6_B_T SCONN288_DDR506112002KQ-SCONN288_DDR506112002KQ,SMA   I367 @T6G_MB_LIB.T6G(SCH_1):PAGE86

M_B_CPU0_SB_DQS_DP<7> @T6G_MB_LIB.T6G(SCH_1):M_B_CPU0_SB_DQS_DP(7)
   U25 CV62 MBB_DQS_H7 GENOA_SP5-SOCKET6096_13568-001,SMLF,IO,DGA^6000030   I171 @T6G_MB_LIB.T6G(SCH_1):PAGE11
   J15  272 DQS7_B_T||TDQS7_B_T SCONN288_DDR506112002KQ-SCONN288_DDR506112002KQ,SMA   I367 @T6G_MB_LIB.T6G(SCH_1):PAGE86

M_B_CPU0_SB_DQS_DP<8> @T6G_MB_LIB.T6G(SCH_1):M_B_CPU0_SB_DQS_DP(8)
   U25 DD62 MBB_DQS_H8 GENOA_SP5-SOCKET6096_13568-001,SMLF,IO,DGA^6000030   I171 @T6G_MB_LIB.T6G(SCH_1):PAGE11
   J15  283 DQS8_B_T||TDQS8_B_T SCONN288_DDR506112002KQ-SCONN288_DDR506112002KQ,SMA   I367 @T6G_MB_LIB.T6G(SCH_1):PAGE86

M_B_CPU0_SB_DQS_DP<9> @T6G_MB_LIB.T6G(SCH_1):M_B_CPU0_SB_DQS_DP(9)
   U25 BV63 MBB_DQS_H9 GENOA_SP5-SOCKET6096_13568-001,SMLF,IO,DGA^6000030   I171 @T6G_MB_LIB.T6G(SCH_1):PAGE11
   J15   93 DQS9_B_T||TDQS9_B_T||DBI4_B_N SCONN288_DDR506112002KQ-SCONN288_DDR506112002KQ,SMA   I367 @T6G_MB_LIB.T6G(SCH_1):PAGE86

M_B_CPU0_SB_PAR @T6G_MB_LIB.T6G(SCH_1):M_B_CPU0_SB_PAR
   U25 BL64 MBB_PAR GENOA_SP5-SOCKET6096_13568-001,SMLF,IO,DGA^6000030   I171 @T6G_MB_LIB.T6G(SCH_1):PAGE11
   J15  227  PAR_B SCONN288_DDR506112002KQ-SCONN288_DDR506112002KQ,SMA   I350 @T6G_MB_LIB.T6G(SCH_1):PAGE86

M_B_CPU0_SB_RSP<0> @T6G_MB_LIB.T6G(SCH_1):M_B_CPU0_SB_RSP(0)
   U25 BP63 MBB0_RSP_L GENOA_SP5-SOCKET6096_13568-001,SMLF,IO,DGA^6000030   I171 @T6G_MB_LIB.T6G(SCH_1):PAGE11
   J15   87 LBS||RSP_B_N SCONN288_DDR506112002KQ-SCONN288_DDR506112002KQ,SMA   I350 @T6G_MB_LIB.T6G(SCH_1):PAGE86

M_B_CPU1_ALERT_N @T6G_MB_LIB.T6G(SCH_1):M_B_CPU1_ALERT_N
  R501    1      A Q_RES_0402LF-15,1%,1/16W,CHIP,CS01502FB03   I314 @T6G_MB_LIB.T6G(SCH_1):PAGE38
   J26   62 ALERT_N SCONN288_DDR506112002KQ-SCONN288_DDR506112002KQ,SMA    I22 @T6G_MB_LIB.T6G(SCH_1):PAGE98

M_B_CPU1_ALERT_R_N @T6G_MB_LIB.T6G(SCH_1):M_B_CPU1_ALERT_R_N
   U26 AT62 MB_ALERT_L GENOA_SP5-SOCKET6096_13568-001,SMLF,IO,DGA^6000030   I159 @T6G_MB_LIB.T6G(SCH_1):PAGE38
  R501    2      B Q_RES_0402LF-15,1%,1/16W,CHIP,CS01502FB03   I314 @T6G_MB_LIB.T6G(SCH_1):PAGE38

M_B_CPU1_CLK_DN<0> @T6G_MB_LIB.T6G(SCH_1):M_B_CPU1_CLK_DN(0)
   U26 BD63 MB0_CLK_L GENOA_SP5-SOCKET6096_13568-001,SMLF,IO,DGA^6000030   I159 @T6G_MB_LIB.T6G(SCH_1):PAGE38
   J26  218   CK_C SCONN288_DDR506112002KQ-SCONN288_DDR506112002KQ,SMA    I22 @T6G_MB_LIB.T6G(SCH_1):PAGE98

M_B_CPU1_CLK_DP<0> @T6G_MB_LIB.T6G(SCH_1):M_B_CPU1_CLK_DP(0)
   U26 BC64 MB0_CLK_H GENOA_SP5-SOCKET6096_13568-001,SMLF,IO,DGA^6000030   I159 @T6G_MB_LIB.T6G(SCH_1):PAGE38
   J26  217   CK_T SCONN288_DDR506112002KQ-SCONN288_DDR506112002KQ,SMA    I22 @T6G_MB_LIB.T6G(SCH_1):PAGE98

M_B_CPU1_RESET_N @T6G_MB_LIB.T6G(SCH_1):M_B_CPU1_RESET_N
   U26 AU62 MB_RESET_L GENOA_SP5-SOCKET6096_13568-001,SMLF,IO,DGA^6000030   I159 @T6G_MB_LIB.T6G(SCH_1):PAGE38
   J26  207 RESET_N SCONN288_DDR506112002KQ-SCONN288_DDR506112002KQ,SMA    I22 @T6G_MB_LIB.T6G(SCH_1):PAGE98

M_B_CPU1_SA_CA<0> @T6G_MB_LIB.T6G(SCH_1):M_B_CPU1_SA_CA(0)
   U26 AW64 MBA_CA0 GENOA_SP5-SOCKET6096_13568-001,SMLF,IO,DGA^6000030   I159 @T6G_MB_LIB.T6G(SCH_1):PAGE38
   J26   66  CA0_A SCONN288_DDR506112002KQ-SCONN288_DDR506112002KQ,SMA    I22 @T6G_MB_LIB.T6G(SCH_1):PAGE98

M_B_CPU1_SA_CA<1> @T6G_MB_LIB.T6G(SCH_1):M_B_CPU1_SA_CA(1)
   U26 AY63 MBA_CA1 GENOA_SP5-SOCKET6096_13568-001,SMLF,IO,DGA^6000030   I159 @T6G_MB_LIB.T6G(SCH_1):PAGE38
   J26  211  CA1_A SCONN288_DDR506112002KQ-SCONN288_DDR506112002KQ,SMA    I22 @T6G_MB_LIB.T6G(SCH_1):PAGE98

M_B_CPU1_SA_CA<2> @T6G_MB_LIB.T6G(SCH_1):M_B_CPU1_SA_CA(2)
   U26 AY62 MBA_CA2 GENOA_SP5-SOCKET6096_13568-001,SMLF,IO,DGA^6000030   I159 @T6G_MB_LIB.T6G(SCH_1):PAGE38
   J26   68  CA2_A SCONN288_DDR506112002KQ-SCONN288_DDR506112002KQ,SMA    I22 @T6G_MB_LIB.T6G(SCH_1):PAGE98

M_B_CPU1_SA_CA<3> @T6G_MB_LIB.T6G(SCH_1):M_B_CPU1_SA_CA(3)
   U26 BA62 MBA_CA3 GENOA_SP5-SOCKET6096_13568-001,SMLF,IO,DGA^6000030   I159 @T6G_MB_LIB.T6G(SCH_1):PAGE38
   J26  213  CA3_A SCONN288_DDR506112002KQ-SCONN288_DDR506112002KQ,SMA    I22 @T6G_MB_LIB.T6G(SCH_1):PAGE98

M_B_CPU1_SA_CA<4> @T6G_MB_LIB.T6G(SCH_1):M_B_CPU1_SA_CA(4)
   U26 BA64 MBA_CA4 GENOA_SP5-SOCKET6096_13568-001,SMLF,IO,DGA^6000030   I159 @T6G_MB_LIB.T6G(SCH_1):PAGE38
   J26   70  CA4_A SCONN288_DDR506112002KQ-SCONN288_DDR506112002KQ,SMA    I22 @T6G_MB_LIB.T6G(SCH_1):PAGE98

M_B_CPU1_SA_CA<5> @T6G_MB_LIB.T6G(SCH_1):M_B_CPU1_SA_CA(5)
   U26 BB63 MBA_CA5 GENOA_SP5-SOCKET6096_13568-001,SMLF,IO,DGA^6000030   I159 @T6G_MB_LIB.T6G(SCH_1):PAGE38
   J26  215  CA5_A SCONN288_DDR506112002KQ-SCONN288_DDR506112002KQ,SMA    I22 @T6G_MB_LIB.T6G(SCH_1):PAGE98

M_B_CPU1_SA_CA<6> @T6G_MB_LIB.T6G(SCH_1):M_B_CPU1_SA_CA(6)
   U26 BB62 MBA_CA6 GENOA_SP5-SOCKET6096_13568-001,SMLF,IO,DGA^6000030   I159 @T6G_MB_LIB.T6G(SCH_1):PAGE38
   J26   72  CA6_A SCONN288_DDR506112002KQ-SCONN288_DDR506112002KQ,SMA    I22 @T6G_MB_LIB.T6G(SCH_1):PAGE98

M_B_CPU1_SA_CB<0> @T6G_MB_LIB.T6G(SCH_1):M_B_CPU1_SA_CB(0)
   U26 AJ64 MBA_CHECK0 GENOA_SP5-SOCKET6096_13568-001,SMLF,IO,DGA^6000030   I159 @T6G_MB_LIB.T6G(SCH_1):PAGE38
   J26   51  CB0_A SCONN288_DDR506112002KQ-SCONN288_DDR506112002KQ,SMA    I22 @T6G_MB_LIB.T6G(SCH_1):PAGE98

M_B_CPU1_SA_CB<1> @T6G_MB_LIB.T6G(SCH_1):M_B_CPU1_SA_CB(1)
   U26 AK62 MBA_CHECK1 GENOA_SP5-SOCKET6096_13568-001,SMLF,IO,DGA^6000030   I159 @T6G_MB_LIB.T6G(SCH_1):PAGE38
   J26   53  CB1_A SCONN288_DDR506112002KQ-SCONN288_DDR506112002KQ,SMA    I22 @T6G_MB_LIB.T6G(SCH_1):PAGE98

M_B_CPU1_SA_CB<2> @T6G_MB_LIB.T6G(SCH_1):M_B_CPU1_SA_CB(2)
   U26 AK63 MBA_CHECK2 GENOA_SP5-SOCKET6096_13568-001,SMLF,IO,DGA^6000030   I159 @T6G_MB_LIB.T6G(SCH_1):PAGE38
   J26  196  CB2_A SCONN288_DDR506112002KQ-SCONN288_DDR506112002KQ,SMA    I22 @T6G_MB_LIB.T6G(SCH_1):PAGE98

M_B_CPU1_SA_CB<3> @T6G_MB_LIB.T6G(SCH_1):M_B_CPU1_SA_CB(3)
   U26 AL62 MBA_CHECK3 GENOA_SP5-SOCKET6096_13568-001,SMLF,IO,DGA^6000030   I159 @T6G_MB_LIB.T6G(SCH_1):PAGE38
   J26  198  CB3_A SCONN288_DDR506112002KQ-SCONN288_DDR506112002KQ,SMA    I22 @T6G_MB_LIB.T6G(SCH_1):PAGE98

M_B_CPU1_SA_CB<4> @T6G_MB_LIB.T6G(SCH_1):M_B_CPU1_SA_CB(4)
   U26 AN64 MBA_CHECK4 GENOA_SP5-SOCKET6096_13568-001,SMLF,IO,DGA^6000030   I159 @T6G_MB_LIB.T6G(SCH_1):PAGE38
   J26   58  CB4_A SCONN288_DDR506112002KQ-SCONN288_DDR506112002KQ,SMA    I22 @T6G_MB_LIB.T6G(SCH_1):PAGE98

M_B_CPU1_SA_CB<5> @T6G_MB_LIB.T6G(SCH_1):M_B_CPU1_SA_CB(5)
   U26 AP62 MBA_CHECK5 GENOA_SP5-SOCKET6096_13568-001,SMLF,IO,DGA^6000030   I159 @T6G_MB_LIB.T6G(SCH_1):PAGE38
   J26   60  CB5_A SCONN288_DDR506112002KQ-SCONN288_DDR506112002KQ,SMA    I22 @T6G_MB_LIB.T6G(SCH_1):PAGE98

M_B_CPU1_SA_CB<6> @T6G_MB_LIB.T6G(SCH_1):M_B_CPU1_SA_CB(6)
   U26 AP63 MBA_CHECK6 GENOA_SP5-SOCKET6096_13568-001,SMLF,IO,DGA^6000030   I159 @T6G_MB_LIB.T6G(SCH_1):PAGE38
   J26  203  CB6_A SCONN288_DDR506112002KQ-SCONN288_DDR506112002KQ,SMA    I22 @T6G_MB_LIB.T6G(SCH_1):PAGE98

M_B_CPU1_SA_CB<7> @T6G_MB_LIB.T6G(SCH_1):M_B_CPU1_SA_CB(7)
   U26 AR62 MBA_CHECK7 GENOA_SP5-SOCKET6096_13568-001,SMLF,IO,DGA^6000030   I159 @T6G_MB_LIB.T6G(SCH_1):PAGE38
   J26  205  CB7_A SCONN288_DDR506112002KQ-SCONN288_DDR506112002KQ,SMA    I22 @T6G_MB_LIB.T6G(SCH_1):PAGE98

M_B_CPU1_SA_CS_N<0> @T6G_MB_LIB.T6G(SCH_1):M_B_CPU1_SA_CS_N(0)
   U26 AV63 MBA0_CS_L0 GENOA_SP5-SOCKET6096_13568-001,SMLF,IO,DGA^6000030   I159 @T6G_MB_LIB.T6G(SCH_1):PAGE38
   J26   64 CS0_A_N SCONN288_DDR506112002KQ-SCONN288_DDR506112002KQ,SMA    I22 @T6G_MB_LIB.T6G(SCH_1):PAGE98

M_B_CPU1_SA_CS_N<1> @T6G_MB_LIB.T6G(SCH_1):M_B_CPU1_SA_CS_N(1)
   U26 AW62 MBA0_CS_L1 GENOA_SP5-SOCKET6096_13568-001,SMLF,IO,DGA^6000030   I159 @T6G_MB_LIB.T6G(SCH_1):PAGE38
   J26  209 CS1_A_N SCONN288_DDR506112002KQ-SCONN288_DDR506112002KQ,SMA    I22 @T6G_MB_LIB.T6G(SCH_1):PAGE98

M_B_CPU1_SA_DQ<0> @T6G_MB_LIB.T6G(SCH_1):M_B_CPU1_SA_DQ(0)
   U26  E64 MBA_DATA0 GENOA_SP5-SOCKET6096_13568-001,SMLF,IO,DGA^6000030   I159 @T6G_MB_LIB.T6G(SCH_1):PAGE38
   J26    7  DQ0_A SCONN288_DDR506112002KQ-SCONN288_DDR506112002KQ,SMA    I22 @T6G_MB_LIB.T6G(SCH_1):PAGE98

M_B_CPU1_SA_DQ<10> @T6G_MB_LIB.T6G(SCH_1):M_B_CPU1_SA_DQ(10)
   U26  M63 MBA_DATA10 GENOA_SP5-SOCKET6096_13568-001,SMLF,IO,DGA^6000030   I159 @T6G_MB_LIB.T6G(SCH_1):PAGE38
   J26  163 DQ10_A SCONN288_DDR506112002KQ-SCONN288_DDR506112002KQ,SMA    I22 @T6G_MB_LIB.T6G(SCH_1):PAGE98

M_B_CPU1_SA_DQ<11> @T6G_MB_LIB.T6G(SCH_1):M_B_CPU1_SA_DQ(11)
   U26  N62 MBA_DATA11 GENOA_SP5-SOCKET6096_13568-001,SMLF,IO,DGA^6000030   I159 @T6G_MB_LIB.T6G(SCH_1):PAGE38
   J26  165 DQ11_A SCONN288_DDR506112002KQ-SCONN288_DDR506112002KQ,SMA    I22 @T6G_MB_LIB.T6G(SCH_1):PAGE98

M_B_CPU1_SA_DQ<12> @T6G_MB_LIB.T6G(SCH_1):M_B_CPU1_SA_DQ(12)
   U26  R64 MBA_DATA12 GENOA_SP5-SOCKET6096_13568-001,SMLF,IO,DGA^6000030   I159 @T6G_MB_LIB.T6G(SCH_1):PAGE38
   J26   25 DQ12_A SCONN288_DDR506112002KQ-SCONN288_DDR506112002KQ,SMA    I22 @T6G_MB_LIB.T6G(SCH_1):PAGE98

M_B_CPU1_SA_DQ<13> @T6G_MB_LIB.T6G(SCH_1):M_B_CPU1_SA_DQ(13)
   U26  T62 MBA_DATA13 GENOA_SP5-SOCKET6096_13568-001,SMLF,IO,DGA^6000030   I159 @T6G_MB_LIB.T6G(SCH_1):PAGE38
   J26   27 DQ13_A SCONN288_DDR506112002KQ-SCONN288_DDR506112002KQ,SMA    I22 @T6G_MB_LIB.T6G(SCH_1):PAGE98

M_B_CPU1_SA_DQ<14> @T6G_MB_LIB.T6G(SCH_1):M_B_CPU1_SA_DQ(14)
   U26  T63 MBA_DATA14 GENOA_SP5-SOCKET6096_13568-001,SMLF,IO,DGA^6000030   I159 @T6G_MB_LIB.T6G(SCH_1):PAGE38
   J26  170 DQ14_A SCONN288_DDR506112002KQ-SCONN288_DDR506112002KQ,SMA    I22 @T6G_MB_LIB.T6G(SCH_1):PAGE98

M_B_CPU1_SA_DQ<15> @T6G_MB_LIB.T6G(SCH_1):M_B_CPU1_SA_DQ(15)
   U26  U62 MBA_DATA15 GENOA_SP5-SOCKET6096_13568-001,SMLF,IO,DGA^6000030   I159 @T6G_MB_LIB.T6G(SCH_1):PAGE38
   J26  172 DQ15_A SCONN288_DDR506112002KQ-SCONN288_DDR506112002KQ,SMA    I22 @T6G_MB_LIB.T6G(SCH_1):PAGE98

M_B_CPU1_SA_DQ<16> @T6G_MB_LIB.T6G(SCH_1):M_B_CPU1_SA_DQ(16)
   U26  U64 MBA_DATA16 GENOA_SP5-SOCKET6096_13568-001,SMLF,IO,DGA^6000030   I159 @T6G_MB_LIB.T6G(SCH_1):PAGE38
   J26   29 DQ16_A SCONN288_DDR506112002KQ-SCONN288_DDR506112002KQ,SMA    I22 @T6G_MB_LIB.T6G(SCH_1):PAGE98

M_B_CPU1_SA_DQ<17> @T6G_MB_LIB.T6G(SCH_1):M_B_CPU1_SA_DQ(17)
   U26  V62 MBA_DATA17 GENOA_SP5-SOCKET6096_13568-001,SMLF,IO,DGA^6000030   I159 @T6G_MB_LIB.T6G(SCH_1):PAGE38
   J26   31 DQ17_A SCONN288_DDR506112002KQ-SCONN288_DDR506112002KQ,SMA    I22 @T6G_MB_LIB.T6G(SCH_1):PAGE98

M_B_CPU1_SA_DQ<18> @T6G_MB_LIB.T6G(SCH_1):M_B_CPU1_SA_DQ(18)
   U26  V63 MBA_DATA18 GENOA_SP5-SOCKET6096_13568-001,SMLF,IO,DGA^6000030   I159 @T6G_MB_LIB.T6G(SCH_1):PAGE38
   J26  174 DQ18_A SCONN288_DDR506112002KQ-SCONN288_DDR506112002KQ,SMA    I22 @T6G_MB_LIB.T6G(SCH_1):PAGE98

M_B_CPU1_SA_DQ<19> @T6G_MB_LIB.T6G(SCH_1):M_B_CPU1_SA_DQ(19)
   U26  W62 MBA_DATA19 GENOA_SP5-SOCKET6096_13568-001,SMLF,IO,DGA^6000030   I159 @T6G_MB_LIB.T6G(SCH_1):PAGE38
   J26  176 DQ19_A SCONN288_DDR506112002KQ-SCONN288_DDR506112002KQ,SMA    I22 @T6G_MB_LIB.T6G(SCH_1):PAGE98

M_B_CPU1_SA_DQ<1> @T6G_MB_LIB.T6G(SCH_1):M_B_CPU1_SA_DQ(1)
   U26  F62 MBA_DATA1 GENOA_SP5-SOCKET6096_13568-001,SMLF,IO,DGA^6000030   I159 @T6G_MB_LIB.T6G(SCH_1):PAGE38
   J26    9  DQ1_A SCONN288_DDR506112002KQ-SCONN288_DDR506112002KQ,SMA    I22 @T6G_MB_LIB.T6G(SCH_1):PAGE98

M_B_CPU1_SA_DQ<20> @T6G_MB_LIB.T6G(SCH_1):M_B_CPU1_SA_DQ(20)
   U26 AA64 MBA_DATA20 GENOA_SP5-SOCKET6096_13568-001,SMLF,IO,DGA^6000030   I159 @T6G_MB_LIB.T6G(SCH_1):PAGE38
   J26   36 DQ20_A SCONN288_DDR506112002KQ-SCONN288_DDR506112002KQ,SMA    I22 @T6G_MB_LIB.T6G(SCH_1):PAGE98

M_B_CPU1_SA_DQ<21> @T6G_MB_LIB.T6G(SCH_1):M_B_CPU1_SA_DQ(21)
   U26 AB62 MBA_DATA21 GENOA_SP5-SOCKET6096_13568-001,SMLF,IO,DGA^6000030   I159 @T6G_MB_LIB.T6G(SCH_1):PAGE38
   J26   38 DQ21_A SCONN288_DDR506112002KQ-SCONN288_DDR506112002KQ,SMA    I22 @T6G_MB_LIB.T6G(SCH_1):PAGE98

M_B_CPU1_SA_DQ<22> @T6G_MB_LIB.T6G(SCH_1):M_B_CPU1_SA_DQ(22)
   U26 AB63 MBA_DATA22 GENOA_SP5-SOCKET6096_13568-001,SMLF,IO,DGA^6000030   I159 @T6G_MB_LIB.T6G(SCH_1):PAGE38
   J26  181 DQ22_A SCONN288_DDR506112002KQ-SCONN288_DDR506112002KQ,SMA    I22 @T6G_MB_LIB.T6G(SCH_1):PAGE98

M_B_CPU1_SA_DQ<23> @T6G_MB_LIB.T6G(SCH_1):M_B_CPU1_SA_DQ(23)
   U26 AC62 MBA_DATA23 GENOA_SP5-SOCKET6096_13568-001,SMLF,IO,DGA^6000030   I159 @T6G_MB_LIB.T6G(SCH_1):PAGE38
   J26  183 DQ23_A SCONN288_DDR506112002KQ-SCONN288_DDR506112002KQ,SMA    I22 @T6G_MB_LIB.T6G(SCH_1):PAGE98

M_B_CPU1_SA_DQ<24> @T6G_MB_LIB.T6G(SCH_1):M_B_CPU1_SA_DQ(24)
   U26 AC64 MBA_DATA24 GENOA_SP5-SOCKET6096_13568-001,SMLF,IO,DGA^6000030   I159 @T6G_MB_LIB.T6G(SCH_1):PAGE38
   J26   40 DQ24_A SCONN288_DDR506112002KQ-SCONN288_DDR506112002KQ,SMA    I22 @T6G_MB_LIB.T6G(SCH_1):PAGE98

M_B_CPU1_SA_DQ<25> @T6G_MB_LIB.T6G(SCH_1):M_B_CPU1_SA_DQ(25)
   U26 AD62 MBA_DATA25 GENOA_SP5-SOCKET6096_13568-001,SMLF,IO,DGA^6000030   I159 @T6G_MB_LIB.T6G(SCH_1):PAGE38
   J26   42 DQ25_A SCONN288_DDR506112002KQ-SCONN288_DDR506112002KQ,SMA    I22 @T6G_MB_LIB.T6G(SCH_1):PAGE98

M_B_CPU1_SA_DQ<26> @T6G_MB_LIB.T6G(SCH_1):M_B_CPU1_SA_DQ(26)
   U26 AD63 MBA_DATA26 GENOA_SP5-SOCKET6096_13568-001,SMLF,IO,DGA^6000030   I159 @T6G_MB_LIB.T6G(SCH_1):PAGE38
   J26  185 DQ26_A SCONN288_DDR506112002KQ-SCONN288_DDR506112002KQ,SMA    I22 @T6G_MB_LIB.T6G(SCH_1):PAGE98

M_B_CPU1_SA_DQ<27> @T6G_MB_LIB.T6G(SCH_1):M_B_CPU1_SA_DQ(27)
   U26 AE62 MBA_DATA27 GENOA_SP5-SOCKET6096_13568-001,SMLF,IO,DGA^6000030   I159 @T6G_MB_LIB.T6G(SCH_1):PAGE38
   J26  187 DQ27_A SCONN288_DDR506112002KQ-SCONN288_DDR506112002KQ,SMA    I22 @T6G_MB_LIB.T6G(SCH_1):PAGE98

M_B_CPU1_SA_DQ<28> @T6G_MB_LIB.T6G(SCH_1):M_B_CPU1_SA_DQ(28)
   U26 AG64 MBA_DATA28 GENOA_SP5-SOCKET6096_13568-001,SMLF,IO,DGA^6000030   I159 @T6G_MB_LIB.T6G(SCH_1):PAGE38
   J26   47 DQ28_A SCONN288_DDR506112002KQ-SCONN288_DDR506112002KQ,SMA    I22 @T6G_MB_LIB.T6G(SCH_1):PAGE98

M_B_CPU1_SA_DQ<29> @T6G_MB_LIB.T6G(SCH_1):M_B_CPU1_SA_DQ(29)
   U26 AH62 MBA_DATA29 GENOA_SP5-SOCKET6096_13568-001,SMLF,IO,DGA^6000030   I159 @T6G_MB_LIB.T6G(SCH_1):PAGE38
   J26   49 DQ29_A SCONN288_DDR506112002KQ-SCONN288_DDR506112002KQ,SMA    I22 @T6G_MB_LIB.T6G(SCH_1):PAGE98

M_B_CPU1_SA_DQ<2> @T6G_MB_LIB.T6G(SCH_1):M_B_CPU1_SA_DQ(2)
   U26  F63 MBA_DATA2 GENOA_SP5-SOCKET6096_13568-001,SMLF,IO,DGA^6000030   I159 @T6G_MB_LIB.T6G(SCH_1):PAGE38
   J26  152  DQ2_A SCONN288_DDR506112002KQ-SCONN288_DDR506112002KQ,SMA    I22 @T6G_MB_LIB.T6G(SCH_1):PAGE98

M_B_CPU1_SA_DQ<30> @T6G_MB_LIB.T6G(SCH_1):M_B_CPU1_SA_DQ(30)
   U26 AH63 MBA_DATA30 GENOA_SP5-SOCKET6096_13568-001,SMLF,IO,DGA^6000030   I159 @T6G_MB_LIB.T6G(SCH_1):PAGE38
   J26  192 DQ30_A SCONN288_DDR506112002KQ-SCONN288_DDR506112002KQ,SMA    I22 @T6G_MB_LIB.T6G(SCH_1):PAGE98

M_B_CPU1_SA_DQ<31> @T6G_MB_LIB.T6G(SCH_1):M_B_CPU1_SA_DQ(31)
   U26 AJ62 MBA_DATA31 GENOA_SP5-SOCKET6096_13568-001,SMLF,IO,DGA^6000030   I159 @T6G_MB_LIB.T6G(SCH_1):PAGE38
   J26  194 DQ31_A SCONN288_DDR506112002KQ-SCONN288_DDR506112002KQ,SMA    I22 @T6G_MB_LIB.T6G(SCH_1):PAGE98

M_B_CPU1_SA_DQ<3> @T6G_MB_LIB.T6G(SCH_1):M_B_CPU1_SA_DQ(3)
   U26  G62 MBA_DATA3 GENOA_SP5-SOCKET6096_13568-001,SMLF,IO,DGA^6000030   I159 @T6G_MB_LIB.T6G(SCH_1):PAGE38
   J26  154  DQ3_A SCONN288_DDR506112002KQ-SCONN288_DDR506112002KQ,SMA    I22 @T6G_MB_LIB.T6G(SCH_1):PAGE98

M_B_CPU1_SA_DQ<4> @T6G_MB_LIB.T6G(SCH_1):M_B_CPU1_SA_DQ(4)
   U26  J64 MBA_DATA4 GENOA_SP5-SOCKET6096_13568-001,SMLF,IO,DGA^6000030   I159 @T6G_MB_LIB.T6G(SCH_1):PAGE38
   J26   14  DQ4_A SCONN288_DDR506112002KQ-SCONN288_DDR506112002KQ,SMA    I22 @T6G_MB_LIB.T6G(SCH_1):PAGE98

M_B_CPU1_SA_DQ<5> @T6G_MB_LIB.T6G(SCH_1):M_B_CPU1_SA_DQ(5)
   U26  K62 MBA_DATA5 GENOA_SP5-SOCKET6096_13568-001,SMLF,IO,DGA^6000030   I159 @T6G_MB_LIB.T6G(SCH_1):PAGE38
   J26   16  DQ5_A SCONN288_DDR506112002KQ-SCONN288_DDR506112002KQ,SMA    I22 @T6G_MB_LIB.T6G(SCH_1):PAGE98

M_B_CPU1_SA_DQ<6> @T6G_MB_LIB.T6G(SCH_1):M_B_CPU1_SA_DQ(6)
   U26  K63 MBA_DATA6 GENOA_SP5-SOCKET6096_13568-001,SMLF,IO,DGA^6000030   I159 @T6G_MB_LIB.T6G(SCH_1):PAGE38
   J26  159  DQ6_A SCONN288_DDR506112002KQ-SCONN288_DDR506112002KQ,SMA    I22 @T6G_MB_LIB.T6G(SCH_1):PAGE98

M_B_CPU1_SA_DQ<7> @T6G_MB_LIB.T6G(SCH_1):M_B_CPU1_SA_DQ(7)
   U26  L62 MBA_DATA7 GENOA_SP5-SOCKET6096_13568-001,SMLF,IO,DGA^6000030   I159 @T6G_MB_LIB.T6G(SCH_1):PAGE38
   J26  161  DQ7_A SCONN288_DDR506112002KQ-SCONN288_DDR506112002KQ,SMA    I22 @T6G_MB_LIB.T6G(SCH_1):PAGE98

M_B_CPU1_SA_DQ<8> @T6G_MB_LIB.T6G(SCH_1):M_B_CPU1_SA_DQ(8)
   U26  L64 MBA_DATA8 GENOA_SP5-SOCKET6096_13568-001,SMLF,IO,DGA^6000030   I159 @T6G_MB_LIB.T6G(SCH_1):PAGE38
   J26   18  DQ8_A SCONN288_DDR506112002KQ-SCONN288_DDR506112002KQ,SMA    I22 @T6G_MB_LIB.T6G(SCH_1):PAGE98

M_B_CPU1_SA_DQ<9> @T6G_MB_LIB.T6G(SCH_1):M_B_CPU1_SA_DQ(9)
   U26  M62 MBA_DATA9 GENOA_SP5-SOCKET6096_13568-001,SMLF,IO,DGA^6000030   I159 @T6G_MB_LIB.T6G(SCH_1):PAGE38
   J26   20  DQ9_A SCONN288_DDR506112002KQ-SCONN288_DDR506112002KQ,SMA    I22 @T6G_MB_LIB.T6G(SCH_1):PAGE98

M_B_CPU1_SA_DQS_DN<0> @T6G_MB_LIB.T6G(SCH_1):M_B_CPU1_SA_DQS_DN(0)
   U26  H63 MBA_DQS_L0 GENOA_SP5-SOCKET6096_13568-001,SMLF,IO,DGA^6000030   I159 @T6G_MB_LIB.T6G(SCH_1):PAGE38
   J26   12 DQS0_A_C SCONN288_DDR506112002KQ-SCONN288_DDR506112002KQ,SMA   I236 @T6G_MB_LIB.T6G(SCH_1):PAGE98

M_B_CPU1_SA_DQS_DN<1> @T6G_MB_LIB.T6G(SCH_1):M_B_CPU1_SA_DQS_DN(1)
   U26  P63 MBA_DQS_L1 GENOA_SP5-SOCKET6096_13568-001,SMLF,IO,DGA^6000030   I159 @T6G_MB_LIB.T6G(SCH_1):PAGE38
   J26   23 DQS1_A_C SCONN288_DDR506112002KQ-SCONN288_DDR506112002KQ,SMA   I236 @T6G_MB_LIB.T6G(SCH_1):PAGE98

M_B_CPU1_SA_DQS_DN<2> @T6G_MB_LIB.T6G(SCH_1):M_B_CPU1_SA_DQS_DN(2)
   U26  Y63 MBA_DQS_L2 GENOA_SP5-SOCKET6096_13568-001,SMLF,IO,DGA^6000030   I159 @T6G_MB_LIB.T6G(SCH_1):PAGE38
   J26   34 DQS2_A_C SCONN288_DDR506112002KQ-SCONN288_DDR506112002KQ,SMA   I236 @T6G_MB_LIB.T6G(SCH_1):PAGE98

M_B_CPU1_SA_DQS_DN<3> @T6G_MB_LIB.T6G(SCH_1):M_B_CPU1_SA_DQS_DN(3)
   U26 AF63 MBA_DQS_L3 GENOA_SP5-SOCKET6096_13568-001,SMLF,IO,DGA^6000030   I159 @T6G_MB_LIB.T6G(SCH_1):PAGE38
   J26   45 DQS3_A_C SCONN288_DDR506112002KQ-SCONN288_DDR506112002KQ,SMA   I236 @T6G_MB_LIB.T6G(SCH_1):PAGE98

M_B_CPU1_SA_DQS_DN<4> @T6G_MB_LIB.T6G(SCH_1):M_B_CPU1_SA_DQS_DN(4)
   U26 AM63 MBA_DQS_L4 GENOA_SP5-SOCKET6096_13568-001,SMLF,IO,DGA^6000030   I159 @T6G_MB_LIB.T6G(SCH_1):PAGE38
   J26   56 DQS4_A_C SCONN288_DDR506112002KQ-SCONN288_DDR506112002KQ,SMA   I236 @T6G_MB_LIB.T6G(SCH_1):PAGE98

M_B_CPU1_SA_DQS_DN<5> @T6G_MB_LIB.T6G(SCH_1):M_B_CPU1_SA_DQS_DN(5)
   U26  H62 MBA_DQS_L5 GENOA_SP5-SOCKET6096_13568-001,SMLF,IO,DGA^6000030   I159 @T6G_MB_LIB.T6G(SCH_1):PAGE38
   J26  156 DQS5_A_C||TDQS5_A_C||DQS5_A_T||TDQS5_A_T SCONN288_DDR506112002KQ-SCONN288_DDR506112002KQ,SMA   I236 @T6G_MB_LIB.T6G(SCH_1):PAGE98

M_B_CPU1_SA_DQS_DN<6> @T6G_MB_LIB.T6G(SCH_1):M_B_CPU1_SA_DQS_DN(6)
   U26  P62 MBA_DQS_L6 GENOA_SP5-SOCKET6096_13568-001,SMLF,IO,DGA^6000030   I159 @T6G_MB_LIB.T6G(SCH_1):PAGE38
   J26  167 DQS6_A_C||TDQS6_A_C||DQS6_A_T||TDQS6_A_T SCONN288_DDR506112002KQ-SCONN288_DDR506112002KQ,SMA   I236 @T6G_MB_LIB.T6G(SCH_1):PAGE98

M_B_CPU1_SA_DQS_DN<7> @T6G_MB_LIB.T6G(SCH_1):M_B_CPU1_SA_DQS_DN(7)
   U26  Y62 MBA_DQS_L7 GENOA_SP5-SOCKET6096_13568-001,SMLF,IO,DGA^6000030   I159 @T6G_MB_LIB.T6G(SCH_1):PAGE38
   J26  178 DQS7_A_C||TDQS7_A_C SCONN288_DDR506112002KQ-SCONN288_DDR506112002KQ,SMA   I236 @T6G_MB_LIB.T6G(SCH_1):PAGE98

M_B_CPU1_SA_DQS_DN<8> @T6G_MB_LIB.T6G(SCH_1):M_B_CPU1_SA_DQS_DN(8)
   U26 AF62 MBA_DQS_L8 GENOA_SP5-SOCKET6096_13568-001,SMLF,IO,DGA^6000030   I159 @T6G_MB_LIB.T6G(SCH_1):PAGE38
   J26  189 DQS8_A_C||TDQS8_A_C SCONN288_DDR506112002KQ-SCONN288_DDR506112002KQ,SMA   I236 @T6G_MB_LIB.T6G(SCH_1):PAGE98

M_B_CPU1_SA_DQS_DN<9> @T6G_MB_LIB.T6G(SCH_1):M_B_CPU1_SA_DQS_DN(9)
   U26 AM62 MBA_DQS_L9 GENOA_SP5-SOCKET6096_13568-001,SMLF,IO,DGA^6000030   I159 @T6G_MB_LIB.T6G(SCH_1):PAGE38
   J26  200 DQS9_A_C||TDQS9_A_C SCONN288_DDR506112002KQ-SCONN288_DDR506112002KQ,SMA   I236 @T6G_MB_LIB.T6G(SCH_1):PAGE98

M_B_CPU1_SA_DQS_DP<0> @T6G_MB_LIB.T6G(SCH_1):M_B_CPU1_SA_DQS_DP(0)
   U26  G64 MBA_DQS_H0 GENOA_SP5-SOCKET6096_13568-001,SMLF,IO,DGA^6000030   I159 @T6G_MB_LIB.T6G(SCH_1):PAGE38
   J26   11 DQS0_A_T SCONN288_DDR506112002KQ-SCONN288_DDR506112002KQ,SMA   I236 @T6G_MB_LIB.T6G(SCH_1):PAGE98

M_B_CPU1_SA_DQS_DP<1> @T6G_MB_LIB.T6G(SCH_1):M_B_CPU1_SA_DQS_DP(1)
   U26  N64 MBA_DQS_H1 GENOA_SP5-SOCKET6096_13568-001,SMLF,IO,DGA^6000030   I159 @T6G_MB_LIB.T6G(SCH_1):PAGE38
   J26   22 DQS1_A_T SCONN288_DDR506112002KQ-SCONN288_DDR506112002KQ,SMA   I236 @T6G_MB_LIB.T6G(SCH_1):PAGE98

M_B_CPU1_SA_DQS_DP<2> @T6G_MB_LIB.T6G(SCH_1):M_B_CPU1_SA_DQS_DP(2)
   U26  W64 MBA_DQS_H2 GENOA_SP5-SOCKET6096_13568-001,SMLF,IO,DGA^6000030   I159 @T6G_MB_LIB.T6G(SCH_1):PAGE38
   J26   33 DQS2_A_T SCONN288_DDR506112002KQ-SCONN288_DDR506112002KQ,SMA   I236 @T6G_MB_LIB.T6G(SCH_1):PAGE98

M_B_CPU1_SA_DQS_DP<3> @T6G_MB_LIB.T6G(SCH_1):M_B_CPU1_SA_DQS_DP(3)
   U26 AE64 MBA_DQS_H3 GENOA_SP5-SOCKET6096_13568-001,SMLF,IO,DGA^6000030   I159 @T6G_MB_LIB.T6G(SCH_1):PAGE38
   J26   44 DQS3_A_T SCONN288_DDR506112002KQ-SCONN288_DDR506112002KQ,SMA   I236 @T6G_MB_LIB.T6G(SCH_1):PAGE98

M_B_CPU1_SA_DQS_DP<4> @T6G_MB_LIB.T6G(SCH_1):M_B_CPU1_SA_DQS_DP(4)
   U26 AL64 MBA_DQS_H4 GENOA_SP5-SOCKET6096_13568-001,SMLF,IO,DGA^6000030   I159 @T6G_MB_LIB.T6G(SCH_1):PAGE38
   J26   55 DQS4_A_T SCONN288_DDR506112002KQ-SCONN288_DDR506112002KQ,SMA   I236 @T6G_MB_LIB.T6G(SCH_1):PAGE98

M_B_CPU1_SA_DQS_DP<5> @T6G_MB_LIB.T6G(SCH_1):M_B_CPU1_SA_DQS_DP(5)
   U26  J62 MBA_DQS_H5 GENOA_SP5-SOCKET6096_13568-001,SMLF,IO,DGA^6000030   I159 @T6G_MB_LIB.T6G(SCH_1):PAGE38
   J26  157 DQS5_A_T||TDQS5_A_T SCONN288_DDR506112002KQ-SCONN288_DDR506112002KQ,SMA   I236 @T6G_MB_LIB.T6G(SCH_1):PAGE98

M_B_CPU1_SA_DQS_DP<6> @T6G_MB_LIB.T6G(SCH_1):M_B_CPU1_SA_DQS_DP(6)
   U26  R62 MBA_DQS_H6 GENOA_SP5-SOCKET6096_13568-001,SMLF,IO,DGA^6000030   I159 @T6G_MB_LIB.T6G(SCH_1):PAGE38
   J26  168 DQS6_A_T||TDQS6_A_T SCONN288_DDR506112002KQ-SCONN288_DDR506112002KQ,SMA   I236 @T6G_MB_LIB.T6G(SCH_1):PAGE98

M_B_CPU1_SA_DQS_DP<7> @T6G_MB_LIB.T6G(SCH_1):M_B_CPU1_SA_DQS_DP(7)
   U26 AA62 MBA_DQS_H7 GENOA_SP5-SOCKET6096_13568-001,SMLF,IO,DGA^6000030   I159 @T6G_MB_LIB.T6G(SCH_1):PAGE38
   J26  179 DQS7_A_T||TDQS7_A_T SCONN288_DDR506112002KQ-SCONN288_DDR506112002KQ,SMA   I236 @T6G_MB_LIB.T6G(SCH_1):PAGE98

M_B_CPU1_SA_DQS_DP<8> @T6G_MB_LIB.T6G(SCH_1):M_B_CPU1_SA_DQS_DP(8)
   U26 AG62 MBA_DQS_H8 GENOA_SP5-SOCKET6096_13568-001,SMLF,IO,DGA^6000030   I159 @T6G_MB_LIB.T6G(SCH_1):PAGE38
   J26  190 DQS8_A_T||TDQS8_A_T SCONN288_DDR506112002KQ-SCONN288_DDR506112002KQ,SMA   I236 @T6G_MB_LIB.T6G(SCH_1):PAGE98

M_B_CPU1_SA_DQS_DP<9> @T6G_MB_LIB.T6G(SCH_1):M_B_CPU1_SA_DQS_DP(9)
   U26 AN62 MBA_DQS_H9 GENOA_SP5-SOCKET6096_13568-001,SMLF,IO,DGA^6000030   I159 @T6G_MB_LIB.T6G(SCH_1):PAGE38
   J26  201 DQS9_A_T||TDQS9_A_T SCONN288_DDR506112002KQ-SCONN288_DDR506112002KQ,SMA   I236 @T6G_MB_LIB.T6G(SCH_1):PAGE98

M_B_CPU1_SA_PAR @T6G_MB_LIB.T6G(SCH_1):M_B_CPU1_SA_PAR
   U26 BC62 MBA_PAR GENOA_SP5-SOCKET6096_13568-001,SMLF,IO,DGA^6000030   I159 @T6G_MB_LIB.T6G(SCH_1):PAGE38
   J26   74  PAR_A SCONN288_DDR506112002KQ-SCONN288_DDR506112002KQ,SMA    I22 @T6G_MB_LIB.T6G(SCH_1):PAGE98

M_B_CPU1_SA_RSP<0> @T6G_MB_LIB.T6G(SCH_1):M_B_CPU1_SA_RSP(0)
   U26 BN62 MBA0_RSP_L GENOA_SP5-SOCKET6096_13568-001,SMLF,IO,DGA^6000030   I159 @T6G_MB_LIB.T6G(SCH_1):PAGE38
   J26   86 LBD||RSP_A_N SCONN288_DDR506112002KQ-SCONN288_DDR506112002KQ,SMA    I22 @T6G_MB_LIB.T6G(SCH_1):PAGE98

M_B_CPU1_SB_CA<0> @T6G_MB_LIB.T6G(SCH_1):M_B_CPU1_SB_CA(0)
   U26 BG62 MBB_CA0 GENOA_SP5-SOCKET6096_13568-001,SMLF,IO,DGA^6000030   I159 @T6G_MB_LIB.T6G(SCH_1):PAGE38
   J26   76  CA0_B SCONN288_DDR506112002KQ-SCONN288_DDR506112002KQ,SMA    I22 @T6G_MB_LIB.T6G(SCH_1):PAGE98

M_B_CPU1_SB_CA<1> @T6G_MB_LIB.T6G(SCH_1):M_B_CPU1_SB_CA(1)
   U26 BH62 MBB_CA1 GENOA_SP5-SOCKET6096_13568-001,SMLF,IO,DGA^6000030   I159 @T6G_MB_LIB.T6G(SCH_1):PAGE38
   J26  221  CA1_B SCONN288_DDR506112002KQ-SCONN288_DDR506112002KQ,SMA    I22 @T6G_MB_LIB.T6G(SCH_1):PAGE98

M_B_CPU1_SB_CA<2> @T6G_MB_LIB.T6G(SCH_1):M_B_CPU1_SB_CA(2)
   U26 BH63 MBB_CA2 GENOA_SP5-SOCKET6096_13568-001,SMLF,IO,DGA^6000030   I159 @T6G_MB_LIB.T6G(SCH_1):PAGE38
   J26   78  CA2_B SCONN288_DDR506112002KQ-SCONN288_DDR506112002KQ,SMA    I22 @T6G_MB_LIB.T6G(SCH_1):PAGE98

M_B_CPU1_SB_CA<3> @T6G_MB_LIB.T6G(SCH_1):M_B_CPU1_SB_CA(3)
   U26 BJ64 MBB_CA3 GENOA_SP5-SOCKET6096_13568-001,SMLF,IO,DGA^6000030   I159 @T6G_MB_LIB.T6G(SCH_1):PAGE38
   J26  223  CA3_B SCONN288_DDR506112002KQ-SCONN288_DDR506112002KQ,SMA    I22 @T6G_MB_LIB.T6G(SCH_1):PAGE98

M_B_CPU1_SB_CA<4> @T6G_MB_LIB.T6G(SCH_1):M_B_CPU1_SB_CA(4)
   U26 BJ62 MBB_CA4 GENOA_SP5-SOCKET6096_13568-001,SMLF,IO,DGA^6000030   I159 @T6G_MB_LIB.T6G(SCH_1):PAGE38
   J26   80  CA4_B SCONN288_DDR506112002KQ-SCONN288_DDR506112002KQ,SMA    I22 @T6G_MB_LIB.T6G(SCH_1):PAGE98

M_B_CPU1_SB_CA<5> @T6G_MB_LIB.T6G(SCH_1):M_B_CPU1_SB_CA(5)
   U26 BK62 MBB_CA5 GENOA_SP5-SOCKET6096_13568-001,SMLF,IO,DGA^6000030   I159 @T6G_MB_LIB.T6G(SCH_1):PAGE38
   J26  225  CA5_B SCONN288_DDR506112002KQ-SCONN288_DDR506112002KQ,SMA    I22 @T6G_MB_LIB.T6G(SCH_1):PAGE98

M_B_CPU1_SB_CA<6> @T6G_MB_LIB.T6G(SCH_1):M_B_CPU1_SB_CA(6)
   U26 BK63 MBB_CA6 GENOA_SP5-SOCKET6096_13568-001,SMLF,IO,DGA^6000030   I159 @T6G_MB_LIB.T6G(SCH_1):PAGE38
   J26   82  CA6_B SCONN288_DDR506112002KQ-SCONN288_DDR506112002KQ,SMA    I22 @T6G_MB_LIB.T6G(SCH_1):PAGE98

M_B_CPU1_SB_CB<0> @T6G_MB_LIB.T6G(SCH_1):M_B_CPU1_SB_CB(0)
   U26 BY63 MBB_CHECK0 GENOA_SP5-SOCKET6096_13568-001,SMLF,IO,DGA^6000030   I159 @T6G_MB_LIB.T6G(SCH_1):PAGE38
   J26   96  CB0_B SCONN288_DDR506112002KQ-SCONN288_DDR506112002KQ,SMA    I22 @T6G_MB_LIB.T6G(SCH_1):PAGE98

M_B_CPU1_SB_CB<1> @T6G_MB_LIB.T6G(SCH_1):M_B_CPU1_SB_CB(1)
   U26 CA62 MBB_CHECK1 GENOA_SP5-SOCKET6096_13568-001,SMLF,IO,DGA^6000030   I159 @T6G_MB_LIB.T6G(SCH_1):PAGE38
   J26   98  CB1_B SCONN288_DDR506112002KQ-SCONN288_DDR506112002KQ,SMA    I22 @T6G_MB_LIB.T6G(SCH_1):PAGE98

M_B_CPU1_SB_CB<2> @T6G_MB_LIB.T6G(SCH_1):M_B_CPU1_SB_CB(2)
   U26 CA64 MBB_CHECK2 GENOA_SP5-SOCKET6096_13568-001,SMLF,IO,DGA^6000030   I159 @T6G_MB_LIB.T6G(SCH_1):PAGE38
   J26  241  CB2_B SCONN288_DDR506112002KQ-SCONN288_DDR506112002KQ,SMA    I22 @T6G_MB_LIB.T6G(SCH_1):PAGE98

M_B_CPU1_SB_CB<3> @T6G_MB_LIB.T6G(SCH_1):M_B_CPU1_SB_CB(3)
   U26 CB62 MBB_CHECK3 GENOA_SP5-SOCKET6096_13568-001,SMLF,IO,DGA^6000030   I159 @T6G_MB_LIB.T6G(SCH_1):PAGE38
   J26  243  CB3_B SCONN288_DDR506112002KQ-SCONN288_DDR506112002KQ,SMA    I22 @T6G_MB_LIB.T6G(SCH_1):PAGE98

M_B_CPU1_SB_CB<4> @T6G_MB_LIB.T6G(SCH_1):M_B_CPU1_SB_CB(4)
   U26 BT63 MBB_CHECK4 GENOA_SP5-SOCKET6096_13568-001,SMLF,IO,DGA^6000030   I159 @T6G_MB_LIB.T6G(SCH_1):PAGE38
   J26   89  CB4_B SCONN288_DDR506112002KQ-SCONN288_DDR506112002KQ,SMA    I22 @T6G_MB_LIB.T6G(SCH_1):PAGE98

M_B_CPU1_SB_CB<5> @T6G_MB_LIB.T6G(SCH_1):M_B_CPU1_SB_CB(5)
   U26 BU62 MBB_CHECK5 GENOA_SP5-SOCKET6096_13568-001,SMLF,IO,DGA^6000030   I159 @T6G_MB_LIB.T6G(SCH_1):PAGE38
   J26   91  CB5_B SCONN288_DDR506112002KQ-SCONN288_DDR506112002KQ,SMA    I22 @T6G_MB_LIB.T6G(SCH_1):PAGE98

M_B_CPU1_SB_CB<6> @T6G_MB_LIB.T6G(SCH_1):M_B_CPU1_SB_CB(6)
   U26 BU64 MBB_CHECK6 GENOA_SP5-SOCKET6096_13568-001,SMLF,IO,DGA^6000030   I159 @T6G_MB_LIB.T6G(SCH_1):PAGE38
   J26  234  CB6_B SCONN288_DDR506112002KQ-SCONN288_DDR506112002KQ,SMA    I22 @T6G_MB_LIB.T6G(SCH_1):PAGE98

M_B_CPU1_SB_CB<7> @T6G_MB_LIB.T6G(SCH_1):M_B_CPU1_SB_CB(7)
   U26 BV62 MBB_CHECK7 GENOA_SP5-SOCKET6096_13568-001,SMLF,IO,DGA^6000030   I159 @T6G_MB_LIB.T6G(SCH_1):PAGE38
   J26  236  CB7_B SCONN288_DDR506112002KQ-SCONN288_DDR506112002KQ,SMA    I22 @T6G_MB_LIB.T6G(SCH_1):PAGE98

M_B_CPU1_SB_CS_N<0> @T6G_MB_LIB.T6G(SCH_1):M_B_CPU1_SB_CS_N(0)
   U26 BM62 MBB0_CS_L0 GENOA_SP5-SOCKET6096_13568-001,SMLF,IO,DGA^6000030   I159 @T6G_MB_LIB.T6G(SCH_1):PAGE38
   J26   84 CS0_B_N SCONN288_DDR506112002KQ-SCONN288_DDR506112002KQ,SMA    I22 @T6G_MB_LIB.T6G(SCH_1):PAGE98

M_B_CPU1_SB_CS_N<1> @T6G_MB_LIB.T6G(SCH_1):M_B_CPU1_SB_CS_N(1)
   U26 BN64 MBB0_CS_L1 GENOA_SP5-SOCKET6096_13568-001,SMLF,IO,DGA^6000030   I159 @T6G_MB_LIB.T6G(SCH_1):PAGE38
   J26  229 CS1_B_N SCONN288_DDR506112002KQ-SCONN288_DDR506112002KQ,SMA    I22 @T6G_MB_LIB.T6G(SCH_1):PAGE98

M_B_CPU1_SB_DQ<0> @T6G_MB_LIB.T6G(SCH_1):M_B_CPU1_SB_DQ(0)
   U26 CB63 MBB_DATA0 GENOA_SP5-SOCKET6096_13568-001,SMLF,IO,DGA^6000030   I159 @T6G_MB_LIB.T6G(SCH_1):PAGE38
   J26  100  DQ0_B SCONN288_DDR506112002KQ-SCONN288_DDR506112002KQ,SMA    I22 @T6G_MB_LIB.T6G(SCH_1):PAGE98

M_B_CPU1_SB_DQ<10> @T6G_MB_LIB.T6G(SCH_1):M_B_CPU1_SB_DQ(10)
   U26 CJ64 MBB_DATA10 GENOA_SP5-SOCKET6096_13568-001,SMLF,IO,DGA^6000030   I159 @T6G_MB_LIB.T6G(SCH_1):PAGE38
   J26  256 DQ10_B SCONN288_DDR506112002KQ-SCONN288_DDR506112002KQ,SMA    I22 @T6G_MB_LIB.T6G(SCH_1):PAGE98

M_B_CPU1_SB_DQ<11> @T6G_MB_LIB.T6G(SCH_1):M_B_CPU1_SB_DQ(11)
   U26 CK62 MBB_DATA11 GENOA_SP5-SOCKET6096_13568-001,SMLF,IO,DGA^6000030   I159 @T6G_MB_LIB.T6G(SCH_1):PAGE38
   J26  258 DQ11_B SCONN288_DDR506112002KQ-SCONN288_DDR506112002KQ,SMA    I22 @T6G_MB_LIB.T6G(SCH_1):PAGE98

M_B_CPU1_SB_DQ<12> @T6G_MB_LIB.T6G(SCH_1):M_B_CPU1_SB_DQ(12)
   U26 CM63 MBB_DATA12 GENOA_SP5-SOCKET6096_13568-001,SMLF,IO,DGA^6000030   I159 @T6G_MB_LIB.T6G(SCH_1):PAGE38
   J26  118 DQ12_B SCONN288_DDR506112002KQ-SCONN288_DDR506112002KQ,SMA    I22 @T6G_MB_LIB.T6G(SCH_1):PAGE98

M_B_CPU1_SB_DQ<13> @T6G_MB_LIB.T6G(SCH_1):M_B_CPU1_SB_DQ(13)
   U26 CN62 MBB_DATA13 GENOA_SP5-SOCKET6096_13568-001,SMLF,IO,DGA^6000030   I159 @T6G_MB_LIB.T6G(SCH_1):PAGE38
   J26  120 DQ13_B SCONN288_DDR506112002KQ-SCONN288_DDR506112002KQ,SMA    I22 @T6G_MB_LIB.T6G(SCH_1):PAGE98

M_B_CPU1_SB_DQ<14> @T6G_MB_LIB.T6G(SCH_1):M_B_CPU1_SB_DQ(14)
   U26 CN64 MBB_DATA14 GENOA_SP5-SOCKET6096_13568-001,SMLF,IO,DGA^6000030   I159 @T6G_MB_LIB.T6G(SCH_1):PAGE38
   J26  263 DQ14_B SCONN288_DDR506112002KQ-SCONN288_DDR506112002KQ,SMA    I22 @T6G_MB_LIB.T6G(SCH_1):PAGE98

M_B_CPU1_SB_DQ<15> @T6G_MB_LIB.T6G(SCH_1):M_B_CPU1_SB_DQ(15)
   U26 CP62 MBB_DATA15 GENOA_SP5-SOCKET6096_13568-001,SMLF,IO,DGA^6000030   I159 @T6G_MB_LIB.T6G(SCH_1):PAGE38
   J26  265 DQ15_B SCONN288_DDR506112002KQ-SCONN288_DDR506112002KQ,SMA    I22 @T6G_MB_LIB.T6G(SCH_1):PAGE98

M_B_CPU1_SB_DQ<16> @T6G_MB_LIB.T6G(SCH_1):M_B_CPU1_SB_DQ(16)
   U26 CP63 MBB_DATA16 GENOA_SP5-SOCKET6096_13568-001,SMLF,IO,DGA^6000030   I159 @T6G_MB_LIB.T6G(SCH_1):PAGE38
   J26  122 DQ16_B SCONN288_DDR506112002KQ-SCONN288_DDR506112002KQ,SMA    I22 @T6G_MB_LIB.T6G(SCH_1):PAGE98

M_B_CPU1_SB_DQ<17> @T6G_MB_LIB.T6G(SCH_1):M_B_CPU1_SB_DQ(17)
   U26 CR62 MBB_DATA17 GENOA_SP5-SOCKET6096_13568-001,SMLF,IO,DGA^6000030   I159 @T6G_MB_LIB.T6G(SCH_1):PAGE38
   J26  124 DQ17_B SCONN288_DDR506112002KQ-SCONN288_DDR506112002KQ,SMA    I22 @T6G_MB_LIB.T6G(SCH_1):PAGE98

M_B_CPU1_SB_DQ<18> @T6G_MB_LIB.T6G(SCH_1):M_B_CPU1_SB_DQ(18)
   U26 CR64 MBB_DATA18 GENOA_SP5-SOCKET6096_13568-001,SMLF,IO,DGA^6000030   I159 @T6G_MB_LIB.T6G(SCH_1):PAGE38
   J26  267 DQ18_B SCONN288_DDR506112002KQ-SCONN288_DDR506112002KQ,SMA    I22 @T6G_MB_LIB.T6G(SCH_1):PAGE98

M_B_CPU1_SB_DQ<19> @T6G_MB_LIB.T6G(SCH_1):M_B_CPU1_SB_DQ(19)
   U26 CT62 MBB_DATA19 GENOA_SP5-SOCKET6096_13568-001,SMLF,IO,DGA^6000030   I159 @T6G_MB_LIB.T6G(SCH_1):PAGE38
   J26  269 DQ19_B SCONN288_DDR506112002KQ-SCONN288_DDR506112002KQ,SMA    I22 @T6G_MB_LIB.T6G(SCH_1):PAGE98

M_B_CPU1_SB_DQ<1> @T6G_MB_LIB.T6G(SCH_1):M_B_CPU1_SB_DQ(1)
   U26 CC62 MBB_DATA1 GENOA_SP5-SOCKET6096_13568-001,SMLF,IO,DGA^6000030   I159 @T6G_MB_LIB.T6G(SCH_1):PAGE38
   J26  102  DQ1_B SCONN288_DDR506112002KQ-SCONN288_DDR506112002KQ,SMA    I22 @T6G_MB_LIB.T6G(SCH_1):PAGE98

M_B_CPU1_SB_DQ<20> @T6G_MB_LIB.T6G(SCH_1):M_B_CPU1_SB_DQ(20)
   U26 CV63 MBB_DATA20 GENOA_SP5-SOCKET6096_13568-001,SMLF,IO,DGA^6000030   I159 @T6G_MB_LIB.T6G(SCH_1):PAGE38
   J26  129 DQ20_B SCONN288_DDR506112002KQ-SCONN288_DDR506112002KQ,SMA    I22 @T6G_MB_LIB.T6G(SCH_1):PAGE98

M_B_CPU1_SB_DQ<21> @T6G_MB_LIB.T6G(SCH_1):M_B_CPU1_SB_DQ(21)
   U26 CW62 MBB_DATA21 GENOA_SP5-SOCKET6096_13568-001,SMLF,IO,DGA^6000030   I159 @T6G_MB_LIB.T6G(SCH_1):PAGE38
   J26  131 DQ21_B SCONN288_DDR506112002KQ-SCONN288_DDR506112002KQ,SMA    I22 @T6G_MB_LIB.T6G(SCH_1):PAGE98

M_B_CPU1_SB_DQ<22> @T6G_MB_LIB.T6G(SCH_1):M_B_CPU1_SB_DQ(22)
   U26 CW64 MBB_DATA22 GENOA_SP5-SOCKET6096_13568-001,SMLF,IO,DGA^6000030   I159 @T6G_MB_LIB.T6G(SCH_1):PAGE38
   J26  274 DQ22_B SCONN288_DDR506112002KQ-SCONN288_DDR506112002KQ,SMA    I22 @T6G_MB_LIB.T6G(SCH_1):PAGE98

M_B_CPU1_SB_DQ<23> @T6G_MB_LIB.T6G(SCH_1):M_B_CPU1_SB_DQ(23)
   U26 CY62 MBB_DATA23 GENOA_SP5-SOCKET6096_13568-001,SMLF,IO,DGA^6000030   I159 @T6G_MB_LIB.T6G(SCH_1):PAGE38
   J26  276 DQ23_B SCONN288_DDR506112002KQ-SCONN288_DDR506112002KQ,SMA    I22 @T6G_MB_LIB.T6G(SCH_1):PAGE98

M_B_CPU1_SB_DQ<24> @T6G_MB_LIB.T6G(SCH_1):M_B_CPU1_SB_DQ(24)
   U26 CY63 MBB_DATA24 GENOA_SP5-SOCKET6096_13568-001,SMLF,IO,DGA^6000030   I159 @T6G_MB_LIB.T6G(SCH_1):PAGE38
   J26  133 DQ24_B SCONN288_DDR506112002KQ-SCONN288_DDR506112002KQ,SMA    I22 @T6G_MB_LIB.T6G(SCH_1):PAGE98

M_B_CPU1_SB_DQ<25> @T6G_MB_LIB.T6G(SCH_1):M_B_CPU1_SB_DQ(25)
   U26 DA62 MBB_DATA25 GENOA_SP5-SOCKET6096_13568-001,SMLF,IO,DGA^6000030   I159 @T6G_MB_LIB.T6G(SCH_1):PAGE38
   J26  135 DQ25_B SCONN288_DDR506112002KQ-SCONN288_DDR506112002KQ,SMA    I22 @T6G_MB_LIB.T6G(SCH_1):PAGE98

M_B_CPU1_SB_DQ<26> @T6G_MB_LIB.T6G(SCH_1):M_B_CPU1_SB_DQ(26)
   U26 DA64 MBB_DATA26 GENOA_SP5-SOCKET6096_13568-001,SMLF,IO,DGA^6000030   I159 @T6G_MB_LIB.T6G(SCH_1):PAGE38
   J26  278 DQ26_B SCONN288_DDR506112002KQ-SCONN288_DDR506112002KQ,SMA    I22 @T6G_MB_LIB.T6G(SCH_1):PAGE98

M_B_CPU1_SB_DQ<27> @T6G_MB_LIB.T6G(SCH_1):M_B_CPU1_SB_DQ(27)
   U26 DB62 MBB_DATA27 GENOA_SP5-SOCKET6096_13568-001,SMLF,IO,DGA^6000030   I159 @T6G_MB_LIB.T6G(SCH_1):PAGE38
   J26  280 DQ27_B SCONN288_DDR506112002KQ-SCONN288_DDR506112002KQ,SMA    I22 @T6G_MB_LIB.T6G(SCH_1):PAGE98

M_B_CPU1_SB_DQ<28> @T6G_MB_LIB.T6G(SCH_1):M_B_CPU1_SB_DQ(28)
   U26 DD63 MBB_DATA28 GENOA_SP5-SOCKET6096_13568-001,SMLF,IO,DGA^6000030   I159 @T6G_MB_LIB.T6G(SCH_1):PAGE38
   J26  140 DQ28_B SCONN288_DDR506112002KQ-SCONN288_DDR506112002KQ,SMA    I22 @T6G_MB_LIB.T6G(SCH_1):PAGE98

M_B_CPU1_SB_DQ<29> @T6G_MB_LIB.T6G(SCH_1):M_B_CPU1_SB_DQ(29)
   U26 DE62 MBB_DATA29 GENOA_SP5-SOCKET6096_13568-001,SMLF,IO,DGA^6000030   I159 @T6G_MB_LIB.T6G(SCH_1):PAGE38
   J26  142 DQ29_B SCONN288_DDR506112002KQ-SCONN288_DDR506112002KQ,SMA    I22 @T6G_MB_LIB.T6G(SCH_1):PAGE98

M_B_CPU1_SB_DQ<2> @T6G_MB_LIB.T6G(SCH_1):M_B_CPU1_SB_DQ(2)
   U26 CC64 MBB_DATA2 GENOA_SP5-SOCKET6096_13568-001,SMLF,IO,DGA^6000030   I159 @T6G_MB_LIB.T6G(SCH_1):PAGE38
   J26  245  DQ2_B SCONN288_DDR506112002KQ-SCONN288_DDR506112002KQ,SMA    I22 @T6G_MB_LIB.T6G(SCH_1):PAGE98

M_B_CPU1_SB_DQ<30> @T6G_MB_LIB.T6G(SCH_1):M_B_CPU1_SB_DQ(30)
   U26 DE64 MBB_DATA30 GENOA_SP5-SOCKET6096_13568-001,SMLF,IO,DGA^6000030   I159 @T6G_MB_LIB.T6G(SCH_1):PAGE38
   J26  285 DQ30_B SCONN288_DDR506112002KQ-SCONN288_DDR506112002KQ,SMA    I22 @T6G_MB_LIB.T6G(SCH_1):PAGE98

M_B_CPU1_SB_DQ<31> @T6G_MB_LIB.T6G(SCH_1):M_B_CPU1_SB_DQ(31)
   U26 DF62 MBB_DATA31 GENOA_SP5-SOCKET6096_13568-001,SMLF,IO,DGA^6000030   I159 @T6G_MB_LIB.T6G(SCH_1):PAGE38
   J26  287 DQ31_B SCONN288_DDR506112002KQ-SCONN288_DDR506112002KQ,SMA    I22 @T6G_MB_LIB.T6G(SCH_1):PAGE98

M_B_CPU1_SB_DQ<3> @T6G_MB_LIB.T6G(SCH_1):M_B_CPU1_SB_DQ(3)
   U26 CD62 MBB_DATA3 GENOA_SP5-SOCKET6096_13568-001,SMLF,IO,DGA^6000030   I159 @T6G_MB_LIB.T6G(SCH_1):PAGE38
   J26  247  DQ3_B SCONN288_DDR506112002KQ-SCONN288_DDR506112002KQ,SMA    I22 @T6G_MB_LIB.T6G(SCH_1):PAGE98

M_B_CPU1_SB_DQ<4> @T6G_MB_LIB.T6G(SCH_1):M_B_CPU1_SB_DQ(4)
   U26 CF63 MBB_DATA4 GENOA_SP5-SOCKET6096_13568-001,SMLF,IO,DGA^6000030   I159 @T6G_MB_LIB.T6G(SCH_1):PAGE38
   J26  107  DQ4_B SCONN288_DDR506112002KQ-SCONN288_DDR506112002KQ,SMA    I22 @T6G_MB_LIB.T6G(SCH_1):PAGE98

M_B_CPU1_SB_DQ<5> @T6G_MB_LIB.T6G(SCH_1):M_B_CPU1_SB_DQ(5)
   U26 CG62 MBB_DATA5 GENOA_SP5-SOCKET6096_13568-001,SMLF,IO,DGA^6000030   I159 @T6G_MB_LIB.T6G(SCH_1):PAGE38
   J26  109  DQ5_B SCONN288_DDR506112002KQ-SCONN288_DDR506112002KQ,SMA    I22 @T6G_MB_LIB.T6G(SCH_1):PAGE98

M_B_CPU1_SB_DQ<6> @T6G_MB_LIB.T6G(SCH_1):M_B_CPU1_SB_DQ(6)
   U26 CG64 MBB_DATA6 GENOA_SP5-SOCKET6096_13568-001,SMLF,IO,DGA^6000030   I159 @T6G_MB_LIB.T6G(SCH_1):PAGE38
   J26  252  DQ6_B SCONN288_DDR506112002KQ-SCONN288_DDR506112002KQ,SMA    I22 @T6G_MB_LIB.T6G(SCH_1):PAGE98

M_B_CPU1_SB_DQ<7> @T6G_MB_LIB.T6G(SCH_1):M_B_CPU1_SB_DQ(7)
   U26 CH62 MBB_DATA7 GENOA_SP5-SOCKET6096_13568-001,SMLF,IO,DGA^6000030   I159 @T6G_MB_LIB.T6G(SCH_1):PAGE38
   J26  254  DQ7_B SCONN288_DDR506112002KQ-SCONN288_DDR506112002KQ,SMA    I22 @T6G_MB_LIB.T6G(SCH_1):PAGE98

M_B_CPU1_SB_DQ<8> @T6G_MB_LIB.T6G(SCH_1):M_B_CPU1_SB_DQ(8)
   U26 CH63 MBB_DATA8 GENOA_SP5-SOCKET6096_13568-001,SMLF,IO,DGA^6000030   I159 @T6G_MB_LIB.T6G(SCH_1):PAGE38
   J26  111  DQ8_B SCONN288_DDR506112002KQ-SCONN288_DDR506112002KQ,SMA    I22 @T6G_MB_LIB.T6G(SCH_1):PAGE98

M_B_CPU1_SB_DQ<9> @T6G_MB_LIB.T6G(SCH_1):M_B_CPU1_SB_DQ(9)
   U26 CJ62 MBB_DATA9 GENOA_SP5-SOCKET6096_13568-001,SMLF,IO,DGA^6000030   I159 @T6G_MB_LIB.T6G(SCH_1):PAGE38
   J26  113  DQ9_B SCONN288_DDR506112002KQ-SCONN288_DDR506112002KQ,SMA    I22 @T6G_MB_LIB.T6G(SCH_1):PAGE98

M_B_CPU1_SB_DQS_DN<0> @T6G_MB_LIB.T6G(SCH_1):M_B_CPU1_SB_DQS_DN(0)
   U26 CE64 MBB_DQS_L0 GENOA_SP5-SOCKET6096_13568-001,SMLF,IO,DGA^6000030   I159 @T6G_MB_LIB.T6G(SCH_1):PAGE38
   J26  105 DQS0_B_C SCONN288_DDR506112002KQ-SCONN288_DDR506112002KQ,SMA   I236 @T6G_MB_LIB.T6G(SCH_1):PAGE98

M_B_CPU1_SB_DQS_DN<1> @T6G_MB_LIB.T6G(SCH_1):M_B_CPU1_SB_DQS_DN(1)
   U26 CL64 MBB_DQS_L1 GENOA_SP5-SOCKET6096_13568-001,SMLF,IO,DGA^6000030   I159 @T6G_MB_LIB.T6G(SCH_1):PAGE38
   J26  116 DQS1_B_C SCONN288_DDR506112002KQ-SCONN288_DDR506112002KQ,SMA   I236 @T6G_MB_LIB.T6G(SCH_1):PAGE98

M_B_CPU1_SB_DQS_DN<2> @T6G_MB_LIB.T6G(SCH_1):M_B_CPU1_SB_DQS_DN(2)
   U26 CU64 MBB_DQS_L2 GENOA_SP5-SOCKET6096_13568-001,SMLF,IO,DGA^6000030   I159 @T6G_MB_LIB.T6G(SCH_1):PAGE38
   J26  127 DQS2_B_C SCONN288_DDR506112002KQ-SCONN288_DDR506112002KQ,SMA   I236 @T6G_MB_LIB.T6G(SCH_1):PAGE98

M_B_CPU1_SB_DQS_DN<3> @T6G_MB_LIB.T6G(SCH_1):M_B_CPU1_SB_DQS_DN(3)
   U26 DC64 MBB_DQS_L3 GENOA_SP5-SOCKET6096_13568-001,SMLF,IO,DGA^6000030   I159 @T6G_MB_LIB.T6G(SCH_1):PAGE38
   J26  138 DQS3_B_C SCONN288_DDR506112002KQ-SCONN288_DDR506112002KQ,SMA   I236 @T6G_MB_LIB.T6G(SCH_1):PAGE98

M_B_CPU1_SB_DQS_DN<4> @T6G_MB_LIB.T6G(SCH_1):M_B_CPU1_SB_DQS_DN(4)
   U26 BW62 MBB_DQS_L4 GENOA_SP5-SOCKET6096_13568-001,SMLF,IO,DGA^6000030   I159 @T6G_MB_LIB.T6G(SCH_1):PAGE38
   J26  238 DQS4_B_C SCONN288_DDR506112002KQ-SCONN288_DDR506112002KQ,SMA   I236 @T6G_MB_LIB.T6G(SCH_1):PAGE98

M_B_CPU1_SB_DQS_DN<5> @T6G_MB_LIB.T6G(SCH_1):M_B_CPU1_SB_DQS_DN(5)
   U26 CE62 MBB_DQS_L5 GENOA_SP5-SOCKET6096_13568-001,SMLF,IO,DGA^6000030   I159 @T6G_MB_LIB.T6G(SCH_1):PAGE38
   J26  249 DQS5_B_C||TDQS5_B_C SCONN288_DDR506112002KQ-SCONN288_DDR506112002KQ,SMA   I236 @T6G_MB_LIB.T6G(SCH_1):PAGE98

M_B_CPU1_SB_DQS_DN<6> @T6G_MB_LIB.T6G(SCH_1):M_B_CPU1_SB_DQS_DN(6)
   U26 CL62 MBB_DQS_L6 GENOA_SP5-SOCKET6096_13568-001,SMLF,IO,DGA^6000030   I159 @T6G_MB_LIB.T6G(SCH_1):PAGE38
   J26  260 DQS6_B_C||TDQS6_B_C SCONN288_DDR506112002KQ-SCONN288_DDR506112002KQ,SMA   I236 @T6G_MB_LIB.T6G(SCH_1):PAGE98

M_B_CPU1_SB_DQS_DN<7> @T6G_MB_LIB.T6G(SCH_1):M_B_CPU1_SB_DQS_DN(7)
   U26 CU62 MBB_DQS_L7 GENOA_SP5-SOCKET6096_13568-001,SMLF,IO,DGA^6000030   I159 @T6G_MB_LIB.T6G(SCH_1):PAGE38
   J26  271 DQS7_B_C||TDQS7_B_C SCONN288_DDR506112002KQ-SCONN288_DDR506112002KQ,SMA   I236 @T6G_MB_LIB.T6G(SCH_1):PAGE98

M_B_CPU1_SB_DQS_DN<8> @T6G_MB_LIB.T6G(SCH_1):M_B_CPU1_SB_DQS_DN(8)
   U26 DC62 MBB_DQS_L8 GENOA_SP5-SOCKET6096_13568-001,SMLF,IO,DGA^6000030   I159 @T6G_MB_LIB.T6G(SCH_1):PAGE38
   J26  282 DQS8_B_C||TDQS8_B_C SCONN288_DDR506112002KQ-SCONN288_DDR506112002KQ,SMA   I236 @T6G_MB_LIB.T6G(SCH_1):PAGE98

M_B_CPU1_SB_DQS_DN<9> @T6G_MB_LIB.T6G(SCH_1):M_B_CPU1_SB_DQS_DN(9)
   U26 BW64 MBB_DQS_L9 GENOA_SP5-SOCKET6096_13568-001,SMLF,IO,DGA^6000030   I159 @T6G_MB_LIB.T6G(SCH_1):PAGE38
   J26   94 DQS9_B_C||TDQS9_B_C SCONN288_DDR506112002KQ-SCONN288_DDR506112002KQ,SMA   I236 @T6G_MB_LIB.T6G(SCH_1):PAGE98

M_B_CPU1_SB_DQS_DP<0> @T6G_MB_LIB.T6G(SCH_1):M_B_CPU1_SB_DQS_DP(0)
   U26 CD63 MBB_DQS_H0 GENOA_SP5-SOCKET6096_13568-001,SMLF,IO,DGA^6000030   I159 @T6G_MB_LIB.T6G(SCH_1):PAGE38
   J26  104 DQS0_B_T SCONN288_DDR506112002KQ-SCONN288_DDR506112002KQ,SMA   I236 @T6G_MB_LIB.T6G(SCH_1):PAGE98

M_B_CPU1_SB_DQS_DP<1> @T6G_MB_LIB.T6G(SCH_1):M_B_CPU1_SB_DQS_DP(1)
   U26 CK63 MBB_DQS_H1 GENOA_SP5-SOCKET6096_13568-001,SMLF,IO,DGA^6000030   I159 @T6G_MB_LIB.T6G(SCH_1):PAGE38
   J26  115 DQS1_B_T SCONN288_DDR506112002KQ-SCONN288_DDR506112002KQ,SMA   I236 @T6G_MB_LIB.T6G(SCH_1):PAGE98

M_B_CPU1_SB_DQS_DP<2> @T6G_MB_LIB.T6G(SCH_1):M_B_CPU1_SB_DQS_DP(2)
   U26 CT63 MBB_DQS_H2 GENOA_SP5-SOCKET6096_13568-001,SMLF,IO,DGA^6000030   I159 @T6G_MB_LIB.T6G(SCH_1):PAGE38
   J26  126 DQS2_B_T SCONN288_DDR506112002KQ-SCONN288_DDR506112002KQ,SMA   I236 @T6G_MB_LIB.T6G(SCH_1):PAGE98

M_B_CPU1_SB_DQS_DP<3> @T6G_MB_LIB.T6G(SCH_1):M_B_CPU1_SB_DQS_DP(3)
   U26 DB63 MBB_DQS_H3 GENOA_SP5-SOCKET6096_13568-001,SMLF,IO,DGA^6000030   I159 @T6G_MB_LIB.T6G(SCH_1):PAGE38
   J26  137 DQS3_B_T SCONN288_DDR506112002KQ-SCONN288_DDR506112002KQ,SMA   I236 @T6G_MB_LIB.T6G(SCH_1):PAGE98

M_B_CPU1_SB_DQS_DP<4> @T6G_MB_LIB.T6G(SCH_1):M_B_CPU1_SB_DQS_DP(4)
   U26 BY62 MBB_DQS_H4 GENOA_SP5-SOCKET6096_13568-001,SMLF,IO,DGA^6000030   I159 @T6G_MB_LIB.T6G(SCH_1):PAGE38
   J26  239 DQS4_B_T SCONN288_DDR506112002KQ-SCONN288_DDR506112002KQ,SMA   I236 @T6G_MB_LIB.T6G(SCH_1):PAGE98

M_B_CPU1_SB_DQS_DP<5> @T6G_MB_LIB.T6G(SCH_1):M_B_CPU1_SB_DQS_DP(5)
   U26 CF62 MBB_DQS_H5 GENOA_SP5-SOCKET6096_13568-001,SMLF,IO,DGA^6000030   I159 @T6G_MB_LIB.T6G(SCH_1):PAGE38
   J26  250 DQS5_B_T||TDQS5_B_T SCONN288_DDR506112002KQ-SCONN288_DDR506112002KQ,SMA   I236 @T6G_MB_LIB.T6G(SCH_1):PAGE98

M_B_CPU1_SB_DQS_DP<6> @T6G_MB_LIB.T6G(SCH_1):M_B_CPU1_SB_DQS_DP(6)
   U26 CM62 MBB_DQS_H6 GENOA_SP5-SOCKET6096_13568-001,SMLF,IO,DGA^6000030   I159 @T6G_MB_LIB.T6G(SCH_1):PAGE38
   J26  261 DQS6_B_T||TDQS6_B_T SCONN288_DDR506112002KQ-SCONN288_DDR506112002KQ,SMA   I236 @T6G_MB_LIB.T6G(SCH_1):PAGE98

M_B_CPU1_SB_DQS_DP<7> @T6G_MB_LIB.T6G(SCH_1):M_B_CPU1_SB_DQS_DP(7)
   U26 CV62 MBB_DQS_H7 GENOA_SP5-SOCKET6096_13568-001,SMLF,IO,DGA^6000030   I159 @T6G_MB_LIB.T6G(SCH_1):PAGE38
   J26  272 DQS7_B_T||TDQS7_B_T SCONN288_DDR506112002KQ-SCONN288_DDR506112002KQ,SMA   I236 @T6G_MB_LIB.T6G(SCH_1):PAGE98

M_B_CPU1_SB_DQS_DP<8> @T6G_MB_LIB.T6G(SCH_1):M_B_CPU1_SB_DQS_DP(8)
   U26 DD62 MBB_DQS_H8 GENOA_SP5-SOCKET6096_13568-001,SMLF,IO,DGA^6000030   I159 @T6G_MB_LIB.T6G(SCH_1):PAGE38
   J26  283 DQS8_B_T||TDQS8_B_T SCONN288_DDR506112002KQ-SCONN288_DDR506112002KQ,SMA   I236 @T6G_MB_LIB.T6G(SCH_1):PAGE98

M_B_CPU1_SB_DQS_DP<9> @T6G_MB_LIB.T6G(SCH_1):M_B_CPU1_SB_DQS_DP(9)
   U26 BV63 MBB_DQS_H9 GENOA_SP5-SOCKET6096_13568-001,SMLF,IO,DGA^6000030   I159 @T6G_MB_LIB.T6G(SCH_1):PAGE38
   J26   93 DQS9_B_T||TDQS9_B_T||DBI4_B_N SCONN288_DDR506112002KQ-SCONN288_DDR506112002KQ,SMA   I236 @T6G_MB_LIB.T6G(SCH_1):PAGE98

M_B_CPU1_SB_PAR @T6G_MB_LIB.T6G(SCH_1):M_B_CPU1_SB_PAR
   U26 BL64 MBB_PAR GENOA_SP5-SOCKET6096_13568-001,SMLF,IO,DGA^6000030   I159 @T6G_MB_LIB.T6G(SCH_1):PAGE38
   J26  227  PAR_B SCONN288_DDR506112002KQ-SCONN288_DDR506112002KQ,SMA    I22 @T6G_MB_LIB.T6G(SCH_1):PAGE98

M_B_CPU1_SB_RSP<0> @T6G_MB_LIB.T6G(SCH_1):M_B_CPU1_SB_RSP(0)
   U26 BP63 MBB0_RSP_L GENOA_SP5-SOCKET6096_13568-001,SMLF,IO,DGA^6000030   I159 @T6G_MB_LIB.T6G(SCH_1):PAGE38
   J26   87 LBS||RSP_B_N SCONN288_DDR506112002KQ-SCONN288_DDR506112002KQ,SMA    I22 @T6G_MB_LIB.T6G(SCH_1):PAGE98

M_C_CPU0_ALERT_N @T6G_MB_LIB.T6G(SCH_1):M_C_CPU0_ALERT_N
  R377    1      A Q_RES_0402LF-15,1%,1/16W,CHIP,CS01502FB03   I314 @T6G_MB_LIB.T6G(SCH_1):PAGE12
   J17   62 ALERT_N SCONN288_DDR506112002KQ-SCONN288_DDR506112002KQ,SMA   I350 @T6G_MB_LIB.T6G(SCH_1):PAGE87

M_C_CPU0_ALERT_R_N @T6G_MB_LIB.T6G(SCH_1):M_C_CPU0_ALERT_R_N
   U25 AT55 MC_ALERT_L GENOA_SP5-SOCKET6096_13568-001,SMLF,IO,DGA^6000030   I159 @T6G_MB_LIB.T6G(SCH_1):PAGE12
  R377    2      B Q_RES_0402LF-15,1%,1/16W,CHIP,CS01502FB03   I314 @T6G_MB_LIB.T6G(SCH_1):PAGE12

M_C_CPU0_CLK_DN<0> @T6G_MB_LIB.T6G(SCH_1):M_C_CPU0_CLK_DN(0)
   U25 BD56 MC0_CLK_L GENOA_SP5-SOCKET6096_13568-001,SMLF,IO,DGA^6000030   I159 @T6G_MB_LIB.T6G(SCH_1):PAGE12
   J17  218   CK_C SCONN288_DDR506112002KQ-SCONN288_DDR506112002KQ,SMA   I350 @T6G_MB_LIB.T6G(SCH_1):PAGE87

M_C_CPU0_CLK_DP<0> @T6G_MB_LIB.T6G(SCH_1):M_C_CPU0_CLK_DP(0)
   U25 BC57 MC0_CLK_H GENOA_SP5-SOCKET6096_13568-001,SMLF,IO,DGA^6000030   I159 @T6G_MB_LIB.T6G(SCH_1):PAGE12
   J17  217   CK_T SCONN288_DDR506112002KQ-SCONN288_DDR506112002KQ,SMA   I350 @T6G_MB_LIB.T6G(SCH_1):PAGE87

M_C_CPU0_RESET_N @T6G_MB_LIB.T6G(SCH_1):M_C_CPU0_RESET_N
   U25 AU55 MC_RESET_L GENOA_SP5-SOCKET6096_13568-001,SMLF,IO,DGA^6000030   I159 @T6G_MB_LIB.T6G(SCH_1):PAGE12
   J17  207 RESET_N SCONN288_DDR506112002KQ-SCONN288_DDR506112002KQ,SMA   I350 @T6G_MB_LIB.T6G(SCH_1):PAGE87

M_C_CPU0_SA_CA<0> @T6G_MB_LIB.T6G(SCH_1):M_C_CPU0_SA_CA(0)
   U25 AW57 MCA_CA0 GENOA_SP5-SOCKET6096_13568-001,SMLF,IO,DGA^6000030   I159 @T6G_MB_LIB.T6G(SCH_1):PAGE12
   J17   66  CA0_A SCONN288_DDR506112002KQ-SCONN288_DDR506112002KQ,SMA   I350 @T6G_MB_LIB.T6G(SCH_1):PAGE87

M_C_CPU0_SA_CA<1> @T6G_MB_LIB.T6G(SCH_1):M_C_CPU0_SA_CA(1)
   U25 AY56 MCA_CA1 GENOA_SP5-SOCKET6096_13568-001,SMLF,IO,DGA^6000030   I159 @T6G_MB_LIB.T6G(SCH_1):PAGE12
   J17  211  CA1_A SCONN288_DDR506112002KQ-SCONN288_DDR506112002KQ,SMA   I350 @T6G_MB_LIB.T6G(SCH_1):PAGE87

M_C_CPU0_SA_CA<2> @T6G_MB_LIB.T6G(SCH_1):M_C_CPU0_SA_CA(2)
   U25 AY55 MCA_CA2 GENOA_SP5-SOCKET6096_13568-001,SMLF,IO,DGA^6000030   I159 @T6G_MB_LIB.T6G(SCH_1):PAGE12
   J17   68  CA2_A SCONN288_DDR506112002KQ-SCONN288_DDR506112002KQ,SMA   I350 @T6G_MB_LIB.T6G(SCH_1):PAGE87

M_C_CPU0_SA_CA<3> @T6G_MB_LIB.T6G(SCH_1):M_C_CPU0_SA_CA(3)
   U25 BA55 MCA_CA3 GENOA_SP5-SOCKET6096_13568-001,SMLF,IO,DGA^6000030   I159 @T6G_MB_LIB.T6G(SCH_1):PAGE12
   J17  213  CA3_A SCONN288_DDR506112002KQ-SCONN288_DDR506112002KQ,SMA   I350 @T6G_MB_LIB.T6G(SCH_1):PAGE87

M_C_CPU0_SA_CA<4> @T6G_MB_LIB.T6G(SCH_1):M_C_CPU0_SA_CA(4)
   U25 BA57 MCA_CA4 GENOA_SP5-SOCKET6096_13568-001,SMLF,IO,DGA^6000030   I159 @T6G_MB_LIB.T6G(SCH_1):PAGE12
   J17   70  CA4_A SCONN288_DDR506112002KQ-SCONN288_DDR506112002KQ,SMA   I350 @T6G_MB_LIB.T6G(SCH_1):PAGE87

M_C_CPU0_SA_CA<5> @T6G_MB_LIB.T6G(SCH_1):M_C_CPU0_SA_CA(5)
   U25 BB56 MCA_CA5 GENOA_SP5-SOCKET6096_13568-001,SMLF,IO,DGA^6000030   I159 @T6G_MB_LIB.T6G(SCH_1):PAGE12
   J17  215  CA5_A SCONN288_DDR506112002KQ-SCONN288_DDR506112002KQ,SMA   I350 @T6G_MB_LIB.T6G(SCH_1):PAGE87

M_C_CPU0_SA_CA<6> @T6G_MB_LIB.T6G(SCH_1):M_C_CPU0_SA_CA(6)
   U25 BB55 MCA_CA6 GENOA_SP5-SOCKET6096_13568-001,SMLF,IO,DGA^6000030   I159 @T6G_MB_LIB.T6G(SCH_1):PAGE12
   J17   72  CA6_A SCONN288_DDR506112002KQ-SCONN288_DDR506112002KQ,SMA   I350 @T6G_MB_LIB.T6G(SCH_1):PAGE87

M_C_CPU0_SA_CB<0> @T6G_MB_LIB.T6G(SCH_1):M_C_CPU0_SA_CB(0)
   U25 AJ57 MCA_CHECK0 GENOA_SP5-SOCKET6096_13568-001,SMLF,IO,DGA^6000030   I159 @T6G_MB_LIB.T6G(SCH_1):PAGE12
   J17   51  CB0_A SCONN288_DDR506112002KQ-SCONN288_DDR506112002KQ,SMA   I350 @T6G_MB_LIB.T6G(SCH_1):PAGE87

M_C_CPU0_SA_CB<1> @T6G_MB_LIB.T6G(SCH_1):M_C_CPU0_SA_CB(1)
   U25 AK55 MCA_CHECK1 GENOA_SP5-SOCKET6096_13568-001,SMLF,IO,DGA^6000030   I159 @T6G_MB_LIB.T6G(SCH_1):PAGE12
   J17   53  CB1_A SCONN288_DDR506112002KQ-SCONN288_DDR506112002KQ,SMA   I350 @T6G_MB_LIB.T6G(SCH_1):PAGE87

M_C_CPU0_SA_CB<2> @T6G_MB_LIB.T6G(SCH_1):M_C_CPU0_SA_CB(2)
   U25 AK56 MCA_CHECK2 GENOA_SP5-SOCKET6096_13568-001,SMLF,IO,DGA^6000030   I159 @T6G_MB_LIB.T6G(SCH_1):PAGE12
   J17  196  CB2_A SCONN288_DDR506112002KQ-SCONN288_DDR506112002KQ,SMA   I350 @T6G_MB_LIB.T6G(SCH_1):PAGE87

M_C_CPU0_SA_CB<3> @T6G_MB_LIB.T6G(SCH_1):M_C_CPU0_SA_CB(3)
   U25 AL55 MCA_CHECK3 GENOA_SP5-SOCKET6096_13568-001,SMLF,IO,DGA^6000030   I159 @T6G_MB_LIB.T6G(SCH_1):PAGE12
   J17  198  CB3_A SCONN288_DDR506112002KQ-SCONN288_DDR506112002KQ,SMA   I350 @T6G_MB_LIB.T6G(SCH_1):PAGE87

M_C_CPU0_SA_CB<4> @T6G_MB_LIB.T6G(SCH_1):M_C_CPU0_SA_CB(4)
   U25 AN57 MCA_CHECK4 GENOA_SP5-SOCKET6096_13568-001,SMLF,IO,DGA^6000030   I159 @T6G_MB_LIB.T6G(SCH_1):PAGE12
   J17   58  CB4_A SCONN288_DDR506112002KQ-SCONN288_DDR506112002KQ,SMA   I350 @T6G_MB_LIB.T6G(SCH_1):PAGE87

M_C_CPU0_SA_CB<5> @T6G_MB_LIB.T6G(SCH_1):M_C_CPU0_SA_CB(5)
   U25 AP55 MCA_CHECK5 GENOA_SP5-SOCKET6096_13568-001,SMLF,IO,DGA^6000030   I159 @T6G_MB_LIB.T6G(SCH_1):PAGE12
   J17   60  CB5_A SCONN288_DDR506112002KQ-SCONN288_DDR506112002KQ,SMA   I350 @T6G_MB_LIB.T6G(SCH_1):PAGE87

M_C_CPU0_SA_CB<6> @T6G_MB_LIB.T6G(SCH_1):M_C_CPU0_SA_CB(6)
   U25 AP56 MCA_CHECK6 GENOA_SP5-SOCKET6096_13568-001,SMLF,IO,DGA^6000030   I159 @T6G_MB_LIB.T6G(SCH_1):PAGE12
   J17  203  CB6_A SCONN288_DDR506112002KQ-SCONN288_DDR506112002KQ,SMA   I350 @T6G_MB_LIB.T6G(SCH_1):PAGE87

M_C_CPU0_SA_CB<7> @T6G_MB_LIB.T6G(SCH_1):M_C_CPU0_SA_CB(7)
   U25 AR55 MCA_CHECK7 GENOA_SP5-SOCKET6096_13568-001,SMLF,IO,DGA^6000030   I159 @T6G_MB_LIB.T6G(SCH_1):PAGE12
   J17  205  CB7_A SCONN288_DDR506112002KQ-SCONN288_DDR506112002KQ,SMA   I350 @T6G_MB_LIB.T6G(SCH_1):PAGE87

M_C_CPU0_SA_CS_N<0> @T6G_MB_LIB.T6G(SCH_1):M_C_CPU0_SA_CS_N(0)
   U25 AV56 MCA0_CS_L0 GENOA_SP5-SOCKET6096_13568-001,SMLF,IO,DGA^6000030   I159 @T6G_MB_LIB.T6G(SCH_1):PAGE12
   J17   64 CS0_A_N SCONN288_DDR506112002KQ-SCONN288_DDR506112002KQ,SMA   I350 @T6G_MB_LIB.T6G(SCH_1):PAGE87

M_C_CPU0_SA_CS_N<1> @T6G_MB_LIB.T6G(SCH_1):M_C_CPU0_SA_CS_N(1)
   U25 AW55 MCA0_CS_L1 GENOA_SP5-SOCKET6096_13568-001,SMLF,IO,DGA^6000030   I159 @T6G_MB_LIB.T6G(SCH_1):PAGE12
   J17  209 CS1_A_N SCONN288_DDR506112002KQ-SCONN288_DDR506112002KQ,SMA   I350 @T6G_MB_LIB.T6G(SCH_1):PAGE87

M_C_CPU0_SA_DQ<0> @T6G_MB_LIB.T6G(SCH_1):M_C_CPU0_SA_DQ(0)
   U25  E57 MCA_DATA0 GENOA_SP5-SOCKET6096_13568-001,SMLF,IO,DGA^6000030   I159 @T6G_MB_LIB.T6G(SCH_1):PAGE12
   J17    7  DQ0_A SCONN288_DDR506112002KQ-SCONN288_DDR506112002KQ,SMA   I350 @T6G_MB_LIB.T6G(SCH_1):PAGE87

M_C_CPU0_SA_DQ<10> @T6G_MB_LIB.T6G(SCH_1):M_C_CPU0_SA_DQ(10)
   U25  M56 MCA_DATA10 GENOA_SP5-SOCKET6096_13568-001,SMLF,IO,DGA^6000030   I159 @T6G_MB_LIB.T6G(SCH_1):PAGE12
   J17  163 DQ10_A SCONN288_DDR506112002KQ-SCONN288_DDR506112002KQ,SMA   I350 @T6G_MB_LIB.T6G(SCH_1):PAGE87

M_C_CPU0_SA_DQ<11> @T6G_MB_LIB.T6G(SCH_1):M_C_CPU0_SA_DQ(11)
   U25  N55 MCA_DATA11 GENOA_SP5-SOCKET6096_13568-001,SMLF,IO,DGA^6000030   I159 @T6G_MB_LIB.T6G(SCH_1):PAGE12
   J17  165 DQ11_A SCONN288_DDR506112002KQ-SCONN288_DDR506112002KQ,SMA   I350 @T6G_MB_LIB.T6G(SCH_1):PAGE87

M_C_CPU0_SA_DQ<12> @T6G_MB_LIB.T6G(SCH_1):M_C_CPU0_SA_DQ(12)
   U25  R57 MCA_DATA12 GENOA_SP5-SOCKET6096_13568-001,SMLF,IO,DGA^6000030   I159 @T6G_MB_LIB.T6G(SCH_1):PAGE12
   J17   25 DQ12_A SCONN288_DDR506112002KQ-SCONN288_DDR506112002KQ,SMA   I350 @T6G_MB_LIB.T6G(SCH_1):PAGE87

M_C_CPU0_SA_DQ<13> @T6G_MB_LIB.T6G(SCH_1):M_C_CPU0_SA_DQ(13)
   U25  T55 MCA_DATA13 GENOA_SP5-SOCKET6096_13568-001,SMLF,IO,DGA^6000030   I159 @T6G_MB_LIB.T6G(SCH_1):PAGE12
   J17   27 DQ13_A SCONN288_DDR506112002KQ-SCONN288_DDR506112002KQ,SMA   I350 @T6G_MB_LIB.T6G(SCH_1):PAGE87

M_C_CPU0_SA_DQ<14> @T6G_MB_LIB.T6G(SCH_1):M_C_CPU0_SA_DQ(14)
   U25  T56 MCA_DATA14 GENOA_SP5-SOCKET6096_13568-001,SMLF,IO,DGA^6000030   I159 @T6G_MB_LIB.T6G(SCH_1):PAGE12
   J17  170 DQ14_A SCONN288_DDR506112002KQ-SCONN288_DDR506112002KQ,SMA   I350 @T6G_MB_LIB.T6G(SCH_1):PAGE87

M_C_CPU0_SA_DQ<15> @T6G_MB_LIB.T6G(SCH_1):M_C_CPU0_SA_DQ(15)
   U25  U55 MCA_DATA15 GENOA_SP5-SOCKET6096_13568-001,SMLF,IO,DGA^6000030   I159 @T6G_MB_LIB.T6G(SCH_1):PAGE12
   J17  172 DQ15_A SCONN288_DDR506112002KQ-SCONN288_DDR506112002KQ,SMA   I350 @T6G_MB_LIB.T6G(SCH_1):PAGE87

M_C_CPU0_SA_DQ<16> @T6G_MB_LIB.T6G(SCH_1):M_C_CPU0_SA_DQ(16)
   U25  U57 MCA_DATA16 GENOA_SP5-SOCKET6096_13568-001,SMLF,IO,DGA^6000030   I159 @T6G_MB_LIB.T6G(SCH_1):PAGE12
   J17   29 DQ16_A SCONN288_DDR506112002KQ-SCONN288_DDR506112002KQ,SMA   I350 @T6G_MB_LIB.T6G(SCH_1):PAGE87

M_C_CPU0_SA_DQ<17> @T6G_MB_LIB.T6G(SCH_1):M_C_CPU0_SA_DQ(17)
   U25  V55 MCA_DATA17 GENOA_SP5-SOCKET6096_13568-001,SMLF,IO,DGA^6000030   I159 @T6G_MB_LIB.T6G(SCH_1):PAGE12
   J17   31 DQ17_A SCONN288_DDR506112002KQ-SCONN288_DDR506112002KQ,SMA   I350 @T6G_MB_LIB.T6G(SCH_1):PAGE87

M_C_CPU0_SA_DQ<18> @T6G_MB_LIB.T6G(SCH_1):M_C_CPU0_SA_DQ(18)
   U25  V56 MCA_DATA18 GENOA_SP5-SOCKET6096_13568-001,SMLF,IO,DGA^6000030   I159 @T6G_MB_LIB.T6G(SCH_1):PAGE12
   J17  174 DQ18_A SCONN288_DDR506112002KQ-SCONN288_DDR506112002KQ,SMA   I350 @T6G_MB_LIB.T6G(SCH_1):PAGE87

M_C_CPU0_SA_DQ<19> @T6G_MB_LIB.T6G(SCH_1):M_C_CPU0_SA_DQ(19)
   U25  W55 MCA_DATA19 GENOA_SP5-SOCKET6096_13568-001,SMLF,IO,DGA^6000030   I159 @T6G_MB_LIB.T6G(SCH_1):PAGE12
   J17  176 DQ19_A SCONN288_DDR506112002KQ-SCONN288_DDR506112002KQ,SMA   I350 @T6G_MB_LIB.T6G(SCH_1):PAGE87

M_C_CPU0_SA_DQ<1> @T6G_MB_LIB.T6G(SCH_1):M_C_CPU0_SA_DQ(1)
   U25  F55 MCA_DATA1 GENOA_SP5-SOCKET6096_13568-001,SMLF,IO,DGA^6000030   I159 @T6G_MB_LIB.T6G(SCH_1):PAGE12
   J17    9  DQ1_A SCONN288_DDR506112002KQ-SCONN288_DDR506112002KQ,SMA   I350 @T6G_MB_LIB.T6G(SCH_1):PAGE87

M_C_CPU0_SA_DQ<20> @T6G_MB_LIB.T6G(SCH_1):M_C_CPU0_SA_DQ(20)
   U25 AA57 MCA_DATA20 GENOA_SP5-SOCKET6096_13568-001,SMLF,IO,DGA^6000030   I159 @T6G_MB_LIB.T6G(SCH_1):PAGE12
   J17   36 DQ20_A SCONN288_DDR506112002KQ-SCONN288_DDR506112002KQ,SMA   I350 @T6G_MB_LIB.T6G(SCH_1):PAGE87

M_C_CPU0_SA_DQ<21> @T6G_MB_LIB.T6G(SCH_1):M_C_CPU0_SA_DQ(21)
   U25 AB55 MCA_DATA21 GENOA_SP5-SOCKET6096_13568-001,SMLF,IO,DGA^6000030   I159 @T6G_MB_LIB.T6G(SCH_1):PAGE12
   J17   38 DQ21_A SCONN288_DDR506112002KQ-SCONN288_DDR506112002KQ,SMA   I350 @T6G_MB_LIB.T6G(SCH_1):PAGE87

M_C_CPU0_SA_DQ<22> @T6G_MB_LIB.T6G(SCH_1):M_C_CPU0_SA_DQ(22)
   U25 AB56 MCA_DATA22 GENOA_SP5-SOCKET6096_13568-001,SMLF,IO,DGA^6000030   I159 @T6G_MB_LIB.T6G(SCH_1):PAGE12
   J17  181 DQ22_A SCONN288_DDR506112002KQ-SCONN288_DDR506112002KQ,SMA   I350 @T6G_MB_LIB.T6G(SCH_1):PAGE87

M_C_CPU0_SA_DQ<23> @T6G_MB_LIB.T6G(SCH_1):M_C_CPU0_SA_DQ(23)
   U25 AC55 MCA_DATA23 GENOA_SP5-SOCKET6096_13568-001,SMLF,IO,DGA^6000030   I159 @T6G_MB_LIB.T6G(SCH_1):PAGE12
   J17  183 DQ23_A SCONN288_DDR506112002KQ-SCONN288_DDR506112002KQ,SMA   I350 @T6G_MB_LIB.T6G(SCH_1):PAGE87

M_C_CPU0_SA_DQ<24> @T6G_MB_LIB.T6G(SCH_1):M_C_CPU0_SA_DQ(24)
   U25 AC57 MCA_DATA24 GENOA_SP5-SOCKET6096_13568-001,SMLF,IO,DGA^6000030   I159 @T6G_MB_LIB.T6G(SCH_1):PAGE12
   J17   40 DQ24_A SCONN288_DDR506112002KQ-SCONN288_DDR506112002KQ,SMA   I350 @T6G_MB_LIB.T6G(SCH_1):PAGE87

M_C_CPU0_SA_DQ<25> @T6G_MB_LIB.T6G(SCH_1):M_C_CPU0_SA_DQ(25)
   U25 AD55 MCA_DATA25 GENOA_SP5-SOCKET6096_13568-001,SMLF,IO,DGA^6000030   I159 @T6G_MB_LIB.T6G(SCH_1):PAGE12
   J17   42 DQ25_A SCONN288_DDR506112002KQ-SCONN288_DDR506112002KQ,SMA   I350 @T6G_MB_LIB.T6G(SCH_1):PAGE87

M_C_CPU0_SA_DQ<26> @T6G_MB_LIB.T6G(SCH_1):M_C_CPU0_SA_DQ(26)
   U25 AD56 MCA_DATA26 GENOA_SP5-SOCKET6096_13568-001,SMLF,IO,DGA^6000030   I159 @T6G_MB_LIB.T6G(SCH_1):PAGE12
   J17  185 DQ26_A SCONN288_DDR506112002KQ-SCONN288_DDR506112002KQ,SMA   I350 @T6G_MB_LIB.T6G(SCH_1):PAGE87

M_C_CPU0_SA_DQ<27> @T6G_MB_LIB.T6G(SCH_1):M_C_CPU0_SA_DQ(27)
   U25 AE55 MCA_DATA27 GENOA_SP5-SOCKET6096_13568-001,SMLF,IO,DGA^6000030   I159 @T6G_MB_LIB.T6G(SCH_1):PAGE12
   J17  187 DQ27_A SCONN288_DDR506112002KQ-SCONN288_DDR506112002KQ,SMA   I350 @T6G_MB_LIB.T6G(SCH_1):PAGE87

M_C_CPU0_SA_DQ<28> @T6G_MB_LIB.T6G(SCH_1):M_C_CPU0_SA_DQ(28)
   U25 AG57 MCA_DATA28 GENOA_SP5-SOCKET6096_13568-001,SMLF,IO,DGA^6000030   I159 @T6G_MB_LIB.T6G(SCH_1):PAGE12
   J17   47 DQ28_A SCONN288_DDR506112002KQ-SCONN288_DDR506112002KQ,SMA   I350 @T6G_MB_LIB.T6G(SCH_1):PAGE87

M_C_CPU0_SA_DQ<29> @T6G_MB_LIB.T6G(SCH_1):M_C_CPU0_SA_DQ(29)
   U25 AH55 MCA_DATA29 GENOA_SP5-SOCKET6096_13568-001,SMLF,IO,DGA^6000030   I159 @T6G_MB_LIB.T6G(SCH_1):PAGE12
   J17   49 DQ29_A SCONN288_DDR506112002KQ-SCONN288_DDR506112002KQ,SMA   I350 @T6G_MB_LIB.T6G(SCH_1):PAGE87

M_C_CPU0_SA_DQ<2> @T6G_MB_LIB.T6G(SCH_1):M_C_CPU0_SA_DQ(2)
   U25  F56 MCA_DATA2 GENOA_SP5-SOCKET6096_13568-001,SMLF,IO,DGA^6000030   I159 @T6G_MB_LIB.T6G(SCH_1):PAGE12
   J17  152  DQ2_A SCONN288_DDR506112002KQ-SCONN288_DDR506112002KQ,SMA   I350 @T6G_MB_LIB.T6G(SCH_1):PAGE87

M_C_CPU0_SA_DQ<30> @T6G_MB_LIB.T6G(SCH_1):M_C_CPU0_SA_DQ(30)
   U25 AH56 MCA_DATA30 GENOA_SP5-SOCKET6096_13568-001,SMLF,IO,DGA^6000030   I159 @T6G_MB_LIB.T6G(SCH_1):PAGE12
   J17  192 DQ30_A SCONN288_DDR506112002KQ-SCONN288_DDR506112002KQ,SMA   I350 @T6G_MB_LIB.T6G(SCH_1):PAGE87

M_C_CPU0_SA_DQ<31> @T6G_MB_LIB.T6G(SCH_1):M_C_CPU0_SA_DQ(31)
   U25 AJ55 MCA_DATA31 GENOA_SP5-SOCKET6096_13568-001,SMLF,IO,DGA^6000030   I159 @T6G_MB_LIB.T6G(SCH_1):PAGE12
   J17  194 DQ31_A SCONN288_DDR506112002KQ-SCONN288_DDR506112002KQ,SMA   I350 @T6G_MB_LIB.T6G(SCH_1):PAGE87

M_C_CPU0_SA_DQ<3> @T6G_MB_LIB.T6G(SCH_1):M_C_CPU0_SA_DQ(3)
   U25  G55 MCA_DATA3 GENOA_SP5-SOCKET6096_13568-001,SMLF,IO,DGA^6000030   I159 @T6G_MB_LIB.T6G(SCH_1):PAGE12
   J17  154  DQ3_A SCONN288_DDR506112002KQ-SCONN288_DDR506112002KQ,SMA   I350 @T6G_MB_LIB.T6G(SCH_1):PAGE87

M_C_CPU0_SA_DQ<4> @T6G_MB_LIB.T6G(SCH_1):M_C_CPU0_SA_DQ(4)
   U25  J57 MCA_DATA4 GENOA_SP5-SOCKET6096_13568-001,SMLF,IO,DGA^6000030   I159 @T6G_MB_LIB.T6G(SCH_1):PAGE12
   J17   14  DQ4_A SCONN288_DDR506112002KQ-SCONN288_DDR506112002KQ,SMA   I350 @T6G_MB_LIB.T6G(SCH_1):PAGE87

M_C_CPU0_SA_DQ<5> @T6G_MB_LIB.T6G(SCH_1):M_C_CPU0_SA_DQ(5)
   U25  K55 MCA_DATA5 GENOA_SP5-SOCKET6096_13568-001,SMLF,IO,DGA^6000030   I159 @T6G_MB_LIB.T6G(SCH_1):PAGE12
   J17   16  DQ5_A SCONN288_DDR506112002KQ-SCONN288_DDR506112002KQ,SMA   I350 @T6G_MB_LIB.T6G(SCH_1):PAGE87

M_C_CPU0_SA_DQ<6> @T6G_MB_LIB.T6G(SCH_1):M_C_CPU0_SA_DQ(6)
   U25  K56 MCA_DATA6 GENOA_SP5-SOCKET6096_13568-001,SMLF,IO,DGA^6000030   I159 @T6G_MB_LIB.T6G(SCH_1):PAGE12
   J17  159  DQ6_A SCONN288_DDR506112002KQ-SCONN288_DDR506112002KQ,SMA   I350 @T6G_MB_LIB.T6G(SCH_1):PAGE87

M_C_CPU0_SA_DQ<7> @T6G_MB_LIB.T6G(SCH_1):M_C_CPU0_SA_DQ(7)
   U25  L55 MCA_DATA7 GENOA_SP5-SOCKET6096_13568-001,SMLF,IO,DGA^6000030   I159 @T6G_MB_LIB.T6G(SCH_1):PAGE12
   J17  161  DQ7_A SCONN288_DDR506112002KQ-SCONN288_DDR506112002KQ,SMA   I350 @T6G_MB_LIB.T6G(SCH_1):PAGE87

M_C_CPU0_SA_DQ<8> @T6G_MB_LIB.T6G(SCH_1):M_C_CPU0_SA_DQ(8)
   U25  L57 MCA_DATA8 GENOA_SP5-SOCKET6096_13568-001,SMLF,IO,DGA^6000030   I159 @T6G_MB_LIB.T6G(SCH_1):PAGE12
   J17   18  DQ8_A SCONN288_DDR506112002KQ-SCONN288_DDR506112002KQ,SMA   I350 @T6G_MB_LIB.T6G(SCH_1):PAGE87

M_C_CPU0_SA_DQ<9> @T6G_MB_LIB.T6G(SCH_1):M_C_CPU0_SA_DQ(9)
   U25  M55 MCA_DATA9 GENOA_SP5-SOCKET6096_13568-001,SMLF,IO,DGA^6000030   I159 @T6G_MB_LIB.T6G(SCH_1):PAGE12
   J17   20  DQ9_A SCONN288_DDR506112002KQ-SCONN288_DDR506112002KQ,SMA   I350 @T6G_MB_LIB.T6G(SCH_1):PAGE87

M_C_CPU0_SA_DQS_DN<0> @T6G_MB_LIB.T6G(SCH_1):M_C_CPU0_SA_DQS_DN(0)
   U25  H56 MCA_DQS_L0 GENOA_SP5-SOCKET6096_13568-001,SMLF,IO,DGA^6000030   I159 @T6G_MB_LIB.T6G(SCH_1):PAGE12
   J17   12 DQS0_A_C SCONN288_DDR506112002KQ-SCONN288_DDR506112002KQ,SMA   I411 @T6G_MB_LIB.T6G(SCH_1):PAGE87

M_C_CPU0_SA_DQS_DN<1> @T6G_MB_LIB.T6G(SCH_1):M_C_CPU0_SA_DQS_DN(1)
   U25  P56 MCA_DQS_L1 GENOA_SP5-SOCKET6096_13568-001,SMLF,IO,DGA^6000030   I159 @T6G_MB_LIB.T6G(SCH_1):PAGE12
   J17   23 DQS1_A_C SCONN288_DDR506112002KQ-SCONN288_DDR506112002KQ,SMA   I411 @T6G_MB_LIB.T6G(SCH_1):PAGE87

M_C_CPU0_SA_DQS_DN<2> @T6G_MB_LIB.T6G(SCH_1):M_C_CPU0_SA_DQS_DN(2)
   U25  Y56 MCA_DQS_L2 GENOA_SP5-SOCKET6096_13568-001,SMLF,IO,DGA^6000030   I159 @T6G_MB_LIB.T6G(SCH_1):PAGE12
   J17   34 DQS2_A_C SCONN288_DDR506112002KQ-SCONN288_DDR506112002KQ,SMA   I411 @T6G_MB_LIB.T6G(SCH_1):PAGE87

M_C_CPU0_SA_DQS_DN<3> @T6G_MB_LIB.T6G(SCH_1):M_C_CPU0_SA_DQS_DN(3)
   U25 AF56 MCA_DQS_L3 GENOA_SP5-SOCKET6096_13568-001,SMLF,IO,DGA^6000030   I159 @T6G_MB_LIB.T6G(SCH_1):PAGE12
   J17   45 DQS3_A_C SCONN288_DDR506112002KQ-SCONN288_DDR506112002KQ,SMA   I411 @T6G_MB_LIB.T6G(SCH_1):PAGE87

M_C_CPU0_SA_DQS_DN<4> @T6G_MB_LIB.T6G(SCH_1):M_C_CPU0_SA_DQS_DN(4)
   U25 AM56 MCA_DQS_L4 GENOA_SP5-SOCKET6096_13568-001,SMLF,IO,DGA^6000030   I159 @T6G_MB_LIB.T6G(SCH_1):PAGE12
   J17   56 DQS4_A_C SCONN288_DDR506112002KQ-SCONN288_DDR506112002KQ,SMA   I411 @T6G_MB_LIB.T6G(SCH_1):PAGE87

M_C_CPU0_SA_DQS_DN<5> @T6G_MB_LIB.T6G(SCH_1):M_C_CPU0_SA_DQS_DN(5)
   U25  H55 MCA_DQS_L5 GENOA_SP5-SOCKET6096_13568-001,SMLF,IO,DGA^6000030   I159 @T6G_MB_LIB.T6G(SCH_1):PAGE12
   J17  156 DQS5_A_C||TDQS5_A_C||DQS5_A_T||TDQS5_A_T SCONN288_DDR506112002KQ-SCONN288_DDR506112002KQ,SMA   I411 @T6G_MB_LIB.T6G(SCH_1):PAGE87

M_C_CPU0_SA_DQS_DN<6> @T6G_MB_LIB.T6G(SCH_1):M_C_CPU0_SA_DQS_DN(6)
   U25  P55 MCA_DQS_L6 GENOA_SP5-SOCKET6096_13568-001,SMLF,IO,DGA^6000030   I159 @T6G_MB_LIB.T6G(SCH_1):PAGE12
   J17  167 DQS6_A_C||TDQS6_A_C||DQS6_A_T||TDQS6_A_T SCONN288_DDR506112002KQ-SCONN288_DDR506112002KQ,SMA   I411 @T6G_MB_LIB.T6G(SCH_1):PAGE87

M_C_CPU0_SA_DQS_DN<7> @T6G_MB_LIB.T6G(SCH_1):M_C_CPU0_SA_DQS_DN(7)
   U25  Y55 MCA_DQS_L7 GENOA_SP5-SOCKET6096_13568-001,SMLF,IO,DGA^6000030   I159 @T6G_MB_LIB.T6G(SCH_1):PAGE12
   J17  178 DQS7_A_C||TDQS7_A_C SCONN288_DDR506112002KQ-SCONN288_DDR506112002KQ,SMA   I411 @T6G_MB_LIB.T6G(SCH_1):PAGE87

M_C_CPU0_SA_DQS_DN<8> @T6G_MB_LIB.T6G(SCH_1):M_C_CPU0_SA_DQS_DN(8)
   U25 AF55 MCA_DQS_L8 GENOA_SP5-SOCKET6096_13568-001,SMLF,IO,DGA^6000030   I159 @T6G_MB_LIB.T6G(SCH_1):PAGE12
   J17  189 DQS8_A_C||TDQS8_A_C SCONN288_DDR506112002KQ-SCONN288_DDR506112002KQ,SMA   I411 @T6G_MB_LIB.T6G(SCH_1):PAGE87

M_C_CPU0_SA_DQS_DN<9> @T6G_MB_LIB.T6G(SCH_1):M_C_CPU0_SA_DQS_DN(9)
   U25 AM55 MCA_DQS_L9 GENOA_SP5-SOCKET6096_13568-001,SMLF,IO,DGA^6000030   I159 @T6G_MB_LIB.T6G(SCH_1):PAGE12
   J17  200 DQS9_A_C||TDQS9_A_C SCONN288_DDR506112002KQ-SCONN288_DDR506112002KQ,SMA   I411 @T6G_MB_LIB.T6G(SCH_1):PAGE87

M_C_CPU0_SA_DQS_DP<0> @T6G_MB_LIB.T6G(SCH_1):M_C_CPU0_SA_DQS_DP(0)
   U25  G57 MCA_DQS_H0 GENOA_SP5-SOCKET6096_13568-001,SMLF,IO,DGA^6000030   I159 @T6G_MB_LIB.T6G(SCH_1):PAGE12
   J17   11 DQS0_A_T SCONN288_DDR506112002KQ-SCONN288_DDR506112002KQ,SMA   I411 @T6G_MB_LIB.T6G(SCH_1):PAGE87

M_C_CPU0_SA_DQS_DP<1> @T6G_MB_LIB.T6G(SCH_1):M_C_CPU0_SA_DQS_DP(1)
   U25  N57 MCA_DQS_H1 GENOA_SP5-SOCKET6096_13568-001,SMLF,IO,DGA^6000030   I159 @T6G_MB_LIB.T6G(SCH_1):PAGE12
   J17   22 DQS1_A_T SCONN288_DDR506112002KQ-SCONN288_DDR506112002KQ,SMA   I411 @T6G_MB_LIB.T6G(SCH_1):PAGE87

M_C_CPU0_SA_DQS_DP<2> @T6G_MB_LIB.T6G(SCH_1):M_C_CPU0_SA_DQS_DP(2)
   U25  W57 MCA_DQS_H2 GENOA_SP5-SOCKET6096_13568-001,SMLF,IO,DGA^6000030   I159 @T6G_MB_LIB.T6G(SCH_1):PAGE12
   J17   33 DQS2_A_T SCONN288_DDR506112002KQ-SCONN288_DDR506112002KQ,SMA   I411 @T6G_MB_LIB.T6G(SCH_1):PAGE87

M_C_CPU0_SA_DQS_DP<3> @T6G_MB_LIB.T6G(SCH_1):M_C_CPU0_SA_DQS_DP(3)
   U25 AE57 MCA_DQS_H3 GENOA_SP5-SOCKET6096_13568-001,SMLF,IO,DGA^6000030   I159 @T6G_MB_LIB.T6G(SCH_1):PAGE12
   J17   44 DQS3_A_T SCONN288_DDR506112002KQ-SCONN288_DDR506112002KQ,SMA   I411 @T6G_MB_LIB.T6G(SCH_1):PAGE87

M_C_CPU0_SA_DQS_DP<4> @T6G_MB_LIB.T6G(SCH_1):M_C_CPU0_SA_DQS_DP(4)
   U25 AL57 MCA_DQS_H4 GENOA_SP5-SOCKET6096_13568-001,SMLF,IO,DGA^6000030   I159 @T6G_MB_LIB.T6G(SCH_1):PAGE12
   J17   55 DQS4_A_T SCONN288_DDR506112002KQ-SCONN288_DDR506112002KQ,SMA   I411 @T6G_MB_LIB.T6G(SCH_1):PAGE87

M_C_CPU0_SA_DQS_DP<5> @T6G_MB_LIB.T6G(SCH_1):M_C_CPU0_SA_DQS_DP(5)
   U25  J55 MCA_DQS_H5 GENOA_SP5-SOCKET6096_13568-001,SMLF,IO,DGA^6000030   I159 @T6G_MB_LIB.T6G(SCH_1):PAGE12
   J17  157 DQS5_A_T||TDQS5_A_T SCONN288_DDR506112002KQ-SCONN288_DDR506112002KQ,SMA   I411 @T6G_MB_LIB.T6G(SCH_1):PAGE87

M_C_CPU0_SA_DQS_DP<6> @T6G_MB_LIB.T6G(SCH_1):M_C_CPU0_SA_DQS_DP(6)
   U25  R55 MCA_DQS_H6 GENOA_SP5-SOCKET6096_13568-001,SMLF,IO,DGA^6000030   I159 @T6G_MB_LIB.T6G(SCH_1):PAGE12
   J17  168 DQS6_A_T||TDQS6_A_T SCONN288_DDR506112002KQ-SCONN288_DDR506112002KQ,SMA   I411 @T6G_MB_LIB.T6G(SCH_1):PAGE87

M_C_CPU0_SA_DQS_DP<7> @T6G_MB_LIB.T6G(SCH_1):M_C_CPU0_SA_DQS_DP(7)
   U25 AA55 MCA_DQS_H7 GENOA_SP5-SOCKET6096_13568-001,SMLF,IO,DGA^6000030   I159 @T6G_MB_LIB.T6G(SCH_1):PAGE12
   J17  179 DQS7_A_T||TDQS7_A_T SCONN288_DDR506112002KQ-SCONN288_DDR506112002KQ,SMA   I411 @T6G_MB_LIB.T6G(SCH_1):PAGE87

M_C_CPU0_SA_DQS_DP<8> @T6G_MB_LIB.T6G(SCH_1):M_C_CPU0_SA_DQS_DP(8)
   U25 AG55 MCA_DQS_H8 GENOA_SP5-SOCKET6096_13568-001,SMLF,IO,DGA^6000030   I159 @T6G_MB_LIB.T6G(SCH_1):PAGE12
   J17  190 DQS8_A_T||TDQS8_A_T SCONN288_DDR506112002KQ-SCONN288_DDR506112002KQ,SMA   I411 @T6G_MB_LIB.T6G(SCH_1):PAGE87

M_C_CPU0_SA_DQS_DP<9> @T6G_MB_LIB.T6G(SCH_1):M_C_CPU0_SA_DQS_DP(9)
   U25 AN55 MCA_DQS_H9 GENOA_SP5-SOCKET6096_13568-001,SMLF,IO,DGA^6000030   I159 @T6G_MB_LIB.T6G(SCH_1):PAGE12
   J17  201 DQS9_A_T||TDQS9_A_T SCONN288_DDR506112002KQ-SCONN288_DDR506112002KQ,SMA   I411 @T6G_MB_LIB.T6G(SCH_1):PAGE87

M_C_CPU0_SA_PAR @T6G_MB_LIB.T6G(SCH_1):M_C_CPU0_SA_PAR
   U25 BC55 MCA_PAR GENOA_SP5-SOCKET6096_13568-001,SMLF,IO,DGA^6000030   I159 @T6G_MB_LIB.T6G(SCH_1):PAGE12
   J17   74  PAR_A SCONN288_DDR506112002KQ-SCONN288_DDR506112002KQ,SMA   I350 @T6G_MB_LIB.T6G(SCH_1):PAGE87

M_C_CPU0_SA_RSP<0> @T6G_MB_LIB.T6G(SCH_1):M_C_CPU0_SA_RSP(0)
   U25 BN55 MCA0_RSP_L GENOA_SP5-SOCKET6096_13568-001,SMLF,IO,DGA^6000030   I159 @T6G_MB_LIB.T6G(SCH_1):PAGE12
   J17   86 LBD||RSP_A_N SCONN288_DDR506112002KQ-SCONN288_DDR506112002KQ,SMA   I350 @T6G_MB_LIB.T6G(SCH_1):PAGE87

M_C_CPU0_SB_CA<0> @T6G_MB_LIB.T6G(SCH_1):M_C_CPU0_SB_CA(0)
   U25 BG55 MCB_CA0 GENOA_SP5-SOCKET6096_13568-001,SMLF,IO,DGA^6000030   I159 @T6G_MB_LIB.T6G(SCH_1):PAGE12
   J17   76  CA0_B SCONN288_DDR506112002KQ-SCONN288_DDR506112002KQ,SMA   I350 @T6G_MB_LIB.T6G(SCH_1):PAGE87

M_C_CPU0_SB_CA<1> @T6G_MB_LIB.T6G(SCH_1):M_C_CPU0_SB_CA(1)
   U25 BH55 MCB_CA1 GENOA_SP5-SOCKET6096_13568-001,SMLF,IO,DGA^6000030   I159 @T6G_MB_LIB.T6G(SCH_1):PAGE12
   J17  221  CA1_B SCONN288_DDR506112002KQ-SCONN288_DDR506112002KQ,SMA   I350 @T6G_MB_LIB.T6G(SCH_1):PAGE87

M_C_CPU0_SB_CA<2> @T6G_MB_LIB.T6G(SCH_1):M_C_CPU0_SB_CA(2)
   U25 BH56 MCB_CA2 GENOA_SP5-SOCKET6096_13568-001,SMLF,IO,DGA^6000030   I159 @T6G_MB_LIB.T6G(SCH_1):PAGE12
   J17   78  CA2_B SCONN288_DDR506112002KQ-SCONN288_DDR506112002KQ,SMA   I350 @T6G_MB_LIB.T6G(SCH_1):PAGE87

M_C_CPU0_SB_CA<3> @T6G_MB_LIB.T6G(SCH_1):M_C_CPU0_SB_CA(3)
   U25 BJ57 MCB_CA3 GENOA_SP5-SOCKET6096_13568-001,SMLF,IO,DGA^6000030   I159 @T6G_MB_LIB.T6G(SCH_1):PAGE12
   J17  223  CA3_B SCONN288_DDR506112002KQ-SCONN288_DDR506112002KQ,SMA   I350 @T6G_MB_LIB.T6G(SCH_1):PAGE87

M_C_CPU0_SB_CA<4> @T6G_MB_LIB.T6G(SCH_1):M_C_CPU0_SB_CA(4)
   U25 BJ55 MCB_CA4 GENOA_SP5-SOCKET6096_13568-001,SMLF,IO,DGA^6000030   I159 @T6G_MB_LIB.T6G(SCH_1):PAGE12
   J17   80  CA4_B SCONN288_DDR506112002KQ-SCONN288_DDR506112002KQ,SMA   I350 @T6G_MB_LIB.T6G(SCH_1):PAGE87

M_C_CPU0_SB_CA<5> @T6G_MB_LIB.T6G(SCH_1):M_C_CPU0_SB_CA(5)
   U25 BK55 MCB_CA5 GENOA_SP5-SOCKET6096_13568-001,SMLF,IO,DGA^6000030   I159 @T6G_MB_LIB.T6G(SCH_1):PAGE12
   J17  225  CA5_B SCONN288_DDR506112002KQ-SCONN288_DDR506112002KQ,SMA   I350 @T6G_MB_LIB.T6G(SCH_1):PAGE87

M_C_CPU0_SB_CA<6> @T6G_MB_LIB.T6G(SCH_1):M_C_CPU0_SB_CA(6)
   U25 BK56 MCB_CA6 GENOA_SP5-SOCKET6096_13568-001,SMLF,IO,DGA^6000030   I159 @T6G_MB_LIB.T6G(SCH_1):PAGE12
   J17   82  CA6_B SCONN288_DDR506112002KQ-SCONN288_DDR506112002KQ,SMA   I350 @T6G_MB_LIB.T6G(SCH_1):PAGE87

M_C_CPU0_SB_CB<0> @T6G_MB_LIB.T6G(SCH_1):M_C_CPU0_SB_CB(0)
   U25 BY56 MCB_CHECK0 GENOA_SP5-SOCKET6096_13568-001,SMLF,IO,DGA^6000030   I159 @T6G_MB_LIB.T6G(SCH_1):PAGE12
   J17   96  CB0_B SCONN288_DDR506112002KQ-SCONN288_DDR506112002KQ,SMA   I350 @T6G_MB_LIB.T6G(SCH_1):PAGE87

M_C_CPU0_SB_CB<1> @T6G_MB_LIB.T6G(SCH_1):M_C_CPU0_SB_CB(1)
   U25 CA55 MCB_CHECK1 GENOA_SP5-SOCKET6096_13568-001,SMLF,IO,DGA^6000030   I159 @T6G_MB_LIB.T6G(SCH_1):PAGE12
   J17   98  CB1_B SCONN288_DDR506112002KQ-SCONN288_DDR506112002KQ,SMA   I350 @T6G_MB_LIB.T6G(SCH_1):PAGE87

M_C_CPU0_SB_CB<2> @T6G_MB_LIB.T6G(SCH_1):M_C_CPU0_SB_CB(2)
   U25 CA57 MCB_CHECK2 GENOA_SP5-SOCKET6096_13568-001,SMLF,IO,DGA^6000030   I159 @T6G_MB_LIB.T6G(SCH_1):PAGE12
   J17  241  CB2_B SCONN288_DDR506112002KQ-SCONN288_DDR506112002KQ,SMA   I350 @T6G_MB_LIB.T6G(SCH_1):PAGE87

M_C_CPU0_SB_CB<3> @T6G_MB_LIB.T6G(SCH_1):M_C_CPU0_SB_CB(3)
   U25 CB55 MCB_CHECK3 GENOA_SP5-SOCKET6096_13568-001,SMLF,IO,DGA^6000030   I159 @T6G_MB_LIB.T6G(SCH_1):PAGE12
   J17  243  CB3_B SCONN288_DDR506112002KQ-SCONN288_DDR506112002KQ,SMA   I350 @T6G_MB_LIB.T6G(SCH_1):PAGE87

M_C_CPU0_SB_CB<4> @T6G_MB_LIB.T6G(SCH_1):M_C_CPU0_SB_CB(4)
   U25 BT56 MCB_CHECK4 GENOA_SP5-SOCKET6096_13568-001,SMLF,IO,DGA^6000030   I159 @T6G_MB_LIB.T6G(SCH_1):PAGE12
   J17   89  CB4_B SCONN288_DDR506112002KQ-SCONN288_DDR506112002KQ,SMA   I350 @T6G_MB_LIB.T6G(SCH_1):PAGE87

M_C_CPU0_SB_CB<5> @T6G_MB_LIB.T6G(SCH_1):M_C_CPU0_SB_CB(5)
   U25 BU55 MCB_CHECK5 GENOA_SP5-SOCKET6096_13568-001,SMLF,IO,DGA^6000030   I159 @T6G_MB_LIB.T6G(SCH_1):PAGE12
   J17   91  CB5_B SCONN288_DDR506112002KQ-SCONN288_DDR506112002KQ,SMA   I350 @T6G_MB_LIB.T6G(SCH_1):PAGE87

M_C_CPU0_SB_CB<6> @T6G_MB_LIB.T6G(SCH_1):M_C_CPU0_SB_CB(6)
   U25 BU57 MCB_CHECK6 GENOA_SP5-SOCKET6096_13568-001,SMLF,IO,DGA^6000030   I159 @T6G_MB_LIB.T6G(SCH_1):PAGE12
   J17  234  CB6_B SCONN288_DDR506112002KQ-SCONN288_DDR506112002KQ,SMA   I350 @T6G_MB_LIB.T6G(SCH_1):PAGE87

M_C_CPU0_SB_CB<7> @T6G_MB_LIB.T6G(SCH_1):M_C_CPU0_SB_CB(7)
   U25 BV55 MCB_CHECK7 GENOA_SP5-SOCKET6096_13568-001,SMLF,IO,DGA^6000030   I159 @T6G_MB_LIB.T6G(SCH_1):PAGE12
   J17  236  CB7_B SCONN288_DDR506112002KQ-SCONN288_DDR506112002KQ,SMA   I350 @T6G_MB_LIB.T6G(SCH_1):PAGE87

M_C_CPU0_SB_CS_N<0> @T6G_MB_LIB.T6G(SCH_1):M_C_CPU0_SB_CS_N(0)
   U25 BM55 MCB0_CS_L0 GENOA_SP5-SOCKET6096_13568-001,SMLF,IO,DGA^6000030   I159 @T6G_MB_LIB.T6G(SCH_1):PAGE12
   J17   84 CS0_B_N SCONN288_DDR506112002KQ-SCONN288_DDR506112002KQ,SMA   I350 @T6G_MB_LIB.T6G(SCH_1):PAGE87

M_C_CPU0_SB_CS_N<1> @T6G_MB_LIB.T6G(SCH_1):M_C_CPU0_SB_CS_N(1)
   U25 BN57 MCB0_CS_L1 GENOA_SP5-SOCKET6096_13568-001,SMLF,IO,DGA^6000030   I159 @T6G_MB_LIB.T6G(SCH_1):PAGE12
   J17  229 CS1_B_N SCONN288_DDR506112002KQ-SCONN288_DDR506112002KQ,SMA   I350 @T6G_MB_LIB.T6G(SCH_1):PAGE87

M_C_CPU0_SB_DQ<0> @T6G_MB_LIB.T6G(SCH_1):M_C_CPU0_SB_DQ(0)
   U25 CB56 MCB_DATA0 GENOA_SP5-SOCKET6096_13568-001,SMLF,IO,DGA^6000030   I159 @T6G_MB_LIB.T6G(SCH_1):PAGE12
   J17  100  DQ0_B SCONN288_DDR506112002KQ-SCONN288_DDR506112002KQ,SMA   I350 @T6G_MB_LIB.T6G(SCH_1):PAGE87

M_C_CPU0_SB_DQ<10> @T6G_MB_LIB.T6G(SCH_1):M_C_CPU0_SB_DQ(10)
   U25 CJ57 MCB_DATA10 GENOA_SP5-SOCKET6096_13568-001,SMLF,IO,DGA^6000030   I159 @T6G_MB_LIB.T6G(SCH_1):PAGE12
   J17  256 DQ10_B SCONN288_DDR506112002KQ-SCONN288_DDR506112002KQ,SMA   I350 @T6G_MB_LIB.T6G(SCH_1):PAGE87

M_C_CPU0_SB_DQ<11> @T6G_MB_LIB.T6G(SCH_1):M_C_CPU0_SB_DQ(11)
   U25 CK55 MCB_DATA11 GENOA_SP5-SOCKET6096_13568-001,SMLF,IO,DGA^6000030   I159 @T6G_MB_LIB.T6G(SCH_1):PAGE12
   J17  258 DQ11_B SCONN288_DDR506112002KQ-SCONN288_DDR506112002KQ,SMA   I350 @T6G_MB_LIB.T6G(SCH_1):PAGE87

M_C_CPU0_SB_DQ<12> @T6G_MB_LIB.T6G(SCH_1):M_C_CPU0_SB_DQ(12)
   U25 CM56 MCB_DATA12 GENOA_SP5-SOCKET6096_13568-001,SMLF,IO,DGA^6000030   I159 @T6G_MB_LIB.T6G(SCH_1):PAGE12
   J17  118 DQ12_B SCONN288_DDR506112002KQ-SCONN288_DDR506112002KQ,SMA   I350 @T6G_MB_LIB.T6G(SCH_1):PAGE87

M_C_CPU0_SB_DQ<13> @T6G_MB_LIB.T6G(SCH_1):M_C_CPU0_SB_DQ(13)
   U25 CN55 MCB_DATA13 GENOA_SP5-SOCKET6096_13568-001,SMLF,IO,DGA^6000030   I159 @T6G_MB_LIB.T6G(SCH_1):PAGE12
   J17  120 DQ13_B SCONN288_DDR506112002KQ-SCONN288_DDR506112002KQ,SMA   I350 @T6G_MB_LIB.T6G(SCH_1):PAGE87

M_C_CPU0_SB_DQ<14> @T6G_MB_LIB.T6G(SCH_1):M_C_CPU0_SB_DQ(14)
   U25 CN57 MCB_DATA14 GENOA_SP5-SOCKET6096_13568-001,SMLF,IO,DGA^6000030   I159 @T6G_MB_LIB.T6G(SCH_1):PAGE12
   J17  263 DQ14_B SCONN288_DDR506112002KQ-SCONN288_DDR506112002KQ,SMA   I350 @T6G_MB_LIB.T6G(SCH_1):PAGE87

M_C_CPU0_SB_DQ<15> @T6G_MB_LIB.T6G(SCH_1):M_C_CPU0_SB_DQ(15)
   U25 CP55 MCB_DATA15 GENOA_SP5-SOCKET6096_13568-001,SMLF,IO,DGA^6000030   I159 @T6G_MB_LIB.T6G(SCH_1):PAGE12
   J17  265 DQ15_B SCONN288_DDR506112002KQ-SCONN288_DDR506112002KQ,SMA   I350 @T6G_MB_LIB.T6G(SCH_1):PAGE87

M_C_CPU0_SB_DQ<16> @T6G_MB_LIB.T6G(SCH_1):M_C_CPU0_SB_DQ(16)
   U25 CP56 MCB_DATA16 GENOA_SP5-SOCKET6096_13568-001,SMLF,IO,DGA^6000030   I159 @T6G_MB_LIB.T6G(SCH_1):PAGE12
   J17  122 DQ16_B SCONN288_DDR506112002KQ-SCONN288_DDR506112002KQ,SMA   I350 @T6G_MB_LIB.T6G(SCH_1):PAGE87

M_C_CPU0_SB_DQ<17> @T6G_MB_LIB.T6G(SCH_1):M_C_CPU0_SB_DQ(17)
   U25 CR55 MCB_DATA17 GENOA_SP5-SOCKET6096_13568-001,SMLF,IO,DGA^6000030   I159 @T6G_MB_LIB.T6G(SCH_1):PAGE12
   J17  124 DQ17_B SCONN288_DDR506112002KQ-SCONN288_DDR506112002KQ,SMA   I350 @T6G_MB_LIB.T6G(SCH_1):PAGE87

M_C_CPU0_SB_DQ<18> @T6G_MB_LIB.T6G(SCH_1):M_C_CPU0_SB_DQ(18)
   U25 CR57 MCB_DATA18 GENOA_SP5-SOCKET6096_13568-001,SMLF,IO,DGA^6000030   I159 @T6G_MB_LIB.T6G(SCH_1):PAGE12
   J17  267 DQ18_B SCONN288_DDR506112002KQ-SCONN288_DDR506112002KQ,SMA   I350 @T6G_MB_LIB.T6G(SCH_1):PAGE87

M_C_CPU0_SB_DQ<19> @T6G_MB_LIB.T6G(SCH_1):M_C_CPU0_SB_DQ(19)
   U25 CT55 MCB_DATA19 GENOA_SP5-SOCKET6096_13568-001,SMLF,IO,DGA^6000030   I159 @T6G_MB_LIB.T6G(SCH_1):PAGE12
   J17  269 DQ19_B SCONN288_DDR506112002KQ-SCONN288_DDR506112002KQ,SMA   I350 @T6G_MB_LIB.T6G(SCH_1):PAGE87

M_C_CPU0_SB_DQ<1> @T6G_MB_LIB.T6G(SCH_1):M_C_CPU0_SB_DQ(1)
   U25 CC55 MCB_DATA1 GENOA_SP5-SOCKET6096_13568-001,SMLF,IO,DGA^6000030   I159 @T6G_MB_LIB.T6G(SCH_1):PAGE12
   J17  102  DQ1_B SCONN288_DDR506112002KQ-SCONN288_DDR506112002KQ,SMA   I350 @T6G_MB_LIB.T6G(SCH_1):PAGE87

M_C_CPU0_SB_DQ<20> @T6G_MB_LIB.T6G(SCH_1):M_C_CPU0_SB_DQ(20)
   U25 CV56 MCB_DATA20 GENOA_SP5-SOCKET6096_13568-001,SMLF,IO,DGA^6000030   I159 @T6G_MB_LIB.T6G(SCH_1):PAGE12
   J17  129 DQ20_B SCONN288_DDR506112002KQ-SCONN288_DDR506112002KQ,SMA   I350 @T6G_MB_LIB.T6G(SCH_1):PAGE87

M_C_CPU0_SB_DQ<21> @T6G_MB_LIB.T6G(SCH_1):M_C_CPU0_SB_DQ(21)
   U25 CW55 MCB_DATA21 GENOA_SP5-SOCKET6096_13568-001,SMLF,IO,DGA^6000030   I159 @T6G_MB_LIB.T6G(SCH_1):PAGE12
   J17  131 DQ21_B SCONN288_DDR506112002KQ-SCONN288_DDR506112002KQ,SMA   I350 @T6G_MB_LIB.T6G(SCH_1):PAGE87

M_C_CPU0_SB_DQ<22> @T6G_MB_LIB.T6G(SCH_1):M_C_CPU0_SB_DQ(22)
   U25 CW57 MCB_DATA22 GENOA_SP5-SOCKET6096_13568-001,SMLF,IO,DGA^6000030   I159 @T6G_MB_LIB.T6G(SCH_1):PAGE12
   J17  274 DQ22_B SCONN288_DDR506112002KQ-SCONN288_DDR506112002KQ,SMA   I350 @T6G_MB_LIB.T6G(SCH_1):PAGE87

M_C_CPU0_SB_DQ<23> @T6G_MB_LIB.T6G(SCH_1):M_C_CPU0_SB_DQ(23)
   U25 CY55 MCB_DATA23 GENOA_SP5-SOCKET6096_13568-001,SMLF,IO,DGA^6000030   I159 @T6G_MB_LIB.T6G(SCH_1):PAGE12
   J17  276 DQ23_B SCONN288_DDR506112002KQ-SCONN288_DDR506112002KQ,SMA   I350 @T6G_MB_LIB.T6G(SCH_1):PAGE87

M_C_CPU0_SB_DQ<24> @T6G_MB_LIB.T6G(SCH_1):M_C_CPU0_SB_DQ(24)
   U25 CY56 MCB_DATA24 GENOA_SP5-SOCKET6096_13568-001,SMLF,IO,DGA^6000030   I159 @T6G_MB_LIB.T6G(SCH_1):PAGE12
   J17  133 DQ24_B SCONN288_DDR506112002KQ-SCONN288_DDR506112002KQ,SMA   I350 @T6G_MB_LIB.T6G(SCH_1):PAGE87

M_C_CPU0_SB_DQ<25> @T6G_MB_LIB.T6G(SCH_1):M_C_CPU0_SB_DQ(25)
   U25 DA55 MCB_DATA25 GENOA_SP5-SOCKET6096_13568-001,SMLF,IO,DGA^6000030   I159 @T6G_MB_LIB.T6G(SCH_1):PAGE12
   J17  135 DQ25_B SCONN288_DDR506112002KQ-SCONN288_DDR506112002KQ,SMA   I350 @T6G_MB_LIB.T6G(SCH_1):PAGE87

M_C_CPU0_SB_DQ<26> @T6G_MB_LIB.T6G(SCH_1):M_C_CPU0_SB_DQ(26)
   U25 DA57 MCB_DATA26 GENOA_SP5-SOCKET6096_13568-001,SMLF,IO,DGA^6000030   I159 @T6G_MB_LIB.T6G(SCH_1):PAGE12
   J17  278 DQ26_B SCONN288_DDR506112002KQ-SCONN288_DDR506112002KQ,SMA   I350 @T6G_MB_LIB.T6G(SCH_1):PAGE87

M_C_CPU0_SB_DQ<27> @T6G_MB_LIB.T6G(SCH_1):M_C_CPU0_SB_DQ(27)
   U25 DB55 MCB_DATA27 GENOA_SP5-SOCKET6096_13568-001,SMLF,IO,DGA^6000030   I159 @T6G_MB_LIB.T6G(SCH_1):PAGE12
   J17  280 DQ27_B SCONN288_DDR506112002KQ-SCONN288_DDR506112002KQ,SMA   I350 @T6G_MB_LIB.T6G(SCH_1):PAGE87

M_C_CPU0_SB_DQ<28> @T6G_MB_LIB.T6G(SCH_1):M_C_CPU0_SB_DQ(28)
   U25 DD56 MCB_DATA28 GENOA_SP5-SOCKET6096_13568-001,SMLF,IO,DGA^6000030   I159 @T6G_MB_LIB.T6G(SCH_1):PAGE12
   J17  140 DQ28_B SCONN288_DDR506112002KQ-SCONN288_DDR506112002KQ,SMA   I350 @T6G_MB_LIB.T6G(SCH_1):PAGE87

M_C_CPU0_SB_DQ<29> @T6G_MB_LIB.T6G(SCH_1):M_C_CPU0_SB_DQ(29)
   U25 DE55 MCB_DATA29 GENOA_SP5-SOCKET6096_13568-001,SMLF,IO,DGA^6000030   I159 @T6G_MB_LIB.T6G(SCH_1):PAGE12
   J17  142 DQ29_B SCONN288_DDR506112002KQ-SCONN288_DDR506112002KQ,SMA   I350 @T6G_MB_LIB.T6G(SCH_1):PAGE87

M_C_CPU0_SB_DQ<2> @T6G_MB_LIB.T6G(SCH_1):M_C_CPU0_SB_DQ(2)
   U25 CC57 MCB_DATA2 GENOA_SP5-SOCKET6096_13568-001,SMLF,IO,DGA^6000030   I159 @T6G_MB_LIB.T6G(SCH_1):PAGE12
   J17  245  DQ2_B SCONN288_DDR506112002KQ-SCONN288_DDR506112002KQ,SMA   I350 @T6G_MB_LIB.T6G(SCH_1):PAGE87

M_C_CPU0_SB_DQ<30> @T6G_MB_LIB.T6G(SCH_1):M_C_CPU0_SB_DQ(30)
   U25 DE57 MCB_DATA30 GENOA_SP5-SOCKET6096_13568-001,SMLF,IO,DGA^6000030   I159 @T6G_MB_LIB.T6G(SCH_1):PAGE12
   J17  285 DQ30_B SCONN288_DDR506112002KQ-SCONN288_DDR506112002KQ,SMA   I350 @T6G_MB_LIB.T6G(SCH_1):PAGE87

M_C_CPU0_SB_DQ<31> @T6G_MB_LIB.T6G(SCH_1):M_C_CPU0_SB_DQ(31)
   U25 DF55 MCB_DATA31 GENOA_SP5-SOCKET6096_13568-001,SMLF,IO,DGA^6000030   I159 @T6G_MB_LIB.T6G(SCH_1):PAGE12
   J17  287 DQ31_B SCONN288_DDR506112002KQ-SCONN288_DDR506112002KQ,SMA   I350 @T6G_MB_LIB.T6G(SCH_1):PAGE87

M_C_CPU0_SB_DQ<3> @T6G_MB_LIB.T6G(SCH_1):M_C_CPU0_SB_DQ(3)
   U25 CD55 MCB_DATA3 GENOA_SP5-SOCKET6096_13568-001,SMLF,IO,DGA^6000030   I159 @T6G_MB_LIB.T6G(SCH_1):PAGE12
   J17  247  DQ3_B SCONN288_DDR506112002KQ-SCONN288_DDR506112002KQ,SMA   I350 @T6G_MB_LIB.T6G(SCH_1):PAGE87

M_C_CPU0_SB_DQ<4> @T6G_MB_LIB.T6G(SCH_1):M_C_CPU0_SB_DQ(4)
   U25 CF56 MCB_DATA4 GENOA_SP5-SOCKET6096_13568-001,SMLF,IO,DGA^6000030   I159 @T6G_MB_LIB.T6G(SCH_1):PAGE12
   J17  107  DQ4_B SCONN288_DDR506112002KQ-SCONN288_DDR506112002KQ,SMA   I350 @T6G_MB_LIB.T6G(SCH_1):PAGE87

M_C_CPU0_SB_DQ<5> @T6G_MB_LIB.T6G(SCH_1):M_C_CPU0_SB_DQ(5)
   U25 CG55 MCB_DATA5 GENOA_SP5-SOCKET6096_13568-001,SMLF,IO,DGA^6000030   I159 @T6G_MB_LIB.T6G(SCH_1):PAGE12
   J17  109  DQ5_B SCONN288_DDR506112002KQ-SCONN288_DDR506112002KQ,SMA   I350 @T6G_MB_LIB.T6G(SCH_1):PAGE87

M_C_CPU0_SB_DQ<6> @T6G_MB_LIB.T6G(SCH_1):M_C_CPU0_SB_DQ(6)
   U25 CG57 MCB_DATA6 GENOA_SP5-SOCKET6096_13568-001,SMLF,IO,DGA^6000030   I159 @T6G_MB_LIB.T6G(SCH_1):PAGE12
   J17  252  DQ6_B SCONN288_DDR506112002KQ-SCONN288_DDR506112002KQ,SMA   I350 @T6G_MB_LIB.T6G(SCH_1):PAGE87

M_C_CPU0_SB_DQ<7> @T6G_MB_LIB.T6G(SCH_1):M_C_CPU0_SB_DQ(7)
   U25 CH55 MCB_DATA7 GENOA_SP5-SOCKET6096_13568-001,SMLF,IO,DGA^6000030   I159 @T6G_MB_LIB.T6G(SCH_1):PAGE12
   J17  254  DQ7_B SCONN288_DDR506112002KQ-SCONN288_DDR506112002KQ,SMA   I350 @T6G_MB_LIB.T6G(SCH_1):PAGE87

M_C_CPU0_SB_DQ<8> @T6G_MB_LIB.T6G(SCH_1):M_C_CPU0_SB_DQ(8)
   U25 CH56 MCB_DATA8 GENOA_SP5-SOCKET6096_13568-001,SMLF,IO,DGA^6000030   I159 @T6G_MB_LIB.T6G(SCH_1):PAGE12
   J17  111  DQ8_B SCONN288_DDR506112002KQ-SCONN288_DDR506112002KQ,SMA   I350 @T6G_MB_LIB.T6G(SCH_1):PAGE87

M_C_CPU0_SB_DQ<9> @T6G_MB_LIB.T6G(SCH_1):M_C_CPU0_SB_DQ(9)
   U25 CJ55 MCB_DATA9 GENOA_SP5-SOCKET6096_13568-001,SMLF,IO,DGA^6000030   I159 @T6G_MB_LIB.T6G(SCH_1):PAGE12
   J17  113  DQ9_B SCONN288_DDR506112002KQ-SCONN288_DDR506112002KQ,SMA   I350 @T6G_MB_LIB.T6G(SCH_1):PAGE87

M_C_CPU0_SB_DQS_DN<0> @T6G_MB_LIB.T6G(SCH_1):M_C_CPU0_SB_DQS_DN(0)
   U25 CE57 MCB_DQS_L0 GENOA_SP5-SOCKET6096_13568-001,SMLF,IO,DGA^6000030   I159 @T6G_MB_LIB.T6G(SCH_1):PAGE12
   J17  105 DQS0_B_C SCONN288_DDR506112002KQ-SCONN288_DDR506112002KQ,SMA   I411 @T6G_MB_LIB.T6G(SCH_1):PAGE87

M_C_CPU0_SB_DQS_DN<1> @T6G_MB_LIB.T6G(SCH_1):M_C_CPU0_SB_DQS_DN(1)
   U25 CL57 MCB_DQS_L1 GENOA_SP5-SOCKET6096_13568-001,SMLF,IO,DGA^6000030   I159 @T6G_MB_LIB.T6G(SCH_1):PAGE12
   J17  116 DQS1_B_C SCONN288_DDR506112002KQ-SCONN288_DDR506112002KQ,SMA   I411 @T6G_MB_LIB.T6G(SCH_1):PAGE87

M_C_CPU0_SB_DQS_DN<2> @T6G_MB_LIB.T6G(SCH_1):M_C_CPU0_SB_DQS_DN(2)
   U25 CU57 MCB_DQS_L2 GENOA_SP5-SOCKET6096_13568-001,SMLF,IO,DGA^6000030   I159 @T6G_MB_LIB.T6G(SCH_1):PAGE12
   J17  127 DQS2_B_C SCONN288_DDR506112002KQ-SCONN288_DDR506112002KQ,SMA   I411 @T6G_MB_LIB.T6G(SCH_1):PAGE87

M_C_CPU0_SB_DQS_DN<3> @T6G_MB_LIB.T6G(SCH_1):M_C_CPU0_SB_DQS_DN(3)
   U25 DC57 MCB_DQS_L3 GENOA_SP5-SOCKET6096_13568-001,SMLF,IO,DGA^6000030   I159 @T6G_MB_LIB.T6G(SCH_1):PAGE12
   J17  138 DQS3_B_C SCONN288_DDR506112002KQ-SCONN288_DDR506112002KQ,SMA   I411 @T6G_MB_LIB.T6G(SCH_1):PAGE87

M_C_CPU0_SB_DQS_DN<4> @T6G_MB_LIB.T6G(SCH_1):M_C_CPU0_SB_DQS_DN(4)
   U25 BW55 MCB_DQS_L4 GENOA_SP5-SOCKET6096_13568-001,SMLF,IO,DGA^6000030   I159 @T6G_MB_LIB.T6G(SCH_1):PAGE12
   J17  238 DQS4_B_C SCONN288_DDR506112002KQ-SCONN288_DDR506112002KQ,SMA   I411 @T6G_MB_LIB.T6G(SCH_1):PAGE87

M_C_CPU0_SB_DQS_DN<5> @T6G_MB_LIB.T6G(SCH_1):M_C_CPU0_SB_DQS_DN(5)
   U25 CE55 MCB_DQS_L5 GENOA_SP5-SOCKET6096_13568-001,SMLF,IO,DGA^6000030   I159 @T6G_MB_LIB.T6G(SCH_1):PAGE12
   J17  249 DQS5_B_C||TDQS5_B_C SCONN288_DDR506112002KQ-SCONN288_DDR506112002KQ,SMA   I411 @T6G_MB_LIB.T6G(SCH_1):PAGE87

M_C_CPU0_SB_DQS_DN<6> @T6G_MB_LIB.T6G(SCH_1):M_C_CPU0_SB_DQS_DN(6)
   U25 CL55 MCB_DQS_L6 GENOA_SP5-SOCKET6096_13568-001,SMLF,IO,DGA^6000030   I159 @T6G_MB_LIB.T6G(SCH_1):PAGE12
   J17  260 DQS6_B_C||TDQS6_B_C SCONN288_DDR506112002KQ-SCONN288_DDR506112002KQ,SMA   I411 @T6G_MB_LIB.T6G(SCH_1):PAGE87

M_C_CPU0_SB_DQS_DN<7> @T6G_MB_LIB.T6G(SCH_1):M_C_CPU0_SB_DQS_DN(7)
   U25 CU55 MCB_DQS_L7 GENOA_SP5-SOCKET6096_13568-001,SMLF,IO,DGA^6000030   I159 @T6G_MB_LIB.T6G(SCH_1):PAGE12
   J17  271 DQS7_B_C||TDQS7_B_C SCONN288_DDR506112002KQ-SCONN288_DDR506112002KQ,SMA   I411 @T6G_MB_LIB.T6G(SCH_1):PAGE87

M_C_CPU0_SB_DQS_DN<8> @T6G_MB_LIB.T6G(SCH_1):M_C_CPU0_SB_DQS_DN(8)
   U25 DC55 MCB_DQS_L8 GENOA_SP5-SOCKET6096_13568-001,SMLF,IO,DGA^6000030   I159 @T6G_MB_LIB.T6G(SCH_1):PAGE12
   J17  282 DQS8_B_C||TDQS8_B_C SCONN288_DDR506112002KQ-SCONN288_DDR506112002KQ,SMA   I411 @T6G_MB_LIB.T6G(SCH_1):PAGE87

M_C_CPU0_SB_DQS_DN<9> @T6G_MB_LIB.T6G(SCH_1):M_C_CPU0_SB_DQS_DN(9)
   U25 BW57 MCB_DQS_L9 GENOA_SP5-SOCKET6096_13568-001,SMLF,IO,DGA^6000030   I159 @T6G_MB_LIB.T6G(SCH_1):PAGE12
   J17   94 DQS9_B_C||TDQS9_B_C SCONN288_DDR506112002KQ-SCONN288_DDR506112002KQ,SMA   I411 @T6G_MB_LIB.T6G(SCH_1):PAGE87

M_C_CPU0_SB_DQS_DP<0> @T6G_MB_LIB.T6G(SCH_1):M_C_CPU0_SB_DQS_DP(0)
   U25 CD56 MCB_DQS_H0 GENOA_SP5-SOCKET6096_13568-001,SMLF,IO,DGA^6000030   I159 @T6G_MB_LIB.T6G(SCH_1):PAGE12
   J17  104 DQS0_B_T SCONN288_DDR506112002KQ-SCONN288_DDR506112002KQ,SMA   I411 @T6G_MB_LIB.T6G(SCH_1):PAGE87

M_C_CPU0_SB_DQS_DP<1> @T6G_MB_LIB.T6G(SCH_1):M_C_CPU0_SB_DQS_DP(1)
   U25 CK56 MCB_DQS_H1 GENOA_SP5-SOCKET6096_13568-001,SMLF,IO,DGA^6000030   I159 @T6G_MB_LIB.T6G(SCH_1):PAGE12
   J17  115 DQS1_B_T SCONN288_DDR506112002KQ-SCONN288_DDR506112002KQ,SMA   I411 @T6G_MB_LIB.T6G(SCH_1):PAGE87

M_C_CPU0_SB_DQS_DP<2> @T6G_MB_LIB.T6G(SCH_1):M_C_CPU0_SB_DQS_DP(2)
   U25 CT56 MCB_DQS_H2 GENOA_SP5-SOCKET6096_13568-001,SMLF,IO,DGA^6000030   I159 @T6G_MB_LIB.T6G(SCH_1):PAGE12
   J17  126 DQS2_B_T SCONN288_DDR506112002KQ-SCONN288_DDR506112002KQ,SMA   I411 @T6G_MB_LIB.T6G(SCH_1):PAGE87

M_C_CPU0_SB_DQS_DP<3> @T6G_MB_LIB.T6G(SCH_1):M_C_CPU0_SB_DQS_DP(3)
   U25 DB56 MCB_DQS_H3 GENOA_SP5-SOCKET6096_13568-001,SMLF,IO,DGA^6000030   I159 @T6G_MB_LIB.T6G(SCH_1):PAGE12
   J17  137 DQS3_B_T SCONN288_DDR506112002KQ-SCONN288_DDR506112002KQ,SMA   I411 @T6G_MB_LIB.T6G(SCH_1):PAGE87

M_C_CPU0_SB_DQS_DP<4> @T6G_MB_LIB.T6G(SCH_1):M_C_CPU0_SB_DQS_DP(4)
   U25 BY55 MCB_DQS_H4 GENOA_SP5-SOCKET6096_13568-001,SMLF,IO,DGA^6000030   I159 @T6G_MB_LIB.T6G(SCH_1):PAGE12
   J17  239 DQS4_B_T SCONN288_DDR506112002KQ-SCONN288_DDR506112002KQ,SMA   I411 @T6G_MB_LIB.T6G(SCH_1):PAGE87

M_C_CPU0_SB_DQS_DP<5> @T6G_MB_LIB.T6G(SCH_1):M_C_CPU0_SB_DQS_DP(5)
   U25 CF55 MCB_DQS_H5 GENOA_SP5-SOCKET6096_13568-001,SMLF,IO,DGA^6000030   I159 @T6G_MB_LIB.T6G(SCH_1):PAGE12
   J17  250 DQS5_B_T||TDQS5_B_T SCONN288_DDR506112002KQ-SCONN288_DDR506112002KQ,SMA   I411 @T6G_MB_LIB.T6G(SCH_1):PAGE87

M_C_CPU0_SB_DQS_DP<6> @T6G_MB_LIB.T6G(SCH_1):M_C_CPU0_SB_DQS_DP(6)
   U25 CM55 MCB_DQS_H6 GENOA_SP5-SOCKET6096_13568-001,SMLF,IO,DGA^6000030   I159 @T6G_MB_LIB.T6G(SCH_1):PAGE12
   J17  261 DQS6_B_T||TDQS6_B_T SCONN288_DDR506112002KQ-SCONN288_DDR506112002KQ,SMA   I411 @T6G_MB_LIB.T6G(SCH_1):PAGE87

M_C_CPU0_SB_DQS_DP<7> @T6G_MB_LIB.T6G(SCH_1):M_C_CPU0_SB_DQS_DP(7)
   U25 CV55 MCB_DQS_H7 GENOA_SP5-SOCKET6096_13568-001,SMLF,IO,DGA^6000030   I159 @T6G_MB_LIB.T6G(SCH_1):PAGE12
   J17  272 DQS7_B_T||TDQS7_B_T SCONN288_DDR506112002KQ-SCONN288_DDR506112002KQ,SMA   I411 @T6G_MB_LIB.T6G(SCH_1):PAGE87

M_C_CPU0_SB_DQS_DP<8> @T6G_MB_LIB.T6G(SCH_1):M_C_CPU0_SB_DQS_DP(8)
   U25 DD55 MCB_DQS_H8 GENOA_SP5-SOCKET6096_13568-001,SMLF,IO,DGA^6000030   I159 @T6G_MB_LIB.T6G(SCH_1):PAGE12
   J17  283 DQS8_B_T||TDQS8_B_T SCONN288_DDR506112002KQ-SCONN288_DDR506112002KQ,SMA   I411 @T6G_MB_LIB.T6G(SCH_1):PAGE87

M_C_CPU0_SB_DQS_DP<9> @T6G_MB_LIB.T6G(SCH_1):M_C_CPU0_SB_DQS_DP(9)
   U25 BV56 MCB_DQS_H9 GENOA_SP5-SOCKET6096_13568-001,SMLF,IO,DGA^6000030   I159 @T6G_MB_LIB.T6G(SCH_1):PAGE12
   J17   93 DQS9_B_T||TDQS9_B_T||DBI4_B_N SCONN288_DDR506112002KQ-SCONN288_DDR506112002KQ,SMA   I411 @T6G_MB_LIB.T6G(SCH_1):PAGE87

M_C_CPU0_SB_PAR @T6G_MB_LIB.T6G(SCH_1):M_C_CPU0_SB_PAR
   U25 BL57 MCB_PAR GENOA_SP5-SOCKET6096_13568-001,SMLF,IO,DGA^6000030   I159 @T6G_MB_LIB.T6G(SCH_1):PAGE12
   J17  227  PAR_B SCONN288_DDR506112002KQ-SCONN288_DDR506112002KQ,SMA   I350 @T6G_MB_LIB.T6G(SCH_1):PAGE87

M_C_CPU0_SB_RSP<0> @T6G_MB_LIB.T6G(SCH_1):M_C_CPU0_SB_RSP(0)
   U25 BP56 MCB0_RSP_L GENOA_SP5-SOCKET6096_13568-001,SMLF,IO,DGA^6000030   I159 @T6G_MB_LIB.T6G(SCH_1):PAGE12
   J17   87 LBS||RSP_B_N SCONN288_DDR506112002KQ-SCONN288_DDR506112002KQ,SMA   I350 @T6G_MB_LIB.T6G(SCH_1):PAGE87

M_C_CPU1_ALERT_N @T6G_MB_LIB.T6G(SCH_1):M_C_CPU1_ALERT_N
  R502    1      A Q_RES_0402LF-15,1%,1/16W,CHIP,CS01502FB03   I313 @T6G_MB_LIB.T6G(SCH_1):PAGE39
   J28   62 ALERT_N SCONN288_DDR506112002KQ-SCONN288_DDR506112002KQ,SMA    I22 @T6G_MB_LIB.T6G(SCH_1):PAGE99

M_C_CPU1_ALERT_R_N @T6G_MB_LIB.T6G(SCH_1):M_C_CPU1_ALERT_R_N
   U26 AT55 MC_ALERT_L GENOA_SP5-SOCKET6096_13568-001,SMLF,IO,DGA^6000030   I159 @T6G_MB_LIB.T6G(SCH_1):PAGE39
  R502    2      B Q_RES_0402LF-15,1%,1/16W,CHIP,CS01502FB03   I313 @T6G_MB_LIB.T6G(SCH_1):PAGE39

M_C_CPU1_CLK_DN<0> @T6G_MB_LIB.T6G(SCH_1):M_C_CPU1_CLK_DN(0)
   U26 BD56 MC0_CLK_L GENOA_SP5-SOCKET6096_13568-001,SMLF,IO,DGA^6000030   I159 @T6G_MB_LIB.T6G(SCH_1):PAGE39
   J28  218   CK_C SCONN288_DDR506112002KQ-SCONN288_DDR506112002KQ,SMA    I22 @T6G_MB_LIB.T6G(SCH_1):PAGE99

M_C_CPU1_CLK_DP<0> @T6G_MB_LIB.T6G(SCH_1):M_C_CPU1_CLK_DP(0)
   U26 BC57 MC0_CLK_H GENOA_SP5-SOCKET6096_13568-001,SMLF,IO,DGA^6000030   I159 @T6G_MB_LIB.T6G(SCH_1):PAGE39
   J28  217   CK_T SCONN288_DDR506112002KQ-SCONN288_DDR506112002KQ,SMA    I22 @T6G_MB_LIB.T6G(SCH_1):PAGE99

M_C_CPU1_RESET_N @T6G_MB_LIB.T6G(SCH_1):M_C_CPU1_RESET_N
   U26 AU55 MC_RESET_L GENOA_SP5-SOCKET6096_13568-001,SMLF,IO,DGA^6000030   I159 @T6G_MB_LIB.T6G(SCH_1):PAGE39
   J28  207 RESET_N SCONN288_DDR506112002KQ-SCONN288_DDR506112002KQ,SMA    I22 @T6G_MB_LIB.T6G(SCH_1):PAGE99

M_C_CPU1_SA_CA<0> @T6G_MB_LIB.T6G(SCH_1):M_C_CPU1_SA_CA(0)
   U26 AW57 MCA_CA0 GENOA_SP5-SOCKET6096_13568-001,SMLF,IO,DGA^6000030   I159 @T6G_MB_LIB.T6G(SCH_1):PAGE39
   J28   66  CA0_A SCONN288_DDR506112002KQ-SCONN288_DDR506112002KQ,SMA    I22 @T6G_MB_LIB.T6G(SCH_1):PAGE99

M_C_CPU1_SA_CA<1> @T6G_MB_LIB.T6G(SCH_1):M_C_CPU1_SA_CA(1)
   U26 AY56 MCA_CA1 GENOA_SP5-SOCKET6096_13568-001,SMLF,IO,DGA^6000030   I159 @T6G_MB_LIB.T6G(SCH_1):PAGE39
   J28  211  CA1_A SCONN288_DDR506112002KQ-SCONN288_DDR506112002KQ,SMA    I22 @T6G_MB_LIB.T6G(SCH_1):PAGE99

M_C_CPU1_SA_CA<2> @T6G_MB_LIB.T6G(SCH_1):M_C_CPU1_SA_CA(2)
   U26 AY55 MCA_CA2 GENOA_SP5-SOCKET6096_13568-001,SMLF,IO,DGA^6000030   I159 @T6G_MB_LIB.T6G(SCH_1):PAGE39
   J28   68  CA2_A SCONN288_DDR506112002KQ-SCONN288_DDR506112002KQ,SMA    I22 @T6G_MB_LIB.T6G(SCH_1):PAGE99

M_C_CPU1_SA_CA<3> @T6G_MB_LIB.T6G(SCH_1):M_C_CPU1_SA_CA(3)
   U26 BA55 MCA_CA3 GENOA_SP5-SOCKET6096_13568-001,SMLF,IO,DGA^6000030   I159 @T6G_MB_LIB.T6G(SCH_1):PAGE39
   J28  213  CA3_A SCONN288_DDR506112002KQ-SCONN288_DDR506112002KQ,SMA    I22 @T6G_MB_LIB.T6G(SCH_1):PAGE99

M_C_CPU1_SA_CA<4> @T6G_MB_LIB.T6G(SCH_1):M_C_CPU1_SA_CA(4)
   U26 BA57 MCA_CA4 GENOA_SP5-SOCKET6096_13568-001,SMLF,IO,DGA^6000030   I159 @T6G_MB_LIB.T6G(SCH_1):PAGE39
   J28   70  CA4_A SCONN288_DDR506112002KQ-SCONN288_DDR506112002KQ,SMA    I22 @T6G_MB_LIB.T6G(SCH_1):PAGE99

M_C_CPU1_SA_CA<5> @T6G_MB_LIB.T6G(SCH_1):M_C_CPU1_SA_CA(5)
   U26 BB56 MCA_CA5 GENOA_SP5-SOCKET6096_13568-001,SMLF,IO,DGA^6000030   I159 @T6G_MB_LIB.T6G(SCH_1):PAGE39
   J28  215  CA5_A SCONN288_DDR506112002KQ-SCONN288_DDR506112002KQ,SMA    I22 @T6G_MB_LIB.T6G(SCH_1):PAGE99

M_C_CPU1_SA_CA<6> @T6G_MB_LIB.T6G(SCH_1):M_C_CPU1_SA_CA(6)
   U26 BB55 MCA_CA6 GENOA_SP5-SOCKET6096_13568-001,SMLF,IO,DGA^6000030   I159 @T6G_MB_LIB.T6G(SCH_1):PAGE39
   J28   72  CA6_A SCONN288_DDR506112002KQ-SCONN288_DDR506112002KQ,SMA    I22 @T6G_MB_LIB.T6G(SCH_1):PAGE99

M_C_CPU1_SA_CB<0> @T6G_MB_LIB.T6G(SCH_1):M_C_CPU1_SA_CB(0)
   U26 AJ57 MCA_CHECK0 GENOA_SP5-SOCKET6096_13568-001,SMLF,IO,DGA^6000030   I159 @T6G_MB_LIB.T6G(SCH_1):PAGE39
   J28   51  CB0_A SCONN288_DDR506112002KQ-SCONN288_DDR506112002KQ,SMA    I22 @T6G_MB_LIB.T6G(SCH_1):PAGE99

M_C_CPU1_SA_CB<1> @T6G_MB_LIB.T6G(SCH_1):M_C_CPU1_SA_CB(1)
   U26 AK55 MCA_CHECK1 GENOA_SP5-SOCKET6096_13568-001,SMLF,IO,DGA^6000030   I159 @T6G_MB_LIB.T6G(SCH_1):PAGE39
   J28   53  CB1_A SCONN288_DDR506112002KQ-SCONN288_DDR506112002KQ,SMA    I22 @T6G_MB_LIB.T6G(SCH_1):PAGE99

M_C_CPU1_SA_CB<2> @T6G_MB_LIB.T6G(SCH_1):M_C_CPU1_SA_CB(2)
   U26 AK56 MCA_CHECK2 GENOA_SP5-SOCKET6096_13568-001,SMLF,IO,DGA^6000030   I159 @T6G_MB_LIB.T6G(SCH_1):PAGE39
   J28  196  CB2_A SCONN288_DDR506112002KQ-SCONN288_DDR506112002KQ,SMA    I22 @T6G_MB_LIB.T6G(SCH_1):PAGE99

M_C_CPU1_SA_CB<3> @T6G_MB_LIB.T6G(SCH_1):M_C_CPU1_SA_CB(3)
   U26 AL55 MCA_CHECK3 GENOA_SP5-SOCKET6096_13568-001,SMLF,IO,DGA^6000030   I159 @T6G_MB_LIB.T6G(SCH_1):PAGE39
   J28  198  CB3_A SCONN288_DDR506112002KQ-SCONN288_DDR506112002KQ,SMA    I22 @T6G_MB_LIB.T6G(SCH_1):PAGE99

M_C_CPU1_SA_CB<4> @T6G_MB_LIB.T6G(SCH_1):M_C_CPU1_SA_CB(4)
   U26 AN57 MCA_CHECK4 GENOA_SP5-SOCKET6096_13568-001,SMLF,IO,DGA^6000030   I159 @T6G_MB_LIB.T6G(SCH_1):PAGE39
   J28   58  CB4_A SCONN288_DDR506112002KQ-SCONN288_DDR506112002KQ,SMA    I22 @T6G_MB_LIB.T6G(SCH_1):PAGE99

M_C_CPU1_SA_CB<5> @T6G_MB_LIB.T6G(SCH_1):M_C_CPU1_SA_CB(5)
   U26 AP55 MCA_CHECK5 GENOA_SP5-SOCKET6096_13568-001,SMLF,IO,DGA^6000030   I159 @T6G_MB_LIB.T6G(SCH_1):PAGE39
   J28   60  CB5_A SCONN288_DDR506112002KQ-SCONN288_DDR506112002KQ,SMA    I22 @T6G_MB_LIB.T6G(SCH_1):PAGE99

M_C_CPU1_SA_CB<6> @T6G_MB_LIB.T6G(SCH_1):M_C_CPU1_SA_CB(6)
   U26 AP56 MCA_CHECK6 GENOA_SP5-SOCKET6096_13568-001,SMLF,IO,DGA^6000030   I159 @T6G_MB_LIB.T6G(SCH_1):PAGE39
   J28  203  CB6_A SCONN288_DDR506112002KQ-SCONN288_DDR506112002KQ,SMA    I22 @T6G_MB_LIB.T6G(SCH_1):PAGE99

M_C_CPU1_SA_CB<7> @T6G_MB_LIB.T6G(SCH_1):M_C_CPU1_SA_CB(7)
   U26 AR55 MCA_CHECK7 GENOA_SP5-SOCKET6096_13568-001,SMLF,IO,DGA^6000030   I159 @T6G_MB_LIB.T6G(SCH_1):PAGE39
   J28  205  CB7_A SCONN288_DDR506112002KQ-SCONN288_DDR506112002KQ,SMA    I22 @T6G_MB_LIB.T6G(SCH_1):PAGE99

M_C_CPU1_SA_CS_N<0> @T6G_MB_LIB.T6G(SCH_1):M_C_CPU1_SA_CS_N(0)
   U26 AV56 MCA0_CS_L0 GENOA_SP5-SOCKET6096_13568-001,SMLF,IO,DGA^6000030   I159 @T6G_MB_LIB.T6G(SCH_1):PAGE39
   J28   64 CS0_A_N SCONN288_DDR506112002KQ-SCONN288_DDR506112002KQ,SMA    I22 @T6G_MB_LIB.T6G(SCH_1):PAGE99

M_C_CPU1_SA_CS_N<1> @T6G_MB_LIB.T6G(SCH_1):M_C_CPU1_SA_CS_N(1)
   U26 AW55 MCA0_CS_L1 GENOA_SP5-SOCKET6096_13568-001,SMLF,IO,DGA^6000030   I159 @T6G_MB_LIB.T6G(SCH_1):PAGE39
   J28  209 CS1_A_N SCONN288_DDR506112002KQ-SCONN288_DDR506112002KQ,SMA    I22 @T6G_MB_LIB.T6G(SCH_1):PAGE99

M_C_CPU1_SA_DQ<0> @T6G_MB_LIB.T6G(SCH_1):M_C_CPU1_SA_DQ(0)
   U26  E57 MCA_DATA0 GENOA_SP5-SOCKET6096_13568-001,SMLF,IO,DGA^6000030   I159 @T6G_MB_LIB.T6G(SCH_1):PAGE39
   J28    7  DQ0_A SCONN288_DDR506112002KQ-SCONN288_DDR506112002KQ,SMA    I22 @T6G_MB_LIB.T6G(SCH_1):PAGE99

M_C_CPU1_SA_DQ<10> @T6G_MB_LIB.T6G(SCH_1):M_C_CPU1_SA_DQ(10)
   U26  M56 MCA_DATA10 GENOA_SP5-SOCKET6096_13568-001,SMLF,IO,DGA^6000030   I159 @T6G_MB_LIB.T6G(SCH_1):PAGE39
   J28  163 DQ10_A SCONN288_DDR506112002KQ-SCONN288_DDR506112002KQ,SMA    I22 @T6G_MB_LIB.T6G(SCH_1):PAGE99

M_C_CPU1_SA_DQ<11> @T6G_MB_LIB.T6G(SCH_1):M_C_CPU1_SA_DQ(11)
   U26  N55 MCA_DATA11 GENOA_SP5-SOCKET6096_13568-001,SMLF,IO,DGA^6000030   I159 @T6G_MB_LIB.T6G(SCH_1):PAGE39
   J28  165 DQ11_A SCONN288_DDR506112002KQ-SCONN288_DDR506112002KQ,SMA    I22 @T6G_MB_LIB.T6G(SCH_1):PAGE99

M_C_CPU1_SA_DQ<12> @T6G_MB_LIB.T6G(SCH_1):M_C_CPU1_SA_DQ(12)
   U26  R57 MCA_DATA12 GENOA_SP5-SOCKET6096_13568-001,SMLF,IO,DGA^6000030   I159 @T6G_MB_LIB.T6G(SCH_1):PAGE39
   J28   25 DQ12_A SCONN288_DDR506112002KQ-SCONN288_DDR506112002KQ,SMA    I22 @T6G_MB_LIB.T6G(SCH_1):PAGE99

M_C_CPU1_SA_DQ<13> @T6G_MB_LIB.T6G(SCH_1):M_C_CPU1_SA_DQ(13)
   U26  T55 MCA_DATA13 GENOA_SP5-SOCKET6096_13568-001,SMLF,IO,DGA^6000030   I159 @T6G_MB_LIB.T6G(SCH_1):PAGE39
   J28   27 DQ13_A SCONN288_DDR506112002KQ-SCONN288_DDR506112002KQ,SMA    I22 @T6G_MB_LIB.T6G(SCH_1):PAGE99

M_C_CPU1_SA_DQ<14> @T6G_MB_LIB.T6G(SCH_1):M_C_CPU1_SA_DQ(14)
   U26  T56 MCA_DATA14 GENOA_SP5-SOCKET6096_13568-001,SMLF,IO,DGA^6000030   I159 @T6G_MB_LIB.T6G(SCH_1):PAGE39
   J28  170 DQ14_A SCONN288_DDR506112002KQ-SCONN288_DDR506112002KQ,SMA    I22 @T6G_MB_LIB.T6G(SCH_1):PAGE99

M_C_CPU1_SA_DQ<15> @T6G_MB_LIB.T6G(SCH_1):M_C_CPU1_SA_DQ(15)
   U26  U55 MCA_DATA15 GENOA_SP5-SOCKET6096_13568-001,SMLF,IO,DGA^6000030   I159 @T6G_MB_LIB.T6G(SCH_1):PAGE39
   J28  172 DQ15_A SCONN288_DDR506112002KQ-SCONN288_DDR506112002KQ,SMA    I22 @T6G_MB_LIB.T6G(SCH_1):PAGE99

M_C_CPU1_SA_DQ<16> @T6G_MB_LIB.T6G(SCH_1):M_C_CPU1_SA_DQ(16)
   U26  U57 MCA_DATA16 GENOA_SP5-SOCKET6096_13568-001,SMLF,IO,DGA^6000030   I159 @T6G_MB_LIB.T6G(SCH_1):PAGE39
   J28   29 DQ16_A SCONN288_DDR506112002KQ-SCONN288_DDR506112002KQ,SMA    I22 @T6G_MB_LIB.T6G(SCH_1):PAGE99

M_C_CPU1_SA_DQ<17> @T6G_MB_LIB.T6G(SCH_1):M_C_CPU1_SA_DQ(17)
   U26  V55 MCA_DATA17 GENOA_SP5-SOCKET6096_13568-001,SMLF,IO,DGA^6000030   I159 @T6G_MB_LIB.T6G(SCH_1):PAGE39
   J28   31 DQ17_A SCONN288_DDR506112002KQ-SCONN288_DDR506112002KQ,SMA    I22 @T6G_MB_LIB.T6G(SCH_1):PAGE99

M_C_CPU1_SA_DQ<18> @T6G_MB_LIB.T6G(SCH_1):M_C_CPU1_SA_DQ(18)
   U26  V56 MCA_DATA18 GENOA_SP5-SOCKET6096_13568-001,SMLF,IO,DGA^6000030   I159 @T6G_MB_LIB.T6G(SCH_1):PAGE39
   J28  174 DQ18_A SCONN288_DDR506112002KQ-SCONN288_DDR506112002KQ,SMA    I22 @T6G_MB_LIB.T6G(SCH_1):PAGE99

M_C_CPU1_SA_DQ<19> @T6G_MB_LIB.T6G(SCH_1):M_C_CPU1_SA_DQ(19)
   U26  W55 MCA_DATA19 GENOA_SP5-SOCKET6096_13568-001,SMLF,IO,DGA^6000030   I159 @T6G_MB_LIB.T6G(SCH_1):PAGE39
   J28  176 DQ19_A SCONN288_DDR506112002KQ-SCONN288_DDR506112002KQ,SMA    I22 @T6G_MB_LIB.T6G(SCH_1):PAGE99

M_C_CPU1_SA_DQ<1> @T6G_MB_LIB.T6G(SCH_1):M_C_CPU1_SA_DQ(1)
   U26  F55 MCA_DATA1 GENOA_SP5-SOCKET6096_13568-001,SMLF,IO,DGA^6000030   I159 @T6G_MB_LIB.T6G(SCH_1):PAGE39
   J28    9  DQ1_A SCONN288_DDR506112002KQ-SCONN288_DDR506112002KQ,SMA    I22 @T6G_MB_LIB.T6G(SCH_1):PAGE99

M_C_CPU1_SA_DQ<20> @T6G_MB_LIB.T6G(SCH_1):M_C_CPU1_SA_DQ(20)
   U26 AA57 MCA_DATA20 GENOA_SP5-SOCKET6096_13568-001,SMLF,IO,DGA^6000030   I159 @T6G_MB_LIB.T6G(SCH_1):PAGE39
   J28   36 DQ20_A SCONN288_DDR506112002KQ-SCONN288_DDR506112002KQ,SMA    I22 @T6G_MB_LIB.T6G(SCH_1):PAGE99

M_C_CPU1_SA_DQ<21> @T6G_MB_LIB.T6G(SCH_1):M_C_CPU1_SA_DQ(21)
   U26 AB55 MCA_DATA21 GENOA_SP5-SOCKET6096_13568-001,SMLF,IO,DGA^6000030   I159 @T6G_MB_LIB.T6G(SCH_1):PAGE39
   J28   38 DQ21_A SCONN288_DDR506112002KQ-SCONN288_DDR506112002KQ,SMA    I22 @T6G_MB_LIB.T6G(SCH_1):PAGE99

M_C_CPU1_SA_DQ<22> @T6G_MB_LIB.T6G(SCH_1):M_C_CPU1_SA_DQ(22)
   U26 AB56 MCA_DATA22 GENOA_SP5-SOCKET6096_13568-001,SMLF,IO,DGA^6000030   I159 @T6G_MB_LIB.T6G(SCH_1):PAGE39
   J28  181 DQ22_A SCONN288_DDR506112002KQ-SCONN288_DDR506112002KQ,SMA    I22 @T6G_MB_LIB.T6G(SCH_1):PAGE99

M_C_CPU1_SA_DQ<23> @T6G_MB_LIB.T6G(SCH_1):M_C_CPU1_SA_DQ(23)
   U26 AC55 MCA_DATA23 GENOA_SP5-SOCKET6096_13568-001,SMLF,IO,DGA^6000030   I159 @T6G_MB_LIB.T6G(SCH_1):PAGE39
   J28  183 DQ23_A SCONN288_DDR506112002KQ-SCONN288_DDR506112002KQ,SMA    I22 @T6G_MB_LIB.T6G(SCH_1):PAGE99

M_C_CPU1_SA_DQ<24> @T6G_MB_LIB.T6G(SCH_1):M_C_CPU1_SA_DQ(24)
   U26 AC57 MCA_DATA24 GENOA_SP5-SOCKET6096_13568-001,SMLF,IO,DGA^6000030   I159 @T6G_MB_LIB.T6G(SCH_1):PAGE39
   J28   40 DQ24_A SCONN288_DDR506112002KQ-SCONN288_DDR506112002KQ,SMA    I22 @T6G_MB_LIB.T6G(SCH_1):PAGE99

M_C_CPU1_SA_DQ<25> @T6G_MB_LIB.T6G(SCH_1):M_C_CPU1_SA_DQ(25)
   U26 AD55 MCA_DATA25 GENOA_SP5-SOCKET6096_13568-001,SMLF,IO,DGA^6000030   I159 @T6G_MB_LIB.T6G(SCH_1):PAGE39
   J28   42 DQ25_A SCONN288_DDR506112002KQ-SCONN288_DDR506112002KQ,SMA    I22 @T6G_MB_LIB.T6G(SCH_1):PAGE99

M_C_CPU1_SA_DQ<26> @T6G_MB_LIB.T6G(SCH_1):M_C_CPU1_SA_DQ(26)
   U26 AD56 MCA_DATA26 GENOA_SP5-SOCKET6096_13568-001,SMLF,IO,DGA^6000030   I159 @T6G_MB_LIB.T6G(SCH_1):PAGE39
   J28  185 DQ26_A SCONN288_DDR506112002KQ-SCONN288_DDR506112002KQ,SMA    I22 @T6G_MB_LIB.T6G(SCH_1):PAGE99

M_C_CPU1_SA_DQ<27> @T6G_MB_LIB.T6G(SCH_1):M_C_CPU1_SA_DQ(27)
   U26 AE55 MCA_DATA27 GENOA_SP5-SOCKET6096_13568-001,SMLF,IO,DGA^6000030   I159 @T6G_MB_LIB.T6G(SCH_1):PAGE39
   J28  187 DQ27_A SCONN288_DDR506112002KQ-SCONN288_DDR506112002KQ,SMA    I22 @T6G_MB_LIB.T6G(SCH_1):PAGE99

M_C_CPU1_SA_DQ<28> @T6G_MB_LIB.T6G(SCH_1):M_C_CPU1_SA_DQ(28)
   U26 AG57 MCA_DATA28 GENOA_SP5-SOCKET6096_13568-001,SMLF,IO,DGA^6000030   I159 @T6G_MB_LIB.T6G(SCH_1):PAGE39
   J28   47 DQ28_A SCONN288_DDR506112002KQ-SCONN288_DDR506112002KQ,SMA    I22 @T6G_MB_LIB.T6G(SCH_1):PAGE99

M_C_CPU1_SA_DQ<29> @T6G_MB_LIB.T6G(SCH_1):M_C_CPU1_SA_DQ(29)
   U26 AH55 MCA_DATA29 GENOA_SP5-SOCKET6096_13568-001,SMLF,IO,DGA^6000030   I159 @T6G_MB_LIB.T6G(SCH_1):PAGE39
   J28   49 DQ29_A SCONN288_DDR506112002KQ-SCONN288_DDR506112002KQ,SMA    I22 @T6G_MB_LIB.T6G(SCH_1):PAGE99

M_C_CPU1_SA_DQ<2> @T6G_MB_LIB.T6G(SCH_1):M_C_CPU1_SA_DQ(2)
   U26  F56 MCA_DATA2 GENOA_SP5-SOCKET6096_13568-001,SMLF,IO,DGA^6000030   I159 @T6G_MB_LIB.T6G(SCH_1):PAGE39
   J28  152  DQ2_A SCONN288_DDR506112002KQ-SCONN288_DDR506112002KQ,SMA    I22 @T6G_MB_LIB.T6G(SCH_1):PAGE99

M_C_CPU1_SA_DQ<30> @T6G_MB_LIB.T6G(SCH_1):M_C_CPU1_SA_DQ(30)
   U26 AH56 MCA_DATA30 GENOA_SP5-SOCKET6096_13568-001,SMLF,IO,DGA^6000030   I159 @T6G_MB_LIB.T6G(SCH_1):PAGE39
   J28  192 DQ30_A SCONN288_DDR506112002KQ-SCONN288_DDR506112002KQ,SMA    I22 @T6G_MB_LIB.T6G(SCH_1):PAGE99

M_C_CPU1_SA_DQ<31> @T6G_MB_LIB.T6G(SCH_1):M_C_CPU1_SA_DQ(31)
   U26 AJ55 MCA_DATA31 GENOA_SP5-SOCKET6096_13568-001,SMLF,IO,DGA^6000030   I159 @T6G_MB_LIB.T6G(SCH_1):PAGE39
   J28  194 DQ31_A SCONN288_DDR506112002KQ-SCONN288_DDR506112002KQ,SMA    I22 @T6G_MB_LIB.T6G(SCH_1):PAGE99

M_C_CPU1_SA_DQ<3> @T6G_MB_LIB.T6G(SCH_1):M_C_CPU1_SA_DQ(3)
   U26  G55 MCA_DATA3 GENOA_SP5-SOCKET6096_13568-001,SMLF,IO,DGA^6000030   I159 @T6G_MB_LIB.T6G(SCH_1):PAGE39
   J28  154  DQ3_A SCONN288_DDR506112002KQ-SCONN288_DDR506112002KQ,SMA    I22 @T6G_MB_LIB.T6G(SCH_1):PAGE99

M_C_CPU1_SA_DQ<4> @T6G_MB_LIB.T6G(SCH_1):M_C_CPU1_SA_DQ(4)
   U26  J57 MCA_DATA4 GENOA_SP5-SOCKET6096_13568-001,SMLF,IO,DGA^6000030   I159 @T6G_MB_LIB.T6G(SCH_1):PAGE39
   J28   14  DQ4_A SCONN288_DDR506112002KQ-SCONN288_DDR506112002KQ,SMA    I22 @T6G_MB_LIB.T6G(SCH_1):PAGE99

M_C_CPU1_SA_DQ<5> @T6G_MB_LIB.T6G(SCH_1):M_C_CPU1_SA_DQ(5)
   U26  K55 MCA_DATA5 GENOA_SP5-SOCKET6096_13568-001,SMLF,IO,DGA^6000030   I159 @T6G_MB_LIB.T6G(SCH_1):PAGE39
   J28   16  DQ5_A SCONN288_DDR506112002KQ-SCONN288_DDR506112002KQ,SMA    I22 @T6G_MB_LIB.T6G(SCH_1):PAGE99

M_C_CPU1_SA_DQ<6> @T6G_MB_LIB.T6G(SCH_1):M_C_CPU1_SA_DQ(6)
   U26  K56 MCA_DATA6 GENOA_SP5-SOCKET6096_13568-001,SMLF,IO,DGA^6000030   I159 @T6G_MB_LIB.T6G(SCH_1):PAGE39
   J28  159  DQ6_A SCONN288_DDR506112002KQ-SCONN288_DDR506112002KQ,SMA    I22 @T6G_MB_LIB.T6G(SCH_1):PAGE99

M_C_CPU1_SA_DQ<7> @T6G_MB_LIB.T6G(SCH_1):M_C_CPU1_SA_DQ(7)
   U26  L55 MCA_DATA7 GENOA_SP5-SOCKET6096_13568-001,SMLF,IO,DGA^6000030   I159 @T6G_MB_LIB.T6G(SCH_1):PAGE39
   J28  161  DQ7_A SCONN288_DDR506112002KQ-SCONN288_DDR506112002KQ,SMA    I22 @T6G_MB_LIB.T6G(SCH_1):PAGE99

M_C_CPU1_SA_DQ<8> @T6G_MB_LIB.T6G(SCH_1):M_C_CPU1_SA_DQ(8)
   U26  L57 MCA_DATA8 GENOA_SP5-SOCKET6096_13568-001,SMLF,IO,DGA^6000030   I159 @T6G_MB_LIB.T6G(SCH_1):PAGE39
   J28   18  DQ8_A SCONN288_DDR506112002KQ-SCONN288_DDR506112002KQ,SMA    I22 @T6G_MB_LIB.T6G(SCH_1):PAGE99

M_C_CPU1_SA_DQ<9> @T6G_MB_LIB.T6G(SCH_1):M_C_CPU1_SA_DQ(9)
   U26  M55 MCA_DATA9 GENOA_SP5-SOCKET6096_13568-001,SMLF,IO,DGA^6000030   I159 @T6G_MB_LIB.T6G(SCH_1):PAGE39
   J28   20  DQ9_A SCONN288_DDR506112002KQ-SCONN288_DDR506112002KQ,SMA    I22 @T6G_MB_LIB.T6G(SCH_1):PAGE99

M_C_CPU1_SA_DQS_DN<0> @T6G_MB_LIB.T6G(SCH_1):M_C_CPU1_SA_DQS_DN(0)
   U26  H56 MCA_DQS_L0 GENOA_SP5-SOCKET6096_13568-001,SMLF,IO,DGA^6000030   I159 @T6G_MB_LIB.T6G(SCH_1):PAGE39
   J28   12 DQS0_A_C SCONN288_DDR506112002KQ-SCONN288_DDR506112002KQ,SMA   I236 @T6G_MB_LIB.T6G(SCH_1):PAGE99

M_C_CPU1_SA_DQS_DN<1> @T6G_MB_LIB.T6G(SCH_1):M_C_CPU1_SA_DQS_DN(1)
   U26  P56 MCA_DQS_L1 GENOA_SP5-SOCKET6096_13568-001,SMLF,IO,DGA^6000030   I159 @T6G_MB_LIB.T6G(SCH_1):PAGE39
   J28   23 DQS1_A_C SCONN288_DDR506112002KQ-SCONN288_DDR506112002KQ,SMA   I236 @T6G_MB_LIB.T6G(SCH_1):PAGE99

M_C_CPU1_SA_DQS_DN<2> @T6G_MB_LIB.T6G(SCH_1):M_C_CPU1_SA_DQS_DN(2)
   U26  Y56 MCA_DQS_L2 GENOA_SP5-SOCKET6096_13568-001,SMLF,IO,DGA^6000030   I159 @T6G_MB_LIB.T6G(SCH_1):PAGE39
   J28   34 DQS2_A_C SCONN288_DDR506112002KQ-SCONN288_DDR506112002KQ,SMA   I236 @T6G_MB_LIB.T6G(SCH_1):PAGE99

M_C_CPU1_SA_DQS_DN<3> @T6G_MB_LIB.T6G(SCH_1):M_C_CPU1_SA_DQS_DN(3)
   U26 AF56 MCA_DQS_L3 GENOA_SP5-SOCKET6096_13568-001,SMLF,IO,DGA^6000030   I159 @T6G_MB_LIB.T6G(SCH_1):PAGE39
   J28   45 DQS3_A_C SCONN288_DDR506112002KQ-SCONN288_DDR506112002KQ,SMA   I236 @T6G_MB_LIB.T6G(SCH_1):PAGE99

M_C_CPU1_SA_DQS_DN<4> @T6G_MB_LIB.T6G(SCH_1):M_C_CPU1_SA_DQS_DN(4)
   U26 AM56 MCA_DQS_L4 GENOA_SP5-SOCKET6096_13568-001,SMLF,IO,DGA^6000030   I159 @T6G_MB_LIB.T6G(SCH_1):PAGE39
   J28   56 DQS4_A_C SCONN288_DDR506112002KQ-SCONN288_DDR506112002KQ,SMA   I236 @T6G_MB_LIB.T6G(SCH_1):PAGE99

M_C_CPU1_SA_DQS_DN<5> @T6G_MB_LIB.T6G(SCH_1):M_C_CPU1_SA_DQS_DN(5)
   U26  H55 MCA_DQS_L5 GENOA_SP5-SOCKET6096_13568-001,SMLF,IO,DGA^6000030   I159 @T6G_MB_LIB.T6G(SCH_1):PAGE39
   J28  156 DQS5_A_C||TDQS5_A_C||DQS5_A_T||TDQS5_A_T SCONN288_DDR506112002KQ-SCONN288_DDR506112002KQ,SMA   I236 @T6G_MB_LIB.T6G(SCH_1):PAGE99

M_C_CPU1_SA_DQS_DN<6> @T6G_MB_LIB.T6G(SCH_1):M_C_CPU1_SA_DQS_DN(6)
   U26  P55 MCA_DQS_L6 GENOA_SP5-SOCKET6096_13568-001,SMLF,IO,DGA^6000030   I159 @T6G_MB_LIB.T6G(SCH_1):PAGE39
   J28  167 DQS6_A_C||TDQS6_A_C||DQS6_A_T||TDQS6_A_T SCONN288_DDR506112002KQ-SCONN288_DDR506112002KQ,SMA   I236 @T6G_MB_LIB.T6G(SCH_1):PAGE99

M_C_CPU1_SA_DQS_DN<7> @T6G_MB_LIB.T6G(SCH_1):M_C_CPU1_SA_DQS_DN(7)
   U26  Y55 MCA_DQS_L7 GENOA_SP5-SOCKET6096_13568-001,SMLF,IO,DGA^6000030   I159 @T6G_MB_LIB.T6G(SCH_1):PAGE39
   J28  178 DQS7_A_C||TDQS7_A_C SCONN288_DDR506112002KQ-SCONN288_DDR506112002KQ,SMA   I236 @T6G_MB_LIB.T6G(SCH_1):PAGE99

M_C_CPU1_SA_DQS_DN<8> @T6G_MB_LIB.T6G(SCH_1):M_C_CPU1_SA_DQS_DN(8)
   U26 AF55 MCA_DQS_L8 GENOA_SP5-SOCKET6096_13568-001,SMLF,IO,DGA^6000030   I159 @T6G_MB_LIB.T6G(SCH_1):PAGE39
   J28  189 DQS8_A_C||TDQS8_A_C SCONN288_DDR506112002KQ-SCONN288_DDR506112002KQ,SMA   I236 @T6G_MB_LIB.T6G(SCH_1):PAGE99

M_C_CPU1_SA_DQS_DN<9> @T6G_MB_LIB.T6G(SCH_1):M_C_CPU1_SA_DQS_DN(9)
   U26 AM55 MCA_DQS_L9 GENOA_SP5-SOCKET6096_13568-001,SMLF,IO,DGA^6000030   I159 @T6G_MB_LIB.T6G(SCH_1):PAGE39
   J28  200 DQS9_A_C||TDQS9_A_C SCONN288_DDR506112002KQ-SCONN288_DDR506112002KQ,SMA   I236 @T6G_MB_LIB.T6G(SCH_1):PAGE99

M_C_CPU1_SA_DQS_DP<0> @T6G_MB_LIB.T6G(SCH_1):M_C_CPU1_SA_DQS_DP(0)
   U26  G57 MCA_DQS_H0 GENOA_SP5-SOCKET6096_13568-001,SMLF,IO,DGA^6000030   I159 @T6G_MB_LIB.T6G(SCH_1):PAGE39
   J28   11 DQS0_A_T SCONN288_DDR506112002KQ-SCONN288_DDR506112002KQ,SMA   I236 @T6G_MB_LIB.T6G(SCH_1):PAGE99

M_C_CPU1_SA_DQS_DP<1> @T6G_MB_LIB.T6G(SCH_1):M_C_CPU1_SA_DQS_DP(1)
   U26  N57 MCA_DQS_H1 GENOA_SP5-SOCKET6096_13568-001,SMLF,IO,DGA^6000030   I159 @T6G_MB_LIB.T6G(SCH_1):PAGE39
   J28   22 DQS1_A_T SCONN288_DDR506112002KQ-SCONN288_DDR506112002KQ,SMA   I236 @T6G_MB_LIB.T6G(SCH_1):PAGE99

M_C_CPU1_SA_DQS_DP<2> @T6G_MB_LIB.T6G(SCH_1):M_C_CPU1_SA_DQS_DP(2)
   U26  W57 MCA_DQS_H2 GENOA_SP5-SOCKET6096_13568-001,SMLF,IO,DGA^6000030   I159 @T6G_MB_LIB.T6G(SCH_1):PAGE39
   J28   33 DQS2_A_T SCONN288_DDR506112002KQ-SCONN288_DDR506112002KQ,SMA   I236 @T6G_MB_LIB.T6G(SCH_1):PAGE99

M_C_CPU1_SA_DQS_DP<3> @T6G_MB_LIB.T6G(SCH_1):M_C_CPU1_SA_DQS_DP(3)
   U26 AE57 MCA_DQS_H3 GENOA_SP5-SOCKET6096_13568-001,SMLF,IO,DGA^6000030   I159 @T6G_MB_LIB.T6G(SCH_1):PAGE39
   J28   44 DQS3_A_T SCONN288_DDR506112002KQ-SCONN288_DDR506112002KQ,SMA   I236 @T6G_MB_LIB.T6G(SCH_1):PAGE99

M_C_CPU1_SA_DQS_DP<4> @T6G_MB_LIB.T6G(SCH_1):M_C_CPU1_SA_DQS_DP(4)
   U26 AL57 MCA_DQS_H4 GENOA_SP5-SOCKET6096_13568-001,SMLF,IO,DGA^6000030   I159 @T6G_MB_LIB.T6G(SCH_1):PAGE39
   J28   55 DQS4_A_T SCONN288_DDR506112002KQ-SCONN288_DDR506112002KQ,SMA   I236 @T6G_MB_LIB.T6G(SCH_1):PAGE99

M_C_CPU1_SA_DQS_DP<5> @T6G_MB_LIB.T6G(SCH_1):M_C_CPU1_SA_DQS_DP(5)
   U26  J55 MCA_DQS_H5 GENOA_SP5-SOCKET6096_13568-001,SMLF,IO,DGA^6000030   I159 @T6G_MB_LIB.T6G(SCH_1):PAGE39
   J28  157 DQS5_A_T||TDQS5_A_T SCONN288_DDR506112002KQ-SCONN288_DDR506112002KQ,SMA   I236 @T6G_MB_LIB.T6G(SCH_1):PAGE99

M_C_CPU1_SA_DQS_DP<6> @T6G_MB_LIB.T6G(SCH_1):M_C_CPU1_SA_DQS_DP(6)
   U26  R55 MCA_DQS_H6 GENOA_SP5-SOCKET6096_13568-001,SMLF,IO,DGA^6000030   I159 @T6G_MB_LIB.T6G(SCH_1):PAGE39
   J28  168 DQS6_A_T||TDQS6_A_T SCONN288_DDR506112002KQ-SCONN288_DDR506112002KQ,SMA   I236 @T6G_MB_LIB.T6G(SCH_1):PAGE99

M_C_CPU1_SA_DQS_DP<7> @T6G_MB_LIB.T6G(SCH_1):M_C_CPU1_SA_DQS_DP(7)
   U26 AA55 MCA_DQS_H7 GENOA_SP5-SOCKET6096_13568-001,SMLF,IO,DGA^6000030   I159 @T6G_MB_LIB.T6G(SCH_1):PAGE39
   J28  179 DQS7_A_T||TDQS7_A_T SCONN288_DDR506112002KQ-SCONN288_DDR506112002KQ,SMA   I236 @T6G_MB_LIB.T6G(SCH_1):PAGE99

M_C_CPU1_SA_DQS_DP<8> @T6G_MB_LIB.T6G(SCH_1):M_C_CPU1_SA_DQS_DP(8)
   U26 AG55 MCA_DQS_H8 GENOA_SP5-SOCKET6096_13568-001,SMLF,IO,DGA^6000030   I159 @T6G_MB_LIB.T6G(SCH_1):PAGE39
   J28  190 DQS8_A_T||TDQS8_A_T SCONN288_DDR506112002KQ-SCONN288_DDR506112002KQ,SMA   I236 @T6G_MB_LIB.T6G(SCH_1):PAGE99

M_C_CPU1_SA_DQS_DP<9> @T6G_MB_LIB.T6G(SCH_1):M_C_CPU1_SA_DQS_DP(9)
   U26 AN55 MCA_DQS_H9 GENOA_SP5-SOCKET6096_13568-001,SMLF,IO,DGA^6000030   I159 @T6G_MB_LIB.T6G(SCH_1):PAGE39
   J28  201 DQS9_A_T||TDQS9_A_T SCONN288_DDR506112002KQ-SCONN288_DDR506112002KQ,SMA   I236 @T6G_MB_LIB.T6G(SCH_1):PAGE99

M_C_CPU1_SA_PAR @T6G_MB_LIB.T6G(SCH_1):M_C_CPU1_SA_PAR
   U26 BC55 MCA_PAR GENOA_SP5-SOCKET6096_13568-001,SMLF,IO,DGA^6000030   I159 @T6G_MB_LIB.T6G(SCH_1):PAGE39
   J28   74  PAR_A SCONN288_DDR506112002KQ-SCONN288_DDR506112002KQ,SMA    I22 @T6G_MB_LIB.T6G(SCH_1):PAGE99

M_C_CPU1_SA_RSP<0> @T6G_MB_LIB.T6G(SCH_1):M_C_CPU1_SA_RSP(0)
   U26 BN55 MCA0_RSP_L GENOA_SP5-SOCKET6096_13568-001,SMLF,IO,DGA^6000030   I159 @T6G_MB_LIB.T6G(SCH_1):PAGE39
   J28   86 LBD||RSP_A_N SCONN288_DDR506112002KQ-SCONN288_DDR506112002KQ,SMA    I22 @T6G_MB_LIB.T6G(SCH_1):PAGE99

M_C_CPU1_SB_CA<0> @T6G_MB_LIB.T6G(SCH_1):M_C_CPU1_SB_CA(0)
   U26 BG55 MCB_CA0 GENOA_SP5-SOCKET6096_13568-001,SMLF,IO,DGA^6000030   I159 @T6G_MB_LIB.T6G(SCH_1):PAGE39
   J28   76  CA0_B SCONN288_DDR506112002KQ-SCONN288_DDR506112002KQ,SMA    I22 @T6G_MB_LIB.T6G(SCH_1):PAGE99

M_C_CPU1_SB_CA<1> @T6G_MB_LIB.T6G(SCH_1):M_C_CPU1_SB_CA(1)
   U26 BH55 MCB_CA1 GENOA_SP5-SOCKET6096_13568-001,SMLF,IO,DGA^6000030   I159 @T6G_MB_LIB.T6G(SCH_1):PAGE39
   J28  221  CA1_B SCONN288_DDR506112002KQ-SCONN288_DDR506112002KQ,SMA    I22 @T6G_MB_LIB.T6G(SCH_1):PAGE99

M_C_CPU1_SB_CA<2> @T6G_MB_LIB.T6G(SCH_1):M_C_CPU1_SB_CA(2)
   U26 BH56 MCB_CA2 GENOA_SP5-SOCKET6096_13568-001,SMLF,IO,DGA^6000030   I159 @T6G_MB_LIB.T6G(SCH_1):PAGE39
   J28   78  CA2_B SCONN288_DDR506112002KQ-SCONN288_DDR506112002KQ,SMA    I22 @T6G_MB_LIB.T6G(SCH_1):PAGE99

M_C_CPU1_SB_CA<3> @T6G_MB_LIB.T6G(SCH_1):M_C_CPU1_SB_CA(3)
   U26 BJ57 MCB_CA3 GENOA_SP5-SOCKET6096_13568-001,SMLF,IO,DGA^6000030   I159 @T6G_MB_LIB.T6G(SCH_1):PAGE39
   J28  223  CA3_B SCONN288_DDR506112002KQ-SCONN288_DDR506112002KQ,SMA    I22 @T6G_MB_LIB.T6G(SCH_1):PAGE99

M_C_CPU1_SB_CA<4> @T6G_MB_LIB.T6G(SCH_1):M_C_CPU1_SB_CA(4)
   U26 BJ55 MCB_CA4 GENOA_SP5-SOCKET6096_13568-001,SMLF,IO,DGA^6000030   I159 @T6G_MB_LIB.T6G(SCH_1):PAGE39
   J28   80  CA4_B SCONN288_DDR506112002KQ-SCONN288_DDR506112002KQ,SMA    I22 @T6G_MB_LIB.T6G(SCH_1):PAGE99

M_C_CPU1_SB_CA<5> @T6G_MB_LIB.T6G(SCH_1):M_C_CPU1_SB_CA(5)
   U26 BK55 MCB_CA5 GENOA_SP5-SOCKET6096_13568-001,SMLF,IO,DGA^6000030   I159 @T6G_MB_LIB.T6G(SCH_1):PAGE39
   J28  225  CA5_B SCONN288_DDR506112002KQ-SCONN288_DDR506112002KQ,SMA    I22 @T6G_MB_LIB.T6G(SCH_1):PAGE99

M_C_CPU1_SB_CA<6> @T6G_MB_LIB.T6G(SCH_1):M_C_CPU1_SB_CA(6)
   U26 BK56 MCB_CA6 GENOA_SP5-SOCKET6096_13568-001,SMLF,IO,DGA^6000030   I159 @T6G_MB_LIB.T6G(SCH_1):PAGE39
   J28   82  CA6_B SCONN288_DDR506112002KQ-SCONN288_DDR506112002KQ,SMA    I22 @T6G_MB_LIB.T6G(SCH_1):PAGE99

M_C_CPU1_SB_CB<0> @T6G_MB_LIB.T6G(SCH_1):M_C_CPU1_SB_CB(0)
   U26 BY56 MCB_CHECK0 GENOA_SP5-SOCKET6096_13568-001,SMLF,IO,DGA^6000030   I159 @T6G_MB_LIB.T6G(SCH_1):PAGE39
   J28   96  CB0_B SCONN288_DDR506112002KQ-SCONN288_DDR506112002KQ,SMA    I22 @T6G_MB_LIB.T6G(SCH_1):PAGE99

M_C_CPU1_SB_CB<1> @T6G_MB_LIB.T6G(SCH_1):M_C_CPU1_SB_CB(1)
   U26 CA55 MCB_CHECK1 GENOA_SP5-SOCKET6096_13568-001,SMLF,IO,DGA^6000030   I159 @T6G_MB_LIB.T6G(SCH_1):PAGE39
   J28   98  CB1_B SCONN288_DDR506112002KQ-SCONN288_DDR506112002KQ,SMA    I22 @T6G_MB_LIB.T6G(SCH_1):PAGE99

M_C_CPU1_SB_CB<2> @T6G_MB_LIB.T6G(SCH_1):M_C_CPU1_SB_CB(2)
   U26 CA57 MCB_CHECK2 GENOA_SP5-SOCKET6096_13568-001,SMLF,IO,DGA^6000030   I159 @T6G_MB_LIB.T6G(SCH_1):PAGE39
   J28  241  CB2_B SCONN288_DDR506112002KQ-SCONN288_DDR506112002KQ,SMA    I22 @T6G_MB_LIB.T6G(SCH_1):PAGE99

M_C_CPU1_SB_CB<3> @T6G_MB_LIB.T6G(SCH_1):M_C_CPU1_SB_CB(3)
   U26 CB55 MCB_CHECK3 GENOA_SP5-SOCKET6096_13568-001,SMLF,IO,DGA^6000030   I159 @T6G_MB_LIB.T6G(SCH_1):PAGE39
   J28  243  CB3_B SCONN288_DDR506112002KQ-SCONN288_DDR506112002KQ,SMA    I22 @T6G_MB_LIB.T6G(SCH_1):PAGE99

M_C_CPU1_SB_CB<4> @T6G_MB_LIB.T6G(SCH_1):M_C_CPU1_SB_CB(4)
   U26 BT56 MCB_CHECK4 GENOA_SP5-SOCKET6096_13568-001,SMLF,IO,DGA^6000030   I159 @T6G_MB_LIB.T6G(SCH_1):PAGE39
   J28   89  CB4_B SCONN288_DDR506112002KQ-SCONN288_DDR506112002KQ,SMA    I22 @T6G_MB_LIB.T6G(SCH_1):PAGE99

M_C_CPU1_SB_CB<5> @T6G_MB_LIB.T6G(SCH_1):M_C_CPU1_SB_CB(5)
   U26 BU55 MCB_CHECK5 GENOA_SP5-SOCKET6096_13568-001,SMLF,IO,DGA^6000030   I159 @T6G_MB_LIB.T6G(SCH_1):PAGE39
   J28   91  CB5_B SCONN288_DDR506112002KQ-SCONN288_DDR506112002KQ,SMA    I22 @T6G_MB_LIB.T6G(SCH_1):PAGE99

M_C_CPU1_SB_CB<6> @T6G_MB_LIB.T6G(SCH_1):M_C_CPU1_SB_CB(6)
   U26 BU57 MCB_CHECK6 GENOA_SP5-SOCKET6096_13568-001,SMLF,IO,DGA^6000030   I159 @T6G_MB_LIB.T6G(SCH_1):PAGE39
   J28  234  CB6_B SCONN288_DDR506112002KQ-SCONN288_DDR506112002KQ,SMA    I22 @T6G_MB_LIB.T6G(SCH_1):PAGE99

M_C_CPU1_SB_CB<7> @T6G_MB_LIB.T6G(SCH_1):M_C_CPU1_SB_CB(7)
   U26 BV55 MCB_CHECK7 GENOA_SP5-SOCKET6096_13568-001,SMLF,IO,DGA^6000030   I159 @T6G_MB_LIB.T6G(SCH_1):PAGE39
   J28  236  CB7_B SCONN288_DDR506112002KQ-SCONN288_DDR506112002KQ,SMA    I22 @T6G_MB_LIB.T6G(SCH_1):PAGE99

M_C_CPU1_SB_CS_N<0> @T6G_MB_LIB.T6G(SCH_1):M_C_CPU1_SB_CS_N(0)
   U26 BM55 MCB0_CS_L0 GENOA_SP5-SOCKET6096_13568-001,SMLF,IO,DGA^6000030   I159 @T6G_MB_LIB.T6G(SCH_1):PAGE39
   J28   84 CS0_B_N SCONN288_DDR506112002KQ-SCONN288_DDR506112002KQ,SMA    I22 @T6G_MB_LIB.T6G(SCH_1):PAGE99

M_C_CPU1_SB_CS_N<1> @T6G_MB_LIB.T6G(SCH_1):M_C_CPU1_SB_CS_N(1)
   U26 BN57 MCB0_CS_L1 GENOA_SP5-SOCKET6096_13568-001,SMLF,IO,DGA^6000030   I159 @T6G_MB_LIB.T6G(SCH_1):PAGE39
   J28  229 CS1_B_N SCONN288_DDR506112002KQ-SCONN288_DDR506112002KQ,SMA    I22 @T6G_MB_LIB.T6G(SCH_1):PAGE99

M_C_CPU1_SB_DQ<0> @T6G_MB_LIB.T6G(SCH_1):M_C_CPU1_SB_DQ(0)
   U26 CB56 MCB_DATA0 GENOA_SP5-SOCKET6096_13568-001,SMLF,IO,DGA^6000030   I159 @T6G_MB_LIB.T6G(SCH_1):PAGE39
   J28  100  DQ0_B SCONN288_DDR506112002KQ-SCONN288_DDR506112002KQ,SMA    I22 @T6G_MB_LIB.T6G(SCH_1):PAGE99

M_C_CPU1_SB_DQ<10> @T6G_MB_LIB.T6G(SCH_1):M_C_CPU1_SB_DQ(10)
   U26 CJ57 MCB_DATA10 GENOA_SP5-SOCKET6096_13568-001,SMLF,IO,DGA^6000030   I159 @T6G_MB_LIB.T6G(SCH_1):PAGE39
   J28  256 DQ10_B SCONN288_DDR506112002KQ-SCONN288_DDR506112002KQ,SMA    I22 @T6G_MB_LIB.T6G(SCH_1):PAGE99

M_C_CPU1_SB_DQ<11> @T6G_MB_LIB.T6G(SCH_1):M_C_CPU1_SB_DQ(11)
   U26 CK55 MCB_DATA11 GENOA_SP5-SOCKET6096_13568-001,SMLF,IO,DGA^6000030   I159 @T6G_MB_LIB.T6G(SCH_1):PAGE39
   J28  258 DQ11_B SCONN288_DDR506112002KQ-SCONN288_DDR506112002KQ,SMA    I22 @T6G_MB_LIB.T6G(SCH_1):PAGE99

M_C_CPU1_SB_DQ<12> @T6G_MB_LIB.T6G(SCH_1):M_C_CPU1_SB_DQ(12)
   U26 CM56 MCB_DATA12 GENOA_SP5-SOCKET6096_13568-001,SMLF,IO,DGA^6000030   I159 @T6G_MB_LIB.T6G(SCH_1):PAGE39
   J28  118 DQ12_B SCONN288_DDR506112002KQ-SCONN288_DDR506112002KQ,SMA    I22 @T6G_MB_LIB.T6G(SCH_1):PAGE99

M_C_CPU1_SB_DQ<13> @T6G_MB_LIB.T6G(SCH_1):M_C_CPU1_SB_DQ(13)
   U26 CN55 MCB_DATA13 GENOA_SP5-SOCKET6096_13568-001,SMLF,IO,DGA^6000030   I159 @T6G_MB_LIB.T6G(SCH_1):PAGE39
   J28  120 DQ13_B SCONN288_DDR506112002KQ-SCONN288_DDR506112002KQ,SMA    I22 @T6G_MB_LIB.T6G(SCH_1):PAGE99

M_C_CPU1_SB_DQ<14> @T6G_MB_LIB.T6G(SCH_1):M_C_CPU1_SB_DQ(14)
   U26 CN57 MCB_DATA14 GENOA_SP5-SOCKET6096_13568-001,SMLF,IO,DGA^6000030   I159 @T6G_MB_LIB.T6G(SCH_1):PAGE39
   J28  263 DQ14_B SCONN288_DDR506112002KQ-SCONN288_DDR506112002KQ,SMA    I22 @T6G_MB_LIB.T6G(SCH_1):PAGE99

M_C_CPU1_SB_DQ<15> @T6G_MB_LIB.T6G(SCH_1):M_C_CPU1_SB_DQ(15)
   U26 CP55 MCB_DATA15 GENOA_SP5-SOCKET6096_13568-001,SMLF,IO,DGA^6000030   I159 @T6G_MB_LIB.T6G(SCH_1):PAGE39
   J28  265 DQ15_B SCONN288_DDR506112002KQ-SCONN288_DDR506112002KQ,SMA    I22 @T6G_MB_LIB.T6G(SCH_1):PAGE99

M_C_CPU1_SB_DQ<16> @T6G_MB_LIB.T6G(SCH_1):M_C_CPU1_SB_DQ(16)
   U26 CP56 MCB_DATA16 GENOA_SP5-SOCKET6096_13568-001,SMLF,IO,DGA^6000030   I159 @T6G_MB_LIB.T6G(SCH_1):PAGE39
   J28  122 DQ16_B SCONN288_DDR506112002KQ-SCONN288_DDR506112002KQ,SMA    I22 @T6G_MB_LIB.T6G(SCH_1):PAGE99

M_C_CPU1_SB_DQ<17> @T6G_MB_LIB.T6G(SCH_1):M_C_CPU1_SB_DQ(17)
   U26 CR55 MCB_DATA17 GENOA_SP5-SOCKET6096_13568-001,SMLF,IO,DGA^6000030   I159 @T6G_MB_LIB.T6G(SCH_1):PAGE39
   J28  124 DQ17_B SCONN288_DDR506112002KQ-SCONN288_DDR506112002KQ,SMA    I22 @T6G_MB_LIB.T6G(SCH_1):PAGE99

M_C_CPU1_SB_DQ<18> @T6G_MB_LIB.T6G(SCH_1):M_C_CPU1_SB_DQ(18)
   U26 CR57 MCB_DATA18 GENOA_SP5-SOCKET6096_13568-001,SMLF,IO,DGA^6000030   I159 @T6G_MB_LIB.T6G(SCH_1):PAGE39
   J28  267 DQ18_B SCONN288_DDR506112002KQ-SCONN288_DDR506112002KQ,SMA    I22 @T6G_MB_LIB.T6G(SCH_1):PAGE99

M_C_CPU1_SB_DQ<19> @T6G_MB_LIB.T6G(SCH_1):M_C_CPU1_SB_DQ(19)
   U26 CT55 MCB_DATA19 GENOA_SP5-SOCKET6096_13568-001,SMLF,IO,DGA^6000030   I159 @T6G_MB_LIB.T6G(SCH_1):PAGE39
   J28  269 DQ19_B SCONN288_DDR506112002KQ-SCONN288_DDR506112002KQ,SMA    I22 @T6G_MB_LIB.T6G(SCH_1):PAGE99

M_C_CPU1_SB_DQ<1> @T6G_MB_LIB.T6G(SCH_1):M_C_CPU1_SB_DQ(1)
   U26 CC55 MCB_DATA1 GENOA_SP5-SOCKET6096_13568-001,SMLF,IO,DGA^6000030   I159 @T6G_MB_LIB.T6G(SCH_1):PAGE39
   J28  102  DQ1_B SCONN288_DDR506112002KQ-SCONN288_DDR506112002KQ,SMA    I22 @T6G_MB_LIB.T6G(SCH_1):PAGE99

M_C_CPU1_SB_DQ<20> @T6G_MB_LIB.T6G(SCH_1):M_C_CPU1_SB_DQ(20)
   U26 CV56 MCB_DATA20 GENOA_SP5-SOCKET6096_13568-001,SMLF,IO,DGA^6000030   I159 @T6G_MB_LIB.T6G(SCH_1):PAGE39
   J28  129 DQ20_B SCONN288_DDR506112002KQ-SCONN288_DDR506112002KQ,SMA    I22 @T6G_MB_LIB.T6G(SCH_1):PAGE99

M_C_CPU1_SB_DQ<21> @T6G_MB_LIB.T6G(SCH_1):M_C_CPU1_SB_DQ(21)
   U26 CW55 MCB_DATA21 GENOA_SP5-SOCKET6096_13568-001,SMLF,IO,DGA^6000030   I159 @T6G_MB_LIB.T6G(SCH_1):PAGE39
   J28  131 DQ21_B SCONN288_DDR506112002KQ-SCONN288_DDR506112002KQ,SMA    I22 @T6G_MB_LIB.T6G(SCH_1):PAGE99

M_C_CPU1_SB_DQ<22> @T6G_MB_LIB.T6G(SCH_1):M_C_CPU1_SB_DQ(22)
   U26 CW57 MCB_DATA22 GENOA_SP5-SOCKET6096_13568-001,SMLF,IO,DGA^6000030   I159 @T6G_MB_LIB.T6G(SCH_1):PAGE39
   J28  274 DQ22_B SCONN288_DDR506112002KQ-SCONN288_DDR506112002KQ,SMA    I22 @T6G_MB_LIB.T6G(SCH_1):PAGE99

M_C_CPU1_SB_DQ<23> @T6G_MB_LIB.T6G(SCH_1):M_C_CPU1_SB_DQ(23)
   U26 CY55 MCB_DATA23 GENOA_SP5-SOCKET6096_13568-001,SMLF,IO,DGA^6000030   I159 @T6G_MB_LIB.T6G(SCH_1):PAGE39
   J28  276 DQ23_B SCONN288_DDR506112002KQ-SCONN288_DDR506112002KQ,SMA    I22 @T6G_MB_LIB.T6G(SCH_1):PAGE99

M_C_CPU1_SB_DQ<24> @T6G_MB_LIB.T6G(SCH_1):M_C_CPU1_SB_DQ(24)
   U26 CY56 MCB_DATA24 GENOA_SP5-SOCKET6096_13568-001,SMLF,IO,DGA^6000030   I159 @T6G_MB_LIB.T6G(SCH_1):PAGE39
   J28  133 DQ24_B SCONN288_DDR506112002KQ-SCONN288_DDR506112002KQ,SMA    I22 @T6G_MB_LIB.T6G(SCH_1):PAGE99

M_C_CPU1_SB_DQ<25> @T6G_MB_LIB.T6G(SCH_1):M_C_CPU1_SB_DQ(25)
   U26 DA55 MCB_DATA25 GENOA_SP5-SOCKET6096_13568-001,SMLF,IO,DGA^6000030   I159 @T6G_MB_LIB.T6G(SCH_1):PAGE39
   J28  135 DQ25_B SCONN288_DDR506112002KQ-SCONN288_DDR506112002KQ,SMA    I22 @T6G_MB_LIB.T6G(SCH_1):PAGE99

M_C_CPU1_SB_DQ<26> @T6G_MB_LIB.T6G(SCH_1):M_C_CPU1_SB_DQ(26)
   U26 DA57 MCB_DATA26 GENOA_SP5-SOCKET6096_13568-001,SMLF,IO,DGA^6000030   I159 @T6G_MB_LIB.T6G(SCH_1):PAGE39
   J28  278 DQ26_B SCONN288_DDR506112002KQ-SCONN288_DDR506112002KQ,SMA    I22 @T6G_MB_LIB.T6G(SCH_1):PAGE99

M_C_CPU1_SB_DQ<27> @T6G_MB_LIB.T6G(SCH_1):M_C_CPU1_SB_DQ(27)
   U26 DB55 MCB_DATA27 GENOA_SP5-SOCKET6096_13568-001,SMLF,IO,DGA^6000030   I159 @T6G_MB_LIB.T6G(SCH_1):PAGE39
   J28  280 DQ27_B SCONN288_DDR506112002KQ-SCONN288_DDR506112002KQ,SMA    I22 @T6G_MB_LIB.T6G(SCH_1):PAGE99

M_C_CPU1_SB_DQ<28> @T6G_MB_LIB.T6G(SCH_1):M_C_CPU1_SB_DQ(28)
   U26 DD56 MCB_DATA28 GENOA_SP5-SOCKET6096_13568-001,SMLF,IO,DGA^6000030   I159 @T6G_MB_LIB.T6G(SCH_1):PAGE39
   J28  140 DQ28_B SCONN288_DDR506112002KQ-SCONN288_DDR506112002KQ,SMA    I22 @T6G_MB_LIB.T6G(SCH_1):PAGE99

M_C_CPU1_SB_DQ<29> @T6G_MB_LIB.T6G(SCH_1):M_C_CPU1_SB_DQ(29)
   U26 DE55 MCB_DATA29 GENOA_SP5-SOCKET6096_13568-001,SMLF,IO,DGA^6000030   I159 @T6G_MB_LIB.T6G(SCH_1):PAGE39
   J28  142 DQ29_B SCONN288_DDR506112002KQ-SCONN288_DDR506112002KQ,SMA    I22 @T6G_MB_LIB.T6G(SCH_1):PAGE99

M_C_CPU1_SB_DQ<2> @T6G_MB_LIB.T6G(SCH_1):M_C_CPU1_SB_DQ(2)
   U26 CC57 MCB_DATA2 GENOA_SP5-SOCKET6096_13568-001,SMLF,IO,DGA^6000030   I159 @T6G_MB_LIB.T6G(SCH_1):PAGE39
   J28  245  DQ2_B SCONN288_DDR506112002KQ-SCONN288_DDR506112002KQ,SMA    I22 @T6G_MB_LIB.T6G(SCH_1):PAGE99

M_C_CPU1_SB_DQ<30> @T6G_MB_LIB.T6G(SCH_1):M_C_CPU1_SB_DQ(30)
   U26 DE57 MCB_DATA30 GENOA_SP5-SOCKET6096_13568-001,SMLF,IO,DGA^6000030   I159 @T6G_MB_LIB.T6G(SCH_1):PAGE39
   J28  285 DQ30_B SCONN288_DDR506112002KQ-SCONN288_DDR506112002KQ,SMA    I22 @T6G_MB_LIB.T6G(SCH_1):PAGE99

M_C_CPU1_SB_DQ<31> @T6G_MB_LIB.T6G(SCH_1):M_C_CPU1_SB_DQ(31)
   U26 DF55 MCB_DATA31 GENOA_SP5-SOCKET6096_13568-001,SMLF,IO,DGA^6000030   I159 @T6G_MB_LIB.T6G(SCH_1):PAGE39
   J28  287 DQ31_B SCONN288_DDR506112002KQ-SCONN288_DDR506112002KQ,SMA    I22 @T6G_MB_LIB.T6G(SCH_1):PAGE99

M_C_CPU1_SB_DQ<3> @T6G_MB_LIB.T6G(SCH_1):M_C_CPU1_SB_DQ(3)
   U26 CD55 MCB_DATA3 GENOA_SP5-SOCKET6096_13568-001,SMLF,IO,DGA^6000030   I159 @T6G_MB_LIB.T6G(SCH_1):PAGE39
   J28  247  DQ3_B SCONN288_DDR506112002KQ-SCONN288_DDR506112002KQ,SMA    I22 @T6G_MB_LIB.T6G(SCH_1):PAGE99

M_C_CPU1_SB_DQ<4> @T6G_MB_LIB.T6G(SCH_1):M_C_CPU1_SB_DQ(4)
   U26 CF56 MCB_DATA4 GENOA_SP5-SOCKET6096_13568-001,SMLF,IO,DGA^6000030   I159 @T6G_MB_LIB.T6G(SCH_1):PAGE39
   J28  107  DQ4_B SCONN288_DDR506112002KQ-SCONN288_DDR506112002KQ,SMA    I22 @T6G_MB_LIB.T6G(SCH_1):PAGE99

M_C_CPU1_SB_DQ<5> @T6G_MB_LIB.T6G(SCH_1):M_C_CPU1_SB_DQ(5)
   U26 CG55 MCB_DATA5 GENOA_SP5-SOCKET6096_13568-001,SMLF,IO,DGA^6000030   I159 @T6G_MB_LIB.T6G(SCH_1):PAGE39
   J28  109  DQ5_B SCONN288_DDR506112002KQ-SCONN288_DDR506112002KQ,SMA    I22 @T6G_MB_LIB.T6G(SCH_1):PAGE99

M_C_CPU1_SB_DQ<6> @T6G_MB_LIB.T6G(SCH_1):M_C_CPU1_SB_DQ(6)
   U26 CG57 MCB_DATA6 GENOA_SP5-SOCKET6096_13568-001,SMLF,IO,DGA^6000030   I159 @T6G_MB_LIB.T6G(SCH_1):PAGE39
   J28  252  DQ6_B SCONN288_DDR506112002KQ-SCONN288_DDR506112002KQ,SMA    I22 @T6G_MB_LIB.T6G(SCH_1):PAGE99

M_C_CPU1_SB_DQ<7> @T6G_MB_LIB.T6G(SCH_1):M_C_CPU1_SB_DQ(7)
   U26 CH55 MCB_DATA7 GENOA_SP5-SOCKET6096_13568-001,SMLF,IO,DGA^6000030   I159 @T6G_MB_LIB.T6G(SCH_1):PAGE39
   J28  254  DQ7_B SCONN288_DDR506112002KQ-SCONN288_DDR506112002KQ,SMA    I22 @T6G_MB_LIB.T6G(SCH_1):PAGE99

M_C_CPU1_SB_DQ<8> @T6G_MB_LIB.T6G(SCH_1):M_C_CPU1_SB_DQ(8)
   U26 CH56 MCB_DATA8 GENOA_SP5-SOCKET6096_13568-001,SMLF,IO,DGA^6000030   I159 @T6G_MB_LIB.T6G(SCH_1):PAGE39
   J28  111  DQ8_B SCONN288_DDR506112002KQ-SCONN288_DDR506112002KQ,SMA    I22 @T6G_MB_LIB.T6G(SCH_1):PAGE99

M_C_CPU1_SB_DQ<9> @T6G_MB_LIB.T6G(SCH_1):M_C_CPU1_SB_DQ(9)
   U26 CJ55 MCB_DATA9 GENOA_SP5-SOCKET6096_13568-001,SMLF,IO,DGA^6000030   I159 @T6G_MB_LIB.T6G(SCH_1):PAGE39
   J28  113  DQ9_B SCONN288_DDR506112002KQ-SCONN288_DDR506112002KQ,SMA    I22 @T6G_MB_LIB.T6G(SCH_1):PAGE99

M_C_CPU1_SB_DQS_DN<0> @T6G_MB_LIB.T6G(SCH_1):M_C_CPU1_SB_DQS_DN(0)
   U26 CE57 MCB_DQS_L0 GENOA_SP5-SOCKET6096_13568-001,SMLF,IO,DGA^6000030   I159 @T6G_MB_LIB.T6G(SCH_1):PAGE39
   J28  105 DQS0_B_C SCONN288_DDR506112002KQ-SCONN288_DDR506112002KQ,SMA   I236 @T6G_MB_LIB.T6G(SCH_1):PAGE99

M_C_CPU1_SB_DQS_DN<1> @T6G_MB_LIB.T6G(SCH_1):M_C_CPU1_SB_DQS_DN(1)
   U26 CL57 MCB_DQS_L1 GENOA_SP5-SOCKET6096_13568-001,SMLF,IO,DGA^6000030   I159 @T6G_MB_LIB.T6G(SCH_1):PAGE39
   J28  116 DQS1_B_C SCONN288_DDR506112002KQ-SCONN288_DDR506112002KQ,SMA   I236 @T6G_MB_LIB.T6G(SCH_1):PAGE99

M_C_CPU1_SB_DQS_DN<2> @T6G_MB_LIB.T6G(SCH_1):M_C_CPU1_SB_DQS_DN(2)
   U26 CU57 MCB_DQS_L2 GENOA_SP5-SOCKET6096_13568-001,SMLF,IO,DGA^6000030   I159 @T6G_MB_LIB.T6G(SCH_1):PAGE39
   J28  127 DQS2_B_C SCONN288_DDR506112002KQ-SCONN288_DDR506112002KQ,SMA   I236 @T6G_MB_LIB.T6G(SCH_1):PAGE99

M_C_CPU1_SB_DQS_DN<3> @T6G_MB_LIB.T6G(SCH_1):M_C_CPU1_SB_DQS_DN(3)
   U26 DC57 MCB_DQS_L3 GENOA_SP5-SOCKET6096_13568-001,SMLF,IO,DGA^6000030   I159 @T6G_MB_LIB.T6G(SCH_1):PAGE39
   J28  138 DQS3_B_C SCONN288_DDR506112002KQ-SCONN288_DDR506112002KQ,SMA   I236 @T6G_MB_LIB.T6G(SCH_1):PAGE99

M_C_CPU1_SB_DQS_DN<4> @T6G_MB_LIB.T6G(SCH_1):M_C_CPU1_SB_DQS_DN(4)
   U26 BW55 MCB_DQS_L4 GENOA_SP5-SOCKET6096_13568-001,SMLF,IO,DGA^6000030   I159 @T6G_MB_LIB.T6G(SCH_1):PAGE39
   J28  238 DQS4_B_C SCONN288_DDR506112002KQ-SCONN288_DDR506112002KQ,SMA   I236 @T6G_MB_LIB.T6G(SCH_1):PAGE99

M_C_CPU1_SB_DQS_DN<5> @T6G_MB_LIB.T6G(SCH_1):M_C_CPU1_SB_DQS_DN(5)
   U26 CE55 MCB_DQS_L5 GENOA_SP5-SOCKET6096_13568-001,SMLF,IO,DGA^6000030   I159 @T6G_MB_LIB.T6G(SCH_1):PAGE39
   J28  249 DQS5_B_C||TDQS5_B_C SCONN288_DDR506112002KQ-SCONN288_DDR506112002KQ,SMA   I236 @T6G_MB_LIB.T6G(SCH_1):PAGE99

M_C_CPU1_SB_DQS_DN<6> @T6G_MB_LIB.T6G(SCH_1):M_C_CPU1_SB_DQS_DN(6)
   U26 CL55 MCB_DQS_L6 GENOA_SP5-SOCKET6096_13568-001,SMLF,IO,DGA^6000030   I159 @T6G_MB_LIB.T6G(SCH_1):PAGE39
   J28  260 DQS6_B_C||TDQS6_B_C SCONN288_DDR506112002KQ-SCONN288_DDR506112002KQ,SMA   I236 @T6G_MB_LIB.T6G(SCH_1):PAGE99

M_C_CPU1_SB_DQS_DN<7> @T6G_MB_LIB.T6G(SCH_1):M_C_CPU1_SB_DQS_DN(7)
   U26 CU55 MCB_DQS_L7 GENOA_SP5-SOCKET6096_13568-001,SMLF,IO,DGA^6000030   I159 @T6G_MB_LIB.T6G(SCH_1):PAGE39
   J28  271 DQS7_B_C||TDQS7_B_C SCONN288_DDR506112002KQ-SCONN288_DDR506112002KQ,SMA   I236 @T6G_MB_LIB.T6G(SCH_1):PAGE99

M_C_CPU1_SB_DQS_DN<8> @T6G_MB_LIB.T6G(SCH_1):M_C_CPU1_SB_DQS_DN(8)
   U26 DC55 MCB_DQS_L8 GENOA_SP5-SOCKET6096_13568-001,SMLF,IO,DGA^6000030   I159 @T6G_MB_LIB.T6G(SCH_1):PAGE39
   J28  282 DQS8_B_C||TDQS8_B_C SCONN288_DDR506112002KQ-SCONN288_DDR506112002KQ,SMA   I236 @T6G_MB_LIB.T6G(SCH_1):PAGE99

M_C_CPU1_SB_DQS_DN<9> @T6G_MB_LIB.T6G(SCH_1):M_C_CPU1_SB_DQS_DN(9)
   U26 BW57 MCB_DQS_L9 GENOA_SP5-SOCKET6096_13568-001,SMLF,IO,DGA^6000030   I159 @T6G_MB_LIB.T6G(SCH_1):PAGE39
   J28   94 DQS9_B_C||TDQS9_B_C SCONN288_DDR506112002KQ-SCONN288_DDR506112002KQ,SMA   I236 @T6G_MB_LIB.T6G(SCH_1):PAGE99

M_C_CPU1_SB_DQS_DP<0> @T6G_MB_LIB.T6G(SCH_1):M_C_CPU1_SB_DQS_DP(0)
   U26 CD56 MCB_DQS_H0 GENOA_SP5-SOCKET6096_13568-001,SMLF,IO,DGA^6000030   I159 @T6G_MB_LIB.T6G(SCH_1):PAGE39
   J28  104 DQS0_B_T SCONN288_DDR506112002KQ-SCONN288_DDR506112002KQ,SMA   I236 @T6G_MB_LIB.T6G(SCH_1):PAGE99

M_C_CPU1_SB_DQS_DP<1> @T6G_MB_LIB.T6G(SCH_1):M_C_CPU1_SB_DQS_DP(1)
   U26 CK56 MCB_DQS_H1 GENOA_SP5-SOCKET6096_13568-001,SMLF,IO,DGA^6000030   I159 @T6G_MB_LIB.T6G(SCH_1):PAGE39
   J28  115 DQS1_B_T SCONN288_DDR506112002KQ-SCONN288_DDR506112002KQ,SMA   I236 @T6G_MB_LIB.T6G(SCH_1):PAGE99

M_C_CPU1_SB_DQS_DP<2> @T6G_MB_LIB.T6G(SCH_1):M_C_CPU1_SB_DQS_DP(2)
   U26 CT56 MCB_DQS_H2 GENOA_SP5-SOCKET6096_13568-001,SMLF,IO,DGA^6000030   I159 @T6G_MB_LIB.T6G(SCH_1):PAGE39
   J28  126 DQS2_B_T SCONN288_DDR506112002KQ-SCONN288_DDR506112002KQ,SMA   I236 @T6G_MB_LIB.T6G(SCH_1):PAGE99

M_C_CPU1_SB_DQS_DP<3> @T6G_MB_LIB.T6G(SCH_1):M_C_CPU1_SB_DQS_DP(3)
   U26 DB56 MCB_DQS_H3 GENOA_SP5-SOCKET6096_13568-001,SMLF,IO,DGA^6000030   I159 @T6G_MB_LIB.T6G(SCH_1):PAGE39
   J28  137 DQS3_B_T SCONN288_DDR506112002KQ-SCONN288_DDR506112002KQ,SMA   I236 @T6G_MB_LIB.T6G(SCH_1):PAGE99

M_C_CPU1_SB_DQS_DP<4> @T6G_MB_LIB.T6G(SCH_1):M_C_CPU1_SB_DQS_DP(4)
   U26 BY55 MCB_DQS_H4 GENOA_SP5-SOCKET6096_13568-001,SMLF,IO,DGA^6000030   I159 @T6G_MB_LIB.T6G(SCH_1):PAGE39
   J28  239 DQS4_B_T SCONN288_DDR506112002KQ-SCONN288_DDR506112002KQ,SMA   I236 @T6G_MB_LIB.T6G(SCH_1):PAGE99

M_C_CPU1_SB_DQS_DP<5> @T6G_MB_LIB.T6G(SCH_1):M_C_CPU1_SB_DQS_DP(5)
   U26 CF55 MCB_DQS_H5 GENOA_SP5-SOCKET6096_13568-001,SMLF,IO,DGA^6000030   I159 @T6G_MB_LIB.T6G(SCH_1):PAGE39
   J28  250 DQS5_B_T||TDQS5_B_T SCONN288_DDR506112002KQ-SCONN288_DDR506112002KQ,SMA   I236 @T6G_MB_LIB.T6G(SCH_1):PAGE99

M_C_CPU1_SB_DQS_DP<6> @T6G_MB_LIB.T6G(SCH_1):M_C_CPU1_SB_DQS_DP(6)
   U26 CM55 MCB_DQS_H6 GENOA_SP5-SOCKET6096_13568-001,SMLF,IO,DGA^6000030   I159 @T6G_MB_LIB.T6G(SCH_1):PAGE39
   J28  261 DQS6_B_T||TDQS6_B_T SCONN288_DDR506112002KQ-SCONN288_DDR506112002KQ,SMA   I236 @T6G_MB_LIB.T6G(SCH_1):PAGE99

M_C_CPU1_SB_DQS_DP<7> @T6G_MB_LIB.T6G(SCH_1):M_C_CPU1_SB_DQS_DP(7)
   U26 CV55 MCB_DQS_H7 GENOA_SP5-SOCKET6096_13568-001,SMLF,IO,DGA^6000030   I159 @T6G_MB_LIB.T6G(SCH_1):PAGE39
   J28  272 DQS7_B_T||TDQS7_B_T SCONN288_DDR506112002KQ-SCONN288_DDR506112002KQ,SMA   I236 @T6G_MB_LIB.T6G(SCH_1):PAGE99

M_C_CPU1_SB_DQS_DP<8> @T6G_MB_LIB.T6G(SCH_1):M_C_CPU1_SB_DQS_DP(8)
   U26 DD55 MCB_DQS_H8 GENOA_SP5-SOCKET6096_13568-001,SMLF,IO,DGA^6000030   I159 @T6G_MB_LIB.T6G(SCH_1):PAGE39
   J28  283 DQS8_B_T||TDQS8_B_T SCONN288_DDR506112002KQ-SCONN288_DDR506112002KQ,SMA   I236 @T6G_MB_LIB.T6G(SCH_1):PAGE99

M_C_CPU1_SB_DQS_DP<9> @T6G_MB_LIB.T6G(SCH_1):M_C_CPU1_SB_DQS_DP(9)
   U26 BV56 MCB_DQS_H9 GENOA_SP5-SOCKET6096_13568-001,SMLF,IO,DGA^6000030   I159 @T6G_MB_LIB.T6G(SCH_1):PAGE39
   J28   93 DQS9_B_T||TDQS9_B_T||DBI4_B_N SCONN288_DDR506112002KQ-SCONN288_DDR506112002KQ,SMA   I236 @T6G_MB_LIB.T6G(SCH_1):PAGE99

M_C_CPU1_SB_PAR @T6G_MB_LIB.T6G(SCH_1):M_C_CPU1_SB_PAR
   U26 BL57 MCB_PAR GENOA_SP5-SOCKET6096_13568-001,SMLF,IO,DGA^6000030   I159 @T6G_MB_LIB.T6G(SCH_1):PAGE39
   J28  227  PAR_B SCONN288_DDR506112002KQ-SCONN288_DDR506112002KQ,SMA    I22 @T6G_MB_LIB.T6G(SCH_1):PAGE99

M_C_CPU1_SB_RSP<0> @T6G_MB_LIB.T6G(SCH_1):M_C_CPU1_SB_RSP(0)
   U26 BP56 MCB0_RSP_L GENOA_SP5-SOCKET6096_13568-001,SMLF,IO,DGA^6000030   I159 @T6G_MB_LIB.T6G(SCH_1):PAGE39
   J28   87 LBS||RSP_B_N SCONN288_DDR506112002KQ-SCONN288_DDR506112002KQ,SMA    I22 @T6G_MB_LIB.T6G(SCH_1):PAGE99

M_D_CPU0_ALERT_N @T6G_MB_LIB.T6G(SCH_1):M_D_CPU0_ALERT_N
  R378    1      A Q_RES_0402LF-15,1%,1/16W,CHIP,CS01502FB03   I314 @T6G_MB_LIB.T6G(SCH_1):PAGE13
   J19   62 ALERT_N SCONN288_DDR506112002KQ-SCONN288_DDR506112002KQ,SMA   I350 @T6G_MB_LIB.T6G(SCH_1):PAGE88

M_D_CPU0_ALERT_R_N @T6G_MB_LIB.T6G(SCH_1):M_D_CPU0_ALERT_R_N
   U25 AT58 MD_ALERT_L GENOA_SP5-SOCKET6096_13568-001,SMLF,IO,DGA^6000030   I159 @T6G_MB_LIB.T6G(SCH_1):PAGE13
  R378    2      B Q_RES_0402LF-15,1%,1/16W,CHIP,CS01502FB03   I314 @T6G_MB_LIB.T6G(SCH_1):PAGE13

M_D_CPU0_CLK_DN<0> @T6G_MB_LIB.T6G(SCH_1):M_D_CPU0_CLK_DN(0)
   U25 BD60 MD0_CLK_L GENOA_SP5-SOCKET6096_13568-001,SMLF,IO,DGA^6000030   I159 @T6G_MB_LIB.T6G(SCH_1):PAGE13
   J19  218   CK_C SCONN288_DDR506112002KQ-SCONN288_DDR506112002KQ,SMA   I350 @T6G_MB_LIB.T6G(SCH_1):PAGE88

M_D_CPU0_CLK_DP<0> @T6G_MB_LIB.T6G(SCH_1):M_D_CPU0_CLK_DP(0)
   U25 BC60 MD0_CLK_H GENOA_SP5-SOCKET6096_13568-001,SMLF,IO,DGA^6000030   I159 @T6G_MB_LIB.T6G(SCH_1):PAGE13
   J19  217   CK_T SCONN288_DDR506112002KQ-SCONN288_DDR506112002KQ,SMA   I350 @T6G_MB_LIB.T6G(SCH_1):PAGE88

M_D_CPU0_RESET_N @T6G_MB_LIB.T6G(SCH_1):M_D_CPU0_RESET_N
   U25 AU59 MD_RESET_L GENOA_SP5-SOCKET6096_13568-001,SMLF,IO,DGA^6000030   I159 @T6G_MB_LIB.T6G(SCH_1):PAGE13
   J19  207 RESET_N SCONN288_DDR506112002KQ-SCONN288_DDR506112002KQ,SMA   I350 @T6G_MB_LIB.T6G(SCH_1):PAGE88

M_D_CPU0_SA_CA<0> @T6G_MB_LIB.T6G(SCH_1):M_D_CPU0_SA_CA(0)
   U25 AW60 MDA_CA0 GENOA_SP5-SOCKET6096_13568-001,SMLF,IO,DGA^6000030   I159 @T6G_MB_LIB.T6G(SCH_1):PAGE13
   J19   66  CA0_A SCONN288_DDR506112002KQ-SCONN288_DDR506112002KQ,SMA   I350 @T6G_MB_LIB.T6G(SCH_1):PAGE88

M_D_CPU0_SA_CA<1> @T6G_MB_LIB.T6G(SCH_1):M_D_CPU0_SA_CA(1)
   U25 AY60 MDA_CA1 GENOA_SP5-SOCKET6096_13568-001,SMLF,IO,DGA^6000030   I159 @T6G_MB_LIB.T6G(SCH_1):PAGE13
   J19  211  CA1_A SCONN288_DDR506112002KQ-SCONN288_DDR506112002KQ,SMA   I350 @T6G_MB_LIB.T6G(SCH_1):PAGE88

M_D_CPU0_SA_CA<2> @T6G_MB_LIB.T6G(SCH_1):M_D_CPU0_SA_CA(2)
   U25 AY58 MDA_CA2 GENOA_SP5-SOCKET6096_13568-001,SMLF,IO,DGA^6000030   I159 @T6G_MB_LIB.T6G(SCH_1):PAGE13
   J19   68  CA2_A SCONN288_DDR506112002KQ-SCONN288_DDR506112002KQ,SMA   I350 @T6G_MB_LIB.T6G(SCH_1):PAGE88

M_D_CPU0_SA_CA<3> @T6G_MB_LIB.T6G(SCH_1):M_D_CPU0_SA_CA(3)
   U25 BA59 MDA_CA3 GENOA_SP5-SOCKET6096_13568-001,SMLF,IO,DGA^6000030   I159 @T6G_MB_LIB.T6G(SCH_1):PAGE13
   J19  213  CA3_A SCONN288_DDR506112002KQ-SCONN288_DDR506112002KQ,SMA   I350 @T6G_MB_LIB.T6G(SCH_1):PAGE88

M_D_CPU0_SA_CA<4> @T6G_MB_LIB.T6G(SCH_1):M_D_CPU0_SA_CA(4)
   U25 BA60 MDA_CA4 GENOA_SP5-SOCKET6096_13568-001,SMLF,IO,DGA^6000030   I159 @T6G_MB_LIB.T6G(SCH_1):PAGE13
   J19   70  CA4_A SCONN288_DDR506112002KQ-SCONN288_DDR506112002KQ,SMA   I350 @T6G_MB_LIB.T6G(SCH_1):PAGE88

M_D_CPU0_SA_CA<5> @T6G_MB_LIB.T6G(SCH_1):M_D_CPU0_SA_CA(5)
   U25 BB60 MDA_CA5 GENOA_SP5-SOCKET6096_13568-001,SMLF,IO,DGA^6000030   I159 @T6G_MB_LIB.T6G(SCH_1):PAGE13
   J19  215  CA5_A SCONN288_DDR506112002KQ-SCONN288_DDR506112002KQ,SMA   I350 @T6G_MB_LIB.T6G(SCH_1):PAGE88

M_D_CPU0_SA_CA<6> @T6G_MB_LIB.T6G(SCH_1):M_D_CPU0_SA_CA(6)
   U25 BB58 MDA_CA6 GENOA_SP5-SOCKET6096_13568-001,SMLF,IO,DGA^6000030   I159 @T6G_MB_LIB.T6G(SCH_1):PAGE13
   J19   72  CA6_A SCONN288_DDR506112002KQ-SCONN288_DDR506112002KQ,SMA   I350 @T6G_MB_LIB.T6G(SCH_1):PAGE88

M_D_CPU0_SA_CB<0> @T6G_MB_LIB.T6G(SCH_1):M_D_CPU0_SA_CB(0)
   U25 AJ60 MDA_CHECK0 GENOA_SP5-SOCKET6096_13568-001,SMLF,IO,DGA^6000030   I159 @T6G_MB_LIB.T6G(SCH_1):PAGE13
   J19   51  CB0_A SCONN288_DDR506112002KQ-SCONN288_DDR506112002KQ,SMA   I350 @T6G_MB_LIB.T6G(SCH_1):PAGE88

M_D_CPU0_SA_CB<1> @T6G_MB_LIB.T6G(SCH_1):M_D_CPU0_SA_CB(1)
   U25 AK58 MDA_CHECK1 GENOA_SP5-SOCKET6096_13568-001,SMLF,IO,DGA^6000030   I159 @T6G_MB_LIB.T6G(SCH_1):PAGE13
   J19   53  CB1_A SCONN288_DDR506112002KQ-SCONN288_DDR506112002KQ,SMA   I350 @T6G_MB_LIB.T6G(SCH_1):PAGE88

M_D_CPU0_SA_CB<2> @T6G_MB_LIB.T6G(SCH_1):M_D_CPU0_SA_CB(2)
   U25 AK60 MDA_CHECK2 GENOA_SP5-SOCKET6096_13568-001,SMLF,IO,DGA^6000030   I159 @T6G_MB_LIB.T6G(SCH_1):PAGE13
   J19  196  CB2_A SCONN288_DDR506112002KQ-SCONN288_DDR506112002KQ,SMA   I350 @T6G_MB_LIB.T6G(SCH_1):PAGE88

M_D_CPU0_SA_CB<3> @T6G_MB_LIB.T6G(SCH_1):M_D_CPU0_SA_CB(3)
   U25 AL59 MDA_CHECK3 GENOA_SP5-SOCKET6096_13568-001,SMLF,IO,DGA^6000030   I159 @T6G_MB_LIB.T6G(SCH_1):PAGE13
   J19  198  CB3_A SCONN288_DDR506112002KQ-SCONN288_DDR506112002KQ,SMA   I350 @T6G_MB_LIB.T6G(SCH_1):PAGE88

M_D_CPU0_SA_CB<4> @T6G_MB_LIB.T6G(SCH_1):M_D_CPU0_SA_CB(4)
   U25 AN60 MDA_CHECK4 GENOA_SP5-SOCKET6096_13568-001,SMLF,IO,DGA^6000030   I159 @T6G_MB_LIB.T6G(SCH_1):PAGE13
   J19   58  CB4_A SCONN288_DDR506112002KQ-SCONN288_DDR506112002KQ,SMA   I350 @T6G_MB_LIB.T6G(SCH_1):PAGE88

M_D_CPU0_SA_CB<5> @T6G_MB_LIB.T6G(SCH_1):M_D_CPU0_SA_CB(5)
   U25 AP58 MDA_CHECK5 GENOA_SP5-SOCKET6096_13568-001,SMLF,IO,DGA^6000030   I159 @T6G_MB_LIB.T6G(SCH_1):PAGE13
   J19   60  CB5_A SCONN288_DDR506112002KQ-SCONN288_DDR506112002KQ,SMA   I350 @T6G_MB_LIB.T6G(SCH_1):PAGE88

M_D_CPU0_SA_CB<6> @T6G_MB_LIB.T6G(SCH_1):M_D_CPU0_SA_CB(6)
   U25 AP60 MDA_CHECK6 GENOA_SP5-SOCKET6096_13568-001,SMLF,IO,DGA^6000030   I159 @T6G_MB_LIB.T6G(SCH_1):PAGE13
   J19  203  CB6_A SCONN288_DDR506112002KQ-SCONN288_DDR506112002KQ,SMA   I350 @T6G_MB_LIB.T6G(SCH_1):PAGE88

M_D_CPU0_SA_CB<7> @T6G_MB_LIB.T6G(SCH_1):M_D_CPU0_SA_CB(7)
   U25 AR59 MDA_CHECK7 GENOA_SP5-SOCKET6096_13568-001,SMLF,IO,DGA^6000030   I159 @T6G_MB_LIB.T6G(SCH_1):PAGE13
   J19  205  CB7_A SCONN288_DDR506112002KQ-SCONN288_DDR506112002KQ,SMA   I350 @T6G_MB_LIB.T6G(SCH_1):PAGE88

M_D_CPU0_SA_CS_N<0> @T6G_MB_LIB.T6G(SCH_1):M_D_CPU0_SA_CS_N(0)
   U25 AV60 MDA0_CS_L0 GENOA_SP5-SOCKET6096_13568-001,SMLF,IO,DGA^6000030   I159 @T6G_MB_LIB.T6G(SCH_1):PAGE13
   J19   64 CS0_A_N SCONN288_DDR506112002KQ-SCONN288_DDR506112002KQ,SMA   I350 @T6G_MB_LIB.T6G(SCH_1):PAGE88

M_D_CPU0_SA_CS_N<1> @T6G_MB_LIB.T6G(SCH_1):M_D_CPU0_SA_CS_N(1)
   U25 AW59 MDA0_CS_L1 GENOA_SP5-SOCKET6096_13568-001,SMLF,IO,DGA^6000030   I159 @T6G_MB_LIB.T6G(SCH_1):PAGE13
   J19  209 CS1_A_N SCONN288_DDR506112002KQ-SCONN288_DDR506112002KQ,SMA   I350 @T6G_MB_LIB.T6G(SCH_1):PAGE88

M_D_CPU0_SA_DQ<0> @T6G_MB_LIB.T6G(SCH_1):M_D_CPU0_SA_DQ(0)
   U25  E60 MDA_DATA0 GENOA_SP5-SOCKET6096_13568-001,SMLF,IO,DGA^6000030   I159 @T6G_MB_LIB.T6G(SCH_1):PAGE13
   J19    7  DQ0_A SCONN288_DDR506112002KQ-SCONN288_DDR506112002KQ,SMA   I350 @T6G_MB_LIB.T6G(SCH_1):PAGE88

M_D_CPU0_SA_DQ<10> @T6G_MB_LIB.T6G(SCH_1):M_D_CPU0_SA_DQ(10)
   U25  M60 MDA_DATA10 GENOA_SP5-SOCKET6096_13568-001,SMLF,IO,DGA^6000030   I159 @T6G_MB_LIB.T6G(SCH_1):PAGE13
   J19  163 DQ10_A SCONN288_DDR506112002KQ-SCONN288_DDR506112002KQ,SMA   I350 @T6G_MB_LIB.T6G(SCH_1):PAGE88

M_D_CPU0_SA_DQ<11> @T6G_MB_LIB.T6G(SCH_1):M_D_CPU0_SA_DQ(11)
   U25  N59 MDA_DATA11 GENOA_SP5-SOCKET6096_13568-001,SMLF,IO,DGA^6000030   I159 @T6G_MB_LIB.T6G(SCH_1):PAGE13
   J19  165 DQ11_A SCONN288_DDR506112002KQ-SCONN288_DDR506112002KQ,SMA   I350 @T6G_MB_LIB.T6G(SCH_1):PAGE88

M_D_CPU0_SA_DQ<12> @T6G_MB_LIB.T6G(SCH_1):M_D_CPU0_SA_DQ(12)
   U25  R60 MDA_DATA12 GENOA_SP5-SOCKET6096_13568-001,SMLF,IO,DGA^6000030   I159 @T6G_MB_LIB.T6G(SCH_1):PAGE13
   J19   25 DQ12_A SCONN288_DDR506112002KQ-SCONN288_DDR506112002KQ,SMA   I350 @T6G_MB_LIB.T6G(SCH_1):PAGE88

M_D_CPU0_SA_DQ<13> @T6G_MB_LIB.T6G(SCH_1):M_D_CPU0_SA_DQ(13)
   U25  T58 MDA_DATA13 GENOA_SP5-SOCKET6096_13568-001,SMLF,IO,DGA^6000030   I159 @T6G_MB_LIB.T6G(SCH_1):PAGE13
   J19   27 DQ13_A SCONN288_DDR506112002KQ-SCONN288_DDR506112002KQ,SMA   I350 @T6G_MB_LIB.T6G(SCH_1):PAGE88

M_D_CPU0_SA_DQ<14> @T6G_MB_LIB.T6G(SCH_1):M_D_CPU0_SA_DQ(14)
   U25  T60 MDA_DATA14 GENOA_SP5-SOCKET6096_13568-001,SMLF,IO,DGA^6000030   I159 @T6G_MB_LIB.T6G(SCH_1):PAGE13
   J19  170 DQ14_A SCONN288_DDR506112002KQ-SCONN288_DDR506112002KQ,SMA   I350 @T6G_MB_LIB.T6G(SCH_1):PAGE88

M_D_CPU0_SA_DQ<15> @T6G_MB_LIB.T6G(SCH_1):M_D_CPU0_SA_DQ(15)
   U25  U59 MDA_DATA15 GENOA_SP5-SOCKET6096_13568-001,SMLF,IO,DGA^6000030   I159 @T6G_MB_LIB.T6G(SCH_1):PAGE13
   J19  172 DQ15_A SCONN288_DDR506112002KQ-SCONN288_DDR506112002KQ,SMA   I350 @T6G_MB_LIB.T6G(SCH_1):PAGE88

M_D_CPU0_SA_DQ<16> @T6G_MB_LIB.T6G(SCH_1):M_D_CPU0_SA_DQ(16)
   U25  U60 MDA_DATA16 GENOA_SP5-SOCKET6096_13568-001,SMLF,IO,DGA^6000030   I159 @T6G_MB_LIB.T6G(SCH_1):PAGE13
   J19   29 DQ16_A SCONN288_DDR506112002KQ-SCONN288_DDR506112002KQ,SMA   I350 @T6G_MB_LIB.T6G(SCH_1):PAGE88

M_D_CPU0_SA_DQ<17> @T6G_MB_LIB.T6G(SCH_1):M_D_CPU0_SA_DQ(17)
   U25  V58 MDA_DATA17 GENOA_SP5-SOCKET6096_13568-001,SMLF,IO,DGA^6000030   I159 @T6G_MB_LIB.T6G(SCH_1):PAGE13
   J19   31 DQ17_A SCONN288_DDR506112002KQ-SCONN288_DDR506112002KQ,SMA   I350 @T6G_MB_LIB.T6G(SCH_1):PAGE88

M_D_CPU0_SA_DQ<18> @T6G_MB_LIB.T6G(SCH_1):M_D_CPU0_SA_DQ(18)
   U25  V60 MDA_DATA18 GENOA_SP5-SOCKET6096_13568-001,SMLF,IO,DGA^6000030   I159 @T6G_MB_LIB.T6G(SCH_1):PAGE13
   J19  174 DQ18_A SCONN288_DDR506112002KQ-SCONN288_DDR506112002KQ,SMA   I350 @T6G_MB_LIB.T6G(SCH_1):PAGE88

M_D_CPU0_SA_DQ<19> @T6G_MB_LIB.T6G(SCH_1):M_D_CPU0_SA_DQ(19)
   U25  W59 MDA_DATA19 GENOA_SP5-SOCKET6096_13568-001,SMLF,IO,DGA^6000030   I159 @T6G_MB_LIB.T6G(SCH_1):PAGE13
   J19  176 DQ19_A SCONN288_DDR506112002KQ-SCONN288_DDR506112002KQ,SMA   I350 @T6G_MB_LIB.T6G(SCH_1):PAGE88

M_D_CPU0_SA_DQ<1> @T6G_MB_LIB.T6G(SCH_1):M_D_CPU0_SA_DQ(1)
   U25  F58 MDA_DATA1 GENOA_SP5-SOCKET6096_13568-001,SMLF,IO,DGA^6000030   I159 @T6G_MB_LIB.T6G(SCH_1):PAGE13
   J19    9  DQ1_A SCONN288_DDR506112002KQ-SCONN288_DDR506112002KQ,SMA   I350 @T6G_MB_LIB.T6G(SCH_1):PAGE88

M_D_CPU0_SA_DQ<20> @T6G_MB_LIB.T6G(SCH_1):M_D_CPU0_SA_DQ(20)
   U25 AA60 MDA_DATA20 GENOA_SP5-SOCKET6096_13568-001,SMLF,IO,DGA^6000030   I159 @T6G_MB_LIB.T6G(SCH_1):PAGE13
   J19   36 DQ20_A SCONN288_DDR506112002KQ-SCONN288_DDR506112002KQ,SMA   I350 @T6G_MB_LIB.T6G(SCH_1):PAGE88

M_D_CPU0_SA_DQ<21> @T6G_MB_LIB.T6G(SCH_1):M_D_CPU0_SA_DQ(21)
   U25 AB58 MDA_DATA21 GENOA_SP5-SOCKET6096_13568-001,SMLF,IO,DGA^6000030   I159 @T6G_MB_LIB.T6G(SCH_1):PAGE13
   J19   38 DQ21_A SCONN288_DDR506112002KQ-SCONN288_DDR506112002KQ,SMA   I350 @T6G_MB_LIB.T6G(SCH_1):PAGE88

M_D_CPU0_SA_DQ<22> @T6G_MB_LIB.T6G(SCH_1):M_D_CPU0_SA_DQ(22)
   U25 AB60 MDA_DATA22 GENOA_SP5-SOCKET6096_13568-001,SMLF,IO,DGA^6000030   I159 @T6G_MB_LIB.T6G(SCH_1):PAGE13
   J19  181 DQ22_A SCONN288_DDR506112002KQ-SCONN288_DDR506112002KQ,SMA   I350 @T6G_MB_LIB.T6G(SCH_1):PAGE88

M_D_CPU0_SA_DQ<23> @T6G_MB_LIB.T6G(SCH_1):M_D_CPU0_SA_DQ(23)
   U25 AC59 MDA_DATA23 GENOA_SP5-SOCKET6096_13568-001,SMLF,IO,DGA^6000030   I159 @T6G_MB_LIB.T6G(SCH_1):PAGE13
   J19  183 DQ23_A SCONN288_DDR506112002KQ-SCONN288_DDR506112002KQ,SMA   I350 @T6G_MB_LIB.T6G(SCH_1):PAGE88

M_D_CPU0_SA_DQ<24> @T6G_MB_LIB.T6G(SCH_1):M_D_CPU0_SA_DQ(24)
   U25 AC60 MDA_DATA24 GENOA_SP5-SOCKET6096_13568-001,SMLF,IO,DGA^6000030   I159 @T6G_MB_LIB.T6G(SCH_1):PAGE13
   J19   40 DQ24_A SCONN288_DDR506112002KQ-SCONN288_DDR506112002KQ,SMA   I350 @T6G_MB_LIB.T6G(SCH_1):PAGE88

M_D_CPU0_SA_DQ<25> @T6G_MB_LIB.T6G(SCH_1):M_D_CPU0_SA_DQ(25)
   U25 AD58 MDA_DATA25 GENOA_SP5-SOCKET6096_13568-001,SMLF,IO,DGA^6000030   I159 @T6G_MB_LIB.T6G(SCH_1):PAGE13
   J19   42 DQ25_A SCONN288_DDR506112002KQ-SCONN288_DDR506112002KQ,SMA   I350 @T6G_MB_LIB.T6G(SCH_1):PAGE88

M_D_CPU0_SA_DQ<26> @T6G_MB_LIB.T6G(SCH_1):M_D_CPU0_SA_DQ(26)
   U25 AD60 MDA_DATA26 GENOA_SP5-SOCKET6096_13568-001,SMLF,IO,DGA^6000030   I159 @T6G_MB_LIB.T6G(SCH_1):PAGE13
   J19  185 DQ26_A SCONN288_DDR506112002KQ-SCONN288_DDR506112002KQ,SMA   I350 @T6G_MB_LIB.T6G(SCH_1):PAGE88

M_D_CPU0_SA_DQ<27> @T6G_MB_LIB.T6G(SCH_1):M_D_CPU0_SA_DQ(27)
   U25 AE59 MDA_DATA27 GENOA_SP5-SOCKET6096_13568-001,SMLF,IO,DGA^6000030   I159 @T6G_MB_LIB.T6G(SCH_1):PAGE13
   J19  187 DQ27_A SCONN288_DDR506112002KQ-SCONN288_DDR506112002KQ,SMA   I350 @T6G_MB_LIB.T6G(SCH_1):PAGE88

M_D_CPU0_SA_DQ<28> @T6G_MB_LIB.T6G(SCH_1):M_D_CPU0_SA_DQ(28)
   U25 AG60 MDA_DATA28 GENOA_SP5-SOCKET6096_13568-001,SMLF,IO,DGA^6000030   I159 @T6G_MB_LIB.T6G(SCH_1):PAGE13
   J19   47 DQ28_A SCONN288_DDR506112002KQ-SCONN288_DDR506112002KQ,SMA   I350 @T6G_MB_LIB.T6G(SCH_1):PAGE88

M_D_CPU0_SA_DQ<29> @T6G_MB_LIB.T6G(SCH_1):M_D_CPU0_SA_DQ(29)
   U25 AH58 MDA_DATA29 GENOA_SP5-SOCKET6096_13568-001,SMLF,IO,DGA^6000030   I159 @T6G_MB_LIB.T6G(SCH_1):PAGE13
   J19   49 DQ29_A SCONN288_DDR506112002KQ-SCONN288_DDR506112002KQ,SMA   I350 @T6G_MB_LIB.T6G(SCH_1):PAGE88

M_D_CPU0_SA_DQ<2> @T6G_MB_LIB.T6G(SCH_1):M_D_CPU0_SA_DQ(2)
   U25  F60 MDA_DATA2 GENOA_SP5-SOCKET6096_13568-001,SMLF,IO,DGA^6000030   I159 @T6G_MB_LIB.T6G(SCH_1):PAGE13
   J19  152  DQ2_A SCONN288_DDR506112002KQ-SCONN288_DDR506112002KQ,SMA   I350 @T6G_MB_LIB.T6G(SCH_1):PAGE88

M_D_CPU0_SA_DQ<30> @T6G_MB_LIB.T6G(SCH_1):M_D_CPU0_SA_DQ(30)
   U25 AH60 MDA_DATA30 GENOA_SP5-SOCKET6096_13568-001,SMLF,IO,DGA^6000030   I159 @T6G_MB_LIB.T6G(SCH_1):PAGE13
   J19  192 DQ30_A SCONN288_DDR506112002KQ-SCONN288_DDR506112002KQ,SMA   I350 @T6G_MB_LIB.T6G(SCH_1):PAGE88

M_D_CPU0_SA_DQ<31> @T6G_MB_LIB.T6G(SCH_1):M_D_CPU0_SA_DQ(31)
   U25 AJ59 MDA_DATA31 GENOA_SP5-SOCKET6096_13568-001,SMLF,IO,DGA^6000030   I159 @T6G_MB_LIB.T6G(SCH_1):PAGE13
   J19  194 DQ31_A SCONN288_DDR506112002KQ-SCONN288_DDR506112002KQ,SMA   I350 @T6G_MB_LIB.T6G(SCH_1):PAGE88

M_D_CPU0_SA_DQ<3> @T6G_MB_LIB.T6G(SCH_1):M_D_CPU0_SA_DQ(3)
   U25  G59 MDA_DATA3 GENOA_SP5-SOCKET6096_13568-001,SMLF,IO,DGA^6000030   I159 @T6G_MB_LIB.T6G(SCH_1):PAGE13
   J19  154  DQ3_A SCONN288_DDR506112002KQ-SCONN288_DDR506112002KQ,SMA   I350 @T6G_MB_LIB.T6G(SCH_1):PAGE88

M_D_CPU0_SA_DQ<4> @T6G_MB_LIB.T6G(SCH_1):M_D_CPU0_SA_DQ(4)
   U25  J60 MDA_DATA4 GENOA_SP5-SOCKET6096_13568-001,SMLF,IO,DGA^6000030   I159 @T6G_MB_LIB.T6G(SCH_1):PAGE13
   J19   14  DQ4_A SCONN288_DDR506112002KQ-SCONN288_DDR506112002KQ,SMA   I350 @T6G_MB_LIB.T6G(SCH_1):PAGE88

M_D_CPU0_SA_DQ<5> @T6G_MB_LIB.T6G(SCH_1):M_D_CPU0_SA_DQ(5)
   U25  K58 MDA_DATA5 GENOA_SP5-SOCKET6096_13568-001,SMLF,IO,DGA^6000030   I159 @T6G_MB_LIB.T6G(SCH_1):PAGE13
   J19   16  DQ5_A SCONN288_DDR506112002KQ-SCONN288_DDR506112002KQ,SMA   I350 @T6G_MB_LIB.T6G(SCH_1):PAGE88

M_D_CPU0_SA_DQ<6> @T6G_MB_LIB.T6G(SCH_1):M_D_CPU0_SA_DQ(6)
   U25  K60 MDA_DATA6 GENOA_SP5-SOCKET6096_13568-001,SMLF,IO,DGA^6000030   I159 @T6G_MB_LIB.T6G(SCH_1):PAGE13
   J19  159  DQ6_A SCONN288_DDR506112002KQ-SCONN288_DDR506112002KQ,SMA   I350 @T6G_MB_LIB.T6G(SCH_1):PAGE88

M_D_CPU0_SA_DQ<7> @T6G_MB_LIB.T6G(SCH_1):M_D_CPU0_SA_DQ(7)
   U25  L59 MDA_DATA7 GENOA_SP5-SOCKET6096_13568-001,SMLF,IO,DGA^6000030   I159 @T6G_MB_LIB.T6G(SCH_1):PAGE13
   J19  161  DQ7_A SCONN288_DDR506112002KQ-SCONN288_DDR506112002KQ,SMA   I350 @T6G_MB_LIB.T6G(SCH_1):PAGE88

M_D_CPU0_SA_DQ<8> @T6G_MB_LIB.T6G(SCH_1):M_D_CPU0_SA_DQ(8)
   U25  L60 MDA_DATA8 GENOA_SP5-SOCKET6096_13568-001,SMLF,IO,DGA^6000030   I159 @T6G_MB_LIB.T6G(SCH_1):PAGE13
   J19   18  DQ8_A SCONN288_DDR506112002KQ-SCONN288_DDR506112002KQ,SMA   I350 @T6G_MB_LIB.T6G(SCH_1):PAGE88

M_D_CPU0_SA_DQ<9> @T6G_MB_LIB.T6G(SCH_1):M_D_CPU0_SA_DQ(9)
   U25  M58 MDA_DATA9 GENOA_SP5-SOCKET6096_13568-001,SMLF,IO,DGA^6000030   I159 @T6G_MB_LIB.T6G(SCH_1):PAGE13
   J19   20  DQ9_A SCONN288_DDR506112002KQ-SCONN288_DDR506112002KQ,SMA   I350 @T6G_MB_LIB.T6G(SCH_1):PAGE88

M_D_CPU0_SA_DQS_DN<0> @T6G_MB_LIB.T6G(SCH_1):M_D_CPU0_SA_DQS_DN(0)
   U25  H60 MDA_DQS_L0 GENOA_SP5-SOCKET6096_13568-001,SMLF,IO,DGA^6000030   I159 @T6G_MB_LIB.T6G(SCH_1):PAGE13
   J19   12 DQS0_A_C SCONN288_DDR506112002KQ-SCONN288_DDR506112002KQ,SMA   I415 @T6G_MB_LIB.T6G(SCH_1):PAGE88

M_D_CPU0_SA_DQS_DN<1> @T6G_MB_LIB.T6G(SCH_1):M_D_CPU0_SA_DQS_DN(1)
   U25  P60 MDA_DQS_L1 GENOA_SP5-SOCKET6096_13568-001,SMLF,IO,DGA^6000030   I159 @T6G_MB_LIB.T6G(SCH_1):PAGE13
   J19   23 DQS1_A_C SCONN288_DDR506112002KQ-SCONN288_DDR506112002KQ,SMA   I415 @T6G_MB_LIB.T6G(SCH_1):PAGE88

M_D_CPU0_SA_DQS_DN<2> @T6G_MB_LIB.T6G(SCH_1):M_D_CPU0_SA_DQS_DN(2)
   U25  Y60 MDA_DQS_L2 GENOA_SP5-SOCKET6096_13568-001,SMLF,IO,DGA^6000030   I159 @T6G_MB_LIB.T6G(SCH_1):PAGE13
   J19   34 DQS2_A_C SCONN288_DDR506112002KQ-SCONN288_DDR506112002KQ,SMA   I415 @T6G_MB_LIB.T6G(SCH_1):PAGE88

M_D_CPU0_SA_DQS_DN<3> @T6G_MB_LIB.T6G(SCH_1):M_D_CPU0_SA_DQS_DN(3)
   U25 AF60 MDA_DQS_L3 GENOA_SP5-SOCKET6096_13568-001,SMLF,IO,DGA^6000030   I159 @T6G_MB_LIB.T6G(SCH_1):PAGE13
   J19   45 DQS3_A_C SCONN288_DDR506112002KQ-SCONN288_DDR506112002KQ,SMA   I415 @T6G_MB_LIB.T6G(SCH_1):PAGE88

M_D_CPU0_SA_DQS_DN<4> @T6G_MB_LIB.T6G(SCH_1):M_D_CPU0_SA_DQS_DN(4)
   U25 AM60 MDA_DQS_L4 GENOA_SP5-SOCKET6096_13568-001,SMLF,IO,DGA^6000030   I159 @T6G_MB_LIB.T6G(SCH_1):PAGE13
   J19   56 DQS4_A_C SCONN288_DDR506112002KQ-SCONN288_DDR506112002KQ,SMA   I415 @T6G_MB_LIB.T6G(SCH_1):PAGE88

M_D_CPU0_SA_DQS_DN<5> @T6G_MB_LIB.T6G(SCH_1):M_D_CPU0_SA_DQS_DN(5)
   U25  H58 MDA_DQS_L5 GENOA_SP5-SOCKET6096_13568-001,SMLF,IO,DGA^6000030   I159 @T6G_MB_LIB.T6G(SCH_1):PAGE13
   J19  156 DQS5_A_C||TDQS5_A_C||DQS5_A_T||TDQS5_A_T SCONN288_DDR506112002KQ-SCONN288_DDR506112002KQ,SMA   I415 @T6G_MB_LIB.T6G(SCH_1):PAGE88

M_D_CPU0_SA_DQS_DN<6> @T6G_MB_LIB.T6G(SCH_1):M_D_CPU0_SA_DQS_DN(6)
   U25  P58 MDA_DQS_L6 GENOA_SP5-SOCKET6096_13568-001,SMLF,IO,DGA^6000030   I159 @T6G_MB_LIB.T6G(SCH_1):PAGE13
   J19  167 DQS6_A_C||TDQS6_A_C||DQS6_A_T||TDQS6_A_T SCONN288_DDR506112002KQ-SCONN288_DDR506112002KQ,SMA   I415 @T6G_MB_LIB.T6G(SCH_1):PAGE88

M_D_CPU0_SA_DQS_DN<7> @T6G_MB_LIB.T6G(SCH_1):M_D_CPU0_SA_DQS_DN(7)
   U25  Y58 MDA_DQS_L7 GENOA_SP5-SOCKET6096_13568-001,SMLF,IO,DGA^6000030   I159 @T6G_MB_LIB.T6G(SCH_1):PAGE13
   J19  178 DQS7_A_C||TDQS7_A_C SCONN288_DDR506112002KQ-SCONN288_DDR506112002KQ,SMA   I415 @T6G_MB_LIB.T6G(SCH_1):PAGE88

M_D_CPU0_SA_DQS_DN<8> @T6G_MB_LIB.T6G(SCH_1):M_D_CPU0_SA_DQS_DN(8)
   U25 AF58 MDA_DQS_L8 GENOA_SP5-SOCKET6096_13568-001,SMLF,IO,DGA^6000030   I159 @T6G_MB_LIB.T6G(SCH_1):PAGE13
   J19  189 DQS8_A_C||TDQS8_A_C SCONN288_DDR506112002KQ-SCONN288_DDR506112002KQ,SMA   I415 @T6G_MB_LIB.T6G(SCH_1):PAGE88

M_D_CPU0_SA_DQS_DN<9> @T6G_MB_LIB.T6G(SCH_1):M_D_CPU0_SA_DQS_DN(9)
   U25 AM58 MDA_DQS_L9 GENOA_SP5-SOCKET6096_13568-001,SMLF,IO,DGA^6000030   I159 @T6G_MB_LIB.T6G(SCH_1):PAGE13
   J19  200 DQS9_A_C||TDQS9_A_C SCONN288_DDR506112002KQ-SCONN288_DDR506112002KQ,SMA   I415 @T6G_MB_LIB.T6G(SCH_1):PAGE88

M_D_CPU0_SA_DQS_DP<0> @T6G_MB_LIB.T6G(SCH_1):M_D_CPU0_SA_DQS_DP(0)
   U25  G60 MDA_DQS_H0 GENOA_SP5-SOCKET6096_13568-001,SMLF,IO,DGA^6000030   I159 @T6G_MB_LIB.T6G(SCH_1):PAGE13
   J19   11 DQS0_A_T SCONN288_DDR506112002KQ-SCONN288_DDR506112002KQ,SMA   I415 @T6G_MB_LIB.T6G(SCH_1):PAGE88

M_D_CPU0_SA_DQS_DP<1> @T6G_MB_LIB.T6G(SCH_1):M_D_CPU0_SA_DQS_DP(1)
   U25  N60 MDA_DQS_H1 GENOA_SP5-SOCKET6096_13568-001,SMLF,IO,DGA^6000030   I159 @T6G_MB_LIB.T6G(SCH_1):PAGE13
   J19   22 DQS1_A_T SCONN288_DDR506112002KQ-SCONN288_DDR506112002KQ,SMA   I415 @T6G_MB_LIB.T6G(SCH_1):PAGE88

M_D_CPU0_SA_DQS_DP<2> @T6G_MB_LIB.T6G(SCH_1):M_D_CPU0_SA_DQS_DP(2)
   U25  W60 MDA_DQS_H2 GENOA_SP5-SOCKET6096_13568-001,SMLF,IO,DGA^6000030   I159 @T6G_MB_LIB.T6G(SCH_1):PAGE13
   J19   33 DQS2_A_T SCONN288_DDR506112002KQ-SCONN288_DDR506112002KQ,SMA   I415 @T6G_MB_LIB.T6G(SCH_1):PAGE88

M_D_CPU0_SA_DQS_DP<3> @T6G_MB_LIB.T6G(SCH_1):M_D_CPU0_SA_DQS_DP(3)
   U25 AE60 MDA_DQS_H3 GENOA_SP5-SOCKET6096_13568-001,SMLF,IO,DGA^6000030   I159 @T6G_MB_LIB.T6G(SCH_1):PAGE13
   J19   44 DQS3_A_T SCONN288_DDR506112002KQ-SCONN288_DDR506112002KQ,SMA   I415 @T6G_MB_LIB.T6G(SCH_1):PAGE88

M_D_CPU0_SA_DQS_DP<4> @T6G_MB_LIB.T6G(SCH_1):M_D_CPU0_SA_DQS_DP(4)
   U25 AL60 MDA_DQS_H4 GENOA_SP5-SOCKET6096_13568-001,SMLF,IO,DGA^6000030   I159 @T6G_MB_LIB.T6G(SCH_1):PAGE13
   J19   55 DQS4_A_T SCONN288_DDR506112002KQ-SCONN288_DDR506112002KQ,SMA   I415 @T6G_MB_LIB.T6G(SCH_1):PAGE88

M_D_CPU0_SA_DQS_DP<5> @T6G_MB_LIB.T6G(SCH_1):M_D_CPU0_SA_DQS_DP(5)
   U25  J59 MDA_DQS_H5 GENOA_SP5-SOCKET6096_13568-001,SMLF,IO,DGA^6000030   I159 @T6G_MB_LIB.T6G(SCH_1):PAGE13
   J19  157 DQS5_A_T||TDQS5_A_T SCONN288_DDR506112002KQ-SCONN288_DDR506112002KQ,SMA   I415 @T6G_MB_LIB.T6G(SCH_1):PAGE88

M_D_CPU0_SA_DQS_DP<6> @T6G_MB_LIB.T6G(SCH_1):M_D_CPU0_SA_DQS_DP(6)
   U25  R59 MDA_DQS_H6 GENOA_SP5-SOCKET6096_13568-001,SMLF,IO,DGA^6000030   I159 @T6G_MB_LIB.T6G(SCH_1):PAGE13
   J19  168 DQS6_A_T||TDQS6_A_T SCONN288_DDR506112002KQ-SCONN288_DDR506112002KQ,SMA   I415 @T6G_MB_LIB.T6G(SCH_1):PAGE88

M_D_CPU0_SA_DQS_DP<7> @T6G_MB_LIB.T6G(SCH_1):M_D_CPU0_SA_DQS_DP(7)
   U25 AA59 MDA_DQS_H7 GENOA_SP5-SOCKET6096_13568-001,SMLF,IO,DGA^6000030   I159 @T6G_MB_LIB.T6G(SCH_1):PAGE13
   J19  179 DQS7_A_T||TDQS7_A_T SCONN288_DDR506112002KQ-SCONN288_DDR506112002KQ,SMA   I415 @T6G_MB_LIB.T6G(SCH_1):PAGE88

M_D_CPU0_SA_DQS_DP<8> @T6G_MB_LIB.T6G(SCH_1):M_D_CPU0_SA_DQS_DP(8)
   U25 AG59 MDA_DQS_H8 GENOA_SP5-SOCKET6096_13568-001,SMLF,IO,DGA^6000030   I159 @T6G_MB_LIB.T6G(SCH_1):PAGE13
   J19  190 DQS8_A_T||TDQS8_A_T SCONN288_DDR506112002KQ-SCONN288_DDR506112002KQ,SMA   I415 @T6G_MB_LIB.T6G(SCH_1):PAGE88

M_D_CPU0_SA_DQS_DP<9> @T6G_MB_LIB.T6G(SCH_1):M_D_CPU0_SA_DQS_DP(9)
   U25 AN59 MDA_DQS_H9 GENOA_SP5-SOCKET6096_13568-001,SMLF,IO,DGA^6000030   I159 @T6G_MB_LIB.T6G(SCH_1):PAGE13
   J19  201 DQS9_A_T||TDQS9_A_T SCONN288_DDR506112002KQ-SCONN288_DDR506112002KQ,SMA   I415 @T6G_MB_LIB.T6G(SCH_1):PAGE88

M_D_CPU0_SA_PAR @T6G_MB_LIB.T6G(SCH_1):M_D_CPU0_SA_PAR
   U25 BC59 MDA_PAR GENOA_SP5-SOCKET6096_13568-001,SMLF,IO,DGA^6000030   I159 @T6G_MB_LIB.T6G(SCH_1):PAGE13
   J19   74  PAR_A SCONN288_DDR506112002KQ-SCONN288_DDR506112002KQ,SMA   I350 @T6G_MB_LIB.T6G(SCH_1):PAGE88

M_D_CPU0_SA_RSP<0> @T6G_MB_LIB.T6G(SCH_1):M_D_CPU0_SA_RSP(0)
   U25 BN59 MDA0_RSP_L GENOA_SP5-SOCKET6096_13568-001,SMLF,IO,DGA^6000030   I159 @T6G_MB_LIB.T6G(SCH_1):PAGE13
   J19   86 LBD||RSP_A_N SCONN288_DDR506112002KQ-SCONN288_DDR506112002KQ,SMA   I350 @T6G_MB_LIB.T6G(SCH_1):PAGE88

M_D_CPU0_SB_CA<0> @T6G_MB_LIB.T6G(SCH_1):M_D_CPU0_SB_CA(0)
   U25 BG59 MDB_CA0 GENOA_SP5-SOCKET6096_13568-001,SMLF,IO,DGA^6000030   I159 @T6G_MB_LIB.T6G(SCH_1):PAGE13
   J19   76  CA0_B SCONN288_DDR506112002KQ-SCONN288_DDR506112002KQ,SMA   I350 @T6G_MB_LIB.T6G(SCH_1):PAGE88

M_D_CPU0_SB_CA<1> @T6G_MB_LIB.T6G(SCH_1):M_D_CPU0_SB_CA(1)
   U25 BH58 MDB_CA1 GENOA_SP5-SOCKET6096_13568-001,SMLF,IO,DGA^6000030   I159 @T6G_MB_LIB.T6G(SCH_1):PAGE13
   J19  221  CA1_B SCONN288_DDR506112002KQ-SCONN288_DDR506112002KQ,SMA   I350 @T6G_MB_LIB.T6G(SCH_1):PAGE88

M_D_CPU0_SB_CA<2> @T6G_MB_LIB.T6G(SCH_1):M_D_CPU0_SB_CA(2)
   U25 BH60 MDB_CA2 GENOA_SP5-SOCKET6096_13568-001,SMLF,IO,DGA^6000030   I159 @T6G_MB_LIB.T6G(SCH_1):PAGE13
   J19   78  CA2_B SCONN288_DDR506112002KQ-SCONN288_DDR506112002KQ,SMA   I350 @T6G_MB_LIB.T6G(SCH_1):PAGE88

M_D_CPU0_SB_CA<3> @T6G_MB_LIB.T6G(SCH_1):M_D_CPU0_SB_CA(3)
   U25 BJ60 MDB_CA3 GENOA_SP5-SOCKET6096_13568-001,SMLF,IO,DGA^6000030   I159 @T6G_MB_LIB.T6G(SCH_1):PAGE13
   J19  223  CA3_B SCONN288_DDR506112002KQ-SCONN288_DDR506112002KQ,SMA   I350 @T6G_MB_LIB.T6G(SCH_1):PAGE88

M_D_CPU0_SB_CA<4> @T6G_MB_LIB.T6G(SCH_1):M_D_CPU0_SB_CA(4)
   U25 BJ59 MDB_CA4 GENOA_SP5-SOCKET6096_13568-001,SMLF,IO,DGA^6000030   I159 @T6G_MB_LIB.T6G(SCH_1):PAGE13
   J19   80  CA4_B SCONN288_DDR506112002KQ-SCONN288_DDR506112002KQ,SMA   I350 @T6G_MB_LIB.T6G(SCH_1):PAGE88

M_D_CPU0_SB_CA<5> @T6G_MB_LIB.T6G(SCH_1):M_D_CPU0_SB_CA(5)
   U25 BK58 MDB_CA5 GENOA_SP5-SOCKET6096_13568-001,SMLF,IO,DGA^6000030   I159 @T6G_MB_LIB.T6G(SCH_1):PAGE13
   J19  225  CA5_B SCONN288_DDR506112002KQ-SCONN288_DDR506112002KQ,SMA   I350 @T6G_MB_LIB.T6G(SCH_1):PAGE88

M_D_CPU0_SB_CA<6> @T6G_MB_LIB.T6G(SCH_1):M_D_CPU0_SB_CA(6)
   U25 BK60 MDB_CA6 GENOA_SP5-SOCKET6096_13568-001,SMLF,IO,DGA^6000030   I159 @T6G_MB_LIB.T6G(SCH_1):PAGE13
   J19   82  CA6_B SCONN288_DDR506112002KQ-SCONN288_DDR506112002KQ,SMA   I350 @T6G_MB_LIB.T6G(SCH_1):PAGE88

M_D_CPU0_SB_CB<0> @T6G_MB_LIB.T6G(SCH_1):M_D_CPU0_SB_CB(0)
   U25 BY60 MDB_CHECK0 GENOA_SP5-SOCKET6096_13568-001,SMLF,IO,DGA^6000030   I159 @T6G_MB_LIB.T6G(SCH_1):PAGE13
   J19   96  CB0_B SCONN288_DDR506112002KQ-SCONN288_DDR506112002KQ,SMA   I350 @T6G_MB_LIB.T6G(SCH_1):PAGE88

M_D_CPU0_SB_CB<1> @T6G_MB_LIB.T6G(SCH_1):M_D_CPU0_SB_CB(1)
   U25 CA59 MDB_CHECK1 GENOA_SP5-SOCKET6096_13568-001,SMLF,IO,DGA^6000030   I159 @T6G_MB_LIB.T6G(SCH_1):PAGE13
   J19   98  CB1_B SCONN288_DDR506112002KQ-SCONN288_DDR506112002KQ,SMA   I350 @T6G_MB_LIB.T6G(SCH_1):PAGE88

M_D_CPU0_SB_CB<2> @T6G_MB_LIB.T6G(SCH_1):M_D_CPU0_SB_CB(2)
   U25 CA60 MDB_CHECK2 GENOA_SP5-SOCKET6096_13568-001,SMLF,IO,DGA^6000030   I159 @T6G_MB_LIB.T6G(SCH_1):PAGE13
   J19  241  CB2_B SCONN288_DDR506112002KQ-SCONN288_DDR506112002KQ,SMA   I350 @T6G_MB_LIB.T6G(SCH_1):PAGE88

M_D_CPU0_SB_CB<3> @T6G_MB_LIB.T6G(SCH_1):M_D_CPU0_SB_CB(3)
   U25 CB58 MDB_CHECK3 GENOA_SP5-SOCKET6096_13568-001,SMLF,IO,DGA^6000030   I159 @T6G_MB_LIB.T6G(SCH_1):PAGE13
   J19  243  CB3_B SCONN288_DDR506112002KQ-SCONN288_DDR506112002KQ,SMA   I350 @T6G_MB_LIB.T6G(SCH_1):PAGE88

M_D_CPU0_SB_CB<4> @T6G_MB_LIB.T6G(SCH_1):M_D_CPU0_SB_CB(4)
   U25 BT60 MDB_CHECK4 GENOA_SP5-SOCKET6096_13568-001,SMLF,IO,DGA^6000030   I159 @T6G_MB_LIB.T6G(SCH_1):PAGE13
   J19   89  CB4_B SCONN288_DDR506112002KQ-SCONN288_DDR506112002KQ,SMA   I350 @T6G_MB_LIB.T6G(SCH_1):PAGE88

M_D_CPU0_SB_CB<5> @T6G_MB_LIB.T6G(SCH_1):M_D_CPU0_SB_CB(5)
   U25 BU59 MDB_CHECK5 GENOA_SP5-SOCKET6096_13568-001,SMLF,IO,DGA^6000030   I159 @T6G_MB_LIB.T6G(SCH_1):PAGE13
   J19   91  CB5_B SCONN288_DDR506112002KQ-SCONN288_DDR506112002KQ,SMA   I350 @T6G_MB_LIB.T6G(SCH_1):PAGE88

M_D_CPU0_SB_CB<6> @T6G_MB_LIB.T6G(SCH_1):M_D_CPU0_SB_CB(6)
   U25 BU60 MDB_CHECK6 GENOA_SP5-SOCKET6096_13568-001,SMLF,IO,DGA^6000030   I159 @T6G_MB_LIB.T6G(SCH_1):PAGE13
   J19  234  CB6_B SCONN288_DDR506112002KQ-SCONN288_DDR506112002KQ,SMA   I350 @T6G_MB_LIB.T6G(SCH_1):PAGE88

M_D_CPU0_SB_CB<7> @T6G_MB_LIB.T6G(SCH_1):M_D_CPU0_SB_CB(7)
   U25 BV58 MDB_CHECK7 GENOA_SP5-SOCKET6096_13568-001,SMLF,IO,DGA^6000030   I159 @T6G_MB_LIB.T6G(SCH_1):PAGE13
   J19  236  CB7_B SCONN288_DDR506112002KQ-SCONN288_DDR506112002KQ,SMA   I350 @T6G_MB_LIB.T6G(SCH_1):PAGE88

M_D_CPU0_SB_CS_N<0> @T6G_MB_LIB.T6G(SCH_1):M_D_CPU0_SB_CS_N(0)
   U25 BM58 MDB0_CS_L0 GENOA_SP5-SOCKET6096_13568-001,SMLF,IO,DGA^6000030   I159 @T6G_MB_LIB.T6G(SCH_1):PAGE13
   J19   84 CS0_B_N SCONN288_DDR506112002KQ-SCONN288_DDR506112002KQ,SMA   I350 @T6G_MB_LIB.T6G(SCH_1):PAGE88

M_D_CPU0_SB_CS_N<1> @T6G_MB_LIB.T6G(SCH_1):M_D_CPU0_SB_CS_N(1)
   U25 BN60 MDB0_CS_L1 GENOA_SP5-SOCKET6096_13568-001,SMLF,IO,DGA^6000030   I159 @T6G_MB_LIB.T6G(SCH_1):PAGE13
   J19  229 CS1_B_N SCONN288_DDR506112002KQ-SCONN288_DDR506112002KQ,SMA   I350 @T6G_MB_LIB.T6G(SCH_1):PAGE88

M_D_CPU0_SB_DQ<0> @T6G_MB_LIB.T6G(SCH_1):M_D_CPU0_SB_DQ(0)
   U25 CB60 MDB_DATA0 GENOA_SP5-SOCKET6096_13568-001,SMLF,IO,DGA^6000030   I159 @T6G_MB_LIB.T6G(SCH_1):PAGE13
   J19  100  DQ0_B SCONN288_DDR506112002KQ-SCONN288_DDR506112002KQ,SMA   I350 @T6G_MB_LIB.T6G(SCH_1):PAGE88

M_D_CPU0_SB_DQ<10> @T6G_MB_LIB.T6G(SCH_1):M_D_CPU0_SB_DQ(10)
   U25 CJ60 MDB_DATA10 GENOA_SP5-SOCKET6096_13568-001,SMLF,IO,DGA^6000030   I159 @T6G_MB_LIB.T6G(SCH_1):PAGE13
   J19  256 DQ10_B SCONN288_DDR506112002KQ-SCONN288_DDR506112002KQ,SMA   I350 @T6G_MB_LIB.T6G(SCH_1):PAGE88

M_D_CPU0_SB_DQ<11> @T6G_MB_LIB.T6G(SCH_1):M_D_CPU0_SB_DQ(11)
   U25 CK58 MDB_DATA11 GENOA_SP5-SOCKET6096_13568-001,SMLF,IO,DGA^6000030   I159 @T6G_MB_LIB.T6G(SCH_1):PAGE13
   J19  258 DQ11_B SCONN288_DDR506112002KQ-SCONN288_DDR506112002KQ,SMA   I350 @T6G_MB_LIB.T6G(SCH_1):PAGE88

M_D_CPU0_SB_DQ<12> @T6G_MB_LIB.T6G(SCH_1):M_D_CPU0_SB_DQ(12)
   U25 CM60 MDB_DATA12 GENOA_SP5-SOCKET6096_13568-001,SMLF,IO,DGA^6000030   I159 @T6G_MB_LIB.T6G(SCH_1):PAGE13
   J19  118 DQ12_B SCONN288_DDR506112002KQ-SCONN288_DDR506112002KQ,SMA   I350 @T6G_MB_LIB.T6G(SCH_1):PAGE88

M_D_CPU0_SB_DQ<13> @T6G_MB_LIB.T6G(SCH_1):M_D_CPU0_SB_DQ(13)
   U25 CN59 MDB_DATA13 GENOA_SP5-SOCKET6096_13568-001,SMLF,IO,DGA^6000030   I159 @T6G_MB_LIB.T6G(SCH_1):PAGE13
   J19  120 DQ13_B SCONN288_DDR506112002KQ-SCONN288_DDR506112002KQ,SMA   I350 @T6G_MB_LIB.T6G(SCH_1):PAGE88

M_D_CPU0_SB_DQ<14> @T6G_MB_LIB.T6G(SCH_1):M_D_CPU0_SB_DQ(14)
   U25 CN60 MDB_DATA14 GENOA_SP5-SOCKET6096_13568-001,SMLF,IO,DGA^6000030   I159 @T6G_MB_LIB.T6G(SCH_1):PAGE13
   J19  263 DQ14_B SCONN288_DDR506112002KQ-SCONN288_DDR506112002KQ,SMA   I350 @T6G_MB_LIB.T6G(SCH_1):PAGE88

M_D_CPU0_SB_DQ<15> @T6G_MB_LIB.T6G(SCH_1):M_D_CPU0_SB_DQ(15)
   U25 CP58 MDB_DATA15 GENOA_SP5-SOCKET6096_13568-001,SMLF,IO,DGA^6000030   I159 @T6G_MB_LIB.T6G(SCH_1):PAGE13
   J19  265 DQ15_B SCONN288_DDR506112002KQ-SCONN288_DDR506112002KQ,SMA   I350 @T6G_MB_LIB.T6G(SCH_1):PAGE88

M_D_CPU0_SB_DQ<16> @T6G_MB_LIB.T6G(SCH_1):M_D_CPU0_SB_DQ(16)
   U25 CP60 MDB_DATA16 GENOA_SP5-SOCKET6096_13568-001,SMLF,IO,DGA^6000030   I159 @T6G_MB_LIB.T6G(SCH_1):PAGE13
   J19  122 DQ16_B SCONN288_DDR506112002KQ-SCONN288_DDR506112002KQ,SMA   I350 @T6G_MB_LIB.T6G(SCH_1):PAGE88

M_D_CPU0_SB_DQ<17> @T6G_MB_LIB.T6G(SCH_1):M_D_CPU0_SB_DQ(17)
   U25 CR59 MDB_DATA17 GENOA_SP5-SOCKET6096_13568-001,SMLF,IO,DGA^6000030   I159 @T6G_MB_LIB.T6G(SCH_1):PAGE13
   J19  124 DQ17_B SCONN288_DDR506112002KQ-SCONN288_DDR506112002KQ,SMA   I350 @T6G_MB_LIB.T6G(SCH_1):PAGE88

M_D_CPU0_SB_DQ<18> @T6G_MB_LIB.T6G(SCH_1):M_D_CPU0_SB_DQ(18)
   U25 CR60 MDB_DATA18 GENOA_SP5-SOCKET6096_13568-001,SMLF,IO,DGA^6000030   I159 @T6G_MB_LIB.T6G(SCH_1):PAGE13
   J19  267 DQ18_B SCONN288_DDR506112002KQ-SCONN288_DDR506112002KQ,SMA   I350 @T6G_MB_LIB.T6G(SCH_1):PAGE88

M_D_CPU0_SB_DQ<19> @T6G_MB_LIB.T6G(SCH_1):M_D_CPU0_SB_DQ(19)
   U25 CT58 MDB_DATA19 GENOA_SP5-SOCKET6096_13568-001,SMLF,IO,DGA^6000030   I159 @T6G_MB_LIB.T6G(SCH_1):PAGE13
   J19  269 DQ19_B SCONN288_DDR506112002KQ-SCONN288_DDR506112002KQ,SMA   I350 @T6G_MB_LIB.T6G(SCH_1):PAGE88

M_D_CPU0_SB_DQ<1> @T6G_MB_LIB.T6G(SCH_1):M_D_CPU0_SB_DQ(1)
   U25 CC59 MDB_DATA1 GENOA_SP5-SOCKET6096_13568-001,SMLF,IO,DGA^6000030   I159 @T6G_MB_LIB.T6G(SCH_1):PAGE13
   J19  102  DQ1_B SCONN288_DDR506112002KQ-SCONN288_DDR506112002KQ,SMA   I350 @T6G_MB_LIB.T6G(SCH_1):PAGE88

M_D_CPU0_SB_DQ<20> @T6G_MB_LIB.T6G(SCH_1):M_D_CPU0_SB_DQ(20)
   U25 CV60 MDB_DATA20 GENOA_SP5-SOCKET6096_13568-001,SMLF,IO,DGA^6000030   I159 @T6G_MB_LIB.T6G(SCH_1):PAGE13
   J19  129 DQ20_B SCONN288_DDR506112002KQ-SCONN288_DDR506112002KQ,SMA   I350 @T6G_MB_LIB.T6G(SCH_1):PAGE88

M_D_CPU0_SB_DQ<21> @T6G_MB_LIB.T6G(SCH_1):M_D_CPU0_SB_DQ(21)
   U25 CW59 MDB_DATA21 GENOA_SP5-SOCKET6096_13568-001,SMLF,IO,DGA^6000030   I159 @T6G_MB_LIB.T6G(SCH_1):PAGE13
   J19  131 DQ21_B SCONN288_DDR506112002KQ-SCONN288_DDR506112002KQ,SMA   I350 @T6G_MB_LIB.T6G(SCH_1):PAGE88

M_D_CPU0_SB_DQ<22> @T6G_MB_LIB.T6G(SCH_1):M_D_CPU0_SB_DQ(22)
   U25 CW60 MDB_DATA22 GENOA_SP5-SOCKET6096_13568-001,SMLF,IO,DGA^6000030   I159 @T6G_MB_LIB.T6G(SCH_1):PAGE13
   J19  274 DQ22_B SCONN288_DDR506112002KQ-SCONN288_DDR506112002KQ,SMA   I350 @T6G_MB_LIB.T6G(SCH_1):PAGE88

M_D_CPU0_SB_DQ<23> @T6G_MB_LIB.T6G(SCH_1):M_D_CPU0_SB_DQ(23)
   U25 CY58 MDB_DATA23 GENOA_SP5-SOCKET6096_13568-001,SMLF,IO,DGA^6000030   I159 @T6G_MB_LIB.T6G(SCH_1):PAGE13
   J19  276 DQ23_B SCONN288_DDR506112002KQ-SCONN288_DDR506112002KQ,SMA   I350 @T6G_MB_LIB.T6G(SCH_1):PAGE88

M_D_CPU0_SB_DQ<24> @T6G_MB_LIB.T6G(SCH_1):M_D_CPU0_SB_DQ(24)
   U25 CY60 MDB_DATA24 GENOA_SP5-SOCKET6096_13568-001,SMLF,IO,DGA^6000030   I159 @T6G_MB_LIB.T6G(SCH_1):PAGE13
   J19  133 DQ24_B SCONN288_DDR506112002KQ-SCONN288_DDR506112002KQ,SMA   I350 @T6G_MB_LIB.T6G(SCH_1):PAGE88

M_D_CPU0_SB_DQ<25> @T6G_MB_LIB.T6G(SCH_1):M_D_CPU0_SB_DQ(25)
   U25 DA59 MDB_DATA25 GENOA_SP5-SOCKET6096_13568-001,SMLF,IO,DGA^6000030   I159 @T6G_MB_LIB.T6G(SCH_1):PAGE13
   J19  135 DQ25_B SCONN288_DDR506112002KQ-SCONN288_DDR506112002KQ,SMA   I350 @T6G_MB_LIB.T6G(SCH_1):PAGE88

M_D_CPU0_SB_DQ<26> @T6G_MB_LIB.T6G(SCH_1):M_D_CPU0_SB_DQ(26)
   U25 DA60 MDB_DATA26 GENOA_SP5-SOCKET6096_13568-001,SMLF,IO,DGA^6000030   I159 @T6G_MB_LIB.T6G(SCH_1):PAGE13
   J19  278 DQ26_B SCONN288_DDR506112002KQ-SCONN288_DDR506112002KQ,SMA   I350 @T6G_MB_LIB.T6G(SCH_1):PAGE88

M_D_CPU0_SB_DQ<27> @T6G_MB_LIB.T6G(SCH_1):M_D_CPU0_SB_DQ(27)
   U25 DB58 MDB_DATA27 GENOA_SP5-SOCKET6096_13568-001,SMLF,IO,DGA^6000030   I159 @T6G_MB_LIB.T6G(SCH_1):PAGE13
   J19  280 DQ27_B SCONN288_DDR506112002KQ-SCONN288_DDR506112002KQ,SMA   I350 @T6G_MB_LIB.T6G(SCH_1):PAGE88

M_D_CPU0_SB_DQ<28> @T6G_MB_LIB.T6G(SCH_1):M_D_CPU0_SB_DQ(28)
   U25 DD60 MDB_DATA28 GENOA_SP5-SOCKET6096_13568-001,SMLF,IO,DGA^6000030   I159 @T6G_MB_LIB.T6G(SCH_1):PAGE13
   J19  140 DQ28_B SCONN288_DDR506112002KQ-SCONN288_DDR506112002KQ,SMA   I350 @T6G_MB_LIB.T6G(SCH_1):PAGE88

M_D_CPU0_SB_DQ<29> @T6G_MB_LIB.T6G(SCH_1):M_D_CPU0_SB_DQ(29)
   U25 DE59 MDB_DATA29 GENOA_SP5-SOCKET6096_13568-001,SMLF,IO,DGA^6000030   I159 @T6G_MB_LIB.T6G(SCH_1):PAGE13
   J19  142 DQ29_B SCONN288_DDR506112002KQ-SCONN288_DDR506112002KQ,SMA   I350 @T6G_MB_LIB.T6G(SCH_1):PAGE88

M_D_CPU0_SB_DQ<2> @T6G_MB_LIB.T6G(SCH_1):M_D_CPU0_SB_DQ(2)
   U25 CC60 MDB_DATA2 GENOA_SP5-SOCKET6096_13568-001,SMLF,IO,DGA^6000030   I159 @T6G_MB_LIB.T6G(SCH_1):PAGE13
   J19  245  DQ2_B SCONN288_DDR506112002KQ-SCONN288_DDR506112002KQ,SMA   I350 @T6G_MB_LIB.T6G(SCH_1):PAGE88

M_D_CPU0_SB_DQ<30> @T6G_MB_LIB.T6G(SCH_1):M_D_CPU0_SB_DQ(30)
   U25 DE60 MDB_DATA30 GENOA_SP5-SOCKET6096_13568-001,SMLF,IO,DGA^6000030   I159 @T6G_MB_LIB.T6G(SCH_1):PAGE13
   J19  285 DQ30_B SCONN288_DDR506112002KQ-SCONN288_DDR506112002KQ,SMA   I350 @T6G_MB_LIB.T6G(SCH_1):PAGE88

M_D_CPU0_SB_DQ<31> @T6G_MB_LIB.T6G(SCH_1):M_D_CPU0_SB_DQ(31)
   U25 DF60 MDB_DATA31 GENOA_SP5-SOCKET6096_13568-001,SMLF,IO,DGA^6000030   I159 @T6G_MB_LIB.T6G(SCH_1):PAGE13
   J19  287 DQ31_B SCONN288_DDR506112002KQ-SCONN288_DDR506112002KQ,SMA   I350 @T6G_MB_LIB.T6G(SCH_1):PAGE88

M_D_CPU0_SB_DQ<3> @T6G_MB_LIB.T6G(SCH_1):M_D_CPU0_SB_DQ(3)
   U25 CD58 MDB_DATA3 GENOA_SP5-SOCKET6096_13568-001,SMLF,IO,DGA^6000030   I159 @T6G_MB_LIB.T6G(SCH_1):PAGE13
   J19  247  DQ3_B SCONN288_DDR506112002KQ-SCONN288_DDR506112002KQ,SMA   I350 @T6G_MB_LIB.T6G(SCH_1):PAGE88

M_D_CPU0_SB_DQ<4> @T6G_MB_LIB.T6G(SCH_1):M_D_CPU0_SB_DQ(4)
   U25 CF60 MDB_DATA4 GENOA_SP5-SOCKET6096_13568-001,SMLF,IO,DGA^6000030   I159 @T6G_MB_LIB.T6G(SCH_1):PAGE13
   J19  107  DQ4_B SCONN288_DDR506112002KQ-SCONN288_DDR506112002KQ,SMA   I350 @T6G_MB_LIB.T6G(SCH_1):PAGE88

M_D_CPU0_SB_DQ<5> @T6G_MB_LIB.T6G(SCH_1):M_D_CPU0_SB_DQ(5)
   U25 CG59 MDB_DATA5 GENOA_SP5-SOCKET6096_13568-001,SMLF,IO,DGA^6000030   I159 @T6G_MB_LIB.T6G(SCH_1):PAGE13
   J19  109  DQ5_B SCONN288_DDR506112002KQ-SCONN288_DDR506112002KQ,SMA   I350 @T6G_MB_LIB.T6G(SCH_1):PAGE88

M_D_CPU0_SB_DQ<6> @T6G_MB_LIB.T6G(SCH_1):M_D_CPU0_SB_DQ(6)
   U25 CG60 MDB_DATA6 GENOA_SP5-SOCKET6096_13568-001,SMLF,IO,DGA^6000030   I159 @T6G_MB_LIB.T6G(SCH_1):PAGE13
   J19  252  DQ6_B SCONN288_DDR506112002KQ-SCONN288_DDR506112002KQ,SMA   I350 @T6G_MB_LIB.T6G(SCH_1):PAGE88

M_D_CPU0_SB_DQ<7> @T6G_MB_LIB.T6G(SCH_1):M_D_CPU0_SB_DQ(7)
   U25 CH58 MDB_DATA7 GENOA_SP5-SOCKET6096_13568-001,SMLF,IO,DGA^6000030   I159 @T6G_MB_LIB.T6G(SCH_1):PAGE13
   J19  254  DQ7_B SCONN288_DDR506112002KQ-SCONN288_DDR506112002KQ,SMA   I350 @T6G_MB_LIB.T6G(SCH_1):PAGE88

M_D_CPU0_SB_DQ<8> @T6G_MB_LIB.T6G(SCH_1):M_D_CPU0_SB_DQ(8)
   U25 CH60 MDB_DATA8 GENOA_SP5-SOCKET6096_13568-001,SMLF,IO,DGA^6000030   I159 @T6G_MB_LIB.T6G(SCH_1):PAGE13
   J19  111  DQ8_B SCONN288_DDR506112002KQ-SCONN288_DDR506112002KQ,SMA   I350 @T6G_MB_LIB.T6G(SCH_1):PAGE88

M_D_CPU0_SB_DQ<9> @T6G_MB_LIB.T6G(SCH_1):M_D_CPU0_SB_DQ(9)
   U25 CJ59 MDB_DATA9 GENOA_SP5-SOCKET6096_13568-001,SMLF,IO,DGA^6000030   I159 @T6G_MB_LIB.T6G(SCH_1):PAGE13
   J19  113  DQ9_B SCONN288_DDR506112002KQ-SCONN288_DDR506112002KQ,SMA   I350 @T6G_MB_LIB.T6G(SCH_1):PAGE88

M_D_CPU0_SB_DQS_DN<0> @T6G_MB_LIB.T6G(SCH_1):M_D_CPU0_SB_DQS_DN(0)
   U25 CE60 MDB_DQS_L0 GENOA_SP5-SOCKET6096_13568-001,SMLF,IO,DGA^6000030   I159 @T6G_MB_LIB.T6G(SCH_1):PAGE13
   J19  105 DQS0_B_C SCONN288_DDR506112002KQ-SCONN288_DDR506112002KQ,SMA   I415 @T6G_MB_LIB.T6G(SCH_1):PAGE88

M_D_CPU0_SB_DQS_DN<1> @T6G_MB_LIB.T6G(SCH_1):M_D_CPU0_SB_DQS_DN(1)
   U25 CL60 MDB_DQS_L1 GENOA_SP5-SOCKET6096_13568-001,SMLF,IO,DGA^6000030   I159 @T6G_MB_LIB.T6G(SCH_1):PAGE13
   J19  116 DQS1_B_C SCONN288_DDR506112002KQ-SCONN288_DDR506112002KQ,SMA   I415 @T6G_MB_LIB.T6G(SCH_1):PAGE88

M_D_CPU0_SB_DQS_DN<2> @T6G_MB_LIB.T6G(SCH_1):M_D_CPU0_SB_DQS_DN(2)
   U25 CU60 MDB_DQS_L2 GENOA_SP5-SOCKET6096_13568-001,SMLF,IO,DGA^6000030   I159 @T6G_MB_LIB.T6G(SCH_1):PAGE13
   J19  127 DQS2_B_C SCONN288_DDR506112002KQ-SCONN288_DDR506112002KQ,SMA   I415 @T6G_MB_LIB.T6G(SCH_1):PAGE88

M_D_CPU0_SB_DQS_DN<3> @T6G_MB_LIB.T6G(SCH_1):M_D_CPU0_SB_DQS_DN(3)
   U25 DC60 MDB_DQS_L3 GENOA_SP5-SOCKET6096_13568-001,SMLF,IO,DGA^6000030   I159 @T6G_MB_LIB.T6G(SCH_1):PAGE13
   J19  138 DQS3_B_C SCONN288_DDR506112002KQ-SCONN288_DDR506112002KQ,SMA   I415 @T6G_MB_LIB.T6G(SCH_1):PAGE88

M_D_CPU0_SB_DQS_DN<4> @T6G_MB_LIB.T6G(SCH_1):M_D_CPU0_SB_DQS_DN(4)
   U25 BW59 MDB_DQS_L4 GENOA_SP5-SOCKET6096_13568-001,SMLF,IO,DGA^6000030   I159 @T6G_MB_LIB.T6G(SCH_1):PAGE13
   J19  238 DQS4_B_C SCONN288_DDR506112002KQ-SCONN288_DDR506112002KQ,SMA   I415 @T6G_MB_LIB.T6G(SCH_1):PAGE88

M_D_CPU0_SB_DQS_DN<5> @T6G_MB_LIB.T6G(SCH_1):M_D_CPU0_SB_DQS_DN(5)
   U25 CE59 MDB_DQS_L5 GENOA_SP5-SOCKET6096_13568-001,SMLF,IO,DGA^6000030   I159 @T6G_MB_LIB.T6G(SCH_1):PAGE13
   J19  249 DQS5_B_C||TDQS5_B_C SCONN288_DDR506112002KQ-SCONN288_DDR506112002KQ,SMA   I415 @T6G_MB_LIB.T6G(SCH_1):PAGE88

M_D_CPU0_SB_DQS_DN<6> @T6G_MB_LIB.T6G(SCH_1):M_D_CPU0_SB_DQS_DN(6)
   U25 CL59 MDB_DQS_L6 GENOA_SP5-SOCKET6096_13568-001,SMLF,IO,DGA^6000030   I159 @T6G_MB_LIB.T6G(SCH_1):PAGE13
   J19  260 DQS6_B_C||TDQS6_B_C SCONN288_DDR506112002KQ-SCONN288_DDR506112002KQ,SMA   I415 @T6G_MB_LIB.T6G(SCH_1):PAGE88

M_D_CPU0_SB_DQS_DN<7> @T6G_MB_LIB.T6G(SCH_1):M_D_CPU0_SB_DQS_DN(7)
   U25 CU59 MDB_DQS_L7 GENOA_SP5-SOCKET6096_13568-001,SMLF,IO,DGA^6000030   I159 @T6G_MB_LIB.T6G(SCH_1):PAGE13
   J19  271 DQS7_B_C||TDQS7_B_C SCONN288_DDR506112002KQ-SCONN288_DDR506112002KQ,SMA   I415 @T6G_MB_LIB.T6G(SCH_1):PAGE88

M_D_CPU0_SB_DQS_DN<8> @T6G_MB_LIB.T6G(SCH_1):M_D_CPU0_SB_DQS_DN(8)
   U25 DC59 MDB_DQS_L8 GENOA_SP5-SOCKET6096_13568-001,SMLF,IO,DGA^6000030   I159 @T6G_MB_LIB.T6G(SCH_1):PAGE13
   J19  282 DQS8_B_C||TDQS8_B_C SCONN288_DDR506112002KQ-SCONN288_DDR506112002KQ,SMA   I415 @T6G_MB_LIB.T6G(SCH_1):PAGE88

M_D_CPU0_SB_DQS_DN<9> @T6G_MB_LIB.T6G(SCH_1):M_D_CPU0_SB_DQS_DN(9)
   U25 BW60 MDB_DQS_L9 GENOA_SP5-SOCKET6096_13568-001,SMLF,IO,DGA^6000030   I159 @T6G_MB_LIB.T6G(SCH_1):PAGE13
   J19   94 DQS9_B_C||TDQS9_B_C SCONN288_DDR506112002KQ-SCONN288_DDR506112002KQ,SMA   I415 @T6G_MB_LIB.T6G(SCH_1):PAGE88

M_D_CPU0_SB_DQS_DP<0> @T6G_MB_LIB.T6G(SCH_1):M_D_CPU0_SB_DQS_DP(0)
   U25 CD60 MDB_DQS_H0 GENOA_SP5-SOCKET6096_13568-001,SMLF,IO,DGA^6000030   I159 @T6G_MB_LIB.T6G(SCH_1):PAGE13
   J19  104 DQS0_B_T SCONN288_DDR506112002KQ-SCONN288_DDR506112002KQ,SMA   I415 @T6G_MB_LIB.T6G(SCH_1):PAGE88

M_D_CPU0_SB_DQS_DP<1> @T6G_MB_LIB.T6G(SCH_1):M_D_CPU0_SB_DQS_DP(1)
   U25 CK60 MDB_DQS_H1 GENOA_SP5-SOCKET6096_13568-001,SMLF,IO,DGA^6000030   I159 @T6G_MB_LIB.T6G(SCH_1):PAGE13
   J19  115 DQS1_B_T SCONN288_DDR506112002KQ-SCONN288_DDR506112002KQ,SMA   I415 @T6G_MB_LIB.T6G(SCH_1):PAGE88

M_D_CPU0_SB_DQS_DP<2> @T6G_MB_LIB.T6G(SCH_1):M_D_CPU0_SB_DQS_DP(2)
   U25 CT60 MDB_DQS_H2 GENOA_SP5-SOCKET6096_13568-001,SMLF,IO,DGA^6000030   I159 @T6G_MB_LIB.T6G(SCH_1):PAGE13
   J19  126 DQS2_B_T SCONN288_DDR506112002KQ-SCONN288_DDR506112002KQ,SMA   I415 @T6G_MB_LIB.T6G(SCH_1):PAGE88

M_D_CPU0_SB_DQS_DP<3> @T6G_MB_LIB.T6G(SCH_1):M_D_CPU0_SB_DQS_DP(3)
   U25 DB60 MDB_DQS_H3 GENOA_SP5-SOCKET6096_13568-001,SMLF,IO,DGA^6000030   I159 @T6G_MB_LIB.T6G(SCH_1):PAGE13
   J19  137 DQS3_B_T SCONN288_DDR506112002KQ-SCONN288_DDR506112002KQ,SMA   I415 @T6G_MB_LIB.T6G(SCH_1):PAGE88

M_D_CPU0_SB_DQS_DP<4> @T6G_MB_LIB.T6G(SCH_1):M_D_CPU0_SB_DQS_DP(4)
   U25 BY58 MDB_DQS_H4 GENOA_SP5-SOCKET6096_13568-001,SMLF,IO,DGA^6000030   I159 @T6G_MB_LIB.T6G(SCH_1):PAGE13
   J19  239 DQS4_B_T SCONN288_DDR506112002KQ-SCONN288_DDR506112002KQ,SMA   I415 @T6G_MB_LIB.T6G(SCH_1):PAGE88

M_D_CPU0_SB_DQS_DP<5> @T6G_MB_LIB.T6G(SCH_1):M_D_CPU0_SB_DQS_DP(5)
   U25 CF58 MDB_DQS_H5 GENOA_SP5-SOCKET6096_13568-001,SMLF,IO,DGA^6000030   I159 @T6G_MB_LIB.T6G(SCH_1):PAGE13
   J19  250 DQS5_B_T||TDQS5_B_T SCONN288_DDR506112002KQ-SCONN288_DDR506112002KQ,SMA   I415 @T6G_MB_LIB.T6G(SCH_1):PAGE88

M_D_CPU0_SB_DQS_DP<6> @T6G_MB_LIB.T6G(SCH_1):M_D_CPU0_SB_DQS_DP(6)
   U25 CM58 MDB_DQS_H6 GENOA_SP5-SOCKET6096_13568-001,SMLF,IO,DGA^6000030   I159 @T6G_MB_LIB.T6G(SCH_1):PAGE13
   J19  261 DQS6_B_T||TDQS6_B_T SCONN288_DDR506112002KQ-SCONN288_DDR506112002KQ,SMA   I415 @T6G_MB_LIB.T6G(SCH_1):PAGE88

M_D_CPU0_SB_DQS_DP<7> @T6G_MB_LIB.T6G(SCH_1):M_D_CPU0_SB_DQS_DP(7)
   U25 CV58 MDB_DQS_H7 GENOA_SP5-SOCKET6096_13568-001,SMLF,IO,DGA^6000030   I159 @T6G_MB_LIB.T6G(SCH_1):PAGE13
   J19  272 DQS7_B_T||TDQS7_B_T SCONN288_DDR506112002KQ-SCONN288_DDR506112002KQ,SMA   I415 @T6G_MB_LIB.T6G(SCH_1):PAGE88

M_D_CPU0_SB_DQS_DP<8> @T6G_MB_LIB.T6G(SCH_1):M_D_CPU0_SB_DQS_DP(8)
   U25 DD58 MDB_DQS_H8 GENOA_SP5-SOCKET6096_13568-001,SMLF,IO,DGA^6000030   I159 @T6G_MB_LIB.T6G(SCH_1):PAGE13
   J19  283 DQS8_B_T||TDQS8_B_T SCONN288_DDR506112002KQ-SCONN288_DDR506112002KQ,SMA   I415 @T6G_MB_LIB.T6G(SCH_1):PAGE88

M_D_CPU0_SB_DQS_DP<9> @T6G_MB_LIB.T6G(SCH_1):M_D_CPU0_SB_DQS_DP(9)
   U25 BV60 MDB_DQS_H9 GENOA_SP5-SOCKET6096_13568-001,SMLF,IO,DGA^6000030   I159 @T6G_MB_LIB.T6G(SCH_1):PAGE13
   J19   93 DQS9_B_T||TDQS9_B_T||DBI4_B_N SCONN288_DDR506112002KQ-SCONN288_DDR506112002KQ,SMA   I415 @T6G_MB_LIB.T6G(SCH_1):PAGE88

M_D_CPU0_SB_PAR @T6G_MB_LIB.T6G(SCH_1):M_D_CPU0_SB_PAR
   U25 BL60 MDB_PAR GENOA_SP5-SOCKET6096_13568-001,SMLF,IO,DGA^6000030   I159 @T6G_MB_LIB.T6G(SCH_1):PAGE13
   J19  227  PAR_B SCONN288_DDR506112002KQ-SCONN288_DDR506112002KQ,SMA   I350 @T6G_MB_LIB.T6G(SCH_1):PAGE88

M_D_CPU0_SB_RSP<0> @T6G_MB_LIB.T6G(SCH_1):M_D_CPU0_SB_RSP(0)
   U25 BP60 MDB0_RSP_L GENOA_SP5-SOCKET6096_13568-001,SMLF,IO,DGA^6000030   I159 @T6G_MB_LIB.T6G(SCH_1):PAGE13
   J19   87 LBS||RSP_B_N SCONN288_DDR506112002KQ-SCONN288_DDR506112002KQ,SMA   I350 @T6G_MB_LIB.T6G(SCH_1):PAGE88

M_D_CPU1_ALERT_N @T6G_MB_LIB.T6G(SCH_1):M_D_CPU1_ALERT_N
  R503    1      A Q_RES_0402LF-15,1%,1/16W,CHIP,CS01502FB03   I314 @T6G_MB_LIB.T6G(SCH_1):PAGE40
   J30   62 ALERT_N SCONN288_DDR506112002KQ-SCONN288_DDR506112002KQ,SMA    I52 @T6G_MB_LIB.T6G(SCH_1):PAGE100

M_D_CPU1_ALERT_R_N @T6G_MB_LIB.T6G(SCH_1):M_D_CPU1_ALERT_R_N
   U26 AT58 MD_ALERT_L GENOA_SP5-SOCKET6096_13568-001,SMLF,IO,DGA^6000030   I159 @T6G_MB_LIB.T6G(SCH_1):PAGE40
  R503    2      B Q_RES_0402LF-15,1%,1/16W,CHIP,CS01502FB03   I314 @T6G_MB_LIB.T6G(SCH_1):PAGE40

M_D_CPU1_CLK_DN<0> @T6G_MB_LIB.T6G(SCH_1):M_D_CPU1_CLK_DN(0)
   U26 BD60 MD0_CLK_L GENOA_SP5-SOCKET6096_13568-001,SMLF,IO,DGA^6000030   I159 @T6G_MB_LIB.T6G(SCH_1):PAGE40
   J30  218   CK_C SCONN288_DDR506112002KQ-SCONN288_DDR506112002KQ,SMA    I52 @T6G_MB_LIB.T6G(SCH_1):PAGE100

M_D_CPU1_CLK_DP<0> @T6G_MB_LIB.T6G(SCH_1):M_D_CPU1_CLK_DP(0)
   U26 BC60 MD0_CLK_H GENOA_SP5-SOCKET6096_13568-001,SMLF,IO,DGA^6000030   I159 @T6G_MB_LIB.T6G(SCH_1):PAGE40
   J30  217   CK_T SCONN288_DDR506112002KQ-SCONN288_DDR506112002KQ,SMA    I52 @T6G_MB_LIB.T6G(SCH_1):PAGE100

M_D_CPU1_RESET_N @T6G_MB_LIB.T6G(SCH_1):M_D_CPU1_RESET_N
   U26 AU59 MD_RESET_L GENOA_SP5-SOCKET6096_13568-001,SMLF,IO,DGA^6000030   I159 @T6G_MB_LIB.T6G(SCH_1):PAGE40
   J30  207 RESET_N SCONN288_DDR506112002KQ-SCONN288_DDR506112002KQ,SMA    I52 @T6G_MB_LIB.T6G(SCH_1):PAGE100

M_D_CPU1_SA_CA<0> @T6G_MB_LIB.T6G(SCH_1):M_D_CPU1_SA_CA(0)
   U26 AW60 MDA_CA0 GENOA_SP5-SOCKET6096_13568-001,SMLF,IO,DGA^6000030   I159 @T6G_MB_LIB.T6G(SCH_1):PAGE40
   J30   66  CA0_A SCONN288_DDR506112002KQ-SCONN288_DDR506112002KQ,SMA    I52 @T6G_MB_LIB.T6G(SCH_1):PAGE100

M_D_CPU1_SA_CA<1> @T6G_MB_LIB.T6G(SCH_1):M_D_CPU1_SA_CA(1)
   U26 AY60 MDA_CA1 GENOA_SP5-SOCKET6096_13568-001,SMLF,IO,DGA^6000030   I159 @T6G_MB_LIB.T6G(SCH_1):PAGE40
   J30  211  CA1_A SCONN288_DDR506112002KQ-SCONN288_DDR506112002KQ,SMA    I52 @T6G_MB_LIB.T6G(SCH_1):PAGE100

M_D_CPU1_SA_CA<2> @T6G_MB_LIB.T6G(SCH_1):M_D_CPU1_SA_CA(2)
   U26 AY58 MDA_CA2 GENOA_SP5-SOCKET6096_13568-001,SMLF,IO,DGA^6000030   I159 @T6G_MB_LIB.T6G(SCH_1):PAGE40
   J30   68  CA2_A SCONN288_DDR506112002KQ-SCONN288_DDR506112002KQ,SMA    I52 @T6G_MB_LIB.T6G(SCH_1):PAGE100

M_D_CPU1_SA_CA<3> @T6G_MB_LIB.T6G(SCH_1):M_D_CPU1_SA_CA(3)
   U26 BA59 MDA_CA3 GENOA_SP5-SOCKET6096_13568-001,SMLF,IO,DGA^6000030   I159 @T6G_MB_LIB.T6G(SCH_1):PAGE40
   J30  213  CA3_A SCONN288_DDR506112002KQ-SCONN288_DDR506112002KQ,SMA    I52 @T6G_MB_LIB.T6G(SCH_1):PAGE100

M_D_CPU1_SA_CA<4> @T6G_MB_LIB.T6G(SCH_1):M_D_CPU1_SA_CA(4)
   U26 BA60 MDA_CA4 GENOA_SP5-SOCKET6096_13568-001,SMLF,IO,DGA^6000030   I159 @T6G_MB_LIB.T6G(SCH_1):PAGE40
   J30   70  CA4_A SCONN288_DDR506112002KQ-SCONN288_DDR506112002KQ,SMA    I52 @T6G_MB_LIB.T6G(SCH_1):PAGE100

M_D_CPU1_SA_CA<5> @T6G_MB_LIB.T6G(SCH_1):M_D_CPU1_SA_CA(5)
   U26 BB60 MDA_CA5 GENOA_SP5-SOCKET6096_13568-001,SMLF,IO,DGA^6000030   I159 @T6G_MB_LIB.T6G(SCH_1):PAGE40
   J30  215  CA5_A SCONN288_DDR506112002KQ-SCONN288_DDR506112002KQ,SMA    I52 @T6G_MB_LIB.T6G(SCH_1):PAGE100

M_D_CPU1_SA_CA<6> @T6G_MB_LIB.T6G(SCH_1):M_D_CPU1_SA_CA(6)
   U26 BB58 MDA_CA6 GENOA_SP5-SOCKET6096_13568-001,SMLF,IO,DGA^6000030   I159 @T6G_MB_LIB.T6G(SCH_1):PAGE40
   J30   72  CA6_A SCONN288_DDR506112002KQ-SCONN288_DDR506112002KQ,SMA    I52 @T6G_MB_LIB.T6G(SCH_1):PAGE100

M_D_CPU1_SA_CB<0> @T6G_MB_LIB.T6G(SCH_1):M_D_CPU1_SA_CB(0)
   U26 AJ60 MDA_CHECK0 GENOA_SP5-SOCKET6096_13568-001,SMLF,IO,DGA^6000030   I159 @T6G_MB_LIB.T6G(SCH_1):PAGE40
   J30   51  CB0_A SCONN288_DDR506112002KQ-SCONN288_DDR506112002KQ,SMA    I52 @T6G_MB_LIB.T6G(SCH_1):PAGE100

M_D_CPU1_SA_CB<1> @T6G_MB_LIB.T6G(SCH_1):M_D_CPU1_SA_CB(1)
   U26 AK58 MDA_CHECK1 GENOA_SP5-SOCKET6096_13568-001,SMLF,IO,DGA^6000030   I159 @T6G_MB_LIB.T6G(SCH_1):PAGE40
   J30   53  CB1_A SCONN288_DDR506112002KQ-SCONN288_DDR506112002KQ,SMA    I52 @T6G_MB_LIB.T6G(SCH_1):PAGE100

M_D_CPU1_SA_CB<2> @T6G_MB_LIB.T6G(SCH_1):M_D_CPU1_SA_CB(2)
   U26 AK60 MDA_CHECK2 GENOA_SP5-SOCKET6096_13568-001,SMLF,IO,DGA^6000030   I159 @T6G_MB_LIB.T6G(SCH_1):PAGE40
   J30  196  CB2_A SCONN288_DDR506112002KQ-SCONN288_DDR506112002KQ,SMA    I52 @T6G_MB_LIB.T6G(SCH_1):PAGE100

M_D_CPU1_SA_CB<3> @T6G_MB_LIB.T6G(SCH_1):M_D_CPU1_SA_CB(3)
   U26 AL59 MDA_CHECK3 GENOA_SP5-SOCKET6096_13568-001,SMLF,IO,DGA^6000030   I159 @T6G_MB_LIB.T6G(SCH_1):PAGE40
   J30  198  CB3_A SCONN288_DDR506112002KQ-SCONN288_DDR506112002KQ,SMA    I52 @T6G_MB_LIB.T6G(SCH_1):PAGE100

M_D_CPU1_SA_CB<4> @T6G_MB_LIB.T6G(SCH_1):M_D_CPU1_SA_CB(4)
   U26 AN60 MDA_CHECK4 GENOA_SP5-SOCKET6096_13568-001,SMLF,IO,DGA^6000030   I159 @T6G_MB_LIB.T6G(SCH_1):PAGE40
   J30   58  CB4_A SCONN288_DDR506112002KQ-SCONN288_DDR506112002KQ,SMA    I52 @T6G_MB_LIB.T6G(SCH_1):PAGE100

M_D_CPU1_SA_CB<5> @T6G_MB_LIB.T6G(SCH_1):M_D_CPU1_SA_CB(5)
   U26 AP58 MDA_CHECK5 GENOA_SP5-SOCKET6096_13568-001,SMLF,IO,DGA^6000030   I159 @T6G_MB_LIB.T6G(SCH_1):PAGE40
   J30   60  CB5_A SCONN288_DDR506112002KQ-SCONN288_DDR506112002KQ,SMA    I52 @T6G_MB_LIB.T6G(SCH_1):PAGE100

M_D_CPU1_SA_CB<6> @T6G_MB_LIB.T6G(SCH_1):M_D_CPU1_SA_CB(6)
   U26 AP60 MDA_CHECK6 GENOA_SP5-SOCKET6096_13568-001,SMLF,IO,DGA^6000030   I159 @T6G_MB_LIB.T6G(SCH_1):PAGE40
   J30  203  CB6_A SCONN288_DDR506112002KQ-SCONN288_DDR506112002KQ,SMA    I52 @T6G_MB_LIB.T6G(SCH_1):PAGE100

M_D_CPU1_SA_CB<7> @T6G_MB_LIB.T6G(SCH_1):M_D_CPU1_SA_CB(7)
   U26 AR59 MDA_CHECK7 GENOA_SP5-SOCKET6096_13568-001,SMLF,IO,DGA^6000030   I159 @T6G_MB_LIB.T6G(SCH_1):PAGE40
   J30  205  CB7_A SCONN288_DDR506112002KQ-SCONN288_DDR506112002KQ,SMA    I52 @T6G_MB_LIB.T6G(SCH_1):PAGE100

M_D_CPU1_SA_CS_N<0> @T6G_MB_LIB.T6G(SCH_1):M_D_CPU1_SA_CS_N(0)
   U26 AV60 MDA0_CS_L0 GENOA_SP5-SOCKET6096_13568-001,SMLF,IO,DGA^6000030   I159 @T6G_MB_LIB.T6G(SCH_1):PAGE40
   J30   64 CS0_A_N SCONN288_DDR506112002KQ-SCONN288_DDR506112002KQ,SMA    I52 @T6G_MB_LIB.T6G(SCH_1):PAGE100

M_D_CPU1_SA_CS_N<1> @T6G_MB_LIB.T6G(SCH_1):M_D_CPU1_SA_CS_N(1)
   U26 AW59 MDA0_CS_L1 GENOA_SP5-SOCKET6096_13568-001,SMLF,IO,DGA^6000030   I159 @T6G_MB_LIB.T6G(SCH_1):PAGE40
   J30  209 CS1_A_N SCONN288_DDR506112002KQ-SCONN288_DDR506112002KQ,SMA    I52 @T6G_MB_LIB.T6G(SCH_1):PAGE100

M_D_CPU1_SA_DQ<0> @T6G_MB_LIB.T6G(SCH_1):M_D_CPU1_SA_DQ(0)
   U26  E60 MDA_DATA0 GENOA_SP5-SOCKET6096_13568-001,SMLF,IO,DGA^6000030   I159 @T6G_MB_LIB.T6G(SCH_1):PAGE40
   J30    7  DQ0_A SCONN288_DDR506112002KQ-SCONN288_DDR506112002KQ,SMA    I52 @T6G_MB_LIB.T6G(SCH_1):PAGE100

M_D_CPU1_SA_DQ<10> @T6G_MB_LIB.T6G(SCH_1):M_D_CPU1_SA_DQ(10)
   U26  M60 MDA_DATA10 GENOA_SP5-SOCKET6096_13568-001,SMLF,IO,DGA^6000030   I159 @T6G_MB_LIB.T6G(SCH_1):PAGE40
   J30  163 DQ10_A SCONN288_DDR506112002KQ-SCONN288_DDR506112002KQ,SMA    I52 @T6G_MB_LIB.T6G(SCH_1):PAGE100

M_D_CPU1_SA_DQ<11> @T6G_MB_LIB.T6G(SCH_1):M_D_CPU1_SA_DQ(11)
   U26  N59 MDA_DATA11 GENOA_SP5-SOCKET6096_13568-001,SMLF,IO,DGA^6000030   I159 @T6G_MB_LIB.T6G(SCH_1):PAGE40
   J30  165 DQ11_A SCONN288_DDR506112002KQ-SCONN288_DDR506112002KQ,SMA    I52 @T6G_MB_LIB.T6G(SCH_1):PAGE100

M_D_CPU1_SA_DQ<12> @T6G_MB_LIB.T6G(SCH_1):M_D_CPU1_SA_DQ(12)
   U26  R60 MDA_DATA12 GENOA_SP5-SOCKET6096_13568-001,SMLF,IO,DGA^6000030   I159 @T6G_MB_LIB.T6G(SCH_1):PAGE40
   J30   25 DQ12_A SCONN288_DDR506112002KQ-SCONN288_DDR506112002KQ,SMA    I52 @T6G_MB_LIB.T6G(SCH_1):PAGE100

M_D_CPU1_SA_DQ<13> @T6G_MB_LIB.T6G(SCH_1):M_D_CPU1_SA_DQ(13)
   U26  T58 MDA_DATA13 GENOA_SP5-SOCKET6096_13568-001,SMLF,IO,DGA^6000030   I159 @T6G_MB_LIB.T6G(SCH_1):PAGE40
   J30   27 DQ13_A SCONN288_DDR506112002KQ-SCONN288_DDR506112002KQ,SMA    I52 @T6G_MB_LIB.T6G(SCH_1):PAGE100

M_D_CPU1_SA_DQ<14> @T6G_MB_LIB.T6G(SCH_1):M_D_CPU1_SA_DQ(14)
   U26  T60 MDA_DATA14 GENOA_SP5-SOCKET6096_13568-001,SMLF,IO,DGA^6000030   I159 @T6G_MB_LIB.T6G(SCH_1):PAGE40
   J30  170 DQ14_A SCONN288_DDR506112002KQ-SCONN288_DDR506112002KQ,SMA    I52 @T6G_MB_LIB.T6G(SCH_1):PAGE100

M_D_CPU1_SA_DQ<15> @T6G_MB_LIB.T6G(SCH_1):M_D_CPU1_SA_DQ(15)
   U26  U59 MDA_DATA15 GENOA_SP5-SOCKET6096_13568-001,SMLF,IO,DGA^6000030   I159 @T6G_MB_LIB.T6G(SCH_1):PAGE40
   J30  172 DQ15_A SCONN288_DDR506112002KQ-SCONN288_DDR506112002KQ,SMA    I52 @T6G_MB_LIB.T6G(SCH_1):PAGE100

M_D_CPU1_SA_DQ<16> @T6G_MB_LIB.T6G(SCH_1):M_D_CPU1_SA_DQ(16)
   U26  U60 MDA_DATA16 GENOA_SP5-SOCKET6096_13568-001,SMLF,IO,DGA^6000030   I159 @T6G_MB_LIB.T6G(SCH_1):PAGE40
   J30   29 DQ16_A SCONN288_DDR506112002KQ-SCONN288_DDR506112002KQ,SMA    I52 @T6G_MB_LIB.T6G(SCH_1):PAGE100

M_D_CPU1_SA_DQ<17> @T6G_MB_LIB.T6G(SCH_1):M_D_CPU1_SA_DQ(17)
   U26  V58 MDA_DATA17 GENOA_SP5-SOCKET6096_13568-001,SMLF,IO,DGA^6000030   I159 @T6G_MB_LIB.T6G(SCH_1):PAGE40
   J30   31 DQ17_A SCONN288_DDR506112002KQ-SCONN288_DDR506112002KQ,SMA    I52 @T6G_MB_LIB.T6G(SCH_1):PAGE100

M_D_CPU1_SA_DQ<18> @T6G_MB_LIB.T6G(SCH_1):M_D_CPU1_SA_DQ(18)
   U26  V60 MDA_DATA18 GENOA_SP5-SOCKET6096_13568-001,SMLF,IO,DGA^6000030   I159 @T6G_MB_LIB.T6G(SCH_1):PAGE40
   J30  174 DQ18_A SCONN288_DDR506112002KQ-SCONN288_DDR506112002KQ,SMA    I52 @T6G_MB_LIB.T6G(SCH_1):PAGE100

M_D_CPU1_SA_DQ<19> @T6G_MB_LIB.T6G(SCH_1):M_D_CPU1_SA_DQ(19)
   U26  W59 MDA_DATA19 GENOA_SP5-SOCKET6096_13568-001,SMLF,IO,DGA^6000030   I159 @T6G_MB_LIB.T6G(SCH_1):PAGE40
   J30  176 DQ19_A SCONN288_DDR506112002KQ-SCONN288_DDR506112002KQ,SMA    I52 @T6G_MB_LIB.T6G(SCH_1):PAGE100

M_D_CPU1_SA_DQ<1> @T6G_MB_LIB.T6G(SCH_1):M_D_CPU1_SA_DQ(1)
   U26  F58 MDA_DATA1 GENOA_SP5-SOCKET6096_13568-001,SMLF,IO,DGA^6000030   I159 @T6G_MB_LIB.T6G(SCH_1):PAGE40
   J30    9  DQ1_A SCONN288_DDR506112002KQ-SCONN288_DDR506112002KQ,SMA    I52 @T6G_MB_LIB.T6G(SCH_1):PAGE100

M_D_CPU1_SA_DQ<20> @T6G_MB_LIB.T6G(SCH_1):M_D_CPU1_SA_DQ(20)
   U26 AA60 MDA_DATA20 GENOA_SP5-SOCKET6096_13568-001,SMLF,IO,DGA^6000030   I159 @T6G_MB_LIB.T6G(SCH_1):PAGE40
   J30   36 DQ20_A SCONN288_DDR506112002KQ-SCONN288_DDR506112002KQ,SMA    I52 @T6G_MB_LIB.T6G(SCH_1):PAGE100

M_D_CPU1_SA_DQ<21> @T6G_MB_LIB.T6G(SCH_1):M_D_CPU1_SA_DQ(21)
   U26 AB58 MDA_DATA21 GENOA_SP5-SOCKET6096_13568-001,SMLF,IO,DGA^6000030   I159 @T6G_MB_LIB.T6G(SCH_1):PAGE40
   J30   38 DQ21_A SCONN288_DDR506112002KQ-SCONN288_DDR506112002KQ,SMA    I52 @T6G_MB_LIB.T6G(SCH_1):PAGE100

M_D_CPU1_SA_DQ<22> @T6G_MB_LIB.T6G(SCH_1):M_D_CPU1_SA_DQ(22)
   U26 AB60 MDA_DATA22 GENOA_SP5-SOCKET6096_13568-001,SMLF,IO,DGA^6000030   I159 @T6G_MB_LIB.T6G(SCH_1):PAGE40
   J30  181 DQ22_A SCONN288_DDR506112002KQ-SCONN288_DDR506112002KQ,SMA    I52 @T6G_MB_LIB.T6G(SCH_1):PAGE100

M_D_CPU1_SA_DQ<23> @T6G_MB_LIB.T6G(SCH_1):M_D_CPU1_SA_DQ(23)
   U26 AC59 MDA_DATA23 GENOA_SP5-SOCKET6096_13568-001,SMLF,IO,DGA^6000030   I159 @T6G_MB_LIB.T6G(SCH_1):PAGE40
   J30  183 DQ23_A SCONN288_DDR506112002KQ-SCONN288_DDR506112002KQ,SMA    I52 @T6G_MB_LIB.T6G(SCH_1):PAGE100

M_D_CPU1_SA_DQ<24> @T6G_MB_LIB.T6G(SCH_1):M_D_CPU1_SA_DQ(24)
   U26 AC60 MDA_DATA24 GENOA_SP5-SOCKET6096_13568-001,SMLF,IO,DGA^6000030   I159 @T6G_MB_LIB.T6G(SCH_1):PAGE40
   J30   40 DQ24_A SCONN288_DDR506112002KQ-SCONN288_DDR506112002KQ,SMA    I52 @T6G_MB_LIB.T6G(SCH_1):PAGE100

M_D_CPU1_SA_DQ<25> @T6G_MB_LIB.T6G(SCH_1):M_D_CPU1_SA_DQ(25)
   U26 AD58 MDA_DATA25 GENOA_SP5-SOCKET6096_13568-001,SMLF,IO,DGA^6000030   I159 @T6G_MB_LIB.T6G(SCH_1):PAGE40
   J30   42 DQ25_A SCONN288_DDR506112002KQ-SCONN288_DDR506112002KQ,SMA    I52 @T6G_MB_LIB.T6G(SCH_1):PAGE100

M_D_CPU1_SA_DQ<26> @T6G_MB_LIB.T6G(SCH_1):M_D_CPU1_SA_DQ(26)
   U26 AD60 MDA_DATA26 GENOA_SP5-SOCKET6096_13568-001,SMLF,IO,DGA^6000030   I159 @T6G_MB_LIB.T6G(SCH_1):PAGE40
   J30  185 DQ26_A SCONN288_DDR506112002KQ-SCONN288_DDR506112002KQ,SMA    I52 @T6G_MB_LIB.T6G(SCH_1):PAGE100

M_D_CPU1_SA_DQ<27> @T6G_MB_LIB.T6G(SCH_1):M_D_CPU1_SA_DQ(27)
   U26 AE59 MDA_DATA27 GENOA_SP5-SOCKET6096_13568-001,SMLF,IO,DGA^6000030   I159 @T6G_MB_LIB.T6G(SCH_1):PAGE40
   J30  187 DQ27_A SCONN288_DDR506112002KQ-SCONN288_DDR506112002KQ,SMA    I52 @T6G_MB_LIB.T6G(SCH_1):PAGE100

M_D_CPU1_SA_DQ<28> @T6G_MB_LIB.T6G(SCH_1):M_D_CPU1_SA_DQ(28)
   U26 AG60 MDA_DATA28 GENOA_SP5-SOCKET6096_13568-001,SMLF,IO,DGA^6000030   I159 @T6G_MB_LIB.T6G(SCH_1):PAGE40
   J30   47 DQ28_A SCONN288_DDR506112002KQ-SCONN288_DDR506112002KQ,SMA    I52 @T6G_MB_LIB.T6G(SCH_1):PAGE100

M_D_CPU1_SA_DQ<29> @T6G_MB_LIB.T6G(SCH_1):M_D_CPU1_SA_DQ(29)
   U26 AH58 MDA_DATA29 GENOA_SP5-SOCKET6096_13568-001,SMLF,IO,DGA^6000030   I159 @T6G_MB_LIB.T6G(SCH_1):PAGE40
   J30   49 DQ29_A SCONN288_DDR506112002KQ-SCONN288_DDR506112002KQ,SMA    I52 @T6G_MB_LIB.T6G(SCH_1):PAGE100

M_D_CPU1_SA_DQ<2> @T6G_MB_LIB.T6G(SCH_1):M_D_CPU1_SA_DQ(2)
   U26  F60 MDA_DATA2 GENOA_SP5-SOCKET6096_13568-001,SMLF,IO,DGA^6000030   I159 @T6G_MB_LIB.T6G(SCH_1):PAGE40
   J30  152  DQ2_A SCONN288_DDR506112002KQ-SCONN288_DDR506112002KQ,SMA    I52 @T6G_MB_LIB.T6G(SCH_1):PAGE100

M_D_CPU1_SA_DQ<30> @T6G_MB_LIB.T6G(SCH_1):M_D_CPU1_SA_DQ(30)
   U26 AH60 MDA_DATA30 GENOA_SP5-SOCKET6096_13568-001,SMLF,IO,DGA^6000030   I159 @T6G_MB_LIB.T6G(SCH_1):PAGE40
   J30  192 DQ30_A SCONN288_DDR506112002KQ-SCONN288_DDR506112002KQ,SMA    I52 @T6G_MB_LIB.T6G(SCH_1):PAGE100

M_D_CPU1_SA_DQ<31> @T6G_MB_LIB.T6G(SCH_1):M_D_CPU1_SA_DQ(31)
   U26 AJ59 MDA_DATA31 GENOA_SP5-SOCKET6096_13568-001,SMLF,IO,DGA^6000030   I159 @T6G_MB_LIB.T6G(SCH_1):PAGE40
   J30  194 DQ31_A SCONN288_DDR506112002KQ-SCONN288_DDR506112002KQ,SMA    I52 @T6G_MB_LIB.T6G(SCH_1):PAGE100

M_D_CPU1_SA_DQ<3> @T6G_MB_LIB.T6G(SCH_1):M_D_CPU1_SA_DQ(3)
   U26  G59 MDA_DATA3 GENOA_SP5-SOCKET6096_13568-001,SMLF,IO,DGA^6000030   I159 @T6G_MB_LIB.T6G(SCH_1):PAGE40
   J30  154  DQ3_A SCONN288_DDR506112002KQ-SCONN288_DDR506112002KQ,SMA    I52 @T6G_MB_LIB.T6G(SCH_1):PAGE100

M_D_CPU1_SA_DQ<4> @T6G_MB_LIB.T6G(SCH_1):M_D_CPU1_SA_DQ(4)
   U26  J60 MDA_DATA4 GENOA_SP5-SOCKET6096_13568-001,SMLF,IO,DGA^6000030   I159 @T6G_MB_LIB.T6G(SCH_1):PAGE40
   J30   14  DQ4_A SCONN288_DDR506112002KQ-SCONN288_DDR506112002KQ,SMA    I52 @T6G_MB_LIB.T6G(SCH_1):PAGE100

M_D_CPU1_SA_DQ<5> @T6G_MB_LIB.T6G(SCH_1):M_D_CPU1_SA_DQ(5)
   U26  K58 MDA_DATA5 GENOA_SP5-SOCKET6096_13568-001,SMLF,IO,DGA^6000030   I159 @T6G_MB_LIB.T6G(SCH_1):PAGE40
   J30   16  DQ5_A SCONN288_DDR506112002KQ-SCONN288_DDR506112002KQ,SMA    I52 @T6G_MB_LIB.T6G(SCH_1):PAGE100

M_D_CPU1_SA_DQ<6> @T6G_MB_LIB.T6G(SCH_1):M_D_CPU1_SA_DQ(6)
   U26  K60 MDA_DATA6 GENOA_SP5-SOCKET6096_13568-001,SMLF,IO,DGA^6000030   I159 @T6G_MB_LIB.T6G(SCH_1):PAGE40
   J30  159  DQ6_A SCONN288_DDR506112002KQ-SCONN288_DDR506112002KQ,SMA    I52 @T6G_MB_LIB.T6G(SCH_1):PAGE100

M_D_CPU1_SA_DQ<7> @T6G_MB_LIB.T6G(SCH_1):M_D_CPU1_SA_DQ(7)
   U26  L59 MDA_DATA7 GENOA_SP5-SOCKET6096_13568-001,SMLF,IO,DGA^6000030   I159 @T6G_MB_LIB.T6G(SCH_1):PAGE40
   J30  161  DQ7_A SCONN288_DDR506112002KQ-SCONN288_DDR506112002KQ,SMA    I52 @T6G_MB_LIB.T6G(SCH_1):PAGE100

M_D_CPU1_SA_DQ<8> @T6G_MB_LIB.T6G(SCH_1):M_D_CPU1_SA_DQ(8)
   U26  L60 MDA_DATA8 GENOA_SP5-SOCKET6096_13568-001,SMLF,IO,DGA^6000030   I159 @T6G_MB_LIB.T6G(SCH_1):PAGE40
   J30   18  DQ8_A SCONN288_DDR506112002KQ-SCONN288_DDR506112002KQ,SMA    I52 @T6G_MB_LIB.T6G(SCH_1):PAGE100

M_D_CPU1_SA_DQ<9> @T6G_MB_LIB.T6G(SCH_1):M_D_CPU1_SA_DQ(9)
   U26  M58 MDA_DATA9 GENOA_SP5-SOCKET6096_13568-001,SMLF,IO,DGA^6000030   I159 @T6G_MB_LIB.T6G(SCH_1):PAGE40
   J30   20  DQ9_A SCONN288_DDR506112002KQ-SCONN288_DDR506112002KQ,SMA    I52 @T6G_MB_LIB.T6G(SCH_1):PAGE100

M_D_CPU1_SA_DQS_DN<0> @T6G_MB_LIB.T6G(SCH_1):M_D_CPU1_SA_DQS_DN(0)
   U26  H60 MDA_DQS_L0 GENOA_SP5-SOCKET6096_13568-001,SMLF,IO,DGA^6000030   I159 @T6G_MB_LIB.T6G(SCH_1):PAGE40
   J30   12 DQS0_A_C SCONN288_DDR506112002KQ-SCONN288_DDR506112002KQ,SMA   I236 @T6G_MB_LIB.T6G(SCH_1):PAGE100

M_D_CPU1_SA_DQS_DN<1> @T6G_MB_LIB.T6G(SCH_1):M_D_CPU1_SA_DQS_DN(1)
   U26  P60 MDA_DQS_L1 GENOA_SP5-SOCKET6096_13568-001,SMLF,IO,DGA^6000030   I159 @T6G_MB_LIB.T6G(SCH_1):PAGE40
   J30   23 DQS1_A_C SCONN288_DDR506112002KQ-SCONN288_DDR506112002KQ,SMA   I236 @T6G_MB_LIB.T6G(SCH_1):PAGE100

M_D_CPU1_SA_DQS_DN<2> @T6G_MB_LIB.T6G(SCH_1):M_D_CPU1_SA_DQS_DN(2)
   U26  Y60 MDA_DQS_L2 GENOA_SP5-SOCKET6096_13568-001,SMLF,IO,DGA^6000030   I159 @T6G_MB_LIB.T6G(SCH_1):PAGE40
   J30   34 DQS2_A_C SCONN288_DDR506112002KQ-SCONN288_DDR506112002KQ,SMA   I236 @T6G_MB_LIB.T6G(SCH_1):PAGE100

M_D_CPU1_SA_DQS_DN<3> @T6G_MB_LIB.T6G(SCH_1):M_D_CPU1_SA_DQS_DN(3)
   U26 AF60 MDA_DQS_L3 GENOA_SP5-SOCKET6096_13568-001,SMLF,IO,DGA^6000030   I159 @T6G_MB_LIB.T6G(SCH_1):PAGE40
   J30   45 DQS3_A_C SCONN288_DDR506112002KQ-SCONN288_DDR506112002KQ,SMA   I236 @T6G_MB_LIB.T6G(SCH_1):PAGE100

M_D_CPU1_SA_DQS_DN<4> @T6G_MB_LIB.T6G(SCH_1):M_D_CPU1_SA_DQS_DN(4)
   U26 AM60 MDA_DQS_L4 GENOA_SP5-SOCKET6096_13568-001,SMLF,IO,DGA^6000030   I159 @T6G_MB_LIB.T6G(SCH_1):PAGE40
   J30   56 DQS4_A_C SCONN288_DDR506112002KQ-SCONN288_DDR506112002KQ,SMA   I236 @T6G_MB_LIB.T6G(SCH_1):PAGE100

M_D_CPU1_SA_DQS_DN<5> @T6G_MB_LIB.T6G(SCH_1):M_D_CPU1_SA_DQS_DN(5)
   U26  H58 MDA_DQS_L5 GENOA_SP5-SOCKET6096_13568-001,SMLF,IO,DGA^6000030   I159 @T6G_MB_LIB.T6G(SCH_1):PAGE40
   J30  156 DQS5_A_C||TDQS5_A_C||DQS5_A_T||TDQS5_A_T SCONN288_DDR506112002KQ-SCONN288_DDR506112002KQ,SMA   I236 @T6G_MB_LIB.T6G(SCH_1):PAGE100

M_D_CPU1_SA_DQS_DN<6> @T6G_MB_LIB.T6G(SCH_1):M_D_CPU1_SA_DQS_DN(6)
   U26  P58 MDA_DQS_L6 GENOA_SP5-SOCKET6096_13568-001,SMLF,IO,DGA^6000030   I159 @T6G_MB_LIB.T6G(SCH_1):PAGE40
   J30  167 DQS6_A_C||TDQS6_A_C||DQS6_A_T||TDQS6_A_T SCONN288_DDR506112002KQ-SCONN288_DDR506112002KQ,SMA   I236 @T6G_MB_LIB.T6G(SCH_1):PAGE100

M_D_CPU1_SA_DQS_DN<7> @T6G_MB_LIB.T6G(SCH_1):M_D_CPU1_SA_DQS_DN(7)
   U26  Y58 MDA_DQS_L7 GENOA_SP5-SOCKET6096_13568-001,SMLF,IO,DGA^6000030   I159 @T6G_MB_LIB.T6G(SCH_1):PAGE40
   J30  178 DQS7_A_C||TDQS7_A_C SCONN288_DDR506112002KQ-SCONN288_DDR506112002KQ,SMA   I236 @T6G_MB_LIB.T6G(SCH_1):PAGE100

M_D_CPU1_SA_DQS_DN<8> @T6G_MB_LIB.T6G(SCH_1):M_D_CPU1_SA_DQS_DN(8)
   U26 AF58 MDA_DQS_L8 GENOA_SP5-SOCKET6096_13568-001,SMLF,IO,DGA^6000030   I159 @T6G_MB_LIB.T6G(SCH_1):PAGE40
   J30  189 DQS8_A_C||TDQS8_A_C SCONN288_DDR506112002KQ-SCONN288_DDR506112002KQ,SMA   I236 @T6G_MB_LIB.T6G(SCH_1):PAGE100

M_D_CPU1_SA_DQS_DN<9> @T6G_MB_LIB.T6G(SCH_1):M_D_CPU1_SA_DQS_DN(9)
   U26 AM58 MDA_DQS_L9 GENOA_SP5-SOCKET6096_13568-001,SMLF,IO,DGA^6000030   I159 @T6G_MB_LIB.T6G(SCH_1):PAGE40
   J30  200 DQS9_A_C||TDQS9_A_C SCONN288_DDR506112002KQ-SCONN288_DDR506112002KQ,SMA   I236 @T6G_MB_LIB.T6G(SCH_1):PAGE100

M_D_CPU1_SA_DQS_DP<0> @T6G_MB_LIB.T6G(SCH_1):M_D_CPU1_SA_DQS_DP(0)
   U26  G60 MDA_DQS_H0 GENOA_SP5-SOCKET6096_13568-001,SMLF,IO,DGA^6000030   I159 @T6G_MB_LIB.T6G(SCH_1):PAGE40
   J30   11 DQS0_A_T SCONN288_DDR506112002KQ-SCONN288_DDR506112002KQ,SMA   I236 @T6G_MB_LIB.T6G(SCH_1):PAGE100

M_D_CPU1_SA_DQS_DP<1> @T6G_MB_LIB.T6G(SCH_1):M_D_CPU1_SA_DQS_DP(1)
   U26  N60 MDA_DQS_H1 GENOA_SP5-SOCKET6096_13568-001,SMLF,IO,DGA^6000030   I159 @T6G_MB_LIB.T6G(SCH_1):PAGE40
   J30   22 DQS1_A_T SCONN288_DDR506112002KQ-SCONN288_DDR506112002KQ,SMA   I236 @T6G_MB_LIB.T6G(SCH_1):PAGE100

M_D_CPU1_SA_DQS_DP<2> @T6G_MB_LIB.T6G(SCH_1):M_D_CPU1_SA_DQS_DP(2)
   U26  W60 MDA_DQS_H2 GENOA_SP5-SOCKET6096_13568-001,SMLF,IO,DGA^6000030   I159 @T6G_MB_LIB.T6G(SCH_1):PAGE40
   J30   33 DQS2_A_T SCONN288_DDR506112002KQ-SCONN288_DDR506112002KQ,SMA   I236 @T6G_MB_LIB.T6G(SCH_1):PAGE100

M_D_CPU1_SA_DQS_DP<3> @T6G_MB_LIB.T6G(SCH_1):M_D_CPU1_SA_DQS_DP(3)
   U26 AE60 MDA_DQS_H3 GENOA_SP5-SOCKET6096_13568-001,SMLF,IO,DGA^6000030   I159 @T6G_MB_LIB.T6G(SCH_1):PAGE40
   J30   44 DQS3_A_T SCONN288_DDR506112002KQ-SCONN288_DDR506112002KQ,SMA   I236 @T6G_MB_LIB.T6G(SCH_1):PAGE100

M_D_CPU1_SA_DQS_DP<4> @T6G_MB_LIB.T6G(SCH_1):M_D_CPU1_SA_DQS_DP(4)
   U26 AL60 MDA_DQS_H4 GENOA_SP5-SOCKET6096_13568-001,SMLF,IO,DGA^6000030   I159 @T6G_MB_LIB.T6G(SCH_1):PAGE40
   J30   55 DQS4_A_T SCONN288_DDR506112002KQ-SCONN288_DDR506112002KQ,SMA   I236 @T6G_MB_LIB.T6G(SCH_1):PAGE100

M_D_CPU1_SA_DQS_DP<5> @T6G_MB_LIB.T6G(SCH_1):M_D_CPU1_SA_DQS_DP(5)
   U26  J59 MDA_DQS_H5 GENOA_SP5-SOCKET6096_13568-001,SMLF,IO,DGA^6000030   I159 @T6G_MB_LIB.T6G(SCH_1):PAGE40
   J30  157 DQS5_A_T||TDQS5_A_T SCONN288_DDR506112002KQ-SCONN288_DDR506112002KQ,SMA   I236 @T6G_MB_LIB.T6G(SCH_1):PAGE100

M_D_CPU1_SA_DQS_DP<6> @T6G_MB_LIB.T6G(SCH_1):M_D_CPU1_SA_DQS_DP(6)
   U26  R59 MDA_DQS_H6 GENOA_SP5-SOCKET6096_13568-001,SMLF,IO,DGA^6000030   I159 @T6G_MB_LIB.T6G(SCH_1):PAGE40
   J30  168 DQS6_A_T||TDQS6_A_T SCONN288_DDR506112002KQ-SCONN288_DDR506112002KQ,SMA   I236 @T6G_MB_LIB.T6G(SCH_1):PAGE100

M_D_CPU1_SA_DQS_DP<7> @T6G_MB_LIB.T6G(SCH_1):M_D_CPU1_SA_DQS_DP(7)
   U26 AA59 MDA_DQS_H7 GENOA_SP5-SOCKET6096_13568-001,SMLF,IO,DGA^6000030   I159 @T6G_MB_LIB.T6G(SCH_1):PAGE40
   J30  179 DQS7_A_T||TDQS7_A_T SCONN288_DDR506112002KQ-SCONN288_DDR506112002KQ,SMA   I236 @T6G_MB_LIB.T6G(SCH_1):PAGE100

M_D_CPU1_SA_DQS_DP<8> @T6G_MB_LIB.T6G(SCH_1):M_D_CPU1_SA_DQS_DP(8)
   U26 AG59 MDA_DQS_H8 GENOA_SP5-SOCKET6096_13568-001,SMLF,IO,DGA^6000030   I159 @T6G_MB_LIB.T6G(SCH_1):PAGE40
   J30  190 DQS8_A_T||TDQS8_A_T SCONN288_DDR506112002KQ-SCONN288_DDR506112002KQ,SMA   I236 @T6G_MB_LIB.T6G(SCH_1):PAGE100

M_D_CPU1_SA_DQS_DP<9> @T6G_MB_LIB.T6G(SCH_1):M_D_CPU1_SA_DQS_DP(9)
   U26 AN59 MDA_DQS_H9 GENOA_SP5-SOCKET6096_13568-001,SMLF,IO,DGA^6000030   I159 @T6G_MB_LIB.T6G(SCH_1):PAGE40
   J30  201 DQS9_A_T||TDQS9_A_T SCONN288_DDR506112002KQ-SCONN288_DDR506112002KQ,SMA   I236 @T6G_MB_LIB.T6G(SCH_1):PAGE100

M_D_CPU1_SA_PAR @T6G_MB_LIB.T6G(SCH_1):M_D_CPU1_SA_PAR
   U26 BC59 MDA_PAR GENOA_SP5-SOCKET6096_13568-001,SMLF,IO,DGA^6000030   I159 @T6G_MB_LIB.T6G(SCH_1):PAGE40
   J30   74  PAR_A SCONN288_DDR506112002KQ-SCONN288_DDR506112002KQ,SMA    I52 @T6G_MB_LIB.T6G(SCH_1):PAGE100

M_D_CPU1_SA_RSP<0> @T6G_MB_LIB.T6G(SCH_1):M_D_CPU1_SA_RSP(0)
   U26 BN59 MDA0_RSP_L GENOA_SP5-SOCKET6096_13568-001,SMLF,IO,DGA^6000030   I159 @T6G_MB_LIB.T6G(SCH_1):PAGE40
   J30   86 LBD||RSP_A_N SCONN288_DDR506112002KQ-SCONN288_DDR506112002KQ,SMA    I52 @T6G_MB_LIB.T6G(SCH_1):PAGE100

M_D_CPU1_SB_CA<0> @T6G_MB_LIB.T6G(SCH_1):M_D_CPU1_SB_CA(0)
   U26 BG59 MDB_CA0 GENOA_SP5-SOCKET6096_13568-001,SMLF,IO,DGA^6000030   I159 @T6G_MB_LIB.T6G(SCH_1):PAGE40
   J30   76  CA0_B SCONN288_DDR506112002KQ-SCONN288_DDR506112002KQ,SMA    I52 @T6G_MB_LIB.T6G(SCH_1):PAGE100

M_D_CPU1_SB_CA<1> @T6G_MB_LIB.T6G(SCH_1):M_D_CPU1_SB_CA(1)
   U26 BH58 MDB_CA1 GENOA_SP5-SOCKET6096_13568-001,SMLF,IO,DGA^6000030   I159 @T6G_MB_LIB.T6G(SCH_1):PAGE40
   J30  221  CA1_B SCONN288_DDR506112002KQ-SCONN288_DDR506112002KQ,SMA    I52 @T6G_MB_LIB.T6G(SCH_1):PAGE100

M_D_CPU1_SB_CA<2> @T6G_MB_LIB.T6G(SCH_1):M_D_CPU1_SB_CA(2)
   U26 BH60 MDB_CA2 GENOA_SP5-SOCKET6096_13568-001,SMLF,IO,DGA^6000030   I159 @T6G_MB_LIB.T6G(SCH_1):PAGE40
   J30   78  CA2_B SCONN288_DDR506112002KQ-SCONN288_DDR506112002KQ,SMA    I52 @T6G_MB_LIB.T6G(SCH_1):PAGE100

M_D_CPU1_SB_CA<3> @T6G_MB_LIB.T6G(SCH_1):M_D_CPU1_SB_CA(3)
   U26 BJ60 MDB_CA3 GENOA_SP5-SOCKET6096_13568-001,SMLF,IO,DGA^6000030   I159 @T6G_MB_LIB.T6G(SCH_1):PAGE40
   J30  223  CA3_B SCONN288_DDR506112002KQ-SCONN288_DDR506112002KQ,SMA    I52 @T6G_MB_LIB.T6G(SCH_1):PAGE100

M_D_CPU1_SB_CA<4> @T6G_MB_LIB.T6G(SCH_1):M_D_CPU1_SB_CA(4)
   U26 BJ59 MDB_CA4 GENOA_SP5-SOCKET6096_13568-001,SMLF,IO,DGA^6000030   I159 @T6G_MB_LIB.T6G(SCH_1):PAGE40
   J30   80  CA4_B SCONN288_DDR506112002KQ-SCONN288_DDR506112002KQ,SMA    I52 @T6G_MB_LIB.T6G(SCH_1):PAGE100

M_D_CPU1_SB_CA<5> @T6G_MB_LIB.T6G(SCH_1):M_D_CPU1_SB_CA(5)
   U26 BK58 MDB_CA5 GENOA_SP5-SOCKET6096_13568-001,SMLF,IO,DGA^6000030   I159 @T6G_MB_LIB.T6G(SCH_1):PAGE40
   J30  225  CA5_B SCONN288_DDR506112002KQ-SCONN288_DDR506112002KQ,SMA    I52 @T6G_MB_LIB.T6G(SCH_1):PAGE100

M_D_CPU1_SB_CA<6> @T6G_MB_LIB.T6G(SCH_1):M_D_CPU1_SB_CA(6)
   U26 BK60 MDB_CA6 GENOA_SP5-SOCKET6096_13568-001,SMLF,IO,DGA^6000030   I159 @T6G_MB_LIB.T6G(SCH_1):PAGE40
   J30   82  CA6_B SCONN288_DDR506112002KQ-SCONN288_DDR506112002KQ,SMA    I52 @T6G_MB_LIB.T6G(SCH_1):PAGE100

M_D_CPU1_SB_CB<0> @T6G_MB_LIB.T6G(SCH_1):M_D_CPU1_SB_CB(0)
   U26 BY60 MDB_CHECK0 GENOA_SP5-SOCKET6096_13568-001,SMLF,IO,DGA^6000030   I159 @T6G_MB_LIB.T6G(SCH_1):PAGE40
   J30   96  CB0_B SCONN288_DDR506112002KQ-SCONN288_DDR506112002KQ,SMA    I52 @T6G_MB_LIB.T6G(SCH_1):PAGE100

M_D_CPU1_SB_CB<1> @T6G_MB_LIB.T6G(SCH_1):M_D_CPU1_SB_CB(1)
   U26 CA59 MDB_CHECK1 GENOA_SP5-SOCKET6096_13568-001,SMLF,IO,DGA^6000030   I159 @T6G_MB_LIB.T6G(SCH_1):PAGE40
   J30   98  CB1_B SCONN288_DDR506112002KQ-SCONN288_DDR506112002KQ,SMA    I52 @T6G_MB_LIB.T6G(SCH_1):PAGE100

M_D_CPU1_SB_CB<2> @T6G_MB_LIB.T6G(SCH_1):M_D_CPU1_SB_CB(2)
   U26 CA60 MDB_CHECK2 GENOA_SP5-SOCKET6096_13568-001,SMLF,IO,DGA^6000030   I159 @T6G_MB_LIB.T6G(SCH_1):PAGE40
   J30  241  CB2_B SCONN288_DDR506112002KQ-SCONN288_DDR506112002KQ,SMA    I52 @T6G_MB_LIB.T6G(SCH_1):PAGE100

M_D_CPU1_SB_CB<3> @T6G_MB_LIB.T6G(SCH_1):M_D_CPU1_SB_CB(3)
   U26 CB58 MDB_CHECK3 GENOA_SP5-SOCKET6096_13568-001,SMLF,IO,DGA^6000030   I159 @T6G_MB_LIB.T6G(SCH_1):PAGE40
   J30  243  CB3_B SCONN288_DDR506112002KQ-SCONN288_DDR506112002KQ,SMA    I52 @T6G_MB_LIB.T6G(SCH_1):PAGE100

M_D_CPU1_SB_CB<4> @T6G_MB_LIB.T6G(SCH_1):M_D_CPU1_SB_CB(4)
   U26 BT60 MDB_CHECK4 GENOA_SP5-SOCKET6096_13568-001,SMLF,IO,DGA^6000030   I159 @T6G_MB_LIB.T6G(SCH_1):PAGE40
   J30   89  CB4_B SCONN288_DDR506112002KQ-SCONN288_DDR506112002KQ,SMA    I52 @T6G_MB_LIB.T6G(SCH_1):PAGE100

M_D_CPU1_SB_CB<5> @T6G_MB_LIB.T6G(SCH_1):M_D_CPU1_SB_CB(5)
   U26 BU59 MDB_CHECK5 GENOA_SP5-SOCKET6096_13568-001,SMLF,IO,DGA^6000030   I159 @T6G_MB_LIB.T6G(SCH_1):PAGE40
   J30   91  CB5_B SCONN288_DDR506112002KQ-SCONN288_DDR506112002KQ,SMA    I52 @T6G_MB_LIB.T6G(SCH_1):PAGE100

M_D_CPU1_SB_CB<6> @T6G_MB_LIB.T6G(SCH_1):M_D_CPU1_SB_CB(6)
   U26 BU60 MDB_CHECK6 GENOA_SP5-SOCKET6096_13568-001,SMLF,IO,DGA^6000030   I159 @T6G_MB_LIB.T6G(SCH_1):PAGE40
   J30  234  CB6_B SCONN288_DDR506112002KQ-SCONN288_DDR506112002KQ,SMA    I52 @T6G_MB_LIB.T6G(SCH_1):PAGE100

M_D_CPU1_SB_CB<7> @T6G_MB_LIB.T6G(SCH_1):M_D_CPU1_SB_CB(7)
   U26 BV58 MDB_CHECK7 GENOA_SP5-SOCKET6096_13568-001,SMLF,IO,DGA^6000030   I159 @T6G_MB_LIB.T6G(SCH_1):PAGE40
   J30  236  CB7_B SCONN288_DDR506112002KQ-SCONN288_DDR506112002KQ,SMA    I52 @T6G_MB_LIB.T6G(SCH_1):PAGE100

M_D_CPU1_SB_CS_N<0> @T6G_MB_LIB.T6G(SCH_1):M_D_CPU1_SB_CS_N(0)
   U26 BM58 MDB0_CS_L0 GENOA_SP5-SOCKET6096_13568-001,SMLF,IO,DGA^6000030   I159 @T6G_MB_LIB.T6G(SCH_1):PAGE40
   J30   84 CS0_B_N SCONN288_DDR506112002KQ-SCONN288_DDR506112002KQ,SMA    I52 @T6G_MB_LIB.T6G(SCH_1):PAGE100

M_D_CPU1_SB_CS_N<1> @T6G_MB_LIB.T6G(SCH_1):M_D_CPU1_SB_CS_N(1)
   U26 BN60 MDB0_CS_L1 GENOA_SP5-SOCKET6096_13568-001,SMLF,IO,DGA^6000030   I159 @T6G_MB_LIB.T6G(SCH_1):PAGE40
   J30  229 CS1_B_N SCONN288_DDR506112002KQ-SCONN288_DDR506112002KQ,SMA    I52 @T6G_MB_LIB.T6G(SCH_1):PAGE100

M_D_CPU1_SB_DQ<0> @T6G_MB_LIB.T6G(SCH_1):M_D_CPU1_SB_DQ(0)
   U26 CB60 MDB_DATA0 GENOA_SP5-SOCKET6096_13568-001,SMLF,IO,DGA^6000030   I159 @T6G_MB_LIB.T6G(SCH_1):PAGE40
   J30  100  DQ0_B SCONN288_DDR506112002KQ-SCONN288_DDR506112002KQ,SMA    I52 @T6G_MB_LIB.T6G(SCH_1):PAGE100

M_D_CPU1_SB_DQ<10> @T6G_MB_LIB.T6G(SCH_1):M_D_CPU1_SB_DQ(10)
   U26 CJ60 MDB_DATA10 GENOA_SP5-SOCKET6096_13568-001,SMLF,IO,DGA^6000030   I159 @T6G_MB_LIB.T6G(SCH_1):PAGE40
   J30  256 DQ10_B SCONN288_DDR506112002KQ-SCONN288_DDR506112002KQ,SMA    I52 @T6G_MB_LIB.T6G(SCH_1):PAGE100

M_D_CPU1_SB_DQ<11> @T6G_MB_LIB.T6G(SCH_1):M_D_CPU1_SB_DQ(11)
   U26 CK58 MDB_DATA11 GENOA_SP5-SOCKET6096_13568-001,SMLF,IO,DGA^6000030   I159 @T6G_MB_LIB.T6G(SCH_1):PAGE40
   J30  258 DQ11_B SCONN288_DDR506112002KQ-SCONN288_DDR506112002KQ,SMA    I52 @T6G_MB_LIB.T6G(SCH_1):PAGE100

M_D_CPU1_SB_DQ<12> @T6G_MB_LIB.T6G(SCH_1):M_D_CPU1_SB_DQ(12)
   U26 CM60 MDB_DATA12 GENOA_SP5-SOCKET6096_13568-001,SMLF,IO,DGA^6000030   I159 @T6G_MB_LIB.T6G(SCH_1):PAGE40
   J30  118 DQ12_B SCONN288_DDR506112002KQ-SCONN288_DDR506112002KQ,SMA    I52 @T6G_MB_LIB.T6G(SCH_1):PAGE100

M_D_CPU1_SB_DQ<13> @T6G_MB_LIB.T6G(SCH_1):M_D_CPU1_SB_DQ(13)
   U26 CN59 MDB_DATA13 GENOA_SP5-SOCKET6096_13568-001,SMLF,IO,DGA^6000030   I159 @T6G_MB_LIB.T6G(SCH_1):PAGE40
   J30  120 DQ13_B SCONN288_DDR506112002KQ-SCONN288_DDR506112002KQ,SMA    I52 @T6G_MB_LIB.T6G(SCH_1):PAGE100

M_D_CPU1_SB_DQ<14> @T6G_MB_LIB.T6G(SCH_1):M_D_CPU1_SB_DQ(14)
   U26 CN60 MDB_DATA14 GENOA_SP5-SOCKET6096_13568-001,SMLF,IO,DGA^6000030   I159 @T6G_MB_LIB.T6G(SCH_1):PAGE40
   J30  263 DQ14_B SCONN288_DDR506112002KQ-SCONN288_DDR506112002KQ,SMA    I52 @T6G_MB_LIB.T6G(SCH_1):PAGE100

M_D_CPU1_SB_DQ<15> @T6G_MB_LIB.T6G(SCH_1):M_D_CPU1_SB_DQ(15)
   U26 CP58 MDB_DATA15 GENOA_SP5-SOCKET6096_13568-001,SMLF,IO,DGA^6000030   I159 @T6G_MB_LIB.T6G(SCH_1):PAGE40
   J30  265 DQ15_B SCONN288_DDR506112002KQ-SCONN288_DDR506112002KQ,SMA    I52 @T6G_MB_LIB.T6G(SCH_1):PAGE100

M_D_CPU1_SB_DQ<16> @T6G_MB_LIB.T6G(SCH_1):M_D_CPU1_SB_DQ(16)
   U26 CP60 MDB_DATA16 GENOA_SP5-SOCKET6096_13568-001,SMLF,IO,DGA^6000030   I159 @T6G_MB_LIB.T6G(SCH_1):PAGE40
   J30  122 DQ16_B SCONN288_DDR506112002KQ-SCONN288_DDR506112002KQ,SMA    I52 @T6G_MB_LIB.T6G(SCH_1):PAGE100

M_D_CPU1_SB_DQ<17> @T6G_MB_LIB.T6G(SCH_1):M_D_CPU1_SB_DQ(17)
   U26 CR59 MDB_DATA17 GENOA_SP5-SOCKET6096_13568-001,SMLF,IO,DGA^6000030   I159 @T6G_MB_LIB.T6G(SCH_1):PAGE40
   J30  124 DQ17_B SCONN288_DDR506112002KQ-SCONN288_DDR506112002KQ,SMA    I52 @T6G_MB_LIB.T6G(SCH_1):PAGE100

M_D_CPU1_SB_DQ<18> @T6G_MB_LIB.T6G(SCH_1):M_D_CPU1_SB_DQ(18)
   U26 CR60 MDB_DATA18 GENOA_SP5-SOCKET6096_13568-001,SMLF,IO,DGA^6000030   I159 @T6G_MB_LIB.T6G(SCH_1):PAGE40
   J30  267 DQ18_B SCONN288_DDR506112002KQ-SCONN288_DDR506112002KQ,SMA    I52 @T6G_MB_LIB.T6G(SCH_1):PAGE100

M_D_CPU1_SB_DQ<19> @T6G_MB_LIB.T6G(SCH_1):M_D_CPU1_SB_DQ(19)
   U26 CT58 MDB_DATA19 GENOA_SP5-SOCKET6096_13568-001,SMLF,IO,DGA^6000030   I159 @T6G_MB_LIB.T6G(SCH_1):PAGE40
   J30  269 DQ19_B SCONN288_DDR506112002KQ-SCONN288_DDR506112002KQ,SMA    I52 @T6G_MB_LIB.T6G(SCH_1):PAGE100

M_D_CPU1_SB_DQ<1> @T6G_MB_LIB.T6G(SCH_1):M_D_CPU1_SB_DQ(1)
   U26 CC59 MDB_DATA1 GENOA_SP5-SOCKET6096_13568-001,SMLF,IO,DGA^6000030   I159 @T6G_MB_LIB.T6G(SCH_1):PAGE40
   J30  102  DQ1_B SCONN288_DDR506112002KQ-SCONN288_DDR506112002KQ,SMA    I52 @T6G_MB_LIB.T6G(SCH_1):PAGE100

M_D_CPU1_SB_DQ<20> @T6G_MB_LIB.T6G(SCH_1):M_D_CPU1_SB_DQ(20)
   U26 CV60 MDB_DATA20 GENOA_SP5-SOCKET6096_13568-001,SMLF,IO,DGA^6000030   I159 @T6G_MB_LIB.T6G(SCH_1):PAGE40
   J30  129 DQ20_B SCONN288_DDR506112002KQ-SCONN288_DDR506112002KQ,SMA    I52 @T6G_MB_LIB.T6G(SCH_1):PAGE100

M_D_CPU1_SB_DQ<21> @T6G_MB_LIB.T6G(SCH_1):M_D_CPU1_SB_DQ(21)
   U26 CW59 MDB_DATA21 GENOA_SP5-SOCKET6096_13568-001,SMLF,IO,DGA^6000030   I159 @T6G_MB_LIB.T6G(SCH_1):PAGE40
   J30  131 DQ21_B SCONN288_DDR506112002KQ-SCONN288_DDR506112002KQ,SMA    I52 @T6G_MB_LIB.T6G(SCH_1):PAGE100

M_D_CPU1_SB_DQ<22> @T6G_MB_LIB.T6G(SCH_1):M_D_CPU1_SB_DQ(22)
   U26 CW60 MDB_DATA22 GENOA_SP5-SOCKET6096_13568-001,SMLF,IO,DGA^6000030   I159 @T6G_MB_LIB.T6G(SCH_1):PAGE40
   J30  274 DQ22_B SCONN288_DDR506112002KQ-SCONN288_DDR506112002KQ,SMA    I52 @T6G_MB_LIB.T6G(SCH_1):PAGE100

M_D_CPU1_SB_DQ<23> @T6G_MB_LIB.T6G(SCH_1):M_D_CPU1_SB_DQ(23)
   U26 CY58 MDB_DATA23 GENOA_SP5-SOCKET6096_13568-001,SMLF,IO,DGA^6000030   I159 @T6G_MB_LIB.T6G(SCH_1):PAGE40
   J30  276 DQ23_B SCONN288_DDR506112002KQ-SCONN288_DDR506112002KQ,SMA    I52 @T6G_MB_LIB.T6G(SCH_1):PAGE100

M_D_CPU1_SB_DQ<24> @T6G_MB_LIB.T6G(SCH_1):M_D_CPU1_SB_DQ(24)
   U26 CY60 MDB_DATA24 GENOA_SP5-SOCKET6096_13568-001,SMLF,IO,DGA^6000030   I159 @T6G_MB_LIB.T6G(SCH_1):PAGE40
   J30  133 DQ24_B SCONN288_DDR506112002KQ-SCONN288_DDR506112002KQ,SMA    I52 @T6G_MB_LIB.T6G(SCH_1):PAGE100

M_D_CPU1_SB_DQ<25> @T6G_MB_LIB.T6G(SCH_1):M_D_CPU1_SB_DQ(25)
   U26 DA59 MDB_DATA25 GENOA_SP5-SOCKET6096_13568-001,SMLF,IO,DGA^6000030   I159 @T6G_MB_LIB.T6G(SCH_1):PAGE40
   J30  135 DQ25_B SCONN288_DDR506112002KQ-SCONN288_DDR506112002KQ,SMA    I52 @T6G_MB_LIB.T6G(SCH_1):PAGE100

M_D_CPU1_SB_DQ<26> @T6G_MB_LIB.T6G(SCH_1):M_D_CPU1_SB_DQ(26)
   U26 DA60 MDB_DATA26 GENOA_SP5-SOCKET6096_13568-001,SMLF,IO,DGA^6000030   I159 @T6G_MB_LIB.T6G(SCH_1):PAGE40
   J30  278 DQ26_B SCONN288_DDR506112002KQ-SCONN288_DDR506112002KQ,SMA    I52 @T6G_MB_LIB.T6G(SCH_1):PAGE100

M_D_CPU1_SB_DQ<27> @T6G_MB_LIB.T6G(SCH_1):M_D_CPU1_SB_DQ(27)
   U26 DB58 MDB_DATA27 GENOA_SP5-SOCKET6096_13568-001,SMLF,IO,DGA^6000030   I159 @T6G_MB_LIB.T6G(SCH_1):PAGE40
   J30  280 DQ27_B SCONN288_DDR506112002KQ-SCONN288_DDR506112002KQ,SMA    I52 @T6G_MB_LIB.T6G(SCH_1):PAGE100

M_D_CPU1_SB_DQ<28> @T6G_MB_LIB.T6G(SCH_1):M_D_CPU1_SB_DQ(28)
   U26 DD60 MDB_DATA28 GENOA_SP5-SOCKET6096_13568-001,SMLF,IO,DGA^6000030   I159 @T6G_MB_LIB.T6G(SCH_1):PAGE40
   J30  140 DQ28_B SCONN288_DDR506112002KQ-SCONN288_DDR506112002KQ,SMA    I52 @T6G_MB_LIB.T6G(SCH_1):PAGE100

M_D_CPU1_SB_DQ<29> @T6G_MB_LIB.T6G(SCH_1):M_D_CPU1_SB_DQ(29)
   U26 DE59 MDB_DATA29 GENOA_SP5-SOCKET6096_13568-001,SMLF,IO,DGA^6000030   I159 @T6G_MB_LIB.T6G(SCH_1):PAGE40
   J30  142 DQ29_B SCONN288_DDR506112002KQ-SCONN288_DDR506112002KQ,SMA    I52 @T6G_MB_LIB.T6G(SCH_1):PAGE100

M_D_CPU1_SB_DQ<2> @T6G_MB_LIB.T6G(SCH_1):M_D_CPU1_SB_DQ(2)
   U26 CC60 MDB_DATA2 GENOA_SP5-SOCKET6096_13568-001,SMLF,IO,DGA^6000030   I159 @T6G_MB_LIB.T6G(SCH_1):PAGE40
   J30  245  DQ2_B SCONN288_DDR506112002KQ-SCONN288_DDR506112002KQ,SMA    I52 @T6G_MB_LIB.T6G(SCH_1):PAGE100

M_D_CPU1_SB_DQ<30> @T6G_MB_LIB.T6G(SCH_1):M_D_CPU1_SB_DQ(30)
   U26 DE60 MDB_DATA30 GENOA_SP5-SOCKET6096_13568-001,SMLF,IO,DGA^6000030   I159 @T6G_MB_LIB.T6G(SCH_1):PAGE40
   J30  285 DQ30_B SCONN288_DDR506112002KQ-SCONN288_DDR506112002KQ,SMA    I52 @T6G_MB_LIB.T6G(SCH_1):PAGE100

M_D_CPU1_SB_DQ<31> @T6G_MB_LIB.T6G(SCH_1):M_D_CPU1_SB_DQ(31)
   U26 DF60 MDB_DATA31 GENOA_SP5-SOCKET6096_13568-001,SMLF,IO,DGA^6000030   I159 @T6G_MB_LIB.T6G(SCH_1):PAGE40
   J30  287 DQ31_B SCONN288_DDR506112002KQ-SCONN288_DDR506112002KQ,SMA    I52 @T6G_MB_LIB.T6G(SCH_1):PAGE100

M_D_CPU1_SB_DQ<3> @T6G_MB_LIB.T6G(SCH_1):M_D_CPU1_SB_DQ(3)
   U26 CD58 MDB_DATA3 GENOA_SP5-SOCKET6096_13568-001,SMLF,IO,DGA^6000030   I159 @T6G_MB_LIB.T6G(SCH_1):PAGE40
   J30  247  DQ3_B SCONN288_DDR506112002KQ-SCONN288_DDR506112002KQ,SMA    I52 @T6G_MB_LIB.T6G(SCH_1):PAGE100

M_D_CPU1_SB_DQ<4> @T6G_MB_LIB.T6G(SCH_1):M_D_CPU1_SB_DQ(4)
   U26 CF60 MDB_DATA4 GENOA_SP5-SOCKET6096_13568-001,SMLF,IO,DGA^6000030   I159 @T6G_MB_LIB.T6G(SCH_1):PAGE40
   J30  107  DQ4_B SCONN288_DDR506112002KQ-SCONN288_DDR506112002KQ,SMA    I52 @T6G_MB_LIB.T6G(SCH_1):PAGE100

M_D_CPU1_SB_DQ<5> @T6G_MB_LIB.T6G(SCH_1):M_D_CPU1_SB_DQ(5)
   U26 CG59 MDB_DATA5 GENOA_SP5-SOCKET6096_13568-001,SMLF,IO,DGA^6000030   I159 @T6G_MB_LIB.T6G(SCH_1):PAGE40
   J30  109  DQ5_B SCONN288_DDR506112002KQ-SCONN288_DDR506112002KQ,SMA    I52 @T6G_MB_LIB.T6G(SCH_1):PAGE100

M_D_CPU1_SB_DQ<6> @T6G_MB_LIB.T6G(SCH_1):M_D_CPU1_SB_DQ(6)
   U26 CG60 MDB_DATA6 GENOA_SP5-SOCKET6096_13568-001,SMLF,IO,DGA^6000030   I159 @T6G_MB_LIB.T6G(SCH_1):PAGE40
   J30  252  DQ6_B SCONN288_DDR506112002KQ-SCONN288_DDR506112002KQ,SMA    I52 @T6G_MB_LIB.T6G(SCH_1):PAGE100

M_D_CPU1_SB_DQ<7> @T6G_MB_LIB.T6G(SCH_1):M_D_CPU1_SB_DQ(7)
   U26 CH58 MDB_DATA7 GENOA_SP5-SOCKET6096_13568-001,SMLF,IO,DGA^6000030   I159 @T6G_MB_LIB.T6G(SCH_1):PAGE40
   J30  254  DQ7_B SCONN288_DDR506112002KQ-SCONN288_DDR506112002KQ,SMA    I52 @T6G_MB_LIB.T6G(SCH_1):PAGE100

M_D_CPU1_SB_DQ<8> @T6G_MB_LIB.T6G(SCH_1):M_D_CPU1_SB_DQ(8)
   U26 CH60 MDB_DATA8 GENOA_SP5-SOCKET6096_13568-001,SMLF,IO,DGA^6000030   I159 @T6G_MB_LIB.T6G(SCH_1):PAGE40
   J30  111  DQ8_B SCONN288_DDR506112002KQ-SCONN288_DDR506112002KQ,SMA    I52 @T6G_MB_LIB.T6G(SCH_1):PAGE100

M_D_CPU1_SB_DQ<9> @T6G_MB_LIB.T6G(SCH_1):M_D_CPU1_SB_DQ(9)
   U26 CJ59 MDB_DATA9 GENOA_SP5-SOCKET6096_13568-001,SMLF,IO,DGA^6000030   I159 @T6G_MB_LIB.T6G(SCH_1):PAGE40
   J30  113  DQ9_B SCONN288_DDR506112002KQ-SCONN288_DDR506112002KQ,SMA    I52 @T6G_MB_LIB.T6G(SCH_1):PAGE100

M_D_CPU1_SB_DQS_DN<0> @T6G_MB_LIB.T6G(SCH_1):M_D_CPU1_SB_DQS_DN(0)
   U26 CE60 MDB_DQS_L0 GENOA_SP5-SOCKET6096_13568-001,SMLF,IO,DGA^6000030   I159 @T6G_MB_LIB.T6G(SCH_1):PAGE40
   J30  105 DQS0_B_C SCONN288_DDR506112002KQ-SCONN288_DDR506112002KQ,SMA   I236 @T6G_MB_LIB.T6G(SCH_1):PAGE100

M_D_CPU1_SB_DQS_DN<1> @T6G_MB_LIB.T6G(SCH_1):M_D_CPU1_SB_DQS_DN(1)
   U26 CL60 MDB_DQS_L1 GENOA_SP5-SOCKET6096_13568-001,SMLF,IO,DGA^6000030   I159 @T6G_MB_LIB.T6G(SCH_1):PAGE40
   J30  116 DQS1_B_C SCONN288_DDR506112002KQ-SCONN288_DDR506112002KQ,SMA   I236 @T6G_MB_LIB.T6G(SCH_1):PAGE100

M_D_CPU1_SB_DQS_DN<2> @T6G_MB_LIB.T6G(SCH_1):M_D_CPU1_SB_DQS_DN(2)
   U26 CU60 MDB_DQS_L2 GENOA_SP5-SOCKET6096_13568-001,SMLF,IO,DGA^6000030   I159 @T6G_MB_LIB.T6G(SCH_1):PAGE40
   J30  127 DQS2_B_C SCONN288_DDR506112002KQ-SCONN288_DDR506112002KQ,SMA   I236 @T6G_MB_LIB.T6G(SCH_1):PAGE100

M_D_CPU1_SB_DQS_DN<3> @T6G_MB_LIB.T6G(SCH_1):M_D_CPU1_SB_DQS_DN(3)
   U26 DC60 MDB_DQS_L3 GENOA_SP5-SOCKET6096_13568-001,SMLF,IO,DGA^6000030   I159 @T6G_MB_LIB.T6G(SCH_1):PAGE40
   J30  138 DQS3_B_C SCONN288_DDR506112002KQ-SCONN288_DDR506112002KQ,SMA   I236 @T6G_MB_LIB.T6G(SCH_1):PAGE100

M_D_CPU1_SB_DQS_DN<4> @T6G_MB_LIB.T6G(SCH_1):M_D_CPU1_SB_DQS_DN(4)
   U26 BW59 MDB_DQS_L4 GENOA_SP5-SOCKET6096_13568-001,SMLF,IO,DGA^6000030   I159 @T6G_MB_LIB.T6G(SCH_1):PAGE40
   J30  238 DQS4_B_C SCONN288_DDR506112002KQ-SCONN288_DDR506112002KQ,SMA   I236 @T6G_MB_LIB.T6G(SCH_1):PAGE100

M_D_CPU1_SB_DQS_DN<5> @T6G_MB_LIB.T6G(SCH_1):M_D_CPU1_SB_DQS_DN(5)
   U26 CE59 MDB_DQS_L5 GENOA_SP5-SOCKET6096_13568-001,SMLF,IO,DGA^6000030   I159 @T6G_MB_LIB.T6G(SCH_1):PAGE40
   J30  249 DQS5_B_C||TDQS5_B_C SCONN288_DDR506112002KQ-SCONN288_DDR506112002KQ,SMA   I236 @T6G_MB_LIB.T6G(SCH_1):PAGE100

M_D_CPU1_SB_DQS_DN<6> @T6G_MB_LIB.T6G(SCH_1):M_D_CPU1_SB_DQS_DN(6)
   U26 CL59 MDB_DQS_L6 GENOA_SP5-SOCKET6096_13568-001,SMLF,IO,DGA^6000030   I159 @T6G_MB_LIB.T6G(SCH_1):PAGE40
   J30  260 DQS6_B_C||TDQS6_B_C SCONN288_DDR506112002KQ-SCONN288_DDR506112002KQ,SMA   I236 @T6G_MB_LIB.T6G(SCH_1):PAGE100

M_D_CPU1_SB_DQS_DN<7> @T6G_MB_LIB.T6G(SCH_1):M_D_CPU1_SB_DQS_DN(7)
   U26 CU59 MDB_DQS_L7 GENOA_SP5-SOCKET6096_13568-001,SMLF,IO,DGA^6000030   I159 @T6G_MB_LIB.T6G(SCH_1):PAGE40
   J30  271 DQS7_B_C||TDQS7_B_C SCONN288_DDR506112002KQ-SCONN288_DDR506112002KQ,SMA   I236 @T6G_MB_LIB.T6G(SCH_1):PAGE100

M_D_CPU1_SB_DQS_DN<8> @T6G_MB_LIB.T6G(SCH_1):M_D_CPU1_SB_DQS_DN(8)
   U26 DC59 MDB_DQS_L8 GENOA_SP5-SOCKET6096_13568-001,SMLF,IO,DGA^6000030   I159 @T6G_MB_LIB.T6G(SCH_1):PAGE40
   J30  282 DQS8_B_C||TDQS8_B_C SCONN288_DDR506112002KQ-SCONN288_DDR506112002KQ,SMA   I236 @T6G_MB_LIB.T6G(SCH_1):PAGE100

M_D_CPU1_SB_DQS_DN<9> @T6G_MB_LIB.T6G(SCH_1):M_D_CPU1_SB_DQS_DN(9)
   U26 BW60 MDB_DQS_L9 GENOA_SP5-SOCKET6096_13568-001,SMLF,IO,DGA^6000030   I159 @T6G_MB_LIB.T6G(SCH_1):PAGE40
   J30   94 DQS9_B_C||TDQS9_B_C SCONN288_DDR506112002KQ-SCONN288_DDR506112002KQ,SMA   I236 @T6G_MB_LIB.T6G(SCH_1):PAGE100

M_D_CPU1_SB_DQS_DP<0> @T6G_MB_LIB.T6G(SCH_1):M_D_CPU1_SB_DQS_DP(0)
   U26 CD60 MDB_DQS_H0 GENOA_SP5-SOCKET6096_13568-001,SMLF,IO,DGA^6000030   I159 @T6G_MB_LIB.T6G(SCH_1):PAGE40
   J30  104 DQS0_B_T SCONN288_DDR506112002KQ-SCONN288_DDR506112002KQ,SMA   I236 @T6G_MB_LIB.T6G(SCH_1):PAGE100

M_D_CPU1_SB_DQS_DP<1> @T6G_MB_LIB.T6G(SCH_1):M_D_CPU1_SB_DQS_DP(1)
   U26 CK60 MDB_DQS_H1 GENOA_SP5-SOCKET6096_13568-001,SMLF,IO,DGA^6000030   I159 @T6G_MB_LIB.T6G(SCH_1):PAGE40
   J30  115 DQS1_B_T SCONN288_DDR506112002KQ-SCONN288_DDR506112002KQ,SMA   I236 @T6G_MB_LIB.T6G(SCH_1):PAGE100

M_D_CPU1_SB_DQS_DP<2> @T6G_MB_LIB.T6G(SCH_1):M_D_CPU1_SB_DQS_DP(2)
   U26 CT60 MDB_DQS_H2 GENOA_SP5-SOCKET6096_13568-001,SMLF,IO,DGA^6000030   I159 @T6G_MB_LIB.T6G(SCH_1):PAGE40
   J30  126 DQS2_B_T SCONN288_DDR506112002KQ-SCONN288_DDR506112002KQ,SMA   I236 @T6G_MB_LIB.T6G(SCH_1):PAGE100

M_D_CPU1_SB_DQS_DP<3> @T6G_MB_LIB.T6G(SCH_1):M_D_CPU1_SB_DQS_DP(3)
   U26 DB60 MDB_DQS_H3 GENOA_SP5-SOCKET6096_13568-001,SMLF,IO,DGA^6000030   I159 @T6G_MB_LIB.T6G(SCH_1):PAGE40
   J30  137 DQS3_B_T SCONN288_DDR506112002KQ-SCONN288_DDR506112002KQ,SMA   I236 @T6G_MB_LIB.T6G(SCH_1):PAGE100

M_D_CPU1_SB_DQS_DP<4> @T6G_MB_LIB.T6G(SCH_1):M_D_CPU1_SB_DQS_DP(4)
   U26 BY58 MDB_DQS_H4 GENOA_SP5-SOCKET6096_13568-001,SMLF,IO,DGA^6000030   I159 @T6G_MB_LIB.T6G(SCH_1):PAGE40
   J30  239 DQS4_B_T SCONN288_DDR506112002KQ-SCONN288_DDR506112002KQ,SMA   I236 @T6G_MB_LIB.T6G(SCH_1):PAGE100

M_D_CPU1_SB_DQS_DP<5> @T6G_MB_LIB.T6G(SCH_1):M_D_CPU1_SB_DQS_DP(5)
   U26 CF58 MDB_DQS_H5 GENOA_SP5-SOCKET6096_13568-001,SMLF,IO,DGA^6000030   I159 @T6G_MB_LIB.T6G(SCH_1):PAGE40
   J30  250 DQS5_B_T||TDQS5_B_T SCONN288_DDR506112002KQ-SCONN288_DDR506112002KQ,SMA   I236 @T6G_MB_LIB.T6G(SCH_1):PAGE100

M_D_CPU1_SB_DQS_DP<6> @T6G_MB_LIB.T6G(SCH_1):M_D_CPU1_SB_DQS_DP(6)
   U26 CM58 MDB_DQS_H6 GENOA_SP5-SOCKET6096_13568-001,SMLF,IO,DGA^6000030   I159 @T6G_MB_LIB.T6G(SCH_1):PAGE40
   J30  261 DQS6_B_T||TDQS6_B_T SCONN288_DDR506112002KQ-SCONN288_DDR506112002KQ,SMA   I236 @T6G_MB_LIB.T6G(SCH_1):PAGE100

M_D_CPU1_SB_DQS_DP<7> @T6G_MB_LIB.T6G(SCH_1):M_D_CPU1_SB_DQS_DP(7)
   U26 CV58 MDB_DQS_H7 GENOA_SP5-SOCKET6096_13568-001,SMLF,IO,DGA^6000030   I159 @T6G_MB_LIB.T6G(SCH_1):PAGE40
   J30  272 DQS7_B_T||TDQS7_B_T SCONN288_DDR506112002KQ-SCONN288_DDR506112002KQ,SMA   I236 @T6G_MB_LIB.T6G(SCH_1):PAGE100

M_D_CPU1_SB_DQS_DP<8> @T6G_MB_LIB.T6G(SCH_1):M_D_CPU1_SB_DQS_DP(8)
   U26 DD58 MDB_DQS_H8 GENOA_SP5-SOCKET6096_13568-001,SMLF,IO,DGA^6000030   I159 @T6G_MB_LIB.T6G(SCH_1):PAGE40
   J30  283 DQS8_B_T||TDQS8_B_T SCONN288_DDR506112002KQ-SCONN288_DDR506112002KQ,SMA   I236 @T6G_MB_LIB.T6G(SCH_1):PAGE100

M_D_CPU1_SB_DQS_DP<9> @T6G_MB_LIB.T6G(SCH_1):M_D_CPU1_SB_DQS_DP(9)
   U26 BV60 MDB_DQS_H9 GENOA_SP5-SOCKET6096_13568-001,SMLF,IO,DGA^6000030   I159 @T6G_MB_LIB.T6G(SCH_1):PAGE40
   J30   93 DQS9_B_T||TDQS9_B_T||DBI4_B_N SCONN288_DDR506112002KQ-SCONN288_DDR506112002KQ,SMA   I236 @T6G_MB_LIB.T6G(SCH_1):PAGE100

M_D_CPU1_SB_PAR @T6G_MB_LIB.T6G(SCH_1):M_D_CPU1_SB_PAR
   U26 BL60 MDB_PAR GENOA_SP5-SOCKET6096_13568-001,SMLF,IO,DGA^6000030   I159 @T6G_MB_LIB.T6G(SCH_1):PAGE40
   J30  227  PAR_B SCONN288_DDR506112002KQ-SCONN288_DDR506112002KQ,SMA    I52 @T6G_MB_LIB.T6G(SCH_1):PAGE100

M_D_CPU1_SB_RSP<0> @T6G_MB_LIB.T6G(SCH_1):M_D_CPU1_SB_RSP(0)
   U26 BP60 MDB0_RSP_L GENOA_SP5-SOCKET6096_13568-001,SMLF,IO,DGA^6000030   I159 @T6G_MB_LIB.T6G(SCH_1):PAGE40
   J30   87 LBS||RSP_B_N SCONN288_DDR506112002KQ-SCONN288_DDR506112002KQ,SMA    I52 @T6G_MB_LIB.T6G(SCH_1):PAGE100

M_E_CPU0_ALERT_N @T6G_MB_LIB.T6G(SCH_1):M_E_CPU0_ALERT_N
  R379    1      A Q_RES_0402LF-15,1%,1/16W,CHIP,CS01502FB03   I315 @T6G_MB_LIB.T6G(SCH_1):PAGE14
   J21   62 ALERT_N SCONN288_DDR506112002KQ-SCONN288_DDR506112002KQ,SMA   I348 @T6G_MB_LIB.T6G(SCH_1):PAGE89

M_E_CPU0_ALERT_R_N @T6G_MB_LIB.T6G(SCH_1):M_E_CPU0_ALERT_R_N
   U25 AT69 ME_ALERT_L GENOA_SP5-SOCKET6096_13568-001,SMLF,IO,DGA^6000030   I159 @T6G_MB_LIB.T6G(SCH_1):PAGE14
  R379    2      B Q_RES_0402LF-15,1%,1/16W,CHIP,CS01502FB03   I315 @T6G_MB_LIB.T6G(SCH_1):PAGE14

M_E_CPU0_CLK_DN<0> @T6G_MB_LIB.T6G(SCH_1):M_E_CPU0_CLK_DN(0)
   U25 BD70 ME0_CLK_L GENOA_SP5-SOCKET6096_13568-001,SMLF,IO,DGA^6000030   I159 @T6G_MB_LIB.T6G(SCH_1):PAGE14
   J21  218   CK_C SCONN288_DDR506112002KQ-SCONN288_DDR506112002KQ,SMA   I348 @T6G_MB_LIB.T6G(SCH_1):PAGE89

M_E_CPU0_CLK_DP<0> @T6G_MB_LIB.T6G(SCH_1):M_E_CPU0_CLK_DP(0)
   U25 BC71 ME0_CLK_H GENOA_SP5-SOCKET6096_13568-001,SMLF,IO,DGA^6000030   I159 @T6G_MB_LIB.T6G(SCH_1):PAGE14
   J21  217   CK_T SCONN288_DDR506112002KQ-SCONN288_DDR506112002KQ,SMA   I348 @T6G_MB_LIB.T6G(SCH_1):PAGE89

M_E_CPU0_RESET_N @T6G_MB_LIB.T6G(SCH_1):M_E_CPU0_RESET_N
   U25 AU69 ME_RESET_L GENOA_SP5-SOCKET6096_13568-001,SMLF,IO,DGA^6000030   I159 @T6G_MB_LIB.T6G(SCH_1):PAGE14
   J21  207 RESET_N SCONN288_DDR506112002KQ-SCONN288_DDR506112002KQ,SMA   I348 @T6G_MB_LIB.T6G(SCH_1):PAGE89

M_E_CPU0_SA_CA<0> @T6G_MB_LIB.T6G(SCH_1):M_E_CPU0_SA_CA(0)
   U25 AW71 MEA_CA0 GENOA_SP5-SOCKET6096_13568-001,SMLF,IO,DGA^6000030   I159 @T6G_MB_LIB.T6G(SCH_1):PAGE14
   J21   66  CA0_A SCONN288_DDR506112002KQ-SCONN288_DDR506112002KQ,SMA   I348 @T6G_MB_LIB.T6G(SCH_1):PAGE89

M_E_CPU0_SA_CA<1> @T6G_MB_LIB.T6G(SCH_1):M_E_CPU0_SA_CA(1)
   U25 AY70 MEA_CA1 GENOA_SP5-SOCKET6096_13568-001,SMLF,IO,DGA^6000030   I159 @T6G_MB_LIB.T6G(SCH_1):PAGE14
   J21  211  CA1_A SCONN288_DDR506112002KQ-SCONN288_DDR506112002KQ,SMA   I348 @T6G_MB_LIB.T6G(SCH_1):PAGE89

M_E_CPU0_SA_CA<2> @T6G_MB_LIB.T6G(SCH_1):M_E_CPU0_SA_CA(2)
   U25 AY69 MEA_CA2 GENOA_SP5-SOCKET6096_13568-001,SMLF,IO,DGA^6000030   I159 @T6G_MB_LIB.T6G(SCH_1):PAGE14
   J21   68  CA2_A SCONN288_DDR506112002KQ-SCONN288_DDR506112002KQ,SMA   I348 @T6G_MB_LIB.T6G(SCH_1):PAGE89

M_E_CPU0_SA_CA<3> @T6G_MB_LIB.T6G(SCH_1):M_E_CPU0_SA_CA(3)
   U25 BA69 MEA_CA3 GENOA_SP5-SOCKET6096_13568-001,SMLF,IO,DGA^6000030   I159 @T6G_MB_LIB.T6G(SCH_1):PAGE14
   J21  213  CA3_A SCONN288_DDR506112002KQ-SCONN288_DDR506112002KQ,SMA   I348 @T6G_MB_LIB.T6G(SCH_1):PAGE89

M_E_CPU0_SA_CA<4> @T6G_MB_LIB.T6G(SCH_1):M_E_CPU0_SA_CA(4)
   U25 BA71 MEA_CA4 GENOA_SP5-SOCKET6096_13568-001,SMLF,IO,DGA^6000030   I159 @T6G_MB_LIB.T6G(SCH_1):PAGE14
   J21   70  CA4_A SCONN288_DDR506112002KQ-SCONN288_DDR506112002KQ,SMA   I348 @T6G_MB_LIB.T6G(SCH_1):PAGE89

M_E_CPU0_SA_CA<5> @T6G_MB_LIB.T6G(SCH_1):M_E_CPU0_SA_CA(5)
   U25 BB70 MEA_CA5 GENOA_SP5-SOCKET6096_13568-001,SMLF,IO,DGA^6000030   I159 @T6G_MB_LIB.T6G(SCH_1):PAGE14
   J21  215  CA5_A SCONN288_DDR506112002KQ-SCONN288_DDR506112002KQ,SMA   I348 @T6G_MB_LIB.T6G(SCH_1):PAGE89

M_E_CPU0_SA_CA<6> @T6G_MB_LIB.T6G(SCH_1):M_E_CPU0_SA_CA(6)
   U25 BB69 MEA_CA6 GENOA_SP5-SOCKET6096_13568-001,SMLF,IO,DGA^6000030   I159 @T6G_MB_LIB.T6G(SCH_1):PAGE14
   J21   72  CA6_A SCONN288_DDR506112002KQ-SCONN288_DDR506112002KQ,SMA   I348 @T6G_MB_LIB.T6G(SCH_1):PAGE89

M_E_CPU0_SA_CB<0> @T6G_MB_LIB.T6G(SCH_1):M_E_CPU0_SA_CB(0)
   U25 AJ71 MEA_CHECK0 GENOA_SP5-SOCKET6096_13568-001,SMLF,IO,DGA^6000030   I159 @T6G_MB_LIB.T6G(SCH_1):PAGE14
   J21   51  CB0_A SCONN288_DDR506112002KQ-SCONN288_DDR506112002KQ,SMA   I348 @T6G_MB_LIB.T6G(SCH_1):PAGE89

M_E_CPU0_SA_CB<1> @T6G_MB_LIB.T6G(SCH_1):M_E_CPU0_SA_CB(1)
   U25 AK69 MEA_CHECK1 GENOA_SP5-SOCKET6096_13568-001,SMLF,IO,DGA^6000030   I159 @T6G_MB_LIB.T6G(SCH_1):PAGE14
   J21   53  CB1_A SCONN288_DDR506112002KQ-SCONN288_DDR506112002KQ,SMA   I348 @T6G_MB_LIB.T6G(SCH_1):PAGE89

M_E_CPU0_SA_CB<2> @T6G_MB_LIB.T6G(SCH_1):M_E_CPU0_SA_CB(2)
   U25 AK70 MEA_CHECK2 GENOA_SP5-SOCKET6096_13568-001,SMLF,IO,DGA^6000030   I159 @T6G_MB_LIB.T6G(SCH_1):PAGE14
   J21  196  CB2_A SCONN288_DDR506112002KQ-SCONN288_DDR506112002KQ,SMA   I348 @T6G_MB_LIB.T6G(SCH_1):PAGE89

M_E_CPU0_SA_CB<3> @T6G_MB_LIB.T6G(SCH_1):M_E_CPU0_SA_CB(3)
   U25 AL69 MEA_CHECK3 GENOA_SP5-SOCKET6096_13568-001,SMLF,IO,DGA^6000030   I159 @T6G_MB_LIB.T6G(SCH_1):PAGE14
   J21  198  CB3_A SCONN288_DDR506112002KQ-SCONN288_DDR506112002KQ,SMA   I348 @T6G_MB_LIB.T6G(SCH_1):PAGE89

M_E_CPU0_SA_CB<4> @T6G_MB_LIB.T6G(SCH_1):M_E_CPU0_SA_CB(4)
   U25 AN71 MEA_CHECK4 GENOA_SP5-SOCKET6096_13568-001,SMLF,IO,DGA^6000030   I159 @T6G_MB_LIB.T6G(SCH_1):PAGE14
   J21   58  CB4_A SCONN288_DDR506112002KQ-SCONN288_DDR506112002KQ,SMA   I348 @T6G_MB_LIB.T6G(SCH_1):PAGE89

M_E_CPU0_SA_CB<5> @T6G_MB_LIB.T6G(SCH_1):M_E_CPU0_SA_CB(5)
   U25 AP69 MEA_CHECK5 GENOA_SP5-SOCKET6096_13568-001,SMLF,IO,DGA^6000030   I159 @T6G_MB_LIB.T6G(SCH_1):PAGE14
   J21   60  CB5_A SCONN288_DDR506112002KQ-SCONN288_DDR506112002KQ,SMA   I348 @T6G_MB_LIB.T6G(SCH_1):PAGE89

M_E_CPU0_SA_CB<6> @T6G_MB_LIB.T6G(SCH_1):M_E_CPU0_SA_CB(6)
   U25 AP70 MEA_CHECK6 GENOA_SP5-SOCKET6096_13568-001,SMLF,IO,DGA^6000030   I159 @T6G_MB_LIB.T6G(SCH_1):PAGE14
   J21  203  CB6_A SCONN288_DDR506112002KQ-SCONN288_DDR506112002KQ,SMA   I348 @T6G_MB_LIB.T6G(SCH_1):PAGE89

M_E_CPU0_SA_CB<7> @T6G_MB_LIB.T6G(SCH_1):M_E_CPU0_SA_CB(7)
   U25 AR69 MEA_CHECK7 GENOA_SP5-SOCKET6096_13568-001,SMLF,IO,DGA^6000030   I159 @T6G_MB_LIB.T6G(SCH_1):PAGE14
   J21  205  CB7_A SCONN288_DDR506112002KQ-SCONN288_DDR506112002KQ,SMA   I348 @T6G_MB_LIB.T6G(SCH_1):PAGE89

M_E_CPU0_SA_CS_N<0> @T6G_MB_LIB.T6G(SCH_1):M_E_CPU0_SA_CS_N(0)
   U25 AV70 MEA0_CS_L0 GENOA_SP5-SOCKET6096_13568-001,SMLF,IO,DGA^6000030   I159 @T6G_MB_LIB.T6G(SCH_1):PAGE14
   J21   64 CS0_A_N SCONN288_DDR506112002KQ-SCONN288_DDR506112002KQ,SMA   I348 @T6G_MB_LIB.T6G(SCH_1):PAGE89

M_E_CPU0_SA_CS_N<1> @T6G_MB_LIB.T6G(SCH_1):M_E_CPU0_SA_CS_N(1)
   U25 AW69 MEA0_CS_L1 GENOA_SP5-SOCKET6096_13568-001,SMLF,IO,DGA^6000030   I159 @T6G_MB_LIB.T6G(SCH_1):PAGE14
   J21  209 CS1_A_N SCONN288_DDR506112002KQ-SCONN288_DDR506112002KQ,SMA   I348 @T6G_MB_LIB.T6G(SCH_1):PAGE89

M_E_CPU0_SA_DQ<0> @T6G_MB_LIB.T6G(SCH_1):M_E_CPU0_SA_DQ(0)
   U25  E71 MEA_DATA0 GENOA_SP5-SOCKET6096_13568-001,SMLF,IO,DGA^6000030   I159 @T6G_MB_LIB.T6G(SCH_1):PAGE14
   J21    7  DQ0_A SCONN288_DDR506112002KQ-SCONN288_DDR506112002KQ,SMA   I348 @T6G_MB_LIB.T6G(SCH_1):PAGE89

M_E_CPU0_SA_DQ<10> @T6G_MB_LIB.T6G(SCH_1):M_E_CPU0_SA_DQ(10)
   U25  M70 MEA_DATA10 GENOA_SP5-SOCKET6096_13568-001,SMLF,IO,DGA^6000030   I159 @T6G_MB_LIB.T6G(SCH_1):PAGE14
   J21  163 DQ10_A SCONN288_DDR506112002KQ-SCONN288_DDR506112002KQ,SMA   I348 @T6G_MB_LIB.T6G(SCH_1):PAGE89

M_E_CPU0_SA_DQ<11> @T6G_MB_LIB.T6G(SCH_1):M_E_CPU0_SA_DQ(11)
   U25  N69 MEA_DATA11 GENOA_SP5-SOCKET6096_13568-001,SMLF,IO,DGA^6000030   I159 @T6G_MB_LIB.T6G(SCH_1):PAGE14
   J21  165 DQ11_A SCONN288_DDR506112002KQ-SCONN288_DDR506112002KQ,SMA   I348 @T6G_MB_LIB.T6G(SCH_1):PAGE89

M_E_CPU0_SA_DQ<12> @T6G_MB_LIB.T6G(SCH_1):M_E_CPU0_SA_DQ(12)
   U25  R71 MEA_DATA12 GENOA_SP5-SOCKET6096_13568-001,SMLF,IO,DGA^6000030   I159 @T6G_MB_LIB.T6G(SCH_1):PAGE14
   J21   25 DQ12_A SCONN288_DDR506112002KQ-SCONN288_DDR506112002KQ,SMA   I348 @T6G_MB_LIB.T6G(SCH_1):PAGE89

M_E_CPU0_SA_DQ<13> @T6G_MB_LIB.T6G(SCH_1):M_E_CPU0_SA_DQ(13)
   U25  T69 MEA_DATA13 GENOA_SP5-SOCKET6096_13568-001,SMLF,IO,DGA^6000030   I159 @T6G_MB_LIB.T6G(SCH_1):PAGE14
   J21   27 DQ13_A SCONN288_DDR506112002KQ-SCONN288_DDR506112002KQ,SMA   I348 @T6G_MB_LIB.T6G(SCH_1):PAGE89

M_E_CPU0_SA_DQ<14> @T6G_MB_LIB.T6G(SCH_1):M_E_CPU0_SA_DQ(14)
   U25  T70 MEA_DATA14 GENOA_SP5-SOCKET6096_13568-001,SMLF,IO,DGA^6000030   I159 @T6G_MB_LIB.T6G(SCH_1):PAGE14
   J21  170 DQ14_A SCONN288_DDR506112002KQ-SCONN288_DDR506112002KQ,SMA   I348 @T6G_MB_LIB.T6G(SCH_1):PAGE89

M_E_CPU0_SA_DQ<15> @T6G_MB_LIB.T6G(SCH_1):M_E_CPU0_SA_DQ(15)
   U25  U69 MEA_DATA15 GENOA_SP5-SOCKET6096_13568-001,SMLF,IO,DGA^6000030   I159 @T6G_MB_LIB.T6G(SCH_1):PAGE14
   J21  172 DQ15_A SCONN288_DDR506112002KQ-SCONN288_DDR506112002KQ,SMA   I348 @T6G_MB_LIB.T6G(SCH_1):PAGE89

M_E_CPU0_SA_DQ<16> @T6G_MB_LIB.T6G(SCH_1):M_E_CPU0_SA_DQ(16)
   U25  U71 MEA_DATA16 GENOA_SP5-SOCKET6096_13568-001,SMLF,IO,DGA^6000030   I159 @T6G_MB_LIB.T6G(SCH_1):PAGE14
   J21   29 DQ16_A SCONN288_DDR506112002KQ-SCONN288_DDR506112002KQ,SMA   I348 @T6G_MB_LIB.T6G(SCH_1):PAGE89

M_E_CPU0_SA_DQ<17> @T6G_MB_LIB.T6G(SCH_1):M_E_CPU0_SA_DQ(17)
   U25  V69 MEA_DATA17 GENOA_SP5-SOCKET6096_13568-001,SMLF,IO,DGA^6000030   I159 @T6G_MB_LIB.T6G(SCH_1):PAGE14
   J21   31 DQ17_A SCONN288_DDR506112002KQ-SCONN288_DDR506112002KQ,SMA   I348 @T6G_MB_LIB.T6G(SCH_1):PAGE89

M_E_CPU0_SA_DQ<18> @T6G_MB_LIB.T6G(SCH_1):M_E_CPU0_SA_DQ(18)
   U25  V70 MEA_DATA18 GENOA_SP5-SOCKET6096_13568-001,SMLF,IO,DGA^6000030   I159 @T6G_MB_LIB.T6G(SCH_1):PAGE14
   J21  174 DQ18_A SCONN288_DDR506112002KQ-SCONN288_DDR506112002KQ,SMA   I348 @T6G_MB_LIB.T6G(SCH_1):PAGE89

M_E_CPU0_SA_DQ<19> @T6G_MB_LIB.T6G(SCH_1):M_E_CPU0_SA_DQ(19)
   U25  W69 MEA_DATA19 GENOA_SP5-SOCKET6096_13568-001,SMLF,IO,DGA^6000030   I159 @T6G_MB_LIB.T6G(SCH_1):PAGE14
   J21  176 DQ19_A SCONN288_DDR506112002KQ-SCONN288_DDR506112002KQ,SMA   I348 @T6G_MB_LIB.T6G(SCH_1):PAGE89

M_E_CPU0_SA_DQ<1> @T6G_MB_LIB.T6G(SCH_1):M_E_CPU0_SA_DQ(1)
   U25  F69 MEA_DATA1 GENOA_SP5-SOCKET6096_13568-001,SMLF,IO,DGA^6000030   I159 @T6G_MB_LIB.T6G(SCH_1):PAGE14
   J21    9  DQ1_A SCONN288_DDR506112002KQ-SCONN288_DDR506112002KQ,SMA   I348 @T6G_MB_LIB.T6G(SCH_1):PAGE89

M_E_CPU0_SA_DQ<20> @T6G_MB_LIB.T6G(SCH_1):M_E_CPU0_SA_DQ(20)
   U25 AA71 MEA_DATA20 GENOA_SP5-SOCKET6096_13568-001,SMLF,IO,DGA^6000030   I159 @T6G_MB_LIB.T6G(SCH_1):PAGE14
   J21   36 DQ20_A SCONN288_DDR506112002KQ-SCONN288_DDR506112002KQ,SMA   I348 @T6G_MB_LIB.T6G(SCH_1):PAGE89

M_E_CPU0_SA_DQ<21> @T6G_MB_LIB.T6G(SCH_1):M_E_CPU0_SA_DQ(21)
   U25 AB69 MEA_DATA21 GENOA_SP5-SOCKET6096_13568-001,SMLF,IO,DGA^6000030   I159 @T6G_MB_LIB.T6G(SCH_1):PAGE14
   J21   38 DQ21_A SCONN288_DDR506112002KQ-SCONN288_DDR506112002KQ,SMA   I348 @T6G_MB_LIB.T6G(SCH_1):PAGE89

M_E_CPU0_SA_DQ<22> @T6G_MB_LIB.T6G(SCH_1):M_E_CPU0_SA_DQ(22)
   U25 AB70 MEA_DATA22 GENOA_SP5-SOCKET6096_13568-001,SMLF,IO,DGA^6000030   I159 @T6G_MB_LIB.T6G(SCH_1):PAGE14
   J21  181 DQ22_A SCONN288_DDR506112002KQ-SCONN288_DDR506112002KQ,SMA   I348 @T6G_MB_LIB.T6G(SCH_1):PAGE89

M_E_CPU0_SA_DQ<23> @T6G_MB_LIB.T6G(SCH_1):M_E_CPU0_SA_DQ(23)
   U25 AC69 MEA_DATA23 GENOA_SP5-SOCKET6096_13568-001,SMLF,IO,DGA^6000030   I159 @T6G_MB_LIB.T6G(SCH_1):PAGE14
   J21  183 DQ23_A SCONN288_DDR506112002KQ-SCONN288_DDR506112002KQ,SMA   I348 @T6G_MB_LIB.T6G(SCH_1):PAGE89

M_E_CPU0_SA_DQ<24> @T6G_MB_LIB.T6G(SCH_1):M_E_CPU0_SA_DQ(24)
   U25 AC71 MEA_DATA24 GENOA_SP5-SOCKET6096_13568-001,SMLF,IO,DGA^6000030   I159 @T6G_MB_LIB.T6G(SCH_1):PAGE14
   J21   40 DQ24_A SCONN288_DDR506112002KQ-SCONN288_DDR506112002KQ,SMA   I348 @T6G_MB_LIB.T6G(SCH_1):PAGE89

M_E_CPU0_SA_DQ<25> @T6G_MB_LIB.T6G(SCH_1):M_E_CPU0_SA_DQ(25)
   U25 AD69 MEA_DATA25 GENOA_SP5-SOCKET6096_13568-001,SMLF,IO,DGA^6000030   I159 @T6G_MB_LIB.T6G(SCH_1):PAGE14
   J21   42 DQ25_A SCONN288_DDR506112002KQ-SCONN288_DDR506112002KQ,SMA   I348 @T6G_MB_LIB.T6G(SCH_1):PAGE89

M_E_CPU0_SA_DQ<26> @T6G_MB_LIB.T6G(SCH_1):M_E_CPU0_SA_DQ(26)
   U25 AD70 MEA_DATA26 GENOA_SP5-SOCKET6096_13568-001,SMLF,IO,DGA^6000030   I159 @T6G_MB_LIB.T6G(SCH_1):PAGE14
   J21  185 DQ26_A SCONN288_DDR506112002KQ-SCONN288_DDR506112002KQ,SMA   I348 @T6G_MB_LIB.T6G(SCH_1):PAGE89

M_E_CPU0_SA_DQ<27> @T6G_MB_LIB.T6G(SCH_1):M_E_CPU0_SA_DQ(27)
   U25 AE69 MEA_DATA27 GENOA_SP5-SOCKET6096_13568-001,SMLF,IO,DGA^6000030   I159 @T6G_MB_LIB.T6G(SCH_1):PAGE14
   J21  187 DQ27_A SCONN288_DDR506112002KQ-SCONN288_DDR506112002KQ,SMA   I348 @T6G_MB_LIB.T6G(SCH_1):PAGE89

M_E_CPU0_SA_DQ<28> @T6G_MB_LIB.T6G(SCH_1):M_E_CPU0_SA_DQ(28)
   U25 AG71 MEA_DATA28 GENOA_SP5-SOCKET6096_13568-001,SMLF,IO,DGA^6000030   I159 @T6G_MB_LIB.T6G(SCH_1):PAGE14
   J21   47 DQ28_A SCONN288_DDR506112002KQ-SCONN288_DDR506112002KQ,SMA   I348 @T6G_MB_LIB.T6G(SCH_1):PAGE89

M_E_CPU0_SA_DQ<29> @T6G_MB_LIB.T6G(SCH_1):M_E_CPU0_SA_DQ(29)
   U25 AH69 MEA_DATA29 GENOA_SP5-SOCKET6096_13568-001,SMLF,IO,DGA^6000030   I159 @T6G_MB_LIB.T6G(SCH_1):PAGE14
   J21   49 DQ29_A SCONN288_DDR506112002KQ-SCONN288_DDR506112002KQ,SMA   I348 @T6G_MB_LIB.T6G(SCH_1):PAGE89

M_E_CPU0_SA_DQ<2> @T6G_MB_LIB.T6G(SCH_1):M_E_CPU0_SA_DQ(2)
   U25  F70 MEA_DATA2 GENOA_SP5-SOCKET6096_13568-001,SMLF,IO,DGA^6000030   I159 @T6G_MB_LIB.T6G(SCH_1):PAGE14
   J21  152  DQ2_A SCONN288_DDR506112002KQ-SCONN288_DDR506112002KQ,SMA   I348 @T6G_MB_LIB.T6G(SCH_1):PAGE89

M_E_CPU0_SA_DQ<30> @T6G_MB_LIB.T6G(SCH_1):M_E_CPU0_SA_DQ(30)
   U25 AH70 MEA_DATA30 GENOA_SP5-SOCKET6096_13568-001,SMLF,IO,DGA^6000030   I159 @T6G_MB_LIB.T6G(SCH_1):PAGE14
   J21  192 DQ30_A SCONN288_DDR506112002KQ-SCONN288_DDR506112002KQ,SMA   I348 @T6G_MB_LIB.T6G(SCH_1):PAGE89

M_E_CPU0_SA_DQ<31> @T6G_MB_LIB.T6G(SCH_1):M_E_CPU0_SA_DQ(31)
   U25 AJ69 MEA_DATA31 GENOA_SP5-SOCKET6096_13568-001,SMLF,IO,DGA^6000030   I159 @T6G_MB_LIB.T6G(SCH_1):PAGE14
   J21  194 DQ31_A SCONN288_DDR506112002KQ-SCONN288_DDR506112002KQ,SMA   I348 @T6G_MB_LIB.T6G(SCH_1):PAGE89

M_E_CPU0_SA_DQ<3> @T6G_MB_LIB.T6G(SCH_1):M_E_CPU0_SA_DQ(3)
   U25  G69 MEA_DATA3 GENOA_SP5-SOCKET6096_13568-001,SMLF,IO,DGA^6000030   I159 @T6G_MB_LIB.T6G(SCH_1):PAGE14
   J21  154  DQ3_A SCONN288_DDR506112002KQ-SCONN288_DDR506112002KQ,SMA   I348 @T6G_MB_LIB.T6G(SCH_1):PAGE89

M_E_CPU0_SA_DQ<4> @T6G_MB_LIB.T6G(SCH_1):M_E_CPU0_SA_DQ(4)
   U25  J71 MEA_DATA4 GENOA_SP5-SOCKET6096_13568-001,SMLF,IO,DGA^6000030   I159 @T6G_MB_LIB.T6G(SCH_1):PAGE14
   J21   14  DQ4_A SCONN288_DDR506112002KQ-SCONN288_DDR506112002KQ,SMA   I348 @T6G_MB_LIB.T6G(SCH_1):PAGE89

M_E_CPU0_SA_DQ<5> @T6G_MB_LIB.T6G(SCH_1):M_E_CPU0_SA_DQ(5)
   U25  K69 MEA_DATA5 GENOA_SP5-SOCKET6096_13568-001,SMLF,IO,DGA^6000030   I159 @T6G_MB_LIB.T6G(SCH_1):PAGE14
   J21   16  DQ5_A SCONN288_DDR506112002KQ-SCONN288_DDR506112002KQ,SMA   I348 @T6G_MB_LIB.T6G(SCH_1):PAGE89

M_E_CPU0_SA_DQ<6> @T6G_MB_LIB.T6G(SCH_1):M_E_CPU0_SA_DQ(6)
   U25  K70 MEA_DATA6 GENOA_SP5-SOCKET6096_13568-001,SMLF,IO,DGA^6000030   I159 @T6G_MB_LIB.T6G(SCH_1):PAGE14
   J21  159  DQ6_A SCONN288_DDR506112002KQ-SCONN288_DDR506112002KQ,SMA   I348 @T6G_MB_LIB.T6G(SCH_1):PAGE89

M_E_CPU0_SA_DQ<7> @T6G_MB_LIB.T6G(SCH_1):M_E_CPU0_SA_DQ(7)
   U25  L69 MEA_DATA7 GENOA_SP5-SOCKET6096_13568-001,SMLF,IO,DGA^6000030   I159 @T6G_MB_LIB.T6G(SCH_1):PAGE14
   J21  161  DQ7_A SCONN288_DDR506112002KQ-SCONN288_DDR506112002KQ,SMA   I348 @T6G_MB_LIB.T6G(SCH_1):PAGE89

M_E_CPU0_SA_DQ<8> @T6G_MB_LIB.T6G(SCH_1):M_E_CPU0_SA_DQ(8)
   U25  L71 MEA_DATA8 GENOA_SP5-SOCKET6096_13568-001,SMLF,IO,DGA^6000030   I159 @T6G_MB_LIB.T6G(SCH_1):PAGE14
   J21   18  DQ8_A SCONN288_DDR506112002KQ-SCONN288_DDR506112002KQ,SMA   I348 @T6G_MB_LIB.T6G(SCH_1):PAGE89

M_E_CPU0_SA_DQ<9> @T6G_MB_LIB.T6G(SCH_1):M_E_CPU0_SA_DQ(9)
   U25  M69 MEA_DATA9 GENOA_SP5-SOCKET6096_13568-001,SMLF,IO,DGA^6000030   I159 @T6G_MB_LIB.T6G(SCH_1):PAGE14
   J21   20  DQ9_A SCONN288_DDR506112002KQ-SCONN288_DDR506112002KQ,SMA   I348 @T6G_MB_LIB.T6G(SCH_1):PAGE89

M_E_CPU0_SA_DQS_DN<0> @T6G_MB_LIB.T6G(SCH_1):M_E_CPU0_SA_DQS_DN(0)
   U25  H70 MEA_DQS_L0 GENOA_SP5-SOCKET6096_13568-001,SMLF,IO,DGA^6000030   I159 @T6G_MB_LIB.T6G(SCH_1):PAGE14
   J21   12 DQS0_A_C SCONN288_DDR506112002KQ-SCONN288_DDR506112002KQ,SMA   I410 @T6G_MB_LIB.T6G(SCH_1):PAGE89

M_E_CPU0_SA_DQS_DN<1> @T6G_MB_LIB.T6G(SCH_1):M_E_CPU0_SA_DQS_DN(1)
   U25  P70 MEA_DQS_L1 GENOA_SP5-SOCKET6096_13568-001,SMLF,IO,DGA^6000030   I159 @T6G_MB_LIB.T6G(SCH_1):PAGE14
   J21   23 DQS1_A_C SCONN288_DDR506112002KQ-SCONN288_DDR506112002KQ,SMA   I410 @T6G_MB_LIB.T6G(SCH_1):PAGE89

M_E_CPU0_SA_DQS_DN<2> @T6G_MB_LIB.T6G(SCH_1):M_E_CPU0_SA_DQS_DN(2)
   U25  Y70 MEA_DQS_L2 GENOA_SP5-SOCKET6096_13568-001,SMLF,IO,DGA^6000030   I159 @T6G_MB_LIB.T6G(SCH_1):PAGE14
   J21   34 DQS2_A_C SCONN288_DDR506112002KQ-SCONN288_DDR506112002KQ,SMA   I410 @T6G_MB_LIB.T6G(SCH_1):PAGE89

M_E_CPU0_SA_DQS_DN<3> @T6G_MB_LIB.T6G(SCH_1):M_E_CPU0_SA_DQS_DN(3)
   U25 AF70 MEA_DQS_L3 GENOA_SP5-SOCKET6096_13568-001,SMLF,IO,DGA^6000030   I159 @T6G_MB_LIB.T6G(SCH_1):PAGE14
   J21   45 DQS3_A_C SCONN288_DDR506112002KQ-SCONN288_DDR506112002KQ,SMA   I410 @T6G_MB_LIB.T6G(SCH_1):PAGE89

M_E_CPU0_SA_DQS_DN<4> @T6G_MB_LIB.T6G(SCH_1):M_E_CPU0_SA_DQS_DN(4)
   U25 AM70 MEA_DQS_L4 GENOA_SP5-SOCKET6096_13568-001,SMLF,IO,DGA^6000030   I159 @T6G_MB_LIB.T6G(SCH_1):PAGE14
   J21   56 DQS4_A_C SCONN288_DDR506112002KQ-SCONN288_DDR506112002KQ,SMA   I410 @T6G_MB_LIB.T6G(SCH_1):PAGE89

M_E_CPU0_SA_DQS_DN<5> @T6G_MB_LIB.T6G(SCH_1):M_E_CPU0_SA_DQS_DN(5)
   U25  H69 MEA_DQS_L5 GENOA_SP5-SOCKET6096_13568-001,SMLF,IO,DGA^6000030   I159 @T6G_MB_LIB.T6G(SCH_1):PAGE14
   J21  156 DQS5_A_C||TDQS5_A_C||DQS5_A_T||TDQS5_A_T SCONN288_DDR506112002KQ-SCONN288_DDR506112002KQ,SMA   I410 @T6G_MB_LIB.T6G(SCH_1):PAGE89

M_E_CPU0_SA_DQS_DN<6> @T6G_MB_LIB.T6G(SCH_1):M_E_CPU0_SA_DQS_DN(6)
   U25  P69 MEA_DQS_L6 GENOA_SP5-SOCKET6096_13568-001,SMLF,IO,DGA^6000030   I159 @T6G_MB_LIB.T6G(SCH_1):PAGE14
   J21  167 DQS6_A_C||TDQS6_A_C||DQS6_A_T||TDQS6_A_T SCONN288_DDR506112002KQ-SCONN288_DDR506112002KQ,SMA   I410 @T6G_MB_LIB.T6G(SCH_1):PAGE89

M_E_CPU0_SA_DQS_DN<7> @T6G_MB_LIB.T6G(SCH_1):M_E_CPU0_SA_DQS_DN(7)
   U25  Y69 MEA_DQS_L7 GENOA_SP5-SOCKET6096_13568-001,SMLF,IO,DGA^6000030   I159 @T6G_MB_LIB.T6G(SCH_1):PAGE14
   J21  178 DQS7_A_C||TDQS7_A_C SCONN288_DDR506112002KQ-SCONN288_DDR506112002KQ,SMA   I410 @T6G_MB_LIB.T6G(SCH_1):PAGE89

M_E_CPU0_SA_DQS_DN<8> @T6G_MB_LIB.T6G(SCH_1):M_E_CPU0_SA_DQS_DN(8)
   U25 AF69 MEA_DQS_L8 GENOA_SP5-SOCKET6096_13568-001,SMLF,IO,DGA^6000030   I159 @T6G_MB_LIB.T6G(SCH_1):PAGE14
   J21  189 DQS8_A_C||TDQS8_A_C SCONN288_DDR506112002KQ-SCONN288_DDR506112002KQ,SMA   I410 @T6G_MB_LIB.T6G(SCH_1):PAGE89

M_E_CPU0_SA_DQS_DN<9> @T6G_MB_LIB.T6G(SCH_1):M_E_CPU0_SA_DQS_DN(9)
   U25 AM69 MEA_DQS_L9 GENOA_SP5-SOCKET6096_13568-001,SMLF,IO,DGA^6000030   I159 @T6G_MB_LIB.T6G(SCH_1):PAGE14
   J21  200 DQS9_A_C||TDQS9_A_C SCONN288_DDR506112002KQ-SCONN288_DDR506112002KQ,SMA   I410 @T6G_MB_LIB.T6G(SCH_1):PAGE89

M_E_CPU0_SA_DQS_DP<0> @T6G_MB_LIB.T6G(SCH_1):M_E_CPU0_SA_DQS_DP(0)
   U25  G71 MEA_DQS_H0 GENOA_SP5-SOCKET6096_13568-001,SMLF,IO,DGA^6000030   I159 @T6G_MB_LIB.T6G(SCH_1):PAGE14
   J21   11 DQS0_A_T SCONN288_DDR506112002KQ-SCONN288_DDR506112002KQ,SMA   I410 @T6G_MB_LIB.T6G(SCH_1):PAGE89

M_E_CPU0_SA_DQS_DP<1> @T6G_MB_LIB.T6G(SCH_1):M_E_CPU0_SA_DQS_DP(1)
   U25  N71 MEA_DQS_H1 GENOA_SP5-SOCKET6096_13568-001,SMLF,IO,DGA^6000030   I159 @T6G_MB_LIB.T6G(SCH_1):PAGE14
   J21   22 DQS1_A_T SCONN288_DDR506112002KQ-SCONN288_DDR506112002KQ,SMA   I410 @T6G_MB_LIB.T6G(SCH_1):PAGE89

M_E_CPU0_SA_DQS_DP<2> @T6G_MB_LIB.T6G(SCH_1):M_E_CPU0_SA_DQS_DP(2)
   U25  W71 MEA_DQS_H2 GENOA_SP5-SOCKET6096_13568-001,SMLF,IO,DGA^6000030   I159 @T6G_MB_LIB.T6G(SCH_1):PAGE14
   J21   33 DQS2_A_T SCONN288_DDR506112002KQ-SCONN288_DDR506112002KQ,SMA   I410 @T6G_MB_LIB.T6G(SCH_1):PAGE89

M_E_CPU0_SA_DQS_DP<3> @T6G_MB_LIB.T6G(SCH_1):M_E_CPU0_SA_DQS_DP(3)
   U25 AE71 MEA_DQS_H3 GENOA_SP5-SOCKET6096_13568-001,SMLF,IO,DGA^6000030   I159 @T6G_MB_LIB.T6G(SCH_1):PAGE14
   J21   44 DQS3_A_T SCONN288_DDR506112002KQ-SCONN288_DDR506112002KQ,SMA   I410 @T6G_MB_LIB.T6G(SCH_1):PAGE89

M_E_CPU0_SA_DQS_DP<4> @T6G_MB_LIB.T6G(SCH_1):M_E_CPU0_SA_DQS_DP(4)
   U25 AL71 MEA_DQS_H4 GENOA_SP5-SOCKET6096_13568-001,SMLF,IO,DGA^6000030   I159 @T6G_MB_LIB.T6G(SCH_1):PAGE14
   J21   55 DQS4_A_T SCONN288_DDR506112002KQ-SCONN288_DDR506112002KQ,SMA   I410 @T6G_MB_LIB.T6G(SCH_1):PAGE89

M_E_CPU0_SA_DQS_DP<5> @T6G_MB_LIB.T6G(SCH_1):M_E_CPU0_SA_DQS_DP(5)
   U25  J69 MEA_DQS_H5 GENOA_SP5-SOCKET6096_13568-001,SMLF,IO,DGA^6000030   I159 @T6G_MB_LIB.T6G(SCH_1):PAGE14
   J21  157 DQS5_A_T||TDQS5_A_T SCONN288_DDR506112002KQ-SCONN288_DDR506112002KQ,SMA   I410 @T6G_MB_LIB.T6G(SCH_1):PAGE89

M_E_CPU0_SA_DQS_DP<6> @T6G_MB_LIB.T6G(SCH_1):M_E_CPU0_SA_DQS_DP(6)
   U25  R69 MEA_DQS_H6 GENOA_SP5-SOCKET6096_13568-001,SMLF,IO,DGA^6000030   I159 @T6G_MB_LIB.T6G(SCH_1):PAGE14
   J21  168 DQS6_A_T||TDQS6_A_T SCONN288_DDR506112002KQ-SCONN288_DDR506112002KQ,SMA   I410 @T6G_MB_LIB.T6G(SCH_1):PAGE89

M_E_CPU0_SA_DQS_DP<7> @T6G_MB_LIB.T6G(SCH_1):M_E_CPU0_SA_DQS_DP(7)
   U25 AA69 MEA_DQS_H7 GENOA_SP5-SOCKET6096_13568-001,SMLF,IO,DGA^6000030   I159 @T6G_MB_LIB.T6G(SCH_1):PAGE14
   J21  179 DQS7_A_T||TDQS7_A_T SCONN288_DDR506112002KQ-SCONN288_DDR506112002KQ,SMA   I410 @T6G_MB_LIB.T6G(SCH_1):PAGE89

M_E_CPU0_SA_DQS_DP<8> @T6G_MB_LIB.T6G(SCH_1):M_E_CPU0_SA_DQS_DP(8)
   U25 AG69 MEA_DQS_H8 GENOA_SP5-SOCKET6096_13568-001,SMLF,IO,DGA^6000030   I159 @T6G_MB_LIB.T6G(SCH_1):PAGE14
   J21  190 DQS8_A_T||TDQS8_A_T SCONN288_DDR506112002KQ-SCONN288_DDR506112002KQ,SMA   I410 @T6G_MB_LIB.T6G(SCH_1):PAGE89

M_E_CPU0_SA_DQS_DP<9> @T6G_MB_LIB.T6G(SCH_1):M_E_CPU0_SA_DQS_DP(9)
   U25 AN69 MEA_DQS_H9 GENOA_SP5-SOCKET6096_13568-001,SMLF,IO,DGA^6000030   I159 @T6G_MB_LIB.T6G(SCH_1):PAGE14
   J21  201 DQS9_A_T||TDQS9_A_T SCONN288_DDR506112002KQ-SCONN288_DDR506112002KQ,SMA   I410 @T6G_MB_LIB.T6G(SCH_1):PAGE89

M_E_CPU0_SA_PAR @T6G_MB_LIB.T6G(SCH_1):M_E_CPU0_SA_PAR
   U25 BC69 MEA_PAR GENOA_SP5-SOCKET6096_13568-001,SMLF,IO,DGA^6000030   I159 @T6G_MB_LIB.T6G(SCH_1):PAGE14
   J21   74  PAR_A SCONN288_DDR506112002KQ-SCONN288_DDR506112002KQ,SMA   I348 @T6G_MB_LIB.T6G(SCH_1):PAGE89

M_E_CPU0_SA_RSP<0> @T6G_MB_LIB.T6G(SCH_1):M_E_CPU0_SA_RSP(0)
   U25 BN69 MEA0_RSP_L GENOA_SP5-SOCKET6096_13568-001,SMLF,IO,DGA^6000030   I159 @T6G_MB_LIB.T6G(SCH_1):PAGE14
   J21   86 LBD||RSP_A_N SCONN288_DDR506112002KQ-SCONN288_DDR506112002KQ,SMA   I348 @T6G_MB_LIB.T6G(SCH_1):PAGE89

M_E_CPU0_SB_CA<0> @T6G_MB_LIB.T6G(SCH_1):M_E_CPU0_SB_CA(0)
   U25 BG69 MEB_CA0 GENOA_SP5-SOCKET6096_13568-001,SMLF,IO,DGA^6000030   I159 @T6G_MB_LIB.T6G(SCH_1):PAGE14
   J21   76  CA0_B SCONN288_DDR506112002KQ-SCONN288_DDR506112002KQ,SMA   I348 @T6G_MB_LIB.T6G(SCH_1):PAGE89

M_E_CPU0_SB_CA<1> @T6G_MB_LIB.T6G(SCH_1):M_E_CPU0_SB_CA(1)
   U25 BH69 MEB_CA1 GENOA_SP5-SOCKET6096_13568-001,SMLF,IO,DGA^6000030   I159 @T6G_MB_LIB.T6G(SCH_1):PAGE14
   J21  221  CA1_B SCONN288_DDR506112002KQ-SCONN288_DDR506112002KQ,SMA   I348 @T6G_MB_LIB.T6G(SCH_1):PAGE89

M_E_CPU0_SB_CA<2> @T6G_MB_LIB.T6G(SCH_1):M_E_CPU0_SB_CA(2)
   U25 BH70 MEB_CA2 GENOA_SP5-SOCKET6096_13568-001,SMLF,IO,DGA^6000030   I159 @T6G_MB_LIB.T6G(SCH_1):PAGE14
   J21   78  CA2_B SCONN288_DDR506112002KQ-SCONN288_DDR506112002KQ,SMA   I348 @T6G_MB_LIB.T6G(SCH_1):PAGE89

M_E_CPU0_SB_CA<3> @T6G_MB_LIB.T6G(SCH_1):M_E_CPU0_SB_CA(3)
   U25 BJ71 MEB_CA3 GENOA_SP5-SOCKET6096_13568-001,SMLF,IO,DGA^6000030   I159 @T6G_MB_LIB.T6G(SCH_1):PAGE14
   J21  223  CA3_B SCONN288_DDR506112002KQ-SCONN288_DDR506112002KQ,SMA   I348 @T6G_MB_LIB.T6G(SCH_1):PAGE89

M_E_CPU0_SB_CA<4> @T6G_MB_LIB.T6G(SCH_1):M_E_CPU0_SB_CA(4)
   U25 BJ69 MEB_CA4 GENOA_SP5-SOCKET6096_13568-001,SMLF,IO,DGA^6000030   I159 @T6G_MB_LIB.T6G(SCH_1):PAGE14
   J21   80  CA4_B SCONN288_DDR506112002KQ-SCONN288_DDR506112002KQ,SMA   I348 @T6G_MB_LIB.T6G(SCH_1):PAGE89

M_E_CPU0_SB_CA<5> @T6G_MB_LIB.T6G(SCH_1):M_E_CPU0_SB_CA(5)
   U25 BK69 MEB_CA5 GENOA_SP5-SOCKET6096_13568-001,SMLF,IO,DGA^6000030   I159 @T6G_MB_LIB.T6G(SCH_1):PAGE14
   J21  225  CA5_B SCONN288_DDR506112002KQ-SCONN288_DDR506112002KQ,SMA   I348 @T6G_MB_LIB.T6G(SCH_1):PAGE89

M_E_CPU0_SB_CA<6> @T6G_MB_LIB.T6G(SCH_1):M_E_CPU0_SB_CA(6)
   U25 BK70 MEB_CA6 GENOA_SP5-SOCKET6096_13568-001,SMLF,IO,DGA^6000030   I159 @T6G_MB_LIB.T6G(SCH_1):PAGE14
   J21   82  CA6_B SCONN288_DDR506112002KQ-SCONN288_DDR506112002KQ,SMA   I348 @T6G_MB_LIB.T6G(SCH_1):PAGE89

M_E_CPU0_SB_CB<0> @T6G_MB_LIB.T6G(SCH_1):M_E_CPU0_SB_CB(0)
   U25 BY70 MEB_CHECK0 GENOA_SP5-SOCKET6096_13568-001,SMLF,IO,DGA^6000030   I159 @T6G_MB_LIB.T6G(SCH_1):PAGE14
   J21   96  CB0_B SCONN288_DDR506112002KQ-SCONN288_DDR506112002KQ,SMA   I348 @T6G_MB_LIB.T6G(SCH_1):PAGE89

M_E_CPU0_SB_CB<1> @T6G_MB_LIB.T6G(SCH_1):M_E_CPU0_SB_CB(1)
   U25 CA69 MEB_CHECK1 GENOA_SP5-SOCKET6096_13568-001,SMLF,IO,DGA^6000030   I159 @T6G_MB_LIB.T6G(SCH_1):PAGE14
   J21   98  CB1_B SCONN288_DDR506112002KQ-SCONN288_DDR506112002KQ,SMA   I348 @T6G_MB_LIB.T6G(SCH_1):PAGE89

M_E_CPU0_SB_CB<2> @T6G_MB_LIB.T6G(SCH_1):M_E_CPU0_SB_CB(2)
   U25 CA71 MEB_CHECK2 GENOA_SP5-SOCKET6096_13568-001,SMLF,IO,DGA^6000030   I159 @T6G_MB_LIB.T6G(SCH_1):PAGE14
   J21  241  CB2_B SCONN288_DDR506112002KQ-SCONN288_DDR506112002KQ,SMA   I348 @T6G_MB_LIB.T6G(SCH_1):PAGE89

M_E_CPU0_SB_CB<3> @T6G_MB_LIB.T6G(SCH_1):M_E_CPU0_SB_CB(3)
   U25 CB69 MEB_CHECK3 GENOA_SP5-SOCKET6096_13568-001,SMLF,IO,DGA^6000030   I159 @T6G_MB_LIB.T6G(SCH_1):PAGE14
   J21  243  CB3_B SCONN288_DDR506112002KQ-SCONN288_DDR506112002KQ,SMA   I348 @T6G_MB_LIB.T6G(SCH_1):PAGE89

M_E_CPU0_SB_CB<4> @T6G_MB_LIB.T6G(SCH_1):M_E_CPU0_SB_CB(4)
   U25 BT70 MEB_CHECK4 GENOA_SP5-SOCKET6096_13568-001,SMLF,IO,DGA^6000030   I159 @T6G_MB_LIB.T6G(SCH_1):PAGE14
   J21   89  CB4_B SCONN288_DDR506112002KQ-SCONN288_DDR506112002KQ,SMA   I348 @T6G_MB_LIB.T6G(SCH_1):PAGE89

M_E_CPU0_SB_CB<5> @T6G_MB_LIB.T6G(SCH_1):M_E_CPU0_SB_CB(5)
   U25 BU69 MEB_CHECK5 GENOA_SP5-SOCKET6096_13568-001,SMLF,IO,DGA^6000030   I159 @T6G_MB_LIB.T6G(SCH_1):PAGE14
   J21   91  CB5_B SCONN288_DDR506112002KQ-SCONN288_DDR506112002KQ,SMA   I348 @T6G_MB_LIB.T6G(SCH_1):PAGE89

M_E_CPU0_SB_CB<6> @T6G_MB_LIB.T6G(SCH_1):M_E_CPU0_SB_CB(6)
   U25 BU71 MEB_CHECK6 GENOA_SP5-SOCKET6096_13568-001,SMLF,IO,DGA^6000030   I159 @T6G_MB_LIB.T6G(SCH_1):PAGE14
   J21  234  CB6_B SCONN288_DDR506112002KQ-SCONN288_DDR506112002KQ,SMA   I348 @T6G_MB_LIB.T6G(SCH_1):PAGE89

M_E_CPU0_SB_CB<7> @T6G_MB_LIB.T6G(SCH_1):M_E_CPU0_SB_CB(7)
   U25 BV69 MEB_CHECK7 GENOA_SP5-SOCKET6096_13568-001,SMLF,IO,DGA^6000030   I159 @T6G_MB_LIB.T6G(SCH_1):PAGE14
   J21  236  CB7_B SCONN288_DDR506112002KQ-SCONN288_DDR506112002KQ,SMA   I348 @T6G_MB_LIB.T6G(SCH_1):PAGE89

M_E_CPU0_SB_CS_N<0> @T6G_MB_LIB.T6G(SCH_1):M_E_CPU0_SB_CS_N(0)
   U25 BM69 MEB0_CS_L0 GENOA_SP5-SOCKET6096_13568-001,SMLF,IO,DGA^6000030   I159 @T6G_MB_LIB.T6G(SCH_1):PAGE14
   J21   84 CS0_B_N SCONN288_DDR506112002KQ-SCONN288_DDR506112002KQ,SMA   I348 @T6G_MB_LIB.T6G(SCH_1):PAGE89

M_E_CPU0_SB_CS_N<1> @T6G_MB_LIB.T6G(SCH_1):M_E_CPU0_SB_CS_N(1)
   U25 BN71 MEB0_CS_L1 GENOA_SP5-SOCKET6096_13568-001,SMLF,IO,DGA^6000030   I159 @T6G_MB_LIB.T6G(SCH_1):PAGE14
   J21  229 CS1_B_N SCONN288_DDR506112002KQ-SCONN288_DDR506112002KQ,SMA   I348 @T6G_MB_LIB.T6G(SCH_1):PAGE89

M_E_CPU0_SB_DQ<0> @T6G_MB_LIB.T6G(SCH_1):M_E_CPU0_SB_DQ(0)
   U25 CB70 MEB_DATA0 GENOA_SP5-SOCKET6096_13568-001,SMLF,IO,DGA^6000030   I159 @T6G_MB_LIB.T6G(SCH_1):PAGE14
   J21  100  DQ0_B SCONN288_DDR506112002KQ-SCONN288_DDR506112002KQ,SMA   I348 @T6G_MB_LIB.T6G(SCH_1):PAGE89

M_E_CPU0_SB_DQ<10> @T6G_MB_LIB.T6G(SCH_1):M_E_CPU0_SB_DQ(10)
   U25 CJ71 MEB_DATA10 GENOA_SP5-SOCKET6096_13568-001,SMLF,IO,DGA^6000030   I159 @T6G_MB_LIB.T6G(SCH_1):PAGE14
   J21  256 DQ10_B SCONN288_DDR506112002KQ-SCONN288_DDR506112002KQ,SMA   I348 @T6G_MB_LIB.T6G(SCH_1):PAGE89

M_E_CPU0_SB_DQ<11> @T6G_MB_LIB.T6G(SCH_1):M_E_CPU0_SB_DQ(11)
   U25 CK69 MEB_DATA11 GENOA_SP5-SOCKET6096_13568-001,SMLF,IO,DGA^6000030   I159 @T6G_MB_LIB.T6G(SCH_1):PAGE14
   J21  258 DQ11_B SCONN288_DDR506112002KQ-SCONN288_DDR506112002KQ,SMA   I348 @T6G_MB_LIB.T6G(SCH_1):PAGE89

M_E_CPU0_SB_DQ<12> @T6G_MB_LIB.T6G(SCH_1):M_E_CPU0_SB_DQ(12)
   U25 CM70 MEB_DATA12 GENOA_SP5-SOCKET6096_13568-001,SMLF,IO,DGA^6000030   I159 @T6G_MB_LIB.T6G(SCH_1):PAGE14
   J21  118 DQ12_B SCONN288_DDR506112002KQ-SCONN288_DDR506112002KQ,SMA   I348 @T6G_MB_LIB.T6G(SCH_1):PAGE89

M_E_CPU0_SB_DQ<13> @T6G_MB_LIB.T6G(SCH_1):M_E_CPU0_SB_DQ(13)
   U25 CN69 MEB_DATA13 GENOA_SP5-SOCKET6096_13568-001,SMLF,IO,DGA^6000030   I159 @T6G_MB_LIB.T6G(SCH_1):PAGE14
   J21  120 DQ13_B SCONN288_DDR506112002KQ-SCONN288_DDR506112002KQ,SMA   I348 @T6G_MB_LIB.T6G(SCH_1):PAGE89

M_E_CPU0_SB_DQ<14> @T6G_MB_LIB.T6G(SCH_1):M_E_CPU0_SB_DQ(14)
   U25 CN71 MEB_DATA14 GENOA_SP5-SOCKET6096_13568-001,SMLF,IO,DGA^6000030   I159 @T6G_MB_LIB.T6G(SCH_1):PAGE14
   J21  263 DQ14_B SCONN288_DDR506112002KQ-SCONN288_DDR506112002KQ,SMA   I348 @T6G_MB_LIB.T6G(SCH_1):PAGE89

M_E_CPU0_SB_DQ<15> @T6G_MB_LIB.T6G(SCH_1):M_E_CPU0_SB_DQ(15)
   U25 CP69 MEB_DATA15 GENOA_SP5-SOCKET6096_13568-001,SMLF,IO,DGA^6000030   I159 @T6G_MB_LIB.T6G(SCH_1):PAGE14
   J21  265 DQ15_B SCONN288_DDR506112002KQ-SCONN288_DDR506112002KQ,SMA   I348 @T6G_MB_LIB.T6G(SCH_1):PAGE89

M_E_CPU0_SB_DQ<16> @T6G_MB_LIB.T6G(SCH_1):M_E_CPU0_SB_DQ(16)
   U25 CP70 MEB_DATA16 GENOA_SP5-SOCKET6096_13568-001,SMLF,IO,DGA^6000030   I159 @T6G_MB_LIB.T6G(SCH_1):PAGE14
   J21  122 DQ16_B SCONN288_DDR506112002KQ-SCONN288_DDR506112002KQ,SMA   I348 @T6G_MB_LIB.T6G(SCH_1):PAGE89

M_E_CPU0_SB_DQ<17> @T6G_MB_LIB.T6G(SCH_1):M_E_CPU0_SB_DQ(17)
   U25 CR69 MEB_DATA17 GENOA_SP5-SOCKET6096_13568-001,SMLF,IO,DGA^6000030   I159 @T6G_MB_LIB.T6G(SCH_1):PAGE14
   J21  124 DQ17_B SCONN288_DDR506112002KQ-SCONN288_DDR506112002KQ,SMA   I348 @T6G_MB_LIB.T6G(SCH_1):PAGE89

M_E_CPU0_SB_DQ<18> @T6G_MB_LIB.T6G(SCH_1):M_E_CPU0_SB_DQ(18)
   U25 CR71 MEB_DATA18 GENOA_SP5-SOCKET6096_13568-001,SMLF,IO,DGA^6000030   I159 @T6G_MB_LIB.T6G(SCH_1):PAGE14
   J21  267 DQ18_B SCONN288_DDR506112002KQ-SCONN288_DDR506112002KQ,SMA   I348 @T6G_MB_LIB.T6G(SCH_1):PAGE89

M_E_CPU0_SB_DQ<19> @T6G_MB_LIB.T6G(SCH_1):M_E_CPU0_SB_DQ(19)
   U25 CT69 MEB_DATA19 GENOA_SP5-SOCKET6096_13568-001,SMLF,IO,DGA^6000030   I159 @T6G_MB_LIB.T6G(SCH_1):PAGE14
   J21  269 DQ19_B SCONN288_DDR506112002KQ-SCONN288_DDR506112002KQ,SMA   I348 @T6G_MB_LIB.T6G(SCH_1):PAGE89

M_E_CPU0_SB_DQ<1> @T6G_MB_LIB.T6G(SCH_1):M_E_CPU0_SB_DQ(1)
   U25 CC69 MEB_DATA1 GENOA_SP5-SOCKET6096_13568-001,SMLF,IO,DGA^6000030   I159 @T6G_MB_LIB.T6G(SCH_1):PAGE14
   J21  102  DQ1_B SCONN288_DDR506112002KQ-SCONN288_DDR506112002KQ,SMA   I348 @T6G_MB_LIB.T6G(SCH_1):PAGE89

M_E_CPU0_SB_DQ<20> @T6G_MB_LIB.T6G(SCH_1):M_E_CPU0_SB_DQ(20)
   U25 CV70 MEB_DATA20 GENOA_SP5-SOCKET6096_13568-001,SMLF,IO,DGA^6000030   I159 @T6G_MB_LIB.T6G(SCH_1):PAGE14
   J21  129 DQ20_B SCONN288_DDR506112002KQ-SCONN288_DDR506112002KQ,SMA   I348 @T6G_MB_LIB.T6G(SCH_1):PAGE89

M_E_CPU0_SB_DQ<21> @T6G_MB_LIB.T6G(SCH_1):M_E_CPU0_SB_DQ(21)
   U25 CW69 MEB_DATA21 GENOA_SP5-SOCKET6096_13568-001,SMLF,IO,DGA^6000030   I159 @T6G_MB_LIB.T6G(SCH_1):PAGE14
   J21  131 DQ21_B SCONN288_DDR506112002KQ-SCONN288_DDR506112002KQ,SMA   I348 @T6G_MB_LIB.T6G(SCH_1):PAGE89

M_E_CPU0_SB_DQ<22> @T6G_MB_LIB.T6G(SCH_1):M_E_CPU0_SB_DQ(22)
   U25 CW71 MEB_DATA22 GENOA_SP5-SOCKET6096_13568-001,SMLF,IO,DGA^6000030   I159 @T6G_MB_LIB.T6G(SCH_1):PAGE14
   J21  274 DQ22_B SCONN288_DDR506112002KQ-SCONN288_DDR506112002KQ,SMA   I348 @T6G_MB_LIB.T6G(SCH_1):PAGE89

M_E_CPU0_SB_DQ<23> @T6G_MB_LIB.T6G(SCH_1):M_E_CPU0_SB_DQ(23)
   U25 CY69 MEB_DATA23 GENOA_SP5-SOCKET6096_13568-001,SMLF,IO,DGA^6000030   I159 @T6G_MB_LIB.T6G(SCH_1):PAGE14
   J21  276 DQ23_B SCONN288_DDR506112002KQ-SCONN288_DDR506112002KQ,SMA   I348 @T6G_MB_LIB.T6G(SCH_1):PAGE89

M_E_CPU0_SB_DQ<24> @T6G_MB_LIB.T6G(SCH_1):M_E_CPU0_SB_DQ(24)
   U25 CY70 MEB_DATA24 GENOA_SP5-SOCKET6096_13568-001,SMLF,IO,DGA^6000030   I159 @T6G_MB_LIB.T6G(SCH_1):PAGE14
   J21  133 DQ24_B SCONN288_DDR506112002KQ-SCONN288_DDR506112002KQ,SMA   I348 @T6G_MB_LIB.T6G(SCH_1):PAGE89

M_E_CPU0_SB_DQ<25> @T6G_MB_LIB.T6G(SCH_1):M_E_CPU0_SB_DQ(25)
   U25 DA69 MEB_DATA25 GENOA_SP5-SOCKET6096_13568-001,SMLF,IO,DGA^6000030   I159 @T6G_MB_LIB.T6G(SCH_1):PAGE14
   J21  135 DQ25_B SCONN288_DDR506112002KQ-SCONN288_DDR506112002KQ,SMA   I348 @T6G_MB_LIB.T6G(SCH_1):PAGE89

M_E_CPU0_SB_DQ<26> @T6G_MB_LIB.T6G(SCH_1):M_E_CPU0_SB_DQ(26)
   U25 DA71 MEB_DATA26 GENOA_SP5-SOCKET6096_13568-001,SMLF,IO,DGA^6000030   I159 @T6G_MB_LIB.T6G(SCH_1):PAGE14
   J21  278 DQ26_B SCONN288_DDR506112002KQ-SCONN288_DDR506112002KQ,SMA   I348 @T6G_MB_LIB.T6G(SCH_1):PAGE89

M_E_CPU0_SB_DQ<27> @T6G_MB_LIB.T6G(SCH_1):M_E_CPU0_SB_DQ(27)
   U25 DB69 MEB_DATA27 GENOA_SP5-SOCKET6096_13568-001,SMLF,IO,DGA^6000030   I159 @T6G_MB_LIB.T6G(SCH_1):PAGE14
   J21  280 DQ27_B SCONN288_DDR506112002KQ-SCONN288_DDR506112002KQ,SMA   I348 @T6G_MB_LIB.T6G(SCH_1):PAGE89

M_E_CPU0_SB_DQ<28> @T6G_MB_LIB.T6G(SCH_1):M_E_CPU0_SB_DQ(28)
   U25 DD70 MEB_DATA28 GENOA_SP5-SOCKET6096_13568-001,SMLF,IO,DGA^6000030   I159 @T6G_MB_LIB.T6G(SCH_1):PAGE14
   J21  140 DQ28_B SCONN288_DDR506112002KQ-SCONN288_DDR506112002KQ,SMA   I348 @T6G_MB_LIB.T6G(SCH_1):PAGE89

M_E_CPU0_SB_DQ<29> @T6G_MB_LIB.T6G(SCH_1):M_E_CPU0_SB_DQ(29)
   U25 DE69 MEB_DATA29 GENOA_SP5-SOCKET6096_13568-001,SMLF,IO,DGA^6000030   I159 @T6G_MB_LIB.T6G(SCH_1):PAGE14
   J21  142 DQ29_B SCONN288_DDR506112002KQ-SCONN288_DDR506112002KQ,SMA   I348 @T6G_MB_LIB.T6G(SCH_1):PAGE89

M_E_CPU0_SB_DQ<2> @T6G_MB_LIB.T6G(SCH_1):M_E_CPU0_SB_DQ(2)
   U25 CC71 MEB_DATA2 GENOA_SP5-SOCKET6096_13568-001,SMLF,IO,DGA^6000030   I159 @T6G_MB_LIB.T6G(SCH_1):PAGE14
   J21  245  DQ2_B SCONN288_DDR506112002KQ-SCONN288_DDR506112002KQ,SMA   I348 @T6G_MB_LIB.T6G(SCH_1):PAGE89

M_E_CPU0_SB_DQ<30> @T6G_MB_LIB.T6G(SCH_1):M_E_CPU0_SB_DQ(30)
   U25 DE71 MEB_DATA30 GENOA_SP5-SOCKET6096_13568-001,SMLF,IO,DGA^6000030   I159 @T6G_MB_LIB.T6G(SCH_1):PAGE14
   J21  285 DQ30_B SCONN288_DDR506112002KQ-SCONN288_DDR506112002KQ,SMA   I348 @T6G_MB_LIB.T6G(SCH_1):PAGE89

M_E_CPU0_SB_DQ<31> @T6G_MB_LIB.T6G(SCH_1):M_E_CPU0_SB_DQ(31)
   U25 DF69 MEB_DATA31 GENOA_SP5-SOCKET6096_13568-001,SMLF,IO,DGA^6000030   I159 @T6G_MB_LIB.T6G(SCH_1):PAGE14
   J21  287 DQ31_B SCONN288_DDR506112002KQ-SCONN288_DDR506112002KQ,SMA   I348 @T6G_MB_LIB.T6G(SCH_1):PAGE89

M_E_CPU0_SB_DQ<3> @T6G_MB_LIB.T6G(SCH_1):M_E_CPU0_SB_DQ(3)
   U25 CD69 MEB_DATA3 GENOA_SP5-SOCKET6096_13568-001,SMLF,IO,DGA^6000030   I159 @T6G_MB_LIB.T6G(SCH_1):PAGE14
   J21  247  DQ3_B SCONN288_DDR506112002KQ-SCONN288_DDR506112002KQ,SMA   I348 @T6G_MB_LIB.T6G(SCH_1):PAGE89

M_E_CPU0_SB_DQ<4> @T6G_MB_LIB.T6G(SCH_1):M_E_CPU0_SB_DQ(4)
   U25 CF70 MEB_DATA4 GENOA_SP5-SOCKET6096_13568-001,SMLF,IO,DGA^6000030   I159 @T6G_MB_LIB.T6G(SCH_1):PAGE14
   J21  107  DQ4_B SCONN288_DDR506112002KQ-SCONN288_DDR506112002KQ,SMA   I348 @T6G_MB_LIB.T6G(SCH_1):PAGE89

M_E_CPU0_SB_DQ<5> @T6G_MB_LIB.T6G(SCH_1):M_E_CPU0_SB_DQ(5)
   U25 CG69 MEB_DATA5 GENOA_SP5-SOCKET6096_13568-001,SMLF,IO,DGA^6000030   I159 @T6G_MB_LIB.T6G(SCH_1):PAGE14
   J21  109  DQ5_B SCONN288_DDR506112002KQ-SCONN288_DDR506112002KQ,SMA   I348 @T6G_MB_LIB.T6G(SCH_1):PAGE89

M_E_CPU0_SB_DQ<6> @T6G_MB_LIB.T6G(SCH_1):M_E_CPU0_SB_DQ(6)
   U25 CG71 MEB_DATA6 GENOA_SP5-SOCKET6096_13568-001,SMLF,IO,DGA^6000030   I159 @T6G_MB_LIB.T6G(SCH_1):PAGE14
   J21  252  DQ6_B SCONN288_DDR506112002KQ-SCONN288_DDR506112002KQ,SMA   I348 @T6G_MB_LIB.T6G(SCH_1):PAGE89

M_E_CPU0_SB_DQ<7> @T6G_MB_LIB.T6G(SCH_1):M_E_CPU0_SB_DQ(7)
   U25 CH69 MEB_DATA7 GENOA_SP5-SOCKET6096_13568-001,SMLF,IO,DGA^6000030   I159 @T6G_MB_LIB.T6G(SCH_1):PAGE14
   J21  254  DQ7_B SCONN288_DDR506112002KQ-SCONN288_DDR506112002KQ,SMA   I348 @T6G_MB_LIB.T6G(SCH_1):PAGE89

M_E_CPU0_SB_DQ<8> @T6G_MB_LIB.T6G(SCH_1):M_E_CPU0_SB_DQ(8)
   U25 CH70 MEB_DATA8 GENOA_SP5-SOCKET6096_13568-001,SMLF,IO,DGA^6000030   I159 @T6G_MB_LIB.T6G(SCH_1):PAGE14
   J21  111  DQ8_B SCONN288_DDR506112002KQ-SCONN288_DDR506112002KQ,SMA   I348 @T6G_MB_LIB.T6G(SCH_1):PAGE89

M_E_CPU0_SB_DQ<9> @T6G_MB_LIB.T6G(SCH_1):M_E_CPU0_SB_DQ(9)
   U25 CJ69 MEB_DATA9 GENOA_SP5-SOCKET6096_13568-001,SMLF,IO,DGA^6000030   I159 @T6G_MB_LIB.T6G(SCH_1):PAGE14
   J21  113  DQ9_B SCONN288_DDR506112002KQ-SCONN288_DDR506112002KQ,SMA   I348 @T6G_MB_LIB.T6G(SCH_1):PAGE89

M_E_CPU0_SB_DQS_DN<0> @T6G_MB_LIB.T6G(SCH_1):M_E_CPU0_SB_DQS_DN(0)
   U25 CE71 MEB_DQS_L0 GENOA_SP5-SOCKET6096_13568-001,SMLF,IO,DGA^6000030   I159 @T6G_MB_LIB.T6G(SCH_1):PAGE14
   J21  105 DQS0_B_C SCONN288_DDR506112002KQ-SCONN288_DDR506112002KQ,SMA   I410 @T6G_MB_LIB.T6G(SCH_1):PAGE89

M_E_CPU0_SB_DQS_DN<1> @T6G_MB_LIB.T6G(SCH_1):M_E_CPU0_SB_DQS_DN(1)
   U25 CL71 MEB_DQS_L1 GENOA_SP5-SOCKET6096_13568-001,SMLF,IO,DGA^6000030   I159 @T6G_MB_LIB.T6G(SCH_1):PAGE14
   J21  116 DQS1_B_C SCONN288_DDR506112002KQ-SCONN288_DDR506112002KQ,SMA   I410 @T6G_MB_LIB.T6G(SCH_1):PAGE89

M_E_CPU0_SB_DQS_DN<2> @T6G_MB_LIB.T6G(SCH_1):M_E_CPU0_SB_DQS_DN(2)
   U25 CU71 MEB_DQS_L2 GENOA_SP5-SOCKET6096_13568-001,SMLF,IO,DGA^6000030   I159 @T6G_MB_LIB.T6G(SCH_1):PAGE14
   J21  127 DQS2_B_C SCONN288_DDR506112002KQ-SCONN288_DDR506112002KQ,SMA   I410 @T6G_MB_LIB.T6G(SCH_1):PAGE89

M_E_CPU0_SB_DQS_DN<3> @T6G_MB_LIB.T6G(SCH_1):M_E_CPU0_SB_DQS_DN(3)
   U25 DC71 MEB_DQS_L3 GENOA_SP5-SOCKET6096_13568-001,SMLF,IO,DGA^6000030   I159 @T6G_MB_LIB.T6G(SCH_1):PAGE14
   J21  138 DQS3_B_C SCONN288_DDR506112002KQ-SCONN288_DDR506112002KQ,SMA   I410 @T6G_MB_LIB.T6G(SCH_1):PAGE89

M_E_CPU0_SB_DQS_DN<4> @T6G_MB_LIB.T6G(SCH_1):M_E_CPU0_SB_DQS_DN(4)
   U25 BW69 MEB_DQS_L4 GENOA_SP5-SOCKET6096_13568-001,SMLF,IO,DGA^6000030   I159 @T6G_MB_LIB.T6G(SCH_1):PAGE14
   J21  238 DQS4_B_C SCONN288_DDR506112002KQ-SCONN288_DDR506112002KQ,SMA   I410 @T6G_MB_LIB.T6G(SCH_1):PAGE89

M_E_CPU0_SB_DQS_DN<5> @T6G_MB_LIB.T6G(SCH_1):M_E_CPU0_SB_DQS_DN(5)
   U25 CE69 MEB_DQS_L5 GENOA_SP5-SOCKET6096_13568-001,SMLF,IO,DGA^6000030   I159 @T6G_MB_LIB.T6G(SCH_1):PAGE14
   J21  249 DQS5_B_C||TDQS5_B_C SCONN288_DDR506112002KQ-SCONN288_DDR506112002KQ,SMA   I410 @T6G_MB_LIB.T6G(SCH_1):PAGE89

M_E_CPU0_SB_DQS_DN<6> @T6G_MB_LIB.T6G(SCH_1):M_E_CPU0_SB_DQS_DN(6)
   U25 CL69 MEB_DQS_L6 GENOA_SP5-SOCKET6096_13568-001,SMLF,IO,DGA^6000030   I159 @T6G_MB_LIB.T6G(SCH_1):PAGE14
   J21  260 DQS6_B_C||TDQS6_B_C SCONN288_DDR506112002KQ-SCONN288_DDR506112002KQ,SMA   I410 @T6G_MB_LIB.T6G(SCH_1):PAGE89

M_E_CPU0_SB_DQS_DN<7> @T6G_MB_LIB.T6G(SCH_1):M_E_CPU0_SB_DQS_DN(7)
   U25 CU69 MEB_DQS_L7 GENOA_SP5-SOCKET6096_13568-001,SMLF,IO,DGA^6000030   I159 @T6G_MB_LIB.T6G(SCH_1):PAGE14
   J21  271 DQS7_B_C||TDQS7_B_C SCONN288_DDR506112002KQ-SCONN288_DDR506112002KQ,SMA   I410 @T6G_MB_LIB.T6G(SCH_1):PAGE89

M_E_CPU0_SB_DQS_DN<8> @T6G_MB_LIB.T6G(SCH_1):M_E_CPU0_SB_DQS_DN(8)
   U25 DC69 MEB_DQS_L8 GENOA_SP5-SOCKET6096_13568-001,SMLF,IO,DGA^6000030   I159 @T6G_MB_LIB.T6G(SCH_1):PAGE14
   J21  282 DQS8_B_C||TDQS8_B_C SCONN288_DDR506112002KQ-SCONN288_DDR506112002KQ,SMA   I410 @T6G_MB_LIB.T6G(SCH_1):PAGE89

M_E_CPU0_SB_DQS_DN<9> @T6G_MB_LIB.T6G(SCH_1):M_E_CPU0_SB_DQS_DN(9)
   U25 BW71 MEB_DQS_L9 GENOA_SP5-SOCKET6096_13568-001,SMLF,IO,DGA^6000030   I159 @T6G_MB_LIB.T6G(SCH_1):PAGE14
   J21   94 DQS9_B_C||TDQS9_B_C SCONN288_DDR506112002KQ-SCONN288_DDR506112002KQ,SMA   I410 @T6G_MB_LIB.T6G(SCH_1):PAGE89

M_E_CPU0_SB_DQS_DP<0> @T6G_MB_LIB.T6G(SCH_1):M_E_CPU0_SB_DQS_DP(0)
   U25 CD70 MEB_DQS_H0 GENOA_SP5-SOCKET6096_13568-001,SMLF,IO,DGA^6000030   I159 @T6G_MB_LIB.T6G(SCH_1):PAGE14
   J21  104 DQS0_B_T SCONN288_DDR506112002KQ-SCONN288_DDR506112002KQ,SMA   I410 @T6G_MB_LIB.T6G(SCH_1):PAGE89

M_E_CPU0_SB_DQS_DP<1> @T6G_MB_LIB.T6G(SCH_1):M_E_CPU0_SB_DQS_DP(1)
   U25 CK70 MEB_DQS_H1 GENOA_SP5-SOCKET6096_13568-001,SMLF,IO,DGA^6000030   I159 @T6G_MB_LIB.T6G(SCH_1):PAGE14
   J21  115 DQS1_B_T SCONN288_DDR506112002KQ-SCONN288_DDR506112002KQ,SMA   I410 @T6G_MB_LIB.T6G(SCH_1):PAGE89

M_E_CPU0_SB_DQS_DP<2> @T6G_MB_LIB.T6G(SCH_1):M_E_CPU0_SB_DQS_DP(2)
   U25 CT70 MEB_DQS_H2 GENOA_SP5-SOCKET6096_13568-001,SMLF,IO,DGA^6000030   I159 @T6G_MB_LIB.T6G(SCH_1):PAGE14
   J21  126 DQS2_B_T SCONN288_DDR506112002KQ-SCONN288_DDR506112002KQ,SMA   I410 @T6G_MB_LIB.T6G(SCH_1):PAGE89

M_E_CPU0_SB_DQS_DP<3> @T6G_MB_LIB.T6G(SCH_1):M_E_CPU0_SB_DQS_DP(3)
   U25 DB70 MEB_DQS_H3 GENOA_SP5-SOCKET6096_13568-001,SMLF,IO,DGA^6000030   I159 @T6G_MB_LIB.T6G(SCH_1):PAGE14
   J21  137 DQS3_B_T SCONN288_DDR506112002KQ-SCONN288_DDR506112002KQ,SMA   I410 @T6G_MB_LIB.T6G(SCH_1):PAGE89

M_E_CPU0_SB_DQS_DP<4> @T6G_MB_LIB.T6G(SCH_1):M_E_CPU0_SB_DQS_DP(4)
   U25 BY69 MEB_DQS_H4 GENOA_SP5-SOCKET6096_13568-001,SMLF,IO,DGA^6000030   I159 @T6G_MB_LIB.T6G(SCH_1):PAGE14
   J21  239 DQS4_B_T SCONN288_DDR506112002KQ-SCONN288_DDR506112002KQ,SMA   I410 @T6G_MB_LIB.T6G(SCH_1):PAGE89

M_E_CPU0_SB_DQS_DP<5> @T6G_MB_LIB.T6G(SCH_1):M_E_CPU0_SB_DQS_DP(5)
   U25 CF69 MEB_DQS_H5 GENOA_SP5-SOCKET6096_13568-001,SMLF,IO,DGA^6000030   I159 @T6G_MB_LIB.T6G(SCH_1):PAGE14
   J21  250 DQS5_B_T||TDQS5_B_T SCONN288_DDR506112002KQ-SCONN288_DDR506112002KQ,SMA   I410 @T6G_MB_LIB.T6G(SCH_1):PAGE89

M_E_CPU0_SB_DQS_DP<6> @T6G_MB_LIB.T6G(SCH_1):M_E_CPU0_SB_DQS_DP(6)
   U25 CM69 MEB_DQS_H6 GENOA_SP5-SOCKET6096_13568-001,SMLF,IO,DGA^6000030   I159 @T6G_MB_LIB.T6G(SCH_1):PAGE14
   J21  261 DQS6_B_T||TDQS6_B_T SCONN288_DDR506112002KQ-SCONN288_DDR506112002KQ,SMA   I410 @T6G_MB_LIB.T6G(SCH_1):PAGE89

M_E_CPU0_SB_DQS_DP<7> @T6G_MB_LIB.T6G(SCH_1):M_E_CPU0_SB_DQS_DP(7)
   U25 CV69 MEB_DQS_H7 GENOA_SP5-SOCKET6096_13568-001,SMLF,IO,DGA^6000030   I159 @T6G_MB_LIB.T6G(SCH_1):PAGE14
   J21  272 DQS7_B_T||TDQS7_B_T SCONN288_DDR506112002KQ-SCONN288_DDR506112002KQ,SMA   I410 @T6G_MB_LIB.T6G(SCH_1):PAGE89

M_E_CPU0_SB_DQS_DP<8> @T6G_MB_LIB.T6G(SCH_1):M_E_CPU0_SB_DQS_DP(8)
   U25 DD69 MEB_DQS_H8 GENOA_SP5-SOCKET6096_13568-001,SMLF,IO,DGA^6000030   I159 @T6G_MB_LIB.T6G(SCH_1):PAGE14
   J21  283 DQS8_B_T||TDQS8_B_T SCONN288_DDR506112002KQ-SCONN288_DDR506112002KQ,SMA   I410 @T6G_MB_LIB.T6G(SCH_1):PAGE89

M_E_CPU0_SB_DQS_DP<9> @T6G_MB_LIB.T6G(SCH_1):M_E_CPU0_SB_DQS_DP(9)
   U25 BV70 MEB_DQS_H9 GENOA_SP5-SOCKET6096_13568-001,SMLF,IO,DGA^6000030   I159 @T6G_MB_LIB.T6G(SCH_1):PAGE14
   J21   93 DQS9_B_T||TDQS9_B_T||DBI4_B_N SCONN288_DDR506112002KQ-SCONN288_DDR506112002KQ,SMA   I410 @T6G_MB_LIB.T6G(SCH_1):PAGE89

M_E_CPU0_SB_PAR @T6G_MB_LIB.T6G(SCH_1):M_E_CPU0_SB_PAR
   U25 BL71 MEB_PAR GENOA_SP5-SOCKET6096_13568-001,SMLF,IO,DGA^6000030   I159 @T6G_MB_LIB.T6G(SCH_1):PAGE14
   J21  227  PAR_B SCONN288_DDR506112002KQ-SCONN288_DDR506112002KQ,SMA   I348 @T6G_MB_LIB.T6G(SCH_1):PAGE89

M_E_CPU0_SB_RSP<0> @T6G_MB_LIB.T6G(SCH_1):M_E_CPU0_SB_RSP(0)
   U25 BP70 MEB0_RSP_L GENOA_SP5-SOCKET6096_13568-001,SMLF,IO,DGA^6000030   I159 @T6G_MB_LIB.T6G(SCH_1):PAGE14
   J21   87 LBS||RSP_B_N SCONN288_DDR506112002KQ-SCONN288_DDR506112002KQ,SMA   I348 @T6G_MB_LIB.T6G(SCH_1):PAGE89

M_E_CPU1_ALERT_N @T6G_MB_LIB.T6G(SCH_1):M_E_CPU1_ALERT_N
  R504    1      A Q_RES_0402LF-15,1%,1/16W,CHIP,CS01502FB03   I314 @T6G_MB_LIB.T6G(SCH_1):PAGE41
   J32   62 ALERT_N SCONN288_DDR506112002KQ-SCONN288_DDR506112002KQ,SMA    I52 @T6G_MB_LIB.T6G(SCH_1):PAGE101

M_E_CPU1_ALERT_R_N @T6G_MB_LIB.T6G(SCH_1):M_E_CPU1_ALERT_R_N
   U26 AT69 ME_ALERT_L GENOA_SP5-SOCKET6096_13568-001,SMLF,IO,DGA^6000030   I159 @T6G_MB_LIB.T6G(SCH_1):PAGE41
  R504    2      B Q_RES_0402LF-15,1%,1/16W,CHIP,CS01502FB03   I314 @T6G_MB_LIB.T6G(SCH_1):PAGE41

M_E_CPU1_CLK_DN<0> @T6G_MB_LIB.T6G(SCH_1):M_E_CPU1_CLK_DN(0)
   U26 BD70 ME0_CLK_L GENOA_SP5-SOCKET6096_13568-001,SMLF,IO,DGA^6000030   I159 @T6G_MB_LIB.T6G(SCH_1):PAGE41
   J32  218   CK_C SCONN288_DDR506112002KQ-SCONN288_DDR506112002KQ,SMA    I52 @T6G_MB_LIB.T6G(SCH_1):PAGE101

M_E_CPU1_CLK_DP<0> @T6G_MB_LIB.T6G(SCH_1):M_E_CPU1_CLK_DP(0)
   U26 BC71 ME0_CLK_H GENOA_SP5-SOCKET6096_13568-001,SMLF,IO,DGA^6000030   I159 @T6G_MB_LIB.T6G(SCH_1):PAGE41
   J32  217   CK_T SCONN288_DDR506112002KQ-SCONN288_DDR506112002KQ,SMA    I52 @T6G_MB_LIB.T6G(SCH_1):PAGE101

M_E_CPU1_RESET_N @T6G_MB_LIB.T6G(SCH_1):M_E_CPU1_RESET_N
   U26 AU69 ME_RESET_L GENOA_SP5-SOCKET6096_13568-001,SMLF,IO,DGA^6000030   I159 @T6G_MB_LIB.T6G(SCH_1):PAGE41
   J32  207 RESET_N SCONN288_DDR506112002KQ-SCONN288_DDR506112002KQ,SMA    I52 @T6G_MB_LIB.T6G(SCH_1):PAGE101

M_E_CPU1_SA_CA<0> @T6G_MB_LIB.T6G(SCH_1):M_E_CPU1_SA_CA(0)
   U26 AW71 MEA_CA0 GENOA_SP5-SOCKET6096_13568-001,SMLF,IO,DGA^6000030   I159 @T6G_MB_LIB.T6G(SCH_1):PAGE41
   J32   66  CA0_A SCONN288_DDR506112002KQ-SCONN288_DDR506112002KQ,SMA    I52 @T6G_MB_LIB.T6G(SCH_1):PAGE101

M_E_CPU1_SA_CA<1> @T6G_MB_LIB.T6G(SCH_1):M_E_CPU1_SA_CA(1)
   U26 AY70 MEA_CA1 GENOA_SP5-SOCKET6096_13568-001,SMLF,IO,DGA^6000030   I159 @T6G_MB_LIB.T6G(SCH_1):PAGE41
   J32  211  CA1_A SCONN288_DDR506112002KQ-SCONN288_DDR506112002KQ,SMA    I52 @T6G_MB_LIB.T6G(SCH_1):PAGE101

M_E_CPU1_SA_CA<2> @T6G_MB_LIB.T6G(SCH_1):M_E_CPU1_SA_CA(2)
   U26 AY69 MEA_CA2 GENOA_SP5-SOCKET6096_13568-001,SMLF,IO,DGA^6000030   I159 @T6G_MB_LIB.T6G(SCH_1):PAGE41
   J32   68  CA2_A SCONN288_DDR506112002KQ-SCONN288_DDR506112002KQ,SMA    I52 @T6G_MB_LIB.T6G(SCH_1):PAGE101

M_E_CPU1_SA_CA<3> @T6G_MB_LIB.T6G(SCH_1):M_E_CPU1_SA_CA(3)
   U26 BA69 MEA_CA3 GENOA_SP5-SOCKET6096_13568-001,SMLF,IO,DGA^6000030   I159 @T6G_MB_LIB.T6G(SCH_1):PAGE41
   J32  213  CA3_A SCONN288_DDR506112002KQ-SCONN288_DDR506112002KQ,SMA    I52 @T6G_MB_LIB.T6G(SCH_1):PAGE101

M_E_CPU1_SA_CA<4> @T6G_MB_LIB.T6G(SCH_1):M_E_CPU1_SA_CA(4)
   U26 BA71 MEA_CA4 GENOA_SP5-SOCKET6096_13568-001,SMLF,IO,DGA^6000030   I159 @T6G_MB_LIB.T6G(SCH_1):PAGE41
   J32   70  CA4_A SCONN288_DDR506112002KQ-SCONN288_DDR506112002KQ,SMA    I52 @T6G_MB_LIB.T6G(SCH_1):PAGE101

M_E_CPU1_SA_CA<5> @T6G_MB_LIB.T6G(SCH_1):M_E_CPU1_SA_CA(5)
   U26 BB70 MEA_CA5 GENOA_SP5-SOCKET6096_13568-001,SMLF,IO,DGA^6000030   I159 @T6G_MB_LIB.T6G(SCH_1):PAGE41
   J32  215  CA5_A SCONN288_DDR506112002KQ-SCONN288_DDR506112002KQ,SMA    I52 @T6G_MB_LIB.T6G(SCH_1):PAGE101

M_E_CPU1_SA_CA<6> @T6G_MB_LIB.T6G(SCH_1):M_E_CPU1_SA_CA(6)
   U26 BB69 MEA_CA6 GENOA_SP5-SOCKET6096_13568-001,SMLF,IO,DGA^6000030   I159 @T6G_MB_LIB.T6G(SCH_1):PAGE41
   J32   72  CA6_A SCONN288_DDR506112002KQ-SCONN288_DDR506112002KQ,SMA    I52 @T6G_MB_LIB.T6G(SCH_1):PAGE101

M_E_CPU1_SA_CB<0> @T6G_MB_LIB.T6G(SCH_1):M_E_CPU1_SA_CB(0)
   U26 AJ71 MEA_CHECK0 GENOA_SP5-SOCKET6096_13568-001,SMLF,IO,DGA^6000030   I159 @T6G_MB_LIB.T6G(SCH_1):PAGE41
   J32   51  CB0_A SCONN288_DDR506112002KQ-SCONN288_DDR506112002KQ,SMA    I52 @T6G_MB_LIB.T6G(SCH_1):PAGE101

M_E_CPU1_SA_CB<1> @T6G_MB_LIB.T6G(SCH_1):M_E_CPU1_SA_CB(1)
   U26 AK69 MEA_CHECK1 GENOA_SP5-SOCKET6096_13568-001,SMLF,IO,DGA^6000030   I159 @T6G_MB_LIB.T6G(SCH_1):PAGE41
   J32   53  CB1_A SCONN288_DDR506112002KQ-SCONN288_DDR506112002KQ,SMA    I52 @T6G_MB_LIB.T6G(SCH_1):PAGE101

M_E_CPU1_SA_CB<2> @T6G_MB_LIB.T6G(SCH_1):M_E_CPU1_SA_CB(2)
   U26 AK70 MEA_CHECK2 GENOA_SP5-SOCKET6096_13568-001,SMLF,IO,DGA^6000030   I159 @T6G_MB_LIB.T6G(SCH_1):PAGE41
   J32  196  CB2_A SCONN288_DDR506112002KQ-SCONN288_DDR506112002KQ,SMA    I52 @T6G_MB_LIB.T6G(SCH_1):PAGE101

M_E_CPU1_SA_CB<3> @T6G_MB_LIB.T6G(SCH_1):M_E_CPU1_SA_CB(3)
   U26 AL69 MEA_CHECK3 GENOA_SP5-SOCKET6096_13568-001,SMLF,IO,DGA^6000030   I159 @T6G_MB_LIB.T6G(SCH_1):PAGE41
   J32  198  CB3_A SCONN288_DDR506112002KQ-SCONN288_DDR506112002KQ,SMA    I52 @T6G_MB_LIB.T6G(SCH_1):PAGE101

M_E_CPU1_SA_CB<4> @T6G_MB_LIB.T6G(SCH_1):M_E_CPU1_SA_CB(4)
   U26 AN71 MEA_CHECK4 GENOA_SP5-SOCKET6096_13568-001,SMLF,IO,DGA^6000030   I159 @T6G_MB_LIB.T6G(SCH_1):PAGE41
   J32   58  CB4_A SCONN288_DDR506112002KQ-SCONN288_DDR506112002KQ,SMA    I52 @T6G_MB_LIB.T6G(SCH_1):PAGE101

M_E_CPU1_SA_CB<5> @T6G_MB_LIB.T6G(SCH_1):M_E_CPU1_SA_CB(5)
   U26 AP69 MEA_CHECK5 GENOA_SP5-SOCKET6096_13568-001,SMLF,IO,DGA^6000030   I159 @T6G_MB_LIB.T6G(SCH_1):PAGE41
   J32   60  CB5_A SCONN288_DDR506112002KQ-SCONN288_DDR506112002KQ,SMA    I52 @T6G_MB_LIB.T6G(SCH_1):PAGE101

M_E_CPU1_SA_CB<6> @T6G_MB_LIB.T6G(SCH_1):M_E_CPU1_SA_CB(6)
   U26 AP70 MEA_CHECK6 GENOA_SP5-SOCKET6096_13568-001,SMLF,IO,DGA^6000030   I159 @T6G_MB_LIB.T6G(SCH_1):PAGE41
   J32  203  CB6_A SCONN288_DDR506112002KQ-SCONN288_DDR506112002KQ,SMA    I52 @T6G_MB_LIB.T6G(SCH_1):PAGE101

M_E_CPU1_SA_CB<7> @T6G_MB_LIB.T6G(SCH_1):M_E_CPU1_SA_CB(7)
   U26 AR69 MEA_CHECK7 GENOA_SP5-SOCKET6096_13568-001,SMLF,IO,DGA^6000030   I159 @T6G_MB_LIB.T6G(SCH_1):PAGE41
   J32  205  CB7_A SCONN288_DDR506112002KQ-SCONN288_DDR506112002KQ,SMA    I52 @T6G_MB_LIB.T6G(SCH_1):PAGE101

M_E_CPU1_SA_CS_N<0> @T6G_MB_LIB.T6G(SCH_1):M_E_CPU1_SA_CS_N(0)
   U26 AV70 MEA0_CS_L0 GENOA_SP5-SOCKET6096_13568-001,SMLF,IO,DGA^6000030   I159 @T6G_MB_LIB.T6G(SCH_1):PAGE41
   J32   64 CS0_A_N SCONN288_DDR506112002KQ-SCONN288_DDR506112002KQ,SMA    I52 @T6G_MB_LIB.T6G(SCH_1):PAGE101

M_E_CPU1_SA_CS_N<1> @T6G_MB_LIB.T6G(SCH_1):M_E_CPU1_SA_CS_N(1)
   U26 AW69 MEA0_CS_L1 GENOA_SP5-SOCKET6096_13568-001,SMLF,IO,DGA^6000030   I159 @T6G_MB_LIB.T6G(SCH_1):PAGE41
   J32  209 CS1_A_N SCONN288_DDR506112002KQ-SCONN288_DDR506112002KQ,SMA    I52 @T6G_MB_LIB.T6G(SCH_1):PAGE101

M_E_CPU1_SA_DQ<0> @T6G_MB_LIB.T6G(SCH_1):M_E_CPU1_SA_DQ(0)
   U26  E71 MEA_DATA0 GENOA_SP5-SOCKET6096_13568-001,SMLF,IO,DGA^6000030   I159 @T6G_MB_LIB.T6G(SCH_1):PAGE41
   J32    7  DQ0_A SCONN288_DDR506112002KQ-SCONN288_DDR506112002KQ,SMA    I52 @T6G_MB_LIB.T6G(SCH_1):PAGE101

M_E_CPU1_SA_DQ<10> @T6G_MB_LIB.T6G(SCH_1):M_E_CPU1_SA_DQ(10)
   U26  M70 MEA_DATA10 GENOA_SP5-SOCKET6096_13568-001,SMLF,IO,DGA^6000030   I159 @T6G_MB_LIB.T6G(SCH_1):PAGE41
   J32  163 DQ10_A SCONN288_DDR506112002KQ-SCONN288_DDR506112002KQ,SMA    I52 @T6G_MB_LIB.T6G(SCH_1):PAGE101

M_E_CPU1_SA_DQ<11> @T6G_MB_LIB.T6G(SCH_1):M_E_CPU1_SA_DQ(11)
   U26  N69 MEA_DATA11 GENOA_SP5-SOCKET6096_13568-001,SMLF,IO,DGA^6000030   I159 @T6G_MB_LIB.T6G(SCH_1):PAGE41
   J32  165 DQ11_A SCONN288_DDR506112002KQ-SCONN288_DDR506112002KQ,SMA    I52 @T6G_MB_LIB.T6G(SCH_1):PAGE101

M_E_CPU1_SA_DQ<12> @T6G_MB_LIB.T6G(SCH_1):M_E_CPU1_SA_DQ(12)
   U26  R71 MEA_DATA12 GENOA_SP5-SOCKET6096_13568-001,SMLF,IO,DGA^6000030   I159 @T6G_MB_LIB.T6G(SCH_1):PAGE41
   J32   25 DQ12_A SCONN288_DDR506112002KQ-SCONN288_DDR506112002KQ,SMA    I52 @T6G_MB_LIB.T6G(SCH_1):PAGE101

M_E_CPU1_SA_DQ<13> @T6G_MB_LIB.T6G(SCH_1):M_E_CPU1_SA_DQ(13)
   U26  T69 MEA_DATA13 GENOA_SP5-SOCKET6096_13568-001,SMLF,IO,DGA^6000030   I159 @T6G_MB_LIB.T6G(SCH_1):PAGE41
   J32   27 DQ13_A SCONN288_DDR506112002KQ-SCONN288_DDR506112002KQ,SMA    I52 @T6G_MB_LIB.T6G(SCH_1):PAGE101

M_E_CPU1_SA_DQ<14> @T6G_MB_LIB.T6G(SCH_1):M_E_CPU1_SA_DQ(14)
   U26  T70 MEA_DATA14 GENOA_SP5-SOCKET6096_13568-001,SMLF,IO,DGA^6000030   I159 @T6G_MB_LIB.T6G(SCH_1):PAGE41
   J32  170 DQ14_A SCONN288_DDR506112002KQ-SCONN288_DDR506112002KQ,SMA    I52 @T6G_MB_LIB.T6G(SCH_1):PAGE101

M_E_CPU1_SA_DQ<15> @T6G_MB_LIB.T6G(SCH_1):M_E_CPU1_SA_DQ(15)
   U26  U69 MEA_DATA15 GENOA_SP5-SOCKET6096_13568-001,SMLF,IO,DGA^6000030   I159 @T6G_MB_LIB.T6G(SCH_1):PAGE41
   J32  172 DQ15_A SCONN288_DDR506112002KQ-SCONN288_DDR506112002KQ,SMA    I52 @T6G_MB_LIB.T6G(SCH_1):PAGE101

M_E_CPU1_SA_DQ<16> @T6G_MB_LIB.T6G(SCH_1):M_E_CPU1_SA_DQ(16)
   U26  U71 MEA_DATA16 GENOA_SP5-SOCKET6096_13568-001,SMLF,IO,DGA^6000030   I159 @T6G_MB_LIB.T6G(SCH_1):PAGE41
   J32   29 DQ16_A SCONN288_DDR506112002KQ-SCONN288_DDR506112002KQ,SMA    I52 @T6G_MB_LIB.T6G(SCH_1):PAGE101

M_E_CPU1_SA_DQ<17> @T6G_MB_LIB.T6G(SCH_1):M_E_CPU1_SA_DQ(17)
   U26  V69 MEA_DATA17 GENOA_SP5-SOCKET6096_13568-001,SMLF,IO,DGA^6000030   I159 @T6G_MB_LIB.T6G(SCH_1):PAGE41
   J32   31 DQ17_A SCONN288_DDR506112002KQ-SCONN288_DDR506112002KQ,SMA    I52 @T6G_MB_LIB.T6G(SCH_1):PAGE101

M_E_CPU1_SA_DQ<18> @T6G_MB_LIB.T6G(SCH_1):M_E_CPU1_SA_DQ(18)
   U26  V70 MEA_DATA18 GENOA_SP5-SOCKET6096_13568-001,SMLF,IO,DGA^6000030   I159 @T6G_MB_LIB.T6G(SCH_1):PAGE41
   J32  174 DQ18_A SCONN288_DDR506112002KQ-SCONN288_DDR506112002KQ,SMA    I52 @T6G_MB_LIB.T6G(SCH_1):PAGE101

M_E_CPU1_SA_DQ<19> @T6G_MB_LIB.T6G(SCH_1):M_E_CPU1_SA_DQ(19)
   U26  W69 MEA_DATA19 GENOA_SP5-SOCKET6096_13568-001,SMLF,IO,DGA^6000030   I159 @T6G_MB_LIB.T6G(SCH_1):PAGE41
   J32  176 DQ19_A SCONN288_DDR506112002KQ-SCONN288_DDR506112002KQ,SMA    I52 @T6G_MB_LIB.T6G(SCH_1):PAGE101

M_E_CPU1_SA_DQ<1> @T6G_MB_LIB.T6G(SCH_1):M_E_CPU1_SA_DQ(1)
   U26  F69 MEA_DATA1 GENOA_SP5-SOCKET6096_13568-001,SMLF,IO,DGA^6000030   I159 @T6G_MB_LIB.T6G(SCH_1):PAGE41
   J32    9  DQ1_A SCONN288_DDR506112002KQ-SCONN288_DDR506112002KQ,SMA    I52 @T6G_MB_LIB.T6G(SCH_1):PAGE101

M_E_CPU1_SA_DQ<20> @T6G_MB_LIB.T6G(SCH_1):M_E_CPU1_SA_DQ(20)
   U26 AA71 MEA_DATA20 GENOA_SP5-SOCKET6096_13568-001,SMLF,IO,DGA^6000030   I159 @T6G_MB_LIB.T6G(SCH_1):PAGE41
   J32   36 DQ20_A SCONN288_DDR506112002KQ-SCONN288_DDR506112002KQ,SMA    I52 @T6G_MB_LIB.T6G(SCH_1):PAGE101

M_E_CPU1_SA_DQ<21> @T6G_MB_LIB.T6G(SCH_1):M_E_CPU1_SA_DQ(21)
   U26 AB69 MEA_DATA21 GENOA_SP5-SOCKET6096_13568-001,SMLF,IO,DGA^6000030   I159 @T6G_MB_LIB.T6G(SCH_1):PAGE41
   J32   38 DQ21_A SCONN288_DDR506112002KQ-SCONN288_DDR506112002KQ,SMA    I52 @T6G_MB_LIB.T6G(SCH_1):PAGE101

M_E_CPU1_SA_DQ<22> @T6G_MB_LIB.T6G(SCH_1):M_E_CPU1_SA_DQ(22)
   U26 AB70 MEA_DATA22 GENOA_SP5-SOCKET6096_13568-001,SMLF,IO,DGA^6000030   I159 @T6G_MB_LIB.T6G(SCH_1):PAGE41
   J32  181 DQ22_A SCONN288_DDR506112002KQ-SCONN288_DDR506112002KQ,SMA    I52 @T6G_MB_LIB.T6G(SCH_1):PAGE101

M_E_CPU1_SA_DQ<23> @T6G_MB_LIB.T6G(SCH_1):M_E_CPU1_SA_DQ(23)
   U26 AC69 MEA_DATA23 GENOA_SP5-SOCKET6096_13568-001,SMLF,IO,DGA^6000030   I159 @T6G_MB_LIB.T6G(SCH_1):PAGE41
   J32  183 DQ23_A SCONN288_DDR506112002KQ-SCONN288_DDR506112002KQ,SMA    I52 @T6G_MB_LIB.T6G(SCH_1):PAGE101

M_E_CPU1_SA_DQ<24> @T6G_MB_LIB.T6G(SCH_1):M_E_CPU1_SA_DQ(24)
   U26 AC71 MEA_DATA24 GENOA_SP5-SOCKET6096_13568-001,SMLF,IO,DGA^6000030   I159 @T6G_MB_LIB.T6G(SCH_1):PAGE41
   J32   40 DQ24_A SCONN288_DDR506112002KQ-SCONN288_DDR506112002KQ,SMA    I52 @T6G_MB_LIB.T6G(SCH_1):PAGE101

M_E_CPU1_SA_DQ<25> @T6G_MB_LIB.T6G(SCH_1):M_E_CPU1_SA_DQ(25)
   U26 AD69 MEA_DATA25 GENOA_SP5-SOCKET6096_13568-001,SMLF,IO,DGA^6000030   I159 @T6G_MB_LIB.T6G(SCH_1):PAGE41
   J32   42 DQ25_A SCONN288_DDR506112002KQ-SCONN288_DDR506112002KQ,SMA    I52 @T6G_MB_LIB.T6G(SCH_1):PAGE101

M_E_CPU1_SA_DQ<26> @T6G_MB_LIB.T6G(SCH_1):M_E_CPU1_SA_DQ(26)
   U26 AD70 MEA_DATA26 GENOA_SP5-SOCKET6096_13568-001,SMLF,IO,DGA^6000030   I159 @T6G_MB_LIB.T6G(SCH_1):PAGE41
   J32  185 DQ26_A SCONN288_DDR506112002KQ-SCONN288_DDR506112002KQ,SMA    I52 @T6G_MB_LIB.T6G(SCH_1):PAGE101

M_E_CPU1_SA_DQ<27> @T6G_MB_LIB.T6G(SCH_1):M_E_CPU1_SA_DQ(27)
   U26 AE69 MEA_DATA27 GENOA_SP5-SOCKET6096_13568-001,SMLF,IO,DGA^6000030   I159 @T6G_MB_LIB.T6G(SCH_1):PAGE41
   J32  187 DQ27_A SCONN288_DDR506112002KQ-SCONN288_DDR506112002KQ,SMA    I52 @T6G_MB_LIB.T6G(SCH_1):PAGE101

M_E_CPU1_SA_DQ<28> @T6G_MB_LIB.T6G(SCH_1):M_E_CPU1_SA_DQ(28)
   U26 AG71 MEA_DATA28 GENOA_SP5-SOCKET6096_13568-001,SMLF,IO,DGA^6000030   I159 @T6G_MB_LIB.T6G(SCH_1):PAGE41
   J32   47 DQ28_A SCONN288_DDR506112002KQ-SCONN288_DDR506112002KQ,SMA    I52 @T6G_MB_LIB.T6G(SCH_1):PAGE101

M_E_CPU1_SA_DQ<29> @T6G_MB_LIB.T6G(SCH_1):M_E_CPU1_SA_DQ(29)
   U26 AH69 MEA_DATA29 GENOA_SP5-SOCKET6096_13568-001,SMLF,IO,DGA^6000030   I159 @T6G_MB_LIB.T6G(SCH_1):PAGE41
   J32   49 DQ29_A SCONN288_DDR506112002KQ-SCONN288_DDR506112002KQ,SMA    I52 @T6G_MB_LIB.T6G(SCH_1):PAGE101

M_E_CPU1_SA_DQ<2> @T6G_MB_LIB.T6G(SCH_1):M_E_CPU1_SA_DQ(2)
   U26  F70 MEA_DATA2 GENOA_SP5-SOCKET6096_13568-001,SMLF,IO,DGA^6000030   I159 @T6G_MB_LIB.T6G(SCH_1):PAGE41
   J32  152  DQ2_A SCONN288_DDR506112002KQ-SCONN288_DDR506112002KQ,SMA    I52 @T6G_MB_LIB.T6G(SCH_1):PAGE101

M_E_CPU1_SA_DQ<30> @T6G_MB_LIB.T6G(SCH_1):M_E_CPU1_SA_DQ(30)
   U26 AH70 MEA_DATA30 GENOA_SP5-SOCKET6096_13568-001,SMLF,IO,DGA^6000030   I159 @T6G_MB_LIB.T6G(SCH_1):PAGE41
   J32  192 DQ30_A SCONN288_DDR506112002KQ-SCONN288_DDR506112002KQ,SMA    I52 @T6G_MB_LIB.T6G(SCH_1):PAGE101

M_E_CPU1_SA_DQ<31> @T6G_MB_LIB.T6G(SCH_1):M_E_CPU1_SA_DQ(31)
   U26 AJ69 MEA_DATA31 GENOA_SP5-SOCKET6096_13568-001,SMLF,IO,DGA^6000030   I159 @T6G_MB_LIB.T6G(SCH_1):PAGE41
   J32  194 DQ31_A SCONN288_DDR506112002KQ-SCONN288_DDR506112002KQ,SMA    I52 @T6G_MB_LIB.T6G(SCH_1):PAGE101

M_E_CPU1_SA_DQ<3> @T6G_MB_LIB.T6G(SCH_1):M_E_CPU1_SA_DQ(3)
   U26  G69 MEA_DATA3 GENOA_SP5-SOCKET6096_13568-001,SMLF,IO,DGA^6000030   I159 @T6G_MB_LIB.T6G(SCH_1):PAGE41
   J32  154  DQ3_A SCONN288_DDR506112002KQ-SCONN288_DDR506112002KQ,SMA    I52 @T6G_MB_LIB.T6G(SCH_1):PAGE101

M_E_CPU1_SA_DQ<4> @T6G_MB_LIB.T6G(SCH_1):M_E_CPU1_SA_DQ(4)
   U26  J71 MEA_DATA4 GENOA_SP5-SOCKET6096_13568-001,SMLF,IO,DGA^6000030   I159 @T6G_MB_LIB.T6G(SCH_1):PAGE41
   J32   14  DQ4_A SCONN288_DDR506112002KQ-SCONN288_DDR506112002KQ,SMA    I52 @T6G_MB_LIB.T6G(SCH_1):PAGE101

M_E_CPU1_SA_DQ<5> @T6G_MB_LIB.T6G(SCH_1):M_E_CPU1_SA_DQ(5)
   U26  K69 MEA_DATA5 GENOA_SP5-SOCKET6096_13568-001,SMLF,IO,DGA^6000030   I159 @T6G_MB_LIB.T6G(SCH_1):PAGE41
   J32   16  DQ5_A SCONN288_DDR506112002KQ-SCONN288_DDR506112002KQ,SMA    I52 @T6G_MB_LIB.T6G(SCH_1):PAGE101

M_E_CPU1_SA_DQ<6> @T6G_MB_LIB.T6G(SCH_1):M_E_CPU1_SA_DQ(6)
   U26  K70 MEA_DATA6 GENOA_SP5-SOCKET6096_13568-001,SMLF,IO,DGA^6000030   I159 @T6G_MB_LIB.T6G(SCH_1):PAGE41
   J32  159  DQ6_A SCONN288_DDR506112002KQ-SCONN288_DDR506112002KQ,SMA    I52 @T6G_MB_LIB.T6G(SCH_1):PAGE101

M_E_CPU1_SA_DQ<7> @T6G_MB_LIB.T6G(SCH_1):M_E_CPU1_SA_DQ(7)
   U26  L69 MEA_DATA7 GENOA_SP5-SOCKET6096_13568-001,SMLF,IO,DGA^6000030   I159 @T6G_MB_LIB.T6G(SCH_1):PAGE41
   J32  161  DQ7_A SCONN288_DDR506112002KQ-SCONN288_DDR506112002KQ,SMA    I52 @T6G_MB_LIB.T6G(SCH_1):PAGE101

M_E_CPU1_SA_DQ<8> @T6G_MB_LIB.T6G(SCH_1):M_E_CPU1_SA_DQ(8)
   U26  L71 MEA_DATA8 GENOA_SP5-SOCKET6096_13568-001,SMLF,IO,DGA^6000030   I159 @T6G_MB_LIB.T6G(SCH_1):PAGE41
   J32   18  DQ8_A SCONN288_DDR506112002KQ-SCONN288_DDR506112002KQ,SMA    I52 @T6G_MB_LIB.T6G(SCH_1):PAGE101

M_E_CPU1_SA_DQ<9> @T6G_MB_LIB.T6G(SCH_1):M_E_CPU1_SA_DQ(9)
   U26  M69 MEA_DATA9 GENOA_SP5-SOCKET6096_13568-001,SMLF,IO,DGA^6000030   I159 @T6G_MB_LIB.T6G(SCH_1):PAGE41
   J32   20  DQ9_A SCONN288_DDR506112002KQ-SCONN288_DDR506112002KQ,SMA    I52 @T6G_MB_LIB.T6G(SCH_1):PAGE101

M_E_CPU1_SA_DQS_DN<0> @T6G_MB_LIB.T6G(SCH_1):M_E_CPU1_SA_DQS_DN(0)
   U26  H70 MEA_DQS_L0 GENOA_SP5-SOCKET6096_13568-001,SMLF,IO,DGA^6000030   I159 @T6G_MB_LIB.T6G(SCH_1):PAGE41
   J32   12 DQS0_A_C SCONN288_DDR506112002KQ-SCONN288_DDR506112002KQ,SMA   I236 @T6G_MB_LIB.T6G(SCH_1):PAGE101

M_E_CPU1_SA_DQS_DN<1> @T6G_MB_LIB.T6G(SCH_1):M_E_CPU1_SA_DQS_DN(1)
   U26  P70 MEA_DQS_L1 GENOA_SP5-SOCKET6096_13568-001,SMLF,IO,DGA^6000030   I159 @T6G_MB_LIB.T6G(SCH_1):PAGE41
   J32   23 DQS1_A_C SCONN288_DDR506112002KQ-SCONN288_DDR506112002KQ,SMA   I236 @T6G_MB_LIB.T6G(SCH_1):PAGE101

M_E_CPU1_SA_DQS_DN<2> @T6G_MB_LIB.T6G(SCH_1):M_E_CPU1_SA_DQS_DN(2)
   U26  Y70 MEA_DQS_L2 GENOA_SP5-SOCKET6096_13568-001,SMLF,IO,DGA^6000030   I159 @T6G_MB_LIB.T6G(SCH_1):PAGE41
   J32   34 DQS2_A_C SCONN288_DDR506112002KQ-SCONN288_DDR506112002KQ,SMA   I236 @T6G_MB_LIB.T6G(SCH_1):PAGE101

M_E_CPU1_SA_DQS_DN<3> @T6G_MB_LIB.T6G(SCH_1):M_E_CPU1_SA_DQS_DN(3)
   U26 AF70 MEA_DQS_L3 GENOA_SP5-SOCKET6096_13568-001,SMLF,IO,DGA^6000030   I159 @T6G_MB_LIB.T6G(SCH_1):PAGE41
   J32   45 DQS3_A_C SCONN288_DDR506112002KQ-SCONN288_DDR506112002KQ,SMA   I236 @T6G_MB_LIB.T6G(SCH_1):PAGE101

M_E_CPU1_SA_DQS_DN<4> @T6G_MB_LIB.T6G(SCH_1):M_E_CPU1_SA_DQS_DN(4)
   U26 AM70 MEA_DQS_L4 GENOA_SP5-SOCKET6096_13568-001,SMLF,IO,DGA^6000030   I159 @T6G_MB_LIB.T6G(SCH_1):PAGE41
   J32   56 DQS4_A_C SCONN288_DDR506112002KQ-SCONN288_DDR506112002KQ,SMA   I236 @T6G_MB_LIB.T6G(SCH_1):PAGE101

M_E_CPU1_SA_DQS_DN<5> @T6G_MB_LIB.T6G(SCH_1):M_E_CPU1_SA_DQS_DN(5)
   U26  H69 MEA_DQS_L5 GENOA_SP5-SOCKET6096_13568-001,SMLF,IO,DGA^6000030   I159 @T6G_MB_LIB.T6G(SCH_1):PAGE41
   J32  156 DQS5_A_C||TDQS5_A_C||DQS5_A_T||TDQS5_A_T SCONN288_DDR506112002KQ-SCONN288_DDR506112002KQ,SMA   I236 @T6G_MB_LIB.T6G(SCH_1):PAGE101

M_E_CPU1_SA_DQS_DN<6> @T6G_MB_LIB.T6G(SCH_1):M_E_CPU1_SA_DQS_DN(6)
   U26  P69 MEA_DQS_L6 GENOA_SP5-SOCKET6096_13568-001,SMLF,IO,DGA^6000030   I159 @T6G_MB_LIB.T6G(SCH_1):PAGE41
   J32  167 DQS6_A_C||TDQS6_A_C||DQS6_A_T||TDQS6_A_T SCONN288_DDR506112002KQ-SCONN288_DDR506112002KQ,SMA   I236 @T6G_MB_LIB.T6G(SCH_1):PAGE101

M_E_CPU1_SA_DQS_DN<7> @T6G_MB_LIB.T6G(SCH_1):M_E_CPU1_SA_DQS_DN(7)
   U26  Y69 MEA_DQS_L7 GENOA_SP5-SOCKET6096_13568-001,SMLF,IO,DGA^6000030   I159 @T6G_MB_LIB.T6G(SCH_1):PAGE41
   J32  178 DQS7_A_C||TDQS7_A_C SCONN288_DDR506112002KQ-SCONN288_DDR506112002KQ,SMA   I236 @T6G_MB_LIB.T6G(SCH_1):PAGE101

M_E_CPU1_SA_DQS_DN<8> @T6G_MB_LIB.T6G(SCH_1):M_E_CPU1_SA_DQS_DN(8)
   U26 AF69 MEA_DQS_L8 GENOA_SP5-SOCKET6096_13568-001,SMLF,IO,DGA^6000030   I159 @T6G_MB_LIB.T6G(SCH_1):PAGE41
   J32  189 DQS8_A_C||TDQS8_A_C SCONN288_DDR506112002KQ-SCONN288_DDR506112002KQ,SMA   I236 @T6G_MB_LIB.T6G(SCH_1):PAGE101

M_E_CPU1_SA_DQS_DN<9> @T6G_MB_LIB.T6G(SCH_1):M_E_CPU1_SA_DQS_DN(9)
   U26 AM69 MEA_DQS_L9 GENOA_SP5-SOCKET6096_13568-001,SMLF,IO,DGA^6000030   I159 @T6G_MB_LIB.T6G(SCH_1):PAGE41
   J32  200 DQS9_A_C||TDQS9_A_C SCONN288_DDR506112002KQ-SCONN288_DDR506112002KQ,SMA   I236 @T6G_MB_LIB.T6G(SCH_1):PAGE101

M_E_CPU1_SA_DQS_DP<0> @T6G_MB_LIB.T6G(SCH_1):M_E_CPU1_SA_DQS_DP(0)
   U26  G71 MEA_DQS_H0 GENOA_SP5-SOCKET6096_13568-001,SMLF,IO,DGA^6000030   I159 @T6G_MB_LIB.T6G(SCH_1):PAGE41
   J32   11 DQS0_A_T SCONN288_DDR506112002KQ-SCONN288_DDR506112002KQ,SMA   I236 @T6G_MB_LIB.T6G(SCH_1):PAGE101

M_E_CPU1_SA_DQS_DP<1> @T6G_MB_LIB.T6G(SCH_1):M_E_CPU1_SA_DQS_DP(1)
   U26  N71 MEA_DQS_H1 GENOA_SP5-SOCKET6096_13568-001,SMLF,IO,DGA^6000030   I159 @T6G_MB_LIB.T6G(SCH_1):PAGE41
   J32   22 DQS1_A_T SCONN288_DDR506112002KQ-SCONN288_DDR506112002KQ,SMA   I236 @T6G_MB_LIB.T6G(SCH_1):PAGE101

M_E_CPU1_SA_DQS_DP<2> @T6G_MB_LIB.T6G(SCH_1):M_E_CPU1_SA_DQS_DP(2)
   U26  W71 MEA_DQS_H2 GENOA_SP5-SOCKET6096_13568-001,SMLF,IO,DGA^6000030   I159 @T6G_MB_LIB.T6G(SCH_1):PAGE41
   J32   33 DQS2_A_T SCONN288_DDR506112002KQ-SCONN288_DDR506112002KQ,SMA   I236 @T6G_MB_LIB.T6G(SCH_1):PAGE101

M_E_CPU1_SA_DQS_DP<3> @T6G_MB_LIB.T6G(SCH_1):M_E_CPU1_SA_DQS_DP(3)
   U26 AE71 MEA_DQS_H3 GENOA_SP5-SOCKET6096_13568-001,SMLF,IO,DGA^6000030   I159 @T6G_MB_LIB.T6G(SCH_1):PAGE41
   J32   44 DQS3_A_T SCONN288_DDR506112002KQ-SCONN288_DDR506112002KQ,SMA   I236 @T6G_MB_LIB.T6G(SCH_1):PAGE101

M_E_CPU1_SA_DQS_DP<4> @T6G_MB_LIB.T6G(SCH_1):M_E_CPU1_SA_DQS_DP(4)
   U26 AL71 MEA_DQS_H4 GENOA_SP5-SOCKET6096_13568-001,SMLF,IO,DGA^6000030   I159 @T6G_MB_LIB.T6G(SCH_1):PAGE41
   J32   55 DQS4_A_T SCONN288_DDR506112002KQ-SCONN288_DDR506112002KQ,SMA   I236 @T6G_MB_LIB.T6G(SCH_1):PAGE101

M_E_CPU1_SA_DQS_DP<5> @T6G_MB_LIB.T6G(SCH_1):M_E_CPU1_SA_DQS_DP(5)
   U26  J69 MEA_DQS_H5 GENOA_SP5-SOCKET6096_13568-001,SMLF,IO,DGA^6000030   I159 @T6G_MB_LIB.T6G(SCH_1):PAGE41
   J32  157 DQS5_A_T||TDQS5_A_T SCONN288_DDR506112002KQ-SCONN288_DDR506112002KQ,SMA   I236 @T6G_MB_LIB.T6G(SCH_1):PAGE101

M_E_CPU1_SA_DQS_DP<6> @T6G_MB_LIB.T6G(SCH_1):M_E_CPU1_SA_DQS_DP(6)
   U26  R69 MEA_DQS_H6 GENOA_SP5-SOCKET6096_13568-001,SMLF,IO,DGA^6000030   I159 @T6G_MB_LIB.T6G(SCH_1):PAGE41
   J32  168 DQS6_A_T||TDQS6_A_T SCONN288_DDR506112002KQ-SCONN288_DDR506112002KQ,SMA   I236 @T6G_MB_LIB.T6G(SCH_1):PAGE101

M_E_CPU1_SA_DQS_DP<7> @T6G_MB_LIB.T6G(SCH_1):M_E_CPU1_SA_DQS_DP(7)
   U26 AA69 MEA_DQS_H7 GENOA_SP5-SOCKET6096_13568-001,SMLF,IO,DGA^6000030   I159 @T6G_MB_LIB.T6G(SCH_1):PAGE41
   J32  179 DQS7_A_T||TDQS7_A_T SCONN288_DDR506112002KQ-SCONN288_DDR506112002KQ,SMA   I236 @T6G_MB_LIB.T6G(SCH_1):PAGE101

M_E_CPU1_SA_DQS_DP<8> @T6G_MB_LIB.T6G(SCH_1):M_E_CPU1_SA_DQS_DP(8)
   U26 AG69 MEA_DQS_H8 GENOA_SP5-SOCKET6096_13568-001,SMLF,IO,DGA^6000030   I159 @T6G_MB_LIB.T6G(SCH_1):PAGE41
   J32  190 DQS8_A_T||TDQS8_A_T SCONN288_DDR506112002KQ-SCONN288_DDR506112002KQ,SMA   I236 @T6G_MB_LIB.T6G(SCH_1):PAGE101

M_E_CPU1_SA_DQS_DP<9> @T6G_MB_LIB.T6G(SCH_1):M_E_CPU1_SA_DQS_DP(9)
   U26 AN69 MEA_DQS_H9 GENOA_SP5-SOCKET6096_13568-001,SMLF,IO,DGA^6000030   I159 @T6G_MB_LIB.T6G(SCH_1):PAGE41
   J32  201 DQS9_A_T||TDQS9_A_T SCONN288_DDR506112002KQ-SCONN288_DDR506112002KQ,SMA   I236 @T6G_MB_LIB.T6G(SCH_1):PAGE101

M_E_CPU1_SA_PAR @T6G_MB_LIB.T6G(SCH_1):M_E_CPU1_SA_PAR
   U26 BC69 MEA_PAR GENOA_SP5-SOCKET6096_13568-001,SMLF,IO,DGA^6000030   I159 @T6G_MB_LIB.T6G(SCH_1):PAGE41
   J32   74  PAR_A SCONN288_DDR506112002KQ-SCONN288_DDR506112002KQ,SMA    I52 @T6G_MB_LIB.T6G(SCH_1):PAGE101

M_E_CPU1_SA_RSP<0> @T6G_MB_LIB.T6G(SCH_1):M_E_CPU1_SA_RSP(0)
   U26 BN69 MEA0_RSP_L GENOA_SP5-SOCKET6096_13568-001,SMLF,IO,DGA^6000030   I159 @T6G_MB_LIB.T6G(SCH_1):PAGE41
   J32   86 LBD||RSP_A_N SCONN288_DDR506112002KQ-SCONN288_DDR506112002KQ,SMA    I52 @T6G_MB_LIB.T6G(SCH_1):PAGE101

M_E_CPU1_SB_CA<0> @T6G_MB_LIB.T6G(SCH_1):M_E_CPU1_SB_CA(0)
   U26 BG69 MEB_CA0 GENOA_SP5-SOCKET6096_13568-001,SMLF,IO,DGA^6000030   I159 @T6G_MB_LIB.T6G(SCH_1):PAGE41
   J32   76  CA0_B SCONN288_DDR506112002KQ-SCONN288_DDR506112002KQ,SMA    I52 @T6G_MB_LIB.T6G(SCH_1):PAGE101

M_E_CPU1_SB_CA<1> @T6G_MB_LIB.T6G(SCH_1):M_E_CPU1_SB_CA(1)
   U26 BH69 MEB_CA1 GENOA_SP5-SOCKET6096_13568-001,SMLF,IO,DGA^6000030   I159 @T6G_MB_LIB.T6G(SCH_1):PAGE41
   J32  221  CA1_B SCONN288_DDR506112002KQ-SCONN288_DDR506112002KQ,SMA    I52 @T6G_MB_LIB.T6G(SCH_1):PAGE101

M_E_CPU1_SB_CA<2> @T6G_MB_LIB.T6G(SCH_1):M_E_CPU1_SB_CA(2)
   U26 BH70 MEB_CA2 GENOA_SP5-SOCKET6096_13568-001,SMLF,IO,DGA^6000030   I159 @T6G_MB_LIB.T6G(SCH_1):PAGE41
   J32   78  CA2_B SCONN288_DDR506112002KQ-SCONN288_DDR506112002KQ,SMA    I52 @T6G_MB_LIB.T6G(SCH_1):PAGE101

M_E_CPU1_SB_CA<3> @T6G_MB_LIB.T6G(SCH_1):M_E_CPU1_SB_CA(3)
   U26 BJ71 MEB_CA3 GENOA_SP5-SOCKET6096_13568-001,SMLF,IO,DGA^6000030   I159 @T6G_MB_LIB.T6G(SCH_1):PAGE41
   J32  223  CA3_B SCONN288_DDR506112002KQ-SCONN288_DDR506112002KQ,SMA    I52 @T6G_MB_LIB.T6G(SCH_1):PAGE101

M_E_CPU1_SB_CA<4> @T6G_MB_LIB.T6G(SCH_1):M_E_CPU1_SB_CA(4)
   U26 BJ69 MEB_CA4 GENOA_SP5-SOCKET6096_13568-001,SMLF,IO,DGA^6000030   I159 @T6G_MB_LIB.T6G(SCH_1):PAGE41
   J32   80  CA4_B SCONN288_DDR506112002KQ-SCONN288_DDR506112002KQ,SMA    I52 @T6G_MB_LIB.T6G(SCH_1):PAGE101

M_E_CPU1_SB_CA<5> @T6G_MB_LIB.T6G(SCH_1):M_E_CPU1_SB_CA(5)
   U26 BK69 MEB_CA5 GENOA_SP5-SOCKET6096_13568-001,SMLF,IO,DGA^6000030   I159 @T6G_MB_LIB.T6G(SCH_1):PAGE41
   J32  225  CA5_B SCONN288_DDR506112002KQ-SCONN288_DDR506112002KQ,SMA    I52 @T6G_MB_LIB.T6G(SCH_1):PAGE101

M_E_CPU1_SB_CA<6> @T6G_MB_LIB.T6G(SCH_1):M_E_CPU1_SB_CA(6)
   U26 BK70 MEB_CA6 GENOA_SP5-SOCKET6096_13568-001,SMLF,IO,DGA^6000030   I159 @T6G_MB_LIB.T6G(SCH_1):PAGE41
   J32   82  CA6_B SCONN288_DDR506112002KQ-SCONN288_DDR506112002KQ,SMA    I52 @T6G_MB_LIB.T6G(SCH_1):PAGE101

M_E_CPU1_SB_CB<0> @T6G_MB_LIB.T6G(SCH_1):M_E_CPU1_SB_CB(0)
   U26 BY70 MEB_CHECK0 GENOA_SP5-SOCKET6096_13568-001,SMLF,IO,DGA^6000030   I159 @T6G_MB_LIB.T6G(SCH_1):PAGE41
   J32   96  CB0_B SCONN288_DDR506112002KQ-SCONN288_DDR506112002KQ,SMA    I52 @T6G_MB_LIB.T6G(SCH_1):PAGE101

M_E_CPU1_SB_CB<1> @T6G_MB_LIB.T6G(SCH_1):M_E_CPU1_SB_CB(1)
   U26 CA69 MEB_CHECK1 GENOA_SP5-SOCKET6096_13568-001,SMLF,IO,DGA^6000030   I159 @T6G_MB_LIB.T6G(SCH_1):PAGE41
   J32   98  CB1_B SCONN288_DDR506112002KQ-SCONN288_DDR506112002KQ,SMA    I52 @T6G_MB_LIB.T6G(SCH_1):PAGE101

M_E_CPU1_SB_CB<2> @T6G_MB_LIB.T6G(SCH_1):M_E_CPU1_SB_CB(2)
   U26 CA71 MEB_CHECK2 GENOA_SP5-SOCKET6096_13568-001,SMLF,IO,DGA^6000030   I159 @T6G_MB_LIB.T6G(SCH_1):PAGE41
   J32  241  CB2_B SCONN288_DDR506112002KQ-SCONN288_DDR506112002KQ,SMA    I52 @T6G_MB_LIB.T6G(SCH_1):PAGE101

M_E_CPU1_SB_CB<3> @T6G_MB_LIB.T6G(SCH_1):M_E_CPU1_SB_CB(3)
   U26 CB69 MEB_CHECK3 GENOA_SP5-SOCKET6096_13568-001,SMLF,IO,DGA^6000030   I159 @T6G_MB_LIB.T6G(SCH_1):PAGE41
   J32  243  CB3_B SCONN288_DDR506112002KQ-SCONN288_DDR506112002KQ,SMA    I52 @T6G_MB_LIB.T6G(SCH_1):PAGE101

M_E_CPU1_SB_CB<4> @T6G_MB_LIB.T6G(SCH_1):M_E_CPU1_SB_CB(4)
   U26 BT70 MEB_CHECK4 GENOA_SP5-SOCKET6096_13568-001,SMLF,IO,DGA^6000030   I159 @T6G_MB_LIB.T6G(SCH_1):PAGE41
   J32   89  CB4_B SCONN288_DDR506112002KQ-SCONN288_DDR506112002KQ,SMA    I52 @T6G_MB_LIB.T6G(SCH_1):PAGE101

M_E_CPU1_SB_CB<5> @T6G_MB_LIB.T6G(SCH_1):M_E_CPU1_SB_CB(5)
   U26 BU69 MEB_CHECK5 GENOA_SP5-SOCKET6096_13568-001,SMLF,IO,DGA^6000030   I159 @T6G_MB_LIB.T6G(SCH_1):PAGE41
   J32   91  CB5_B SCONN288_DDR506112002KQ-SCONN288_DDR506112002KQ,SMA    I52 @T6G_MB_LIB.T6G(SCH_1):PAGE101

M_E_CPU1_SB_CB<6> @T6G_MB_LIB.T6G(SCH_1):M_E_CPU1_SB_CB(6)
   U26 BU71 MEB_CHECK6 GENOA_SP5-SOCKET6096_13568-001,SMLF,IO,DGA^6000030   I159 @T6G_MB_LIB.T6G(SCH_1):PAGE41
   J32  234  CB6_B SCONN288_DDR506112002KQ-SCONN288_DDR506112002KQ,SMA    I52 @T6G_MB_LIB.T6G(SCH_1):PAGE101

M_E_CPU1_SB_CB<7> @T6G_MB_LIB.T6G(SCH_1):M_E_CPU1_SB_CB(7)
   U26 BV69 MEB_CHECK7 GENOA_SP5-SOCKET6096_13568-001,SMLF,IO,DGA^6000030   I159 @T6G_MB_LIB.T6G(SCH_1):PAGE41
   J32  236  CB7_B SCONN288_DDR506112002KQ-SCONN288_DDR506112002KQ,SMA    I52 @T6G_MB_LIB.T6G(SCH_1):PAGE101

M_E_CPU1_SB_CS_N<0> @T6G_MB_LIB.T6G(SCH_1):M_E_CPU1_SB_CS_N(0)
   U26 BM69 MEB0_CS_L0 GENOA_SP5-SOCKET6096_13568-001,SMLF,IO,DGA^6000030   I159 @T6G_MB_LIB.T6G(SCH_1):PAGE41
   J32   84 CS0_B_N SCONN288_DDR506112002KQ-SCONN288_DDR506112002KQ,SMA    I52 @T6G_MB_LIB.T6G(SCH_1):PAGE101

M_E_CPU1_SB_CS_N<1> @T6G_MB_LIB.T6G(SCH_1):M_E_CPU1_SB_CS_N(1)
   U26 BN71 MEB0_CS_L1 GENOA_SP5-SOCKET6096_13568-001,SMLF,IO,DGA^6000030   I159 @T6G_MB_LIB.T6G(SCH_1):PAGE41
   J32  229 CS1_B_N SCONN288_DDR506112002KQ-SCONN288_DDR506112002KQ,SMA    I52 @T6G_MB_LIB.T6G(SCH_1):PAGE101

M_E_CPU1_SB_DQ<0> @T6G_MB_LIB.T6G(SCH_1):M_E_CPU1_SB_DQ(0)
   U26 CB70 MEB_DATA0 GENOA_SP5-SOCKET6096_13568-001,SMLF,IO,DGA^6000030   I159 @T6G_MB_LIB.T6G(SCH_1):PAGE41
   J32  100  DQ0_B SCONN288_DDR506112002KQ-SCONN288_DDR506112002KQ,SMA    I52 @T6G_MB_LIB.T6G(SCH_1):PAGE101

M_E_CPU1_SB_DQ<10> @T6G_MB_LIB.T6G(SCH_1):M_E_CPU1_SB_DQ(10)
   U26 CJ71 MEB_DATA10 GENOA_SP5-SOCKET6096_13568-001,SMLF,IO,DGA^6000030   I159 @T6G_MB_LIB.T6G(SCH_1):PAGE41
   J32  256 DQ10_B SCONN288_DDR506112002KQ-SCONN288_DDR506112002KQ,SMA    I52 @T6G_MB_LIB.T6G(SCH_1):PAGE101

M_E_CPU1_SB_DQ<11> @T6G_MB_LIB.T6G(SCH_1):M_E_CPU1_SB_DQ(11)
   U26 CK69 MEB_DATA11 GENOA_SP5-SOCKET6096_13568-001,SMLF,IO,DGA^6000030   I159 @T6G_MB_LIB.T6G(SCH_1):PAGE41
   J32  258 DQ11_B SCONN288_DDR506112002KQ-SCONN288_DDR506112002KQ,SMA    I52 @T6G_MB_LIB.T6G(SCH_1):PAGE101

M_E_CPU1_SB_DQ<12> @T6G_MB_LIB.T6G(SCH_1):M_E_CPU1_SB_DQ(12)
   U26 CM70 MEB_DATA12 GENOA_SP5-SOCKET6096_13568-001,SMLF,IO,DGA^6000030   I159 @T6G_MB_LIB.T6G(SCH_1):PAGE41
   J32  118 DQ12_B SCONN288_DDR506112002KQ-SCONN288_DDR506112002KQ,SMA    I52 @T6G_MB_LIB.T6G(SCH_1):PAGE101

M_E_CPU1_SB_DQ<13> @T6G_MB_LIB.T6G(SCH_1):M_E_CPU1_SB_DQ(13)
   U26 CN69 MEB_DATA13 GENOA_SP5-SOCKET6096_13568-001,SMLF,IO,DGA^6000030   I159 @T6G_MB_LIB.T6G(SCH_1):PAGE41
   J32  120 DQ13_B SCONN288_DDR506112002KQ-SCONN288_DDR506112002KQ,SMA    I52 @T6G_MB_LIB.T6G(SCH_1):PAGE101

M_E_CPU1_SB_DQ<14> @T6G_MB_LIB.T6G(SCH_1):M_E_CPU1_SB_DQ(14)
   U26 CN71 MEB_DATA14 GENOA_SP5-SOCKET6096_13568-001,SMLF,IO,DGA^6000030   I159 @T6G_MB_LIB.T6G(SCH_1):PAGE41
   J32  263 DQ14_B SCONN288_DDR506112002KQ-SCONN288_DDR506112002KQ,SMA    I52 @T6G_MB_LIB.T6G(SCH_1):PAGE101

M_E_CPU1_SB_DQ<15> @T6G_MB_LIB.T6G(SCH_1):M_E_CPU1_SB_DQ(15)
   U26 CP69 MEB_DATA15 GENOA_SP5-SOCKET6096_13568-001,SMLF,IO,DGA^6000030   I159 @T6G_MB_LIB.T6G(SCH_1):PAGE41
   J32  265 DQ15_B SCONN288_DDR506112002KQ-SCONN288_DDR506112002KQ,SMA    I52 @T6G_MB_LIB.T6G(SCH_1):PAGE101

M_E_CPU1_SB_DQ<16> @T6G_MB_LIB.T6G(SCH_1):M_E_CPU1_SB_DQ(16)
   U26 CP70 MEB_DATA16 GENOA_SP5-SOCKET6096_13568-001,SMLF,IO,DGA^6000030   I159 @T6G_MB_LIB.T6G(SCH_1):PAGE41
   J32  122 DQ16_B SCONN288_DDR506112002KQ-SCONN288_DDR506112002KQ,SMA    I52 @T6G_MB_LIB.T6G(SCH_1):PAGE101

M_E_CPU1_SB_DQ<17> @T6G_MB_LIB.T6G(SCH_1):M_E_CPU1_SB_DQ(17)
   U26 CR69 MEB_DATA17 GENOA_SP5-SOCKET6096_13568-001,SMLF,IO,DGA^6000030   I159 @T6G_MB_LIB.T6G(SCH_1):PAGE41
   J32  124 DQ17_B SCONN288_DDR506112002KQ-SCONN288_DDR506112002KQ,SMA    I52 @T6G_MB_LIB.T6G(SCH_1):PAGE101

M_E_CPU1_SB_DQ<18> @T6G_MB_LIB.T6G(SCH_1):M_E_CPU1_SB_DQ(18)
   U26 CR71 MEB_DATA18 GENOA_SP5-SOCKET6096_13568-001,SMLF,IO,DGA^6000030   I159 @T6G_MB_LIB.T6G(SCH_1):PAGE41
   J32  267 DQ18_B SCONN288_DDR506112002KQ-SCONN288_DDR506112002KQ,SMA    I52 @T6G_MB_LIB.T6G(SCH_1):PAGE101

M_E_CPU1_SB_DQ<19> @T6G_MB_LIB.T6G(SCH_1):M_E_CPU1_SB_DQ(19)
   U26 CT69 MEB_DATA19 GENOA_SP5-SOCKET6096_13568-001,SMLF,IO,DGA^6000030   I159 @T6G_MB_LIB.T6G(SCH_1):PAGE41
   J32  269 DQ19_B SCONN288_DDR506112002KQ-SCONN288_DDR506112002KQ,SMA    I52 @T6G_MB_LIB.T6G(SCH_1):PAGE101

M_E_CPU1_SB_DQ<1> @T6G_MB_LIB.T6G(SCH_1):M_E_CPU1_SB_DQ(1)
   U26 CC69 MEB_DATA1 GENOA_SP5-SOCKET6096_13568-001,SMLF,IO,DGA^6000030   I159 @T6G_MB_LIB.T6G(SCH_1):PAGE41
   J32  102  DQ1_B SCONN288_DDR506112002KQ-SCONN288_DDR506112002KQ,SMA    I52 @T6G_MB_LIB.T6G(SCH_1):PAGE101

M_E_CPU1_SB_DQ<20> @T6G_MB_LIB.T6G(SCH_1):M_E_CPU1_SB_DQ(20)
   U26 CV70 MEB_DATA20 GENOA_SP5-SOCKET6096_13568-001,SMLF,IO,DGA^6000030   I159 @T6G_MB_LIB.T6G(SCH_1):PAGE41
   J32  129 DQ20_B SCONN288_DDR506112002KQ-SCONN288_DDR506112002KQ,SMA    I52 @T6G_MB_LIB.T6G(SCH_1):PAGE101

M_E_CPU1_SB_DQ<21> @T6G_MB_LIB.T6G(SCH_1):M_E_CPU1_SB_DQ(21)
   U26 CW69 MEB_DATA21 GENOA_SP5-SOCKET6096_13568-001,SMLF,IO,DGA^6000030   I159 @T6G_MB_LIB.T6G(SCH_1):PAGE41
   J32  131 DQ21_B SCONN288_DDR506112002KQ-SCONN288_DDR506112002KQ,SMA    I52 @T6G_MB_LIB.T6G(SCH_1):PAGE101

M_E_CPU1_SB_DQ<22> @T6G_MB_LIB.T6G(SCH_1):M_E_CPU1_SB_DQ(22)
   U26 CW71 MEB_DATA22 GENOA_SP5-SOCKET6096_13568-001,SMLF,IO,DGA^6000030   I159 @T6G_MB_LIB.T6G(SCH_1):PAGE41
   J32  274 DQ22_B SCONN288_DDR506112002KQ-SCONN288_DDR506112002KQ,SMA    I52 @T6G_MB_LIB.T6G(SCH_1):PAGE101

M_E_CPU1_SB_DQ<23> @T6G_MB_LIB.T6G(SCH_1):M_E_CPU1_SB_DQ(23)
   U26 CY69 MEB_DATA23 GENOA_SP5-SOCKET6096_13568-001,SMLF,IO,DGA^6000030   I159 @T6G_MB_LIB.T6G(SCH_1):PAGE41
   J32  276 DQ23_B SCONN288_DDR506112002KQ-SCONN288_DDR506112002KQ,SMA    I52 @T6G_MB_LIB.T6G(SCH_1):PAGE101

M_E_CPU1_SB_DQ<24> @T6G_MB_LIB.T6G(SCH_1):M_E_CPU1_SB_DQ(24)
   U26 CY70 MEB_DATA24 GENOA_SP5-SOCKET6096_13568-001,SMLF,IO,DGA^6000030   I159 @T6G_MB_LIB.T6G(SCH_1):PAGE41
   J32  133 DQ24_B SCONN288_DDR506112002KQ-SCONN288_DDR506112002KQ,SMA    I52 @T6G_MB_LIB.T6G(SCH_1):PAGE101

M_E_CPU1_SB_DQ<25> @T6G_MB_LIB.T6G(SCH_1):M_E_CPU1_SB_DQ(25)
   U26 DA69 MEB_DATA25 GENOA_SP5-SOCKET6096_13568-001,SMLF,IO,DGA^6000030   I159 @T6G_MB_LIB.T6G(SCH_1):PAGE41
   J32  135 DQ25_B SCONN288_DDR506112002KQ-SCONN288_DDR506112002KQ,SMA    I52 @T6G_MB_LIB.T6G(SCH_1):PAGE101

M_E_CPU1_SB_DQ<26> @T6G_MB_LIB.T6G(SCH_1):M_E_CPU1_SB_DQ(26)
   U26 DA71 MEB_DATA26 GENOA_SP5-SOCKET6096_13568-001,SMLF,IO,DGA^6000030   I159 @T6G_MB_LIB.T6G(SCH_1):PAGE41
   J32  278 DQ26_B SCONN288_DDR506112002KQ-SCONN288_DDR506112002KQ,SMA    I52 @T6G_MB_LIB.T6G(SCH_1):PAGE101

M_E_CPU1_SB_DQ<27> @T6G_MB_LIB.T6G(SCH_1):M_E_CPU1_SB_DQ(27)
   U26 DB69 MEB_DATA27 GENOA_SP5-SOCKET6096_13568-001,SMLF,IO,DGA^6000030   I159 @T6G_MB_LIB.T6G(SCH_1):PAGE41
   J32  280 DQ27_B SCONN288_DDR506112002KQ-SCONN288_DDR506112002KQ,SMA    I52 @T6G_MB_LIB.T6G(SCH_1):PAGE101

M_E_CPU1_SB_DQ<28> @T6G_MB_LIB.T6G(SCH_1):M_E_CPU1_SB_DQ(28)
   U26 DD70 MEB_DATA28 GENOA_SP5-SOCKET6096_13568-001,SMLF,IO,DGA^6000030   I159 @T6G_MB_LIB.T6G(SCH_1):PAGE41
   J32  140 DQ28_B SCONN288_DDR506112002KQ-SCONN288_DDR506112002KQ,SMA    I52 @T6G_MB_LIB.T6G(SCH_1):PAGE101

M_E_CPU1_SB_DQ<29> @T6G_MB_LIB.T6G(SCH_1):M_E_CPU1_SB_DQ(29)
   U26 DE69 MEB_DATA29 GENOA_SP5-SOCKET6096_13568-001,SMLF,IO,DGA^6000030   I159 @T6G_MB_LIB.T6G(SCH_1):PAGE41
   J32  142 DQ29_B SCONN288_DDR506112002KQ-SCONN288_DDR506112002KQ,SMA    I52 @T6G_MB_LIB.T6G(SCH_1):PAGE101

M_E_CPU1_SB_DQ<2> @T6G_MB_LIB.T6G(SCH_1):M_E_CPU1_SB_DQ(2)
   U26 CC71 MEB_DATA2 GENOA_SP5-SOCKET6096_13568-001,SMLF,IO,DGA^6000030   I159 @T6G_MB_LIB.T6G(SCH_1):PAGE41
   J32  245  DQ2_B SCONN288_DDR506112002KQ-SCONN288_DDR506112002KQ,SMA    I52 @T6G_MB_LIB.T6G(SCH_1):PAGE101

M_E_CPU1_SB_DQ<30> @T6G_MB_LIB.T6G(SCH_1):M_E_CPU1_SB_DQ(30)
   U26 DE71 MEB_DATA30 GENOA_SP5-SOCKET6096_13568-001,SMLF,IO,DGA^6000030   I159 @T6G_MB_LIB.T6G(SCH_1):PAGE41
   J32  285 DQ30_B SCONN288_DDR506112002KQ-SCONN288_DDR506112002KQ,SMA    I52 @T6G_MB_LIB.T6G(SCH_1):PAGE101

M_E_CPU1_SB_DQ<31> @T6G_MB_LIB.T6G(SCH_1):M_E_CPU1_SB_DQ(31)
   U26 DF69 MEB_DATA31 GENOA_SP5-SOCKET6096_13568-001,SMLF,IO,DGA^6000030   I159 @T6G_MB_LIB.T6G(SCH_1):PAGE41
   J32  287 DQ31_B SCONN288_DDR506112002KQ-SCONN288_DDR506112002KQ,SMA    I52 @T6G_MB_LIB.T6G(SCH_1):PAGE101

M_E_CPU1_SB_DQ<3> @T6G_MB_LIB.T6G(SCH_1):M_E_CPU1_SB_DQ(3)
   U26 CD69 MEB_DATA3 GENOA_SP5-SOCKET6096_13568-001,SMLF,IO,DGA^6000030   I159 @T6G_MB_LIB.T6G(SCH_1):PAGE41
   J32  247  DQ3_B SCONN288_DDR506112002KQ-SCONN288_DDR506112002KQ,SMA    I52 @T6G_MB_LIB.T6G(SCH_1):PAGE101

M_E_CPU1_SB_DQ<4> @T6G_MB_LIB.T6G(SCH_1):M_E_CPU1_SB_DQ(4)
   U26 CF70 MEB_DATA4 GENOA_SP5-SOCKET6096_13568-001,SMLF,IO,DGA^6000030   I159 @T6G_MB_LIB.T6G(SCH_1):PAGE41
   J32  107  DQ4_B SCONN288_DDR506112002KQ-SCONN288_DDR506112002KQ,SMA    I52 @T6G_MB_LIB.T6G(SCH_1):PAGE101

M_E_CPU1_SB_DQ<5> @T6G_MB_LIB.T6G(SCH_1):M_E_CPU1_SB_DQ(5)
   U26 CG69 MEB_DATA5 GENOA_SP5-SOCKET6096_13568-001,SMLF,IO,DGA^6000030   I159 @T6G_MB_LIB.T6G(SCH_1):PAGE41
   J32  109  DQ5_B SCONN288_DDR506112002KQ-SCONN288_DDR506112002KQ,SMA    I52 @T6G_MB_LIB.T6G(SCH_1):PAGE101

M_E_CPU1_SB_DQ<6> @T6G_MB_LIB.T6G(SCH_1):M_E_CPU1_SB_DQ(6)
   U26 CG71 MEB_DATA6 GENOA_SP5-SOCKET6096_13568-001,SMLF,IO,DGA^6000030   I159 @T6G_MB_LIB.T6G(SCH_1):PAGE41
   J32  252  DQ6_B SCONN288_DDR506112002KQ-SCONN288_DDR506112002KQ,SMA    I52 @T6G_MB_LIB.T6G(SCH_1):PAGE101

M_E_CPU1_SB_DQ<7> @T6G_MB_LIB.T6G(SCH_1):M_E_CPU1_SB_DQ(7)
   U26 CH69 MEB_DATA7 GENOA_SP5-SOCKET6096_13568-001,SMLF,IO,DGA^6000030   I159 @T6G_MB_LIB.T6G(SCH_1):PAGE41
   J32  254  DQ7_B SCONN288_DDR506112002KQ-SCONN288_DDR506112002KQ,SMA    I52 @T6G_MB_LIB.T6G(SCH_1):PAGE101

M_E_CPU1_SB_DQ<8> @T6G_MB_LIB.T6G(SCH_1):M_E_CPU1_SB_DQ(8)
   U26 CH70 MEB_DATA8 GENOA_SP5-SOCKET6096_13568-001,SMLF,IO,DGA^6000030   I159 @T6G_MB_LIB.T6G(SCH_1):PAGE41
   J32  111  DQ8_B SCONN288_DDR506112002KQ-SCONN288_DDR506112002KQ,SMA    I52 @T6G_MB_LIB.T6G(SCH_1):PAGE101

M_E_CPU1_SB_DQ<9> @T6G_MB_LIB.T6G(SCH_1):M_E_CPU1_SB_DQ(9)
   U26 CJ69 MEB_DATA9 GENOA_SP5-SOCKET6096_13568-001,SMLF,IO,DGA^6000030   I159 @T6G_MB_LIB.T6G(SCH_1):PAGE41
   J32  113  DQ9_B SCONN288_DDR506112002KQ-SCONN288_DDR506112002KQ,SMA    I52 @T6G_MB_LIB.T6G(SCH_1):PAGE101

M_E_CPU1_SB_DQS_DN<0> @T6G_MB_LIB.T6G(SCH_1):M_E_CPU1_SB_DQS_DN(0)
   U26 CE71 MEB_DQS_L0 GENOA_SP5-SOCKET6096_13568-001,SMLF,IO,DGA^6000030   I159 @T6G_MB_LIB.T6G(SCH_1):PAGE41
   J32  105 DQS0_B_C SCONN288_DDR506112002KQ-SCONN288_DDR506112002KQ,SMA   I236 @T6G_MB_LIB.T6G(SCH_1):PAGE101

M_E_CPU1_SB_DQS_DN<1> @T6G_MB_LIB.T6G(SCH_1):M_E_CPU1_SB_DQS_DN(1)
   U26 CL71 MEB_DQS_L1 GENOA_SP5-SOCKET6096_13568-001,SMLF,IO,DGA^6000030   I159 @T6G_MB_LIB.T6G(SCH_1):PAGE41
   J32  116 DQS1_B_C SCONN288_DDR506112002KQ-SCONN288_DDR506112002KQ,SMA   I236 @T6G_MB_LIB.T6G(SCH_1):PAGE101

M_E_CPU1_SB_DQS_DN<2> @T6G_MB_LIB.T6G(SCH_1):M_E_CPU1_SB_DQS_DN(2)
   U26 CU71 MEB_DQS_L2 GENOA_SP5-SOCKET6096_13568-001,SMLF,IO,DGA^6000030   I159 @T6G_MB_LIB.T6G(SCH_1):PAGE41
   J32  127 DQS2_B_C SCONN288_DDR506112002KQ-SCONN288_DDR506112002KQ,SMA   I236 @T6G_MB_LIB.T6G(SCH_1):PAGE101

M_E_CPU1_SB_DQS_DN<3> @T6G_MB_LIB.T6G(SCH_1):M_E_CPU1_SB_DQS_DN(3)
   U26 DC71 MEB_DQS_L3 GENOA_SP5-SOCKET6096_13568-001,SMLF,IO,DGA^6000030   I159 @T6G_MB_LIB.T6G(SCH_1):PAGE41
   J32  138 DQS3_B_C SCONN288_DDR506112002KQ-SCONN288_DDR506112002KQ,SMA   I236 @T6G_MB_LIB.T6G(SCH_1):PAGE101

M_E_CPU1_SB_DQS_DN<4> @T6G_MB_LIB.T6G(SCH_1):M_E_CPU1_SB_DQS_DN(4)
   U26 BW69 MEB_DQS_L4 GENOA_SP5-SOCKET6096_13568-001,SMLF,IO,DGA^6000030   I159 @T6G_MB_LIB.T6G(SCH_1):PAGE41
   J32  238 DQS4_B_C SCONN288_DDR506112002KQ-SCONN288_DDR506112002KQ,SMA   I236 @T6G_MB_LIB.T6G(SCH_1):PAGE101

M_E_CPU1_SB_DQS_DN<5> @T6G_MB_LIB.T6G(SCH_1):M_E_CPU1_SB_DQS_DN(5)
   U26 CE69 MEB_DQS_L5 GENOA_SP5-SOCKET6096_13568-001,SMLF,IO,DGA^6000030   I159 @T6G_MB_LIB.T6G(SCH_1):PAGE41
   J32  249 DQS5_B_C||TDQS5_B_C SCONN288_DDR506112002KQ-SCONN288_DDR506112002KQ,SMA   I236 @T6G_MB_LIB.T6G(SCH_1):PAGE101

M_E_CPU1_SB_DQS_DN<6> @T6G_MB_LIB.T6G(SCH_1):M_E_CPU1_SB_DQS_DN(6)
   U26 CL69 MEB_DQS_L6 GENOA_SP5-SOCKET6096_13568-001,SMLF,IO,DGA^6000030   I159 @T6G_MB_LIB.T6G(SCH_1):PAGE41
   J32  260 DQS6_B_C||TDQS6_B_C SCONN288_DDR506112002KQ-SCONN288_DDR506112002KQ,SMA   I236 @T6G_MB_LIB.T6G(SCH_1):PAGE101

M_E_CPU1_SB_DQS_DN<7> @T6G_MB_LIB.T6G(SCH_1):M_E_CPU1_SB_DQS_DN(7)
   U26 CU69 MEB_DQS_L7 GENOA_SP5-SOCKET6096_13568-001,SMLF,IO,DGA^6000030   I159 @T6G_MB_LIB.T6G(SCH_1):PAGE41
   J32  271 DQS7_B_C||TDQS7_B_C SCONN288_DDR506112002KQ-SCONN288_DDR506112002KQ,SMA   I236 @T6G_MB_LIB.T6G(SCH_1):PAGE101

M_E_CPU1_SB_DQS_DN<8> @T6G_MB_LIB.T6G(SCH_1):M_E_CPU1_SB_DQS_DN(8)
   U26 DC69 MEB_DQS_L8 GENOA_SP5-SOCKET6096_13568-001,SMLF,IO,DGA^6000030   I159 @T6G_MB_LIB.T6G(SCH_1):PAGE41
   J32  282 DQS8_B_C||TDQS8_B_C SCONN288_DDR506112002KQ-SCONN288_DDR506112002KQ,SMA   I236 @T6G_MB_LIB.T6G(SCH_1):PAGE101

M_E_CPU1_SB_DQS_DN<9> @T6G_MB_LIB.T6G(SCH_1):M_E_CPU1_SB_DQS_DN(9)
   U26 BW71 MEB_DQS_L9 GENOA_SP5-SOCKET6096_13568-001,SMLF,IO,DGA^6000030   I159 @T6G_MB_LIB.T6G(SCH_1):PAGE41
   J32   94 DQS9_B_C||TDQS9_B_C SCONN288_DDR506112002KQ-SCONN288_DDR506112002KQ,SMA   I236 @T6G_MB_LIB.T6G(SCH_1):PAGE101

M_E_CPU1_SB_DQS_DP<0> @T6G_MB_LIB.T6G(SCH_1):M_E_CPU1_SB_DQS_DP(0)
   U26 CD70 MEB_DQS_H0 GENOA_SP5-SOCKET6096_13568-001,SMLF,IO,DGA^6000030   I159 @T6G_MB_LIB.T6G(SCH_1):PAGE41
   J32  104 DQS0_B_T SCONN288_DDR506112002KQ-SCONN288_DDR506112002KQ,SMA   I236 @T6G_MB_LIB.T6G(SCH_1):PAGE101

M_E_CPU1_SB_DQS_DP<1> @T6G_MB_LIB.T6G(SCH_1):M_E_CPU1_SB_DQS_DP(1)
   U26 CK70 MEB_DQS_H1 GENOA_SP5-SOCKET6096_13568-001,SMLF,IO,DGA^6000030   I159 @T6G_MB_LIB.T6G(SCH_1):PAGE41
   J32  115 DQS1_B_T SCONN288_DDR506112002KQ-SCONN288_DDR506112002KQ,SMA   I236 @T6G_MB_LIB.T6G(SCH_1):PAGE101

M_E_CPU1_SB_DQS_DP<2> @T6G_MB_LIB.T6G(SCH_1):M_E_CPU1_SB_DQS_DP(2)
   U26 CT70 MEB_DQS_H2 GENOA_SP5-SOCKET6096_13568-001,SMLF,IO,DGA^6000030   I159 @T6G_MB_LIB.T6G(SCH_1):PAGE41
   J32  126 DQS2_B_T SCONN288_DDR506112002KQ-SCONN288_DDR506112002KQ,SMA   I236 @T6G_MB_LIB.T6G(SCH_1):PAGE101

M_E_CPU1_SB_DQS_DP<3> @T6G_MB_LIB.T6G(SCH_1):M_E_CPU1_SB_DQS_DP(3)
   U26 DB70 MEB_DQS_H3 GENOA_SP5-SOCKET6096_13568-001,SMLF,IO,DGA^6000030   I159 @T6G_MB_LIB.T6G(SCH_1):PAGE41
   J32  137 DQS3_B_T SCONN288_DDR506112002KQ-SCONN288_DDR506112002KQ,SMA   I236 @T6G_MB_LIB.T6G(SCH_1):PAGE101

M_E_CPU1_SB_DQS_DP<4> @T6G_MB_LIB.T6G(SCH_1):M_E_CPU1_SB_DQS_DP(4)
   U26 BY69 MEB_DQS_H4 GENOA_SP5-SOCKET6096_13568-001,SMLF,IO,DGA^6000030   I159 @T6G_MB_LIB.T6G(SCH_1):PAGE41
   J32  239 DQS4_B_T SCONN288_DDR506112002KQ-SCONN288_DDR506112002KQ,SMA   I236 @T6G_MB_LIB.T6G(SCH_1):PAGE101

M_E_CPU1_SB_DQS_DP<5> @T6G_MB_LIB.T6G(SCH_1):M_E_CPU1_SB_DQS_DP(5)
   U26 CF69 MEB_DQS_H5 GENOA_SP5-SOCKET6096_13568-001,SMLF,IO,DGA^6000030   I159 @T6G_MB_LIB.T6G(SCH_1):PAGE41
   J32  250 DQS5_B_T||TDQS5_B_T SCONN288_DDR506112002KQ-SCONN288_DDR506112002KQ,SMA   I236 @T6G_MB_LIB.T6G(SCH_1):PAGE101

M_E_CPU1_SB_DQS_DP<6> @T6G_MB_LIB.T6G(SCH_1):M_E_CPU1_SB_DQS_DP(6)
   U26 CM69 MEB_DQS_H6 GENOA_SP5-SOCKET6096_13568-001,SMLF,IO,DGA^6000030   I159 @T6G_MB_LIB.T6G(SCH_1):PAGE41
   J32  261 DQS6_B_T||TDQS6_B_T SCONN288_DDR506112002KQ-SCONN288_DDR506112002KQ,SMA   I236 @T6G_MB_LIB.T6G(SCH_1):PAGE101

M_E_CPU1_SB_DQS_DP<7> @T6G_MB_LIB.T6G(SCH_1):M_E_CPU1_SB_DQS_DP(7)
   U26 CV69 MEB_DQS_H7 GENOA_SP5-SOCKET6096_13568-001,SMLF,IO,DGA^6000030   I159 @T6G_MB_LIB.T6G(SCH_1):PAGE41
   J32  272 DQS7_B_T||TDQS7_B_T SCONN288_DDR506112002KQ-SCONN288_DDR506112002KQ,SMA   I236 @T6G_MB_LIB.T6G(SCH_1):PAGE101

M_E_CPU1_SB_DQS_DP<8> @T6G_MB_LIB.T6G(SCH_1):M_E_CPU1_SB_DQS_DP(8)
   U26 DD69 MEB_DQS_H8 GENOA_SP5-SOCKET6096_13568-001,SMLF,IO,DGA^6000030   I159 @T6G_MB_LIB.T6G(SCH_1):PAGE41
   J32  283 DQS8_B_T||TDQS8_B_T SCONN288_DDR506112002KQ-SCONN288_DDR506112002KQ,SMA   I236 @T6G_MB_LIB.T6G(SCH_1):PAGE101

M_E_CPU1_SB_DQS_DP<9> @T6G_MB_LIB.T6G(SCH_1):M_E_CPU1_SB_DQS_DP(9)
   U26 BV70 MEB_DQS_H9 GENOA_SP5-SOCKET6096_13568-001,SMLF,IO,DGA^6000030   I159 @T6G_MB_LIB.T6G(SCH_1):PAGE41
   J32   93 DQS9_B_T||TDQS9_B_T||DBI4_B_N SCONN288_DDR506112002KQ-SCONN288_DDR506112002KQ,SMA   I236 @T6G_MB_LIB.T6G(SCH_1):PAGE101

M_E_CPU1_SB_PAR @T6G_MB_LIB.T6G(SCH_1):M_E_CPU1_SB_PAR
   U26 BL71 MEB_PAR GENOA_SP5-SOCKET6096_13568-001,SMLF,IO,DGA^6000030   I159 @T6G_MB_LIB.T6G(SCH_1):PAGE41
   J32  227  PAR_B SCONN288_DDR506112002KQ-SCONN288_DDR506112002KQ,SMA    I52 @T6G_MB_LIB.T6G(SCH_1):PAGE101

M_E_CPU1_SB_RSP<0> @T6G_MB_LIB.T6G(SCH_1):M_E_CPU1_SB_RSP(0)
   U26 BP70 MEB0_RSP_L GENOA_SP5-SOCKET6096_13568-001,SMLF,IO,DGA^6000030   I159 @T6G_MB_LIB.T6G(SCH_1):PAGE41
   J32   87 LBS||RSP_B_N SCONN288_DDR506112002KQ-SCONN288_DDR506112002KQ,SMA    I52 @T6G_MB_LIB.T6G(SCH_1):PAGE101

M_F_CPU0_ALERT_N @T6G_MB_LIB.T6G(SCH_1):M_F_CPU0_ALERT_N
  R380    1      A Q_RES_0402LF-15,1%,1/16W,CHIP,CS01502FB03   I314 @T6G_MB_LIB.T6G(SCH_1):PAGE15
   J23   62 ALERT_N SCONN288_DDR506112002KQ-SCONN288_DDR506112002KQ,SMA   I350 @T6G_MB_LIB.T6G(SCH_1):PAGE90

M_F_CPU0_ALERT_R_N @T6G_MB_LIB.T6G(SCH_1):M_F_CPU0_ALERT_R_N
   U25 AT65 MF_ALERT_L GENOA_SP5-SOCKET6096_13568-001,SMLF,IO,DGA^6000030   I159 @T6G_MB_LIB.T6G(SCH_1):PAGE15
  R380    2      B Q_RES_0402LF-15,1%,1/16W,CHIP,CS01502FB03   I314 @T6G_MB_LIB.T6G(SCH_1):PAGE15

M_F_CPU0_CLK_DN<0> @T6G_MB_LIB.T6G(SCH_1):M_F_CPU0_CLK_DN(0)
   U25 BD67 MF0_CLK_L GENOA_SP5-SOCKET6096_13568-001,SMLF,IO,DGA^6000030   I159 @T6G_MB_LIB.T6G(SCH_1):PAGE15
   J23  218   CK_C SCONN288_DDR506112002KQ-SCONN288_DDR506112002KQ,SMA   I350 @T6G_MB_LIB.T6G(SCH_1):PAGE90

M_F_CPU0_CLK_DP<0> @T6G_MB_LIB.T6G(SCH_1):M_F_CPU0_CLK_DP(0)
   U25 BC67 MF0_CLK_H GENOA_SP5-SOCKET6096_13568-001,SMLF,IO,DGA^6000030   I159 @T6G_MB_LIB.T6G(SCH_1):PAGE15
   J23  217   CK_T SCONN288_DDR506112002KQ-SCONN288_DDR506112002KQ,SMA   I350 @T6G_MB_LIB.T6G(SCH_1):PAGE90

M_F_CPU0_RESET_N @T6G_MB_LIB.T6G(SCH_1):M_F_CPU0_RESET_N
   U25 AU66 MF_RESET_L GENOA_SP5-SOCKET6096_13568-001,SMLF,IO,DGA^6000030   I159 @T6G_MB_LIB.T6G(SCH_1):PAGE15
   J23  207 RESET_N SCONN288_DDR506112002KQ-SCONN288_DDR506112002KQ,SMA   I350 @T6G_MB_LIB.T6G(SCH_1):PAGE90

M_F_CPU0_SA_CA<0> @T6G_MB_LIB.T6G(SCH_1):M_F_CPU0_SA_CA(0)
   U25 AW67 MFA_CA0 GENOA_SP5-SOCKET6096_13568-001,SMLF,IO,DGA^6000030   I159 @T6G_MB_LIB.T6G(SCH_1):PAGE15
   J23   66  CA0_A SCONN288_DDR506112002KQ-SCONN288_DDR506112002KQ,SMA   I350 @T6G_MB_LIB.T6G(SCH_1):PAGE90

M_F_CPU0_SA_CA<1> @T6G_MB_LIB.T6G(SCH_1):M_F_CPU0_SA_CA(1)
   U25 AY67 MFA_CA1 GENOA_SP5-SOCKET6096_13568-001,SMLF,IO,DGA^6000030   I159 @T6G_MB_LIB.T6G(SCH_1):PAGE15
   J23  211  CA1_A SCONN288_DDR506112002KQ-SCONN288_DDR506112002KQ,SMA   I350 @T6G_MB_LIB.T6G(SCH_1):PAGE90

M_F_CPU0_SA_CA<2> @T6G_MB_LIB.T6G(SCH_1):M_F_CPU0_SA_CA(2)
   U25 AY65 MFA_CA2 GENOA_SP5-SOCKET6096_13568-001,SMLF,IO,DGA^6000030   I159 @T6G_MB_LIB.T6G(SCH_1):PAGE15
   J23   68  CA2_A SCONN288_DDR506112002KQ-SCONN288_DDR506112002KQ,SMA   I350 @T6G_MB_LIB.T6G(SCH_1):PAGE90

M_F_CPU0_SA_CA<3> @T6G_MB_LIB.T6G(SCH_1):M_F_CPU0_SA_CA(3)
   U25 BA66 MFA_CA3 GENOA_SP5-SOCKET6096_13568-001,SMLF,IO,DGA^6000030   I159 @T6G_MB_LIB.T6G(SCH_1):PAGE15
   J23  213  CA3_A SCONN288_DDR506112002KQ-SCONN288_DDR506112002KQ,SMA   I350 @T6G_MB_LIB.T6G(SCH_1):PAGE90

M_F_CPU0_SA_CA<4> @T6G_MB_LIB.T6G(SCH_1):M_F_CPU0_SA_CA(4)
   U25 BA67 MFA_CA4 GENOA_SP5-SOCKET6096_13568-001,SMLF,IO,DGA^6000030   I159 @T6G_MB_LIB.T6G(SCH_1):PAGE15
   J23   70  CA4_A SCONN288_DDR506112002KQ-SCONN288_DDR506112002KQ,SMA   I350 @T6G_MB_LIB.T6G(SCH_1):PAGE90

M_F_CPU0_SA_CA<5> @T6G_MB_LIB.T6G(SCH_1):M_F_CPU0_SA_CA(5)
   U25 BB67 MFA_CA5 GENOA_SP5-SOCKET6096_13568-001,SMLF,IO,DGA^6000030   I159 @T6G_MB_LIB.T6G(SCH_1):PAGE15
   J23  215  CA5_A SCONN288_DDR506112002KQ-SCONN288_DDR506112002KQ,SMA   I350 @T6G_MB_LIB.T6G(SCH_1):PAGE90

M_F_CPU0_SA_CA<6> @T6G_MB_LIB.T6G(SCH_1):M_F_CPU0_SA_CA(6)
   U25 BB65 MFA_CA6 GENOA_SP5-SOCKET6096_13568-001,SMLF,IO,DGA^6000030   I159 @T6G_MB_LIB.T6G(SCH_1):PAGE15
   J23   72  CA6_A SCONN288_DDR506112002KQ-SCONN288_DDR506112002KQ,SMA   I350 @T6G_MB_LIB.T6G(SCH_1):PAGE90

M_F_CPU0_SA_CB<0> @T6G_MB_LIB.T6G(SCH_1):M_F_CPU0_SA_CB(0)
   U25 AJ67 MFA_CHECK0 GENOA_SP5-SOCKET6096_13568-001,SMLF,IO,DGA^6000030   I159 @T6G_MB_LIB.T6G(SCH_1):PAGE15
   J23   51  CB0_A SCONN288_DDR506112002KQ-SCONN288_DDR506112002KQ,SMA   I350 @T6G_MB_LIB.T6G(SCH_1):PAGE90

M_F_CPU0_SA_CB<1> @T6G_MB_LIB.T6G(SCH_1):M_F_CPU0_SA_CB(1)
   U25 AK65 MFA_CHECK1 GENOA_SP5-SOCKET6096_13568-001,SMLF,IO,DGA^6000030   I159 @T6G_MB_LIB.T6G(SCH_1):PAGE15
   J23   53  CB1_A SCONN288_DDR506112002KQ-SCONN288_DDR506112002KQ,SMA   I350 @T6G_MB_LIB.T6G(SCH_1):PAGE90

M_F_CPU0_SA_CB<2> @T6G_MB_LIB.T6G(SCH_1):M_F_CPU0_SA_CB(2)
   U25 AK67 MFA_CHECK2 GENOA_SP5-SOCKET6096_13568-001,SMLF,IO,DGA^6000030   I159 @T6G_MB_LIB.T6G(SCH_1):PAGE15
   J23  196  CB2_A SCONN288_DDR506112002KQ-SCONN288_DDR506112002KQ,SMA   I350 @T6G_MB_LIB.T6G(SCH_1):PAGE90

M_F_CPU0_SA_CB<3> @T6G_MB_LIB.T6G(SCH_1):M_F_CPU0_SA_CB(3)
   U25 AL66 MFA_CHECK3 GENOA_SP5-SOCKET6096_13568-001,SMLF,IO,DGA^6000030   I159 @T6G_MB_LIB.T6G(SCH_1):PAGE15
   J23  198  CB3_A SCONN288_DDR506112002KQ-SCONN288_DDR506112002KQ,SMA   I350 @T6G_MB_LIB.T6G(SCH_1):PAGE90

M_F_CPU0_SA_CB<4> @T6G_MB_LIB.T6G(SCH_1):M_F_CPU0_SA_CB(4)
   U25 AN67 MFA_CHECK4 GENOA_SP5-SOCKET6096_13568-001,SMLF,IO,DGA^6000030   I159 @T6G_MB_LIB.T6G(SCH_1):PAGE15
   J23   58  CB4_A SCONN288_DDR506112002KQ-SCONN288_DDR506112002KQ,SMA   I350 @T6G_MB_LIB.T6G(SCH_1):PAGE90

M_F_CPU0_SA_CB<5> @T6G_MB_LIB.T6G(SCH_1):M_F_CPU0_SA_CB(5)
   U25 AP65 MFA_CHECK5 GENOA_SP5-SOCKET6096_13568-001,SMLF,IO,DGA^6000030   I159 @T6G_MB_LIB.T6G(SCH_1):PAGE15
   J23   60  CB5_A SCONN288_DDR506112002KQ-SCONN288_DDR506112002KQ,SMA   I350 @T6G_MB_LIB.T6G(SCH_1):PAGE90

M_F_CPU0_SA_CB<6> @T6G_MB_LIB.T6G(SCH_1):M_F_CPU0_SA_CB(6)
   U25 AP67 MFA_CHECK6 GENOA_SP5-SOCKET6096_13568-001,SMLF,IO,DGA^6000030   I159 @T6G_MB_LIB.T6G(SCH_1):PAGE15
   J23  203  CB6_A SCONN288_DDR506112002KQ-SCONN288_DDR506112002KQ,SMA   I350 @T6G_MB_LIB.T6G(SCH_1):PAGE90

M_F_CPU0_SA_CB<7> @T6G_MB_LIB.T6G(SCH_1):M_F_CPU0_SA_CB(7)
   U25 AR66 MFA_CHECK7 GENOA_SP5-SOCKET6096_13568-001,SMLF,IO,DGA^6000030   I159 @T6G_MB_LIB.T6G(SCH_1):PAGE15
   J23  205  CB7_A SCONN288_DDR506112002KQ-SCONN288_DDR506112002KQ,SMA   I350 @T6G_MB_LIB.T6G(SCH_1):PAGE90

M_F_CPU0_SA_CS_N<0> @T6G_MB_LIB.T6G(SCH_1):M_F_CPU0_SA_CS_N(0)
   U25 AV67 MFA0_CS_L0 GENOA_SP5-SOCKET6096_13568-001,SMLF,IO,DGA^6000030   I159 @T6G_MB_LIB.T6G(SCH_1):PAGE15
   J23   64 CS0_A_N SCONN288_DDR506112002KQ-SCONN288_DDR506112002KQ,SMA   I350 @T6G_MB_LIB.T6G(SCH_1):PAGE90

M_F_CPU0_SA_CS_N<1> @T6G_MB_LIB.T6G(SCH_1):M_F_CPU0_SA_CS_N(1)
   U25 AW66 MFA0_CS_L1 GENOA_SP5-SOCKET6096_13568-001,SMLF,IO,DGA^6000030   I159 @T6G_MB_LIB.T6G(SCH_1):PAGE15
   J23  209 CS1_A_N SCONN288_DDR506112002KQ-SCONN288_DDR506112002KQ,SMA   I350 @T6G_MB_LIB.T6G(SCH_1):PAGE90

M_F_CPU0_SA_DQ<0> @T6G_MB_LIB.T6G(SCH_1):M_F_CPU0_SA_DQ(0)
   U25  E67 MFA_DATA0 GENOA_SP5-SOCKET6096_13568-001,SMLF,IO,DGA^6000030   I159 @T6G_MB_LIB.T6G(SCH_1):PAGE15
   J23    7  DQ0_A SCONN288_DDR506112002KQ-SCONN288_DDR506112002KQ,SMA   I350 @T6G_MB_LIB.T6G(SCH_1):PAGE90

M_F_CPU0_SA_DQ<10> @T6G_MB_LIB.T6G(SCH_1):M_F_CPU0_SA_DQ(10)
   U25  M67 MFA_DATA10 GENOA_SP5-SOCKET6096_13568-001,SMLF,IO,DGA^6000030   I159 @T6G_MB_LIB.T6G(SCH_1):PAGE15
   J23  163 DQ10_A SCONN288_DDR506112002KQ-SCONN288_DDR506112002KQ,SMA   I350 @T6G_MB_LIB.T6G(SCH_1):PAGE90

M_F_CPU0_SA_DQ<11> @T6G_MB_LIB.T6G(SCH_1):M_F_CPU0_SA_DQ(11)
   U25  N66 MFA_DATA11 GENOA_SP5-SOCKET6096_13568-001,SMLF,IO,DGA^6000030   I159 @T6G_MB_LIB.T6G(SCH_1):PAGE15
   J23  165 DQ11_A SCONN288_DDR506112002KQ-SCONN288_DDR506112002KQ,SMA   I350 @T6G_MB_LIB.T6G(SCH_1):PAGE90

M_F_CPU0_SA_DQ<12> @T6G_MB_LIB.T6G(SCH_1):M_F_CPU0_SA_DQ(12)
   U25  R67 MFA_DATA12 GENOA_SP5-SOCKET6096_13568-001,SMLF,IO,DGA^6000030   I159 @T6G_MB_LIB.T6G(SCH_1):PAGE15
   J23   25 DQ12_A SCONN288_DDR506112002KQ-SCONN288_DDR506112002KQ,SMA   I350 @T6G_MB_LIB.T6G(SCH_1):PAGE90

M_F_CPU0_SA_DQ<13> @T6G_MB_LIB.T6G(SCH_1):M_F_CPU0_SA_DQ(13)
   U25  T65 MFA_DATA13 GENOA_SP5-SOCKET6096_13568-001,SMLF,IO,DGA^6000030   I159 @T6G_MB_LIB.T6G(SCH_1):PAGE15
   J23   27 DQ13_A SCONN288_DDR506112002KQ-SCONN288_DDR506112002KQ,SMA   I350 @T6G_MB_LIB.T6G(SCH_1):PAGE90

M_F_CPU0_SA_DQ<14> @T6G_MB_LIB.T6G(SCH_1):M_F_CPU0_SA_DQ(14)
   U25  T67 MFA_DATA14 GENOA_SP5-SOCKET6096_13568-001,SMLF,IO,DGA^6000030   I159 @T6G_MB_LIB.T6G(SCH_1):PAGE15
   J23  170 DQ14_A SCONN288_DDR506112002KQ-SCONN288_DDR506112002KQ,SMA   I350 @T6G_MB_LIB.T6G(SCH_1):PAGE90

M_F_CPU0_SA_DQ<15> @T6G_MB_LIB.T6G(SCH_1):M_F_CPU0_SA_DQ(15)
   U25  U66 MFA_DATA15 GENOA_SP5-SOCKET6096_13568-001,SMLF,IO,DGA^6000030   I159 @T6G_MB_LIB.T6G(SCH_1):PAGE15
   J23  172 DQ15_A SCONN288_DDR506112002KQ-SCONN288_DDR506112002KQ,SMA   I350 @T6G_MB_LIB.T6G(SCH_1):PAGE90

M_F_CPU0_SA_DQ<16> @T6G_MB_LIB.T6G(SCH_1):M_F_CPU0_SA_DQ(16)
   U25  U67 MFA_DATA16 GENOA_SP5-SOCKET6096_13568-001,SMLF,IO,DGA^6000030   I159 @T6G_MB_LIB.T6G(SCH_1):PAGE15
   J23   29 DQ16_A SCONN288_DDR506112002KQ-SCONN288_DDR506112002KQ,SMA   I350 @T6G_MB_LIB.T6G(SCH_1):PAGE90

M_F_CPU0_SA_DQ<17> @T6G_MB_LIB.T6G(SCH_1):M_F_CPU0_SA_DQ(17)
   U25  V65 MFA_DATA17 GENOA_SP5-SOCKET6096_13568-001,SMLF,IO,DGA^6000030   I159 @T6G_MB_LIB.T6G(SCH_1):PAGE15
   J23   31 DQ17_A SCONN288_DDR506112002KQ-SCONN288_DDR506112002KQ,SMA   I350 @T6G_MB_LIB.T6G(SCH_1):PAGE90

M_F_CPU0_SA_DQ<18> @T6G_MB_LIB.T6G(SCH_1):M_F_CPU0_SA_DQ(18)
   U25  V67 MFA_DATA18 GENOA_SP5-SOCKET6096_13568-001,SMLF,IO,DGA^6000030   I159 @T6G_MB_LIB.T6G(SCH_1):PAGE15
   J23  174 DQ18_A SCONN288_DDR506112002KQ-SCONN288_DDR506112002KQ,SMA   I350 @T6G_MB_LIB.T6G(SCH_1):PAGE90

M_F_CPU0_SA_DQ<19> @T6G_MB_LIB.T6G(SCH_1):M_F_CPU0_SA_DQ(19)
   U25  W66 MFA_DATA19 GENOA_SP5-SOCKET6096_13568-001,SMLF,IO,DGA^6000030   I159 @T6G_MB_LIB.T6G(SCH_1):PAGE15
   J23  176 DQ19_A SCONN288_DDR506112002KQ-SCONN288_DDR506112002KQ,SMA   I350 @T6G_MB_LIB.T6G(SCH_1):PAGE90

M_F_CPU0_SA_DQ<1> @T6G_MB_LIB.T6G(SCH_1):M_F_CPU0_SA_DQ(1)
   U25  F65 MFA_DATA1 GENOA_SP5-SOCKET6096_13568-001,SMLF,IO,DGA^6000030   I159 @T6G_MB_LIB.T6G(SCH_1):PAGE15
   J23    9  DQ1_A SCONN288_DDR506112002KQ-SCONN288_DDR506112002KQ,SMA   I350 @T6G_MB_LIB.T6G(SCH_1):PAGE90

M_F_CPU0_SA_DQ<20> @T6G_MB_LIB.T6G(SCH_1):M_F_CPU0_SA_DQ(20)
   U25 AA67 MFA_DATA20 GENOA_SP5-SOCKET6096_13568-001,SMLF,IO,DGA^6000030   I159 @T6G_MB_LIB.T6G(SCH_1):PAGE15
   J23   36 DQ20_A SCONN288_DDR506112002KQ-SCONN288_DDR506112002KQ,SMA   I350 @T6G_MB_LIB.T6G(SCH_1):PAGE90

M_F_CPU0_SA_DQ<21> @T6G_MB_LIB.T6G(SCH_1):M_F_CPU0_SA_DQ(21)
   U25 AB65 MFA_DATA21 GENOA_SP5-SOCKET6096_13568-001,SMLF,IO,DGA^6000030   I159 @T6G_MB_LIB.T6G(SCH_1):PAGE15
   J23   38 DQ21_A SCONN288_DDR506112002KQ-SCONN288_DDR506112002KQ,SMA   I350 @T6G_MB_LIB.T6G(SCH_1):PAGE90

M_F_CPU0_SA_DQ<22> @T6G_MB_LIB.T6G(SCH_1):M_F_CPU0_SA_DQ(22)
   U25 AB67 MFA_DATA22 GENOA_SP5-SOCKET6096_13568-001,SMLF,IO,DGA^6000030   I159 @T6G_MB_LIB.T6G(SCH_1):PAGE15
   J23  181 DQ22_A SCONN288_DDR506112002KQ-SCONN288_DDR506112002KQ,SMA   I350 @T6G_MB_LIB.T6G(SCH_1):PAGE90

M_F_CPU0_SA_DQ<23> @T6G_MB_LIB.T6G(SCH_1):M_F_CPU0_SA_DQ(23)
   U25 AC66 MFA_DATA23 GENOA_SP5-SOCKET6096_13568-001,SMLF,IO,DGA^6000030   I159 @T6G_MB_LIB.T6G(SCH_1):PAGE15
   J23  183 DQ23_A SCONN288_DDR506112002KQ-SCONN288_DDR506112002KQ,SMA   I350 @T6G_MB_LIB.T6G(SCH_1):PAGE90

M_F_CPU0_SA_DQ<24> @T6G_MB_LIB.T6G(SCH_1):M_F_CPU0_SA_DQ(24)
   U25 AC67 MFA_DATA24 GENOA_SP5-SOCKET6096_13568-001,SMLF,IO,DGA^6000030   I159 @T6G_MB_LIB.T6G(SCH_1):PAGE15
   J23   40 DQ24_A SCONN288_DDR506112002KQ-SCONN288_DDR506112002KQ,SMA   I350 @T6G_MB_LIB.T6G(SCH_1):PAGE90

M_F_CPU0_SA_DQ<25> @T6G_MB_LIB.T6G(SCH_1):M_F_CPU0_SA_DQ(25)
   U25 AD65 MFA_DATA25 GENOA_SP5-SOCKET6096_13568-001,SMLF,IO,DGA^6000030   I159 @T6G_MB_LIB.T6G(SCH_1):PAGE15
   J23   42 DQ25_A SCONN288_DDR506112002KQ-SCONN288_DDR506112002KQ,SMA   I350 @T6G_MB_LIB.T6G(SCH_1):PAGE90

M_F_CPU0_SA_DQ<26> @T6G_MB_LIB.T6G(SCH_1):M_F_CPU0_SA_DQ(26)
   U25 AD67 MFA_DATA26 GENOA_SP5-SOCKET6096_13568-001,SMLF,IO,DGA^6000030   I159 @T6G_MB_LIB.T6G(SCH_1):PAGE15
   J23  185 DQ26_A SCONN288_DDR506112002KQ-SCONN288_DDR506112002KQ,SMA   I350 @T6G_MB_LIB.T6G(SCH_1):PAGE90

M_F_CPU0_SA_DQ<27> @T6G_MB_LIB.T6G(SCH_1):M_F_CPU0_SA_DQ(27)
   U25 AE66 MFA_DATA27 GENOA_SP5-SOCKET6096_13568-001,SMLF,IO,DGA^6000030   I159 @T6G_MB_LIB.T6G(SCH_1):PAGE15
   J23  187 DQ27_A SCONN288_DDR506112002KQ-SCONN288_DDR506112002KQ,SMA   I350 @T6G_MB_LIB.T6G(SCH_1):PAGE90

M_F_CPU0_SA_DQ<28> @T6G_MB_LIB.T6G(SCH_1):M_F_CPU0_SA_DQ(28)
   U25 AG67 MFA_DATA28 GENOA_SP5-SOCKET6096_13568-001,SMLF,IO,DGA^6000030   I159 @T6G_MB_LIB.T6G(SCH_1):PAGE15
   J23   47 DQ28_A SCONN288_DDR506112002KQ-SCONN288_DDR506112002KQ,SMA   I350 @T6G_MB_LIB.T6G(SCH_1):PAGE90

M_F_CPU0_SA_DQ<29> @T6G_MB_LIB.T6G(SCH_1):M_F_CPU0_SA_DQ(29)
   U25 AH65 MFA_DATA29 GENOA_SP5-SOCKET6096_13568-001,SMLF,IO,DGA^6000030   I159 @T6G_MB_LIB.T6G(SCH_1):PAGE15
   J23   49 DQ29_A SCONN288_DDR506112002KQ-SCONN288_DDR506112002KQ,SMA   I350 @T6G_MB_LIB.T6G(SCH_1):PAGE90

M_F_CPU0_SA_DQ<2> @T6G_MB_LIB.T6G(SCH_1):M_F_CPU0_SA_DQ(2)
   U25  F67 MFA_DATA2 GENOA_SP5-SOCKET6096_13568-001,SMLF,IO,DGA^6000030   I159 @T6G_MB_LIB.T6G(SCH_1):PAGE15
   J23  152  DQ2_A SCONN288_DDR506112002KQ-SCONN288_DDR506112002KQ,SMA   I350 @T6G_MB_LIB.T6G(SCH_1):PAGE90

M_F_CPU0_SA_DQ<30> @T6G_MB_LIB.T6G(SCH_1):M_F_CPU0_SA_DQ(30)
   U25 AH67 MFA_DATA30 GENOA_SP5-SOCKET6096_13568-001,SMLF,IO,DGA^6000030   I159 @T6G_MB_LIB.T6G(SCH_1):PAGE15
   J23  192 DQ30_A SCONN288_DDR506112002KQ-SCONN288_DDR506112002KQ,SMA   I350 @T6G_MB_LIB.T6G(SCH_1):PAGE90

M_F_CPU0_SA_DQ<31> @T6G_MB_LIB.T6G(SCH_1):M_F_CPU0_SA_DQ(31)
   U25 AJ66 MFA_DATA31 GENOA_SP5-SOCKET6096_13568-001,SMLF,IO,DGA^6000030   I159 @T6G_MB_LIB.T6G(SCH_1):PAGE15
   J23  194 DQ31_A SCONN288_DDR506112002KQ-SCONN288_DDR506112002KQ,SMA   I350 @T6G_MB_LIB.T6G(SCH_1):PAGE90

M_F_CPU0_SA_DQ<3> @T6G_MB_LIB.T6G(SCH_1):M_F_CPU0_SA_DQ(3)
   U25  G66 MFA_DATA3 GENOA_SP5-SOCKET6096_13568-001,SMLF,IO,DGA^6000030   I159 @T6G_MB_LIB.T6G(SCH_1):PAGE15
   J23  154  DQ3_A SCONN288_DDR506112002KQ-SCONN288_DDR506112002KQ,SMA   I350 @T6G_MB_LIB.T6G(SCH_1):PAGE90

M_F_CPU0_SA_DQ<4> @T6G_MB_LIB.T6G(SCH_1):M_F_CPU0_SA_DQ(4)
   U25  J67 MFA_DATA4 GENOA_SP5-SOCKET6096_13568-001,SMLF,IO,DGA^6000030   I159 @T6G_MB_LIB.T6G(SCH_1):PAGE15
   J23   14  DQ4_A SCONN288_DDR506112002KQ-SCONN288_DDR506112002KQ,SMA   I350 @T6G_MB_LIB.T6G(SCH_1):PAGE90

M_F_CPU0_SA_DQ<5> @T6G_MB_LIB.T6G(SCH_1):M_F_CPU0_SA_DQ(5)
   U25  K65 MFA_DATA5 GENOA_SP5-SOCKET6096_13568-001,SMLF,IO,DGA^6000030   I159 @T6G_MB_LIB.T6G(SCH_1):PAGE15
   J23   16  DQ5_A SCONN288_DDR506112002KQ-SCONN288_DDR506112002KQ,SMA   I350 @T6G_MB_LIB.T6G(SCH_1):PAGE90

M_F_CPU0_SA_DQ<6> @T6G_MB_LIB.T6G(SCH_1):M_F_CPU0_SA_DQ(6)
   U25  K67 MFA_DATA6 GENOA_SP5-SOCKET6096_13568-001,SMLF,IO,DGA^6000030   I159 @T6G_MB_LIB.T6G(SCH_1):PAGE15
   J23  159  DQ6_A SCONN288_DDR506112002KQ-SCONN288_DDR506112002KQ,SMA   I350 @T6G_MB_LIB.T6G(SCH_1):PAGE90

M_F_CPU0_SA_DQ<7> @T6G_MB_LIB.T6G(SCH_1):M_F_CPU0_SA_DQ(7)
   U25  L66 MFA_DATA7 GENOA_SP5-SOCKET6096_13568-001,SMLF,IO,DGA^6000030   I159 @T6G_MB_LIB.T6G(SCH_1):PAGE15
   J23  161  DQ7_A SCONN288_DDR506112002KQ-SCONN288_DDR506112002KQ,SMA   I350 @T6G_MB_LIB.T6G(SCH_1):PAGE90

M_F_CPU0_SA_DQ<8> @T6G_MB_LIB.T6G(SCH_1):M_F_CPU0_SA_DQ(8)
   U25  L67 MFA_DATA8 GENOA_SP5-SOCKET6096_13568-001,SMLF,IO,DGA^6000030   I159 @T6G_MB_LIB.T6G(SCH_1):PAGE15
   J23   18  DQ8_A SCONN288_DDR506112002KQ-SCONN288_DDR506112002KQ,SMA   I350 @T6G_MB_LIB.T6G(SCH_1):PAGE90

M_F_CPU0_SA_DQ<9> @T6G_MB_LIB.T6G(SCH_1):M_F_CPU0_SA_DQ(9)
   U25  M65 MFA_DATA9 GENOA_SP5-SOCKET6096_13568-001,SMLF,IO,DGA^6000030   I159 @T6G_MB_LIB.T6G(SCH_1):PAGE15
   J23   20  DQ9_A SCONN288_DDR506112002KQ-SCONN288_DDR506112002KQ,SMA   I350 @T6G_MB_LIB.T6G(SCH_1):PAGE90

M_F_CPU0_SA_DQS_DN<0> @T6G_MB_LIB.T6G(SCH_1):M_F_CPU0_SA_DQS_DN(0)
   U25  H67 MFA_DQS_L0 GENOA_SP5-SOCKET6096_13568-001,SMLF,IO,DGA^6000030   I159 @T6G_MB_LIB.T6G(SCH_1):PAGE15
   J23   12 DQS0_A_C SCONN288_DDR506112002KQ-SCONN288_DDR506112002KQ,SMA   I412 @T6G_MB_LIB.T6G(SCH_1):PAGE90

M_F_CPU0_SA_DQS_DN<1> @T6G_MB_LIB.T6G(SCH_1):M_F_CPU0_SA_DQS_DN(1)
   U25  P67 MFA_DQS_L1 GENOA_SP5-SOCKET6096_13568-001,SMLF,IO,DGA^6000030   I159 @T6G_MB_LIB.T6G(SCH_1):PAGE15
   J23   23 DQS1_A_C SCONN288_DDR506112002KQ-SCONN288_DDR506112002KQ,SMA   I412 @T6G_MB_LIB.T6G(SCH_1):PAGE90

M_F_CPU0_SA_DQS_DN<2> @T6G_MB_LIB.T6G(SCH_1):M_F_CPU0_SA_DQS_DN(2)
   U25  Y67 MFA_DQS_L2 GENOA_SP5-SOCKET6096_13568-001,SMLF,IO,DGA^6000030   I159 @T6G_MB_LIB.T6G(SCH_1):PAGE15
   J23   34 DQS2_A_C SCONN288_DDR506112002KQ-SCONN288_DDR506112002KQ,SMA   I412 @T6G_MB_LIB.T6G(SCH_1):PAGE90

M_F_CPU0_SA_DQS_DN<3> @T6G_MB_LIB.T6G(SCH_1):M_F_CPU0_SA_DQS_DN(3)
   U25 AF67 MFA_DQS_L3 GENOA_SP5-SOCKET6096_13568-001,SMLF,IO,DGA^6000030   I159 @T6G_MB_LIB.T6G(SCH_1):PAGE15
   J23   45 DQS3_A_C SCONN288_DDR506112002KQ-SCONN288_DDR506112002KQ,SMA   I412 @T6G_MB_LIB.T6G(SCH_1):PAGE90

M_F_CPU0_SA_DQS_DN<4> @T6G_MB_LIB.T6G(SCH_1):M_F_CPU0_SA_DQS_DN(4)
   U25 AM67 MFA_DQS_L4 GENOA_SP5-SOCKET6096_13568-001,SMLF,IO,DGA^6000030   I159 @T6G_MB_LIB.T6G(SCH_1):PAGE15
   J23   56 DQS4_A_C SCONN288_DDR506112002KQ-SCONN288_DDR506112002KQ,SMA   I412 @T6G_MB_LIB.T6G(SCH_1):PAGE90

M_F_CPU0_SA_DQS_DN<5> @T6G_MB_LIB.T6G(SCH_1):M_F_CPU0_SA_DQS_DN(5)
   U25  H65 MFA_DQS_L5 GENOA_SP5-SOCKET6096_13568-001,SMLF,IO,DGA^6000030   I159 @T6G_MB_LIB.T6G(SCH_1):PAGE15
   J23  156 DQS5_A_C||TDQS5_A_C||DQS5_A_T||TDQS5_A_T SCONN288_DDR506112002KQ-SCONN288_DDR506112002KQ,SMA   I412 @T6G_MB_LIB.T6G(SCH_1):PAGE90

M_F_CPU0_SA_DQS_DN<6> @T6G_MB_LIB.T6G(SCH_1):M_F_CPU0_SA_DQS_DN(6)
   U25  P65 MFA_DQS_L6 GENOA_SP5-SOCKET6096_13568-001,SMLF,IO,DGA^6000030   I159 @T6G_MB_LIB.T6G(SCH_1):PAGE15
   J23  167 DQS6_A_C||TDQS6_A_C||DQS6_A_T||TDQS6_A_T SCONN288_DDR506112002KQ-SCONN288_DDR506112002KQ,SMA   I412 @T6G_MB_LIB.T6G(SCH_1):PAGE90

M_F_CPU0_SA_DQS_DN<7> @T6G_MB_LIB.T6G(SCH_1):M_F_CPU0_SA_DQS_DN(7)
   U25  Y65 MFA_DQS_L7 GENOA_SP5-SOCKET6096_13568-001,SMLF,IO,DGA^6000030   I159 @T6G_MB_LIB.T6G(SCH_1):PAGE15
   J23  178 DQS7_A_C||TDQS7_A_C SCONN288_DDR506112002KQ-SCONN288_DDR506112002KQ,SMA   I412 @T6G_MB_LIB.T6G(SCH_1):PAGE90

M_F_CPU0_SA_DQS_DN<8> @T6G_MB_LIB.T6G(SCH_1):M_F_CPU0_SA_DQS_DN(8)
   U25 AF65 MFA_DQS_L8 GENOA_SP5-SOCKET6096_13568-001,SMLF,IO,DGA^6000030   I159 @T6G_MB_LIB.T6G(SCH_1):PAGE15
   J23  189 DQS8_A_C||TDQS8_A_C SCONN288_DDR506112002KQ-SCONN288_DDR506112002KQ,SMA   I412 @T6G_MB_LIB.T6G(SCH_1):PAGE90

M_F_CPU0_SA_DQS_DN<9> @T6G_MB_LIB.T6G(SCH_1):M_F_CPU0_SA_DQS_DN(9)
   U25 AM65 MFA_DQS_L9 GENOA_SP5-SOCKET6096_13568-001,SMLF,IO,DGA^6000030   I159 @T6G_MB_LIB.T6G(SCH_1):PAGE15
   J23  200 DQS9_A_C||TDQS9_A_C SCONN288_DDR506112002KQ-SCONN288_DDR506112002KQ,SMA   I412 @T6G_MB_LIB.T6G(SCH_1):PAGE90

M_F_CPU0_SA_DQS_DP<0> @T6G_MB_LIB.T6G(SCH_1):M_F_CPU0_SA_DQS_DP(0)
   U25  G67 MFA_DQS_H0 GENOA_SP5-SOCKET6096_13568-001,SMLF,IO,DGA^6000030   I159 @T6G_MB_LIB.T6G(SCH_1):PAGE15
   J23   11 DQS0_A_T SCONN288_DDR506112002KQ-SCONN288_DDR506112002KQ,SMA   I412 @T6G_MB_LIB.T6G(SCH_1):PAGE90

M_F_CPU0_SA_DQS_DP<1> @T6G_MB_LIB.T6G(SCH_1):M_F_CPU0_SA_DQS_DP(1)
   U25  N67 MFA_DQS_H1 GENOA_SP5-SOCKET6096_13568-001,SMLF,IO,DGA^6000030   I159 @T6G_MB_LIB.T6G(SCH_1):PAGE15
   J23   22 DQS1_A_T SCONN288_DDR506112002KQ-SCONN288_DDR506112002KQ,SMA   I412 @T6G_MB_LIB.T6G(SCH_1):PAGE90

M_F_CPU0_SA_DQS_DP<2> @T6G_MB_LIB.T6G(SCH_1):M_F_CPU0_SA_DQS_DP(2)
   U25  W67 MFA_DQS_H2 GENOA_SP5-SOCKET6096_13568-001,SMLF,IO,DGA^6000030   I159 @T6G_MB_LIB.T6G(SCH_1):PAGE15
   J23   33 DQS2_A_T SCONN288_DDR506112002KQ-SCONN288_DDR506112002KQ,SMA   I412 @T6G_MB_LIB.T6G(SCH_1):PAGE90

M_F_CPU0_SA_DQS_DP<3> @T6G_MB_LIB.T6G(SCH_1):M_F_CPU0_SA_DQS_DP(3)
   U25 AE67 MFA_DQS_H3 GENOA_SP5-SOCKET6096_13568-001,SMLF,IO,DGA^6000030   I159 @T6G_MB_LIB.T6G(SCH_1):PAGE15
   J23   44 DQS3_A_T SCONN288_DDR506112002KQ-SCONN288_DDR506112002KQ,SMA   I412 @T6G_MB_LIB.T6G(SCH_1):PAGE90

M_F_CPU0_SA_DQS_DP<4> @T6G_MB_LIB.T6G(SCH_1):M_F_CPU0_SA_DQS_DP(4)
   U25 AL67 MFA_DQS_H4 GENOA_SP5-SOCKET6096_13568-001,SMLF,IO,DGA^6000030   I159 @T6G_MB_LIB.T6G(SCH_1):PAGE15
   J23   55 DQS4_A_T SCONN288_DDR506112002KQ-SCONN288_DDR506112002KQ,SMA   I412 @T6G_MB_LIB.T6G(SCH_1):PAGE90

M_F_CPU0_SA_DQS_DP<5> @T6G_MB_LIB.T6G(SCH_1):M_F_CPU0_SA_DQS_DP(5)
   U25  J66 MFA_DQS_H5 GENOA_SP5-SOCKET6096_13568-001,SMLF,IO,DGA^6000030   I159 @T6G_MB_LIB.T6G(SCH_1):PAGE15
   J23  157 DQS5_A_T||TDQS5_A_T SCONN288_DDR506112002KQ-SCONN288_DDR506112002KQ,SMA   I412 @T6G_MB_LIB.T6G(SCH_1):PAGE90

M_F_CPU0_SA_DQS_DP<6> @T6G_MB_LIB.T6G(SCH_1):M_F_CPU0_SA_DQS_DP(6)
   U25  R66 MFA_DQS_H6 GENOA_SP5-SOCKET6096_13568-001,SMLF,IO,DGA^6000030   I159 @T6G_MB_LIB.T6G(SCH_1):PAGE15
   J23  168 DQS6_A_T||TDQS6_A_T SCONN288_DDR506112002KQ-SCONN288_DDR506112002KQ,SMA   I412 @T6G_MB_LIB.T6G(SCH_1):PAGE90

M_F_CPU0_SA_DQS_DP<7> @T6G_MB_LIB.T6G(SCH_1):M_F_CPU0_SA_DQS_DP(7)
   U25 AA66 MFA_DQS_H7 GENOA_SP5-SOCKET6096_13568-001,SMLF,IO,DGA^6000030   I159 @T6G_MB_LIB.T6G(SCH_1):PAGE15
   J23  179 DQS7_A_T||TDQS7_A_T SCONN288_DDR506112002KQ-SCONN288_DDR506112002KQ,SMA   I412 @T6G_MB_LIB.T6G(SCH_1):PAGE90

M_F_CPU0_SA_DQS_DP<8> @T6G_MB_LIB.T6G(SCH_1):M_F_CPU0_SA_DQS_DP(8)
   U25 AG66 MFA_DQS_H8 GENOA_SP5-SOCKET6096_13568-001,SMLF,IO,DGA^6000030   I159 @T6G_MB_LIB.T6G(SCH_1):PAGE15
   J23  190 DQS8_A_T||TDQS8_A_T SCONN288_DDR506112002KQ-SCONN288_DDR506112002KQ,SMA   I412 @T6G_MB_LIB.T6G(SCH_1):PAGE90

M_F_CPU0_SA_DQS_DP<9> @T6G_MB_LIB.T6G(SCH_1):M_F_CPU0_SA_DQS_DP(9)
   U25 AN66 MFA_DQS_H9 GENOA_SP5-SOCKET6096_13568-001,SMLF,IO,DGA^6000030   I159 @T6G_MB_LIB.T6G(SCH_1):PAGE15
   J23  201 DQS9_A_T||TDQS9_A_T SCONN288_DDR506112002KQ-SCONN288_DDR506112002KQ,SMA   I412 @T6G_MB_LIB.T6G(SCH_1):PAGE90

M_F_CPU0_SA_PAR @T6G_MB_LIB.T6G(SCH_1):M_F_CPU0_SA_PAR
   U25 BC66 MFA_PAR GENOA_SP5-SOCKET6096_13568-001,SMLF,IO,DGA^6000030   I159 @T6G_MB_LIB.T6G(SCH_1):PAGE15
   J23   74  PAR_A SCONN288_DDR506112002KQ-SCONN288_DDR506112002KQ,SMA   I350 @T6G_MB_LIB.T6G(SCH_1):PAGE90

M_F_CPU0_SA_RSP<0> @T6G_MB_LIB.T6G(SCH_1):M_F_CPU0_SA_RSP(0)
   U25 BN66 MFA0_RSP_L GENOA_SP5-SOCKET6096_13568-001,SMLF,IO,DGA^6000030   I159 @T6G_MB_LIB.T6G(SCH_1):PAGE15
   J23   86 LBD||RSP_A_N SCONN288_DDR506112002KQ-SCONN288_DDR506112002KQ,SMA   I350 @T6G_MB_LIB.T6G(SCH_1):PAGE90

M_F_CPU0_SB_CA<0> @T6G_MB_LIB.T6G(SCH_1):M_F_CPU0_SB_CA(0)
   U25 BG66 MFB_CA0 GENOA_SP5-SOCKET6096_13568-001,SMLF,IO,DGA^6000030   I159 @T6G_MB_LIB.T6G(SCH_1):PAGE15
   J23   76  CA0_B SCONN288_DDR506112002KQ-SCONN288_DDR506112002KQ,SMA   I350 @T6G_MB_LIB.T6G(SCH_1):PAGE90

M_F_CPU0_SB_CA<1> @T6G_MB_LIB.T6G(SCH_1):M_F_CPU0_SB_CA(1)
   U25 BH65 MFB_CA1 GENOA_SP5-SOCKET6096_13568-001,SMLF,IO,DGA^6000030   I159 @T6G_MB_LIB.T6G(SCH_1):PAGE15
   J23  221  CA1_B SCONN288_DDR506112002KQ-SCONN288_DDR506112002KQ,SMA   I350 @T6G_MB_LIB.T6G(SCH_1):PAGE90

M_F_CPU0_SB_CA<2> @T6G_MB_LIB.T6G(SCH_1):M_F_CPU0_SB_CA(2)
   U25 BH67 MFB_CA2 GENOA_SP5-SOCKET6096_13568-001,SMLF,IO,DGA^6000030   I159 @T6G_MB_LIB.T6G(SCH_1):PAGE15
   J23   78  CA2_B SCONN288_DDR506112002KQ-SCONN288_DDR506112002KQ,SMA   I350 @T6G_MB_LIB.T6G(SCH_1):PAGE90

M_F_CPU0_SB_CA<3> @T6G_MB_LIB.T6G(SCH_1):M_F_CPU0_SB_CA(3)
   U25 BJ67 MFB_CA3 GENOA_SP5-SOCKET6096_13568-001,SMLF,IO,DGA^6000030   I159 @T6G_MB_LIB.T6G(SCH_1):PAGE15
   J23  223  CA3_B SCONN288_DDR506112002KQ-SCONN288_DDR506112002KQ,SMA   I350 @T6G_MB_LIB.T6G(SCH_1):PAGE90

M_F_CPU0_SB_CA<4> @T6G_MB_LIB.T6G(SCH_1):M_F_CPU0_SB_CA(4)
   U25 BJ66 MFB_CA4 GENOA_SP5-SOCKET6096_13568-001,SMLF,IO,DGA^6000030   I159 @T6G_MB_LIB.T6G(SCH_1):PAGE15
   J23   80  CA4_B SCONN288_DDR506112002KQ-SCONN288_DDR506112002KQ,SMA   I350 @T6G_MB_LIB.T6G(SCH_1):PAGE90

M_F_CPU0_SB_CA<5> @T6G_MB_LIB.T6G(SCH_1):M_F_CPU0_SB_CA(5)
   U25 BK65 MFB_CA5 GENOA_SP5-SOCKET6096_13568-001,SMLF,IO,DGA^6000030   I159 @T6G_MB_LIB.T6G(SCH_1):PAGE15
   J23  225  CA5_B SCONN288_DDR506112002KQ-SCONN288_DDR506112002KQ,SMA   I350 @T6G_MB_LIB.T6G(SCH_1):PAGE90

M_F_CPU0_SB_CA<6> @T6G_MB_LIB.T6G(SCH_1):M_F_CPU0_SB_CA(6)
   U25 BK67 MFB_CA6 GENOA_SP5-SOCKET6096_13568-001,SMLF,IO,DGA^6000030   I159 @T6G_MB_LIB.T6G(SCH_1):PAGE15
   J23   82  CA6_B SCONN288_DDR506112002KQ-SCONN288_DDR506112002KQ,SMA   I350 @T6G_MB_LIB.T6G(SCH_1):PAGE90

M_F_CPU0_SB_CB<0> @T6G_MB_LIB.T6G(SCH_1):M_F_CPU0_SB_CB(0)
   U25 BY67 MFB_CHECK0 GENOA_SP5-SOCKET6096_13568-001,SMLF,IO,DGA^6000030   I159 @T6G_MB_LIB.T6G(SCH_1):PAGE15
   J23   96  CB0_B SCONN288_DDR506112002KQ-SCONN288_DDR506112002KQ,SMA   I350 @T6G_MB_LIB.T6G(SCH_1):PAGE90

M_F_CPU0_SB_CB<1> @T6G_MB_LIB.T6G(SCH_1):M_F_CPU0_SB_CB(1)
   U25 CA66 MFB_CHECK1 GENOA_SP5-SOCKET6096_13568-001,SMLF,IO,DGA^6000030   I159 @T6G_MB_LIB.T6G(SCH_1):PAGE15
   J23   98  CB1_B SCONN288_DDR506112002KQ-SCONN288_DDR506112002KQ,SMA   I350 @T6G_MB_LIB.T6G(SCH_1):PAGE90

M_F_CPU0_SB_CB<2> @T6G_MB_LIB.T6G(SCH_1):M_F_CPU0_SB_CB(2)
   U25 CA67 MFB_CHECK2 GENOA_SP5-SOCKET6096_13568-001,SMLF,IO,DGA^6000030   I159 @T6G_MB_LIB.T6G(SCH_1):PAGE15
   J23  241  CB2_B SCONN288_DDR506112002KQ-SCONN288_DDR506112002KQ,SMA   I350 @T6G_MB_LIB.T6G(SCH_1):PAGE90

M_F_CPU0_SB_CB<3> @T6G_MB_LIB.T6G(SCH_1):M_F_CPU0_SB_CB(3)
   U25 CB65 MFB_CHECK3 GENOA_SP5-SOCKET6096_13568-001,SMLF,IO,DGA^6000030   I159 @T6G_MB_LIB.T6G(SCH_1):PAGE15
   J23  243  CB3_B SCONN288_DDR506112002KQ-SCONN288_DDR506112002KQ,SMA   I350 @T6G_MB_LIB.T6G(SCH_1):PAGE90

M_F_CPU0_SB_CB<4> @T6G_MB_LIB.T6G(SCH_1):M_F_CPU0_SB_CB(4)
   U25 BT67 MFB_CHECK4 GENOA_SP5-SOCKET6096_13568-001,SMLF,IO,DGA^6000030   I159 @T6G_MB_LIB.T6G(SCH_1):PAGE15
   J23   89  CB4_B SCONN288_DDR506112002KQ-SCONN288_DDR506112002KQ,SMA   I350 @T6G_MB_LIB.T6G(SCH_1):PAGE90

M_F_CPU0_SB_CB<5> @T6G_MB_LIB.T6G(SCH_1):M_F_CPU0_SB_CB(5)
   U25 BU66 MFB_CHECK5 GENOA_SP5-SOCKET6096_13568-001,SMLF,IO,DGA^6000030   I159 @T6G_MB_LIB.T6G(SCH_1):PAGE15
   J23   91  CB5_B SCONN288_DDR506112002KQ-SCONN288_DDR506112002KQ,SMA   I350 @T6G_MB_LIB.T6G(SCH_1):PAGE90

M_F_CPU0_SB_CB<6> @T6G_MB_LIB.T6G(SCH_1):M_F_CPU0_SB_CB(6)
   U25 BU67 MFB_CHECK6 GENOA_SP5-SOCKET6096_13568-001,SMLF,IO,DGA^6000030   I159 @T6G_MB_LIB.T6G(SCH_1):PAGE15
   J23  234  CB6_B SCONN288_DDR506112002KQ-SCONN288_DDR506112002KQ,SMA   I350 @T6G_MB_LIB.T6G(SCH_1):PAGE90

M_F_CPU0_SB_CB<7> @T6G_MB_LIB.T6G(SCH_1):M_F_CPU0_SB_CB(7)
   U25 BV65 MFB_CHECK7 GENOA_SP5-SOCKET6096_13568-001,SMLF,IO,DGA^6000030   I159 @T6G_MB_LIB.T6G(SCH_1):PAGE15
   J23  236  CB7_B SCONN288_DDR506112002KQ-SCONN288_DDR506112002KQ,SMA   I350 @T6G_MB_LIB.T6G(SCH_1):PAGE90

M_F_CPU0_SB_CS_N<0> @T6G_MB_LIB.T6G(SCH_1):M_F_CPU0_SB_CS_N(0)
   U25 BM65 MFB0_CS_L0 GENOA_SP5-SOCKET6096_13568-001,SMLF,IO,DGA^6000030   I159 @T6G_MB_LIB.T6G(SCH_1):PAGE15
   J23   84 CS0_B_N SCONN288_DDR506112002KQ-SCONN288_DDR506112002KQ,SMA   I350 @T6G_MB_LIB.T6G(SCH_1):PAGE90

M_F_CPU0_SB_CS_N<1> @T6G_MB_LIB.T6G(SCH_1):M_F_CPU0_SB_CS_N(1)
   U25 BN67 MFB0_CS_L1 GENOA_SP5-SOCKET6096_13568-001,SMLF,IO,DGA^6000030   I159 @T6G_MB_LIB.T6G(SCH_1):PAGE15
   J23  229 CS1_B_N SCONN288_DDR506112002KQ-SCONN288_DDR506112002KQ,SMA   I350 @T6G_MB_LIB.T6G(SCH_1):PAGE90

M_F_CPU0_SB_DQ<0> @T6G_MB_LIB.T6G(SCH_1):M_F_CPU0_SB_DQ(0)
   U25 CB67 MFB_DATA0 GENOA_SP5-SOCKET6096_13568-001,SMLF,IO,DGA^6000030   I159 @T6G_MB_LIB.T6G(SCH_1):PAGE15
   J23  100  DQ0_B SCONN288_DDR506112002KQ-SCONN288_DDR506112002KQ,SMA   I350 @T6G_MB_LIB.T6G(SCH_1):PAGE90

M_F_CPU0_SB_DQ<10> @T6G_MB_LIB.T6G(SCH_1):M_F_CPU0_SB_DQ(10)
   U25 CJ67 MFB_DATA10 GENOA_SP5-SOCKET6096_13568-001,SMLF,IO,DGA^6000030   I159 @T6G_MB_LIB.T6G(SCH_1):PAGE15
   J23  256 DQ10_B SCONN288_DDR506112002KQ-SCONN288_DDR506112002KQ,SMA   I350 @T6G_MB_LIB.T6G(SCH_1):PAGE90

M_F_CPU0_SB_DQ<11> @T6G_MB_LIB.T6G(SCH_1):M_F_CPU0_SB_DQ(11)
   U25 CK65 MFB_DATA11 GENOA_SP5-SOCKET6096_13568-001,SMLF,IO,DGA^6000030   I159 @T6G_MB_LIB.T6G(SCH_1):PAGE15
   J23  258 DQ11_B SCONN288_DDR506112002KQ-SCONN288_DDR506112002KQ,SMA   I350 @T6G_MB_LIB.T6G(SCH_1):PAGE90

M_F_CPU0_SB_DQ<12> @T6G_MB_LIB.T6G(SCH_1):M_F_CPU0_SB_DQ(12)
   U25 CM67 MFB_DATA12 GENOA_SP5-SOCKET6096_13568-001,SMLF,IO,DGA^6000030   I159 @T6G_MB_LIB.T6G(SCH_1):PAGE15
   J23  118 DQ12_B SCONN288_DDR506112002KQ-SCONN288_DDR506112002KQ,SMA   I350 @T6G_MB_LIB.T6G(SCH_1):PAGE90

M_F_CPU0_SB_DQ<13> @T6G_MB_LIB.T6G(SCH_1):M_F_CPU0_SB_DQ(13)
   U25 CN66 MFB_DATA13 GENOA_SP5-SOCKET6096_13568-001,SMLF,IO,DGA^6000030   I159 @T6G_MB_LIB.T6G(SCH_1):PAGE15
   J23  120 DQ13_B SCONN288_DDR506112002KQ-SCONN288_DDR506112002KQ,SMA   I350 @T6G_MB_LIB.T6G(SCH_1):PAGE90

M_F_CPU0_SB_DQ<14> @T6G_MB_LIB.T6G(SCH_1):M_F_CPU0_SB_DQ(14)
   U25 CN67 MFB_DATA14 GENOA_SP5-SOCKET6096_13568-001,SMLF,IO,DGA^6000030   I159 @T6G_MB_LIB.T6G(SCH_1):PAGE15
   J23  263 DQ14_B SCONN288_DDR506112002KQ-SCONN288_DDR506112002KQ,SMA   I350 @T6G_MB_LIB.T6G(SCH_1):PAGE90

M_F_CPU0_SB_DQ<15> @T6G_MB_LIB.T6G(SCH_1):M_F_CPU0_SB_DQ(15)
   U25 CP65 MFB_DATA15 GENOA_SP5-SOCKET6096_13568-001,SMLF,IO,DGA^6000030   I159 @T6G_MB_LIB.T6G(SCH_1):PAGE15
   J23  265 DQ15_B SCONN288_DDR506112002KQ-SCONN288_DDR506112002KQ,SMA   I350 @T6G_MB_LIB.T6G(SCH_1):PAGE90

M_F_CPU0_SB_DQ<16> @T6G_MB_LIB.T6G(SCH_1):M_F_CPU0_SB_DQ(16)
   U25 CP67 MFB_DATA16 GENOA_SP5-SOCKET6096_13568-001,SMLF,IO,DGA^6000030   I159 @T6G_MB_LIB.T6G(SCH_1):PAGE15
   J23  122 DQ16_B SCONN288_DDR506112002KQ-SCONN288_DDR506112002KQ,SMA   I350 @T6G_MB_LIB.T6G(SCH_1):PAGE90

M_F_CPU0_SB_DQ<17> @T6G_MB_LIB.T6G(SCH_1):M_F_CPU0_SB_DQ(17)
   U25 CR66 MFB_DATA17 GENOA_SP5-SOCKET6096_13568-001,SMLF,IO,DGA^6000030   I159 @T6G_MB_LIB.T6G(SCH_1):PAGE15
   J23  124 DQ17_B SCONN288_DDR506112002KQ-SCONN288_DDR506112002KQ,SMA   I350 @T6G_MB_LIB.T6G(SCH_1):PAGE90

M_F_CPU0_SB_DQ<18> @T6G_MB_LIB.T6G(SCH_1):M_F_CPU0_SB_DQ(18)
   U25 CR67 MFB_DATA18 GENOA_SP5-SOCKET6096_13568-001,SMLF,IO,DGA^6000030   I159 @T6G_MB_LIB.T6G(SCH_1):PAGE15
   J23  267 DQ18_B SCONN288_DDR506112002KQ-SCONN288_DDR506112002KQ,SMA   I350 @T6G_MB_LIB.T6G(SCH_1):PAGE90

M_F_CPU0_SB_DQ<19> @T6G_MB_LIB.T6G(SCH_1):M_F_CPU0_SB_DQ(19)
   U25 CT65 MFB_DATA19 GENOA_SP5-SOCKET6096_13568-001,SMLF,IO,DGA^6000030   I159 @T6G_MB_LIB.T6G(SCH_1):PAGE15
   J23  269 DQ19_B SCONN288_DDR506112002KQ-SCONN288_DDR506112002KQ,SMA   I350 @T6G_MB_LIB.T6G(SCH_1):PAGE90

M_F_CPU0_SB_DQ<1> @T6G_MB_LIB.T6G(SCH_1):M_F_CPU0_SB_DQ(1)
   U25 CC66 MFB_DATA1 GENOA_SP5-SOCKET6096_13568-001,SMLF,IO,DGA^6000030   I159 @T6G_MB_LIB.T6G(SCH_1):PAGE15
   J23  102  DQ1_B SCONN288_DDR506112002KQ-SCONN288_DDR506112002KQ,SMA   I350 @T6G_MB_LIB.T6G(SCH_1):PAGE90

M_F_CPU0_SB_DQ<20> @T6G_MB_LIB.T6G(SCH_1):M_F_CPU0_SB_DQ(20)
   U25 CV67 MFB_DATA20 GENOA_SP5-SOCKET6096_13568-001,SMLF,IO,DGA^6000030   I159 @T6G_MB_LIB.T6G(SCH_1):PAGE15
   J23  129 DQ20_B SCONN288_DDR506112002KQ-SCONN288_DDR506112002KQ,SMA   I350 @T6G_MB_LIB.T6G(SCH_1):PAGE90

M_F_CPU0_SB_DQ<21> @T6G_MB_LIB.T6G(SCH_1):M_F_CPU0_SB_DQ(21)
   U25 CW66 MFB_DATA21 GENOA_SP5-SOCKET6096_13568-001,SMLF,IO,DGA^6000030   I159 @T6G_MB_LIB.T6G(SCH_1):PAGE15
   J23  131 DQ21_B SCONN288_DDR506112002KQ-SCONN288_DDR506112002KQ,SMA   I350 @T6G_MB_LIB.T6G(SCH_1):PAGE90

M_F_CPU0_SB_DQ<22> @T6G_MB_LIB.T6G(SCH_1):M_F_CPU0_SB_DQ(22)
   U25 CW67 MFB_DATA22 GENOA_SP5-SOCKET6096_13568-001,SMLF,IO,DGA^6000030   I159 @T6G_MB_LIB.T6G(SCH_1):PAGE15
   J23  274 DQ22_B SCONN288_DDR506112002KQ-SCONN288_DDR506112002KQ,SMA   I350 @T6G_MB_LIB.T6G(SCH_1):PAGE90

M_F_CPU0_SB_DQ<23> @T6G_MB_LIB.T6G(SCH_1):M_F_CPU0_SB_DQ(23)
   U25 CY65 MFB_DATA23 GENOA_SP5-SOCKET6096_13568-001,SMLF,IO,DGA^6000030   I159 @T6G_MB_LIB.T6G(SCH_1):PAGE15
   J23  276 DQ23_B SCONN288_DDR506112002KQ-SCONN288_DDR506112002KQ,SMA   I350 @T6G_MB_LIB.T6G(SCH_1):PAGE90

M_F_CPU0_SB_DQ<24> @T6G_MB_LIB.T6G(SCH_1):M_F_CPU0_SB_DQ(24)
   U25 CY67 MFB_DATA24 GENOA_SP5-SOCKET6096_13568-001,SMLF,IO,DGA^6000030   I159 @T6G_MB_LIB.T6G(SCH_1):PAGE15
   J23  133 DQ24_B SCONN288_DDR506112002KQ-SCONN288_DDR506112002KQ,SMA   I350 @T6G_MB_LIB.T6G(SCH_1):PAGE90

M_F_CPU0_SB_DQ<25> @T6G_MB_LIB.T6G(SCH_1):M_F_CPU0_SB_DQ(25)
   U25 DA66 MFB_DATA25 GENOA_SP5-SOCKET6096_13568-001,SMLF,IO,DGA^6000030   I159 @T6G_MB_LIB.T6G(SCH_1):PAGE15
   J23  135 DQ25_B SCONN288_DDR506112002KQ-SCONN288_DDR506112002KQ,SMA   I350 @T6G_MB_LIB.T6G(SCH_1):PAGE90

M_F_CPU0_SB_DQ<26> @T6G_MB_LIB.T6G(SCH_1):M_F_CPU0_SB_DQ(26)
   U25 DA67 MFB_DATA26 GENOA_SP5-SOCKET6096_13568-001,SMLF,IO,DGA^6000030   I159 @T6G_MB_LIB.T6G(SCH_1):PAGE15
   J23  278 DQ26_B SCONN288_DDR506112002KQ-SCONN288_DDR506112002KQ,SMA   I350 @T6G_MB_LIB.T6G(SCH_1):PAGE90

M_F_CPU0_SB_DQ<27> @T6G_MB_LIB.T6G(SCH_1):M_F_CPU0_SB_DQ(27)
   U25 DB65 MFB_DATA27 GENOA_SP5-SOCKET6096_13568-001,SMLF,IO,DGA^6000030   I159 @T6G_MB_LIB.T6G(SCH_1):PAGE15
   J23  280 DQ27_B SCONN288_DDR506112002KQ-SCONN288_DDR506112002KQ,SMA   I350 @T6G_MB_LIB.T6G(SCH_1):PAGE90

M_F_CPU0_SB_DQ<28> @T6G_MB_LIB.T6G(SCH_1):M_F_CPU0_SB_DQ(28)
   U25 DD67 MFB_DATA28 GENOA_SP5-SOCKET6096_13568-001,SMLF,IO,DGA^6000030   I159 @T6G_MB_LIB.T6G(SCH_1):PAGE15
   J23  140 DQ28_B SCONN288_DDR506112002KQ-SCONN288_DDR506112002KQ,SMA   I350 @T6G_MB_LIB.T6G(SCH_1):PAGE90

M_F_CPU0_SB_DQ<29> @T6G_MB_LIB.T6G(SCH_1):M_F_CPU0_SB_DQ(29)
   U25 DE66 MFB_DATA29 GENOA_SP5-SOCKET6096_13568-001,SMLF,IO,DGA^6000030   I159 @T6G_MB_LIB.T6G(SCH_1):PAGE15
   J23  142 DQ29_B SCONN288_DDR506112002KQ-SCONN288_DDR506112002KQ,SMA   I350 @T6G_MB_LIB.T6G(SCH_1):PAGE90

M_F_CPU0_SB_DQ<2> @T6G_MB_LIB.T6G(SCH_1):M_F_CPU0_SB_DQ(2)
   U25 CC67 MFB_DATA2 GENOA_SP5-SOCKET6096_13568-001,SMLF,IO,DGA^6000030   I159 @T6G_MB_LIB.T6G(SCH_1):PAGE15
   J23  245  DQ2_B SCONN288_DDR506112002KQ-SCONN288_DDR506112002KQ,SMA   I350 @T6G_MB_LIB.T6G(SCH_1):PAGE90

M_F_CPU0_SB_DQ<30> @T6G_MB_LIB.T6G(SCH_1):M_F_CPU0_SB_DQ(30)
   U25 DE67 MFB_DATA30 GENOA_SP5-SOCKET6096_13568-001,SMLF,IO,DGA^6000030   I159 @T6G_MB_LIB.T6G(SCH_1):PAGE15
   J23  285 DQ30_B SCONN288_DDR506112002KQ-SCONN288_DDR506112002KQ,SMA   I350 @T6G_MB_LIB.T6G(SCH_1):PAGE90

M_F_CPU0_SB_DQ<31> @T6G_MB_LIB.T6G(SCH_1):M_F_CPU0_SB_DQ(31)
   U25 DF67 MFB_DATA31 GENOA_SP5-SOCKET6096_13568-001,SMLF,IO,DGA^6000030   I159 @T6G_MB_LIB.T6G(SCH_1):PAGE15
   J23  287 DQ31_B SCONN288_DDR506112002KQ-SCONN288_DDR506112002KQ,SMA   I350 @T6G_MB_LIB.T6G(SCH_1):PAGE90

M_F_CPU0_SB_DQ<3> @T6G_MB_LIB.T6G(SCH_1):M_F_CPU0_SB_DQ(3)
   U25 CD65 MFB_DATA3 GENOA_SP5-SOCKET6096_13568-001,SMLF,IO,DGA^6000030   I159 @T6G_MB_LIB.T6G(SCH_1):PAGE15
   J23  247  DQ3_B SCONN288_DDR506112002KQ-SCONN288_DDR506112002KQ,SMA   I350 @T6G_MB_LIB.T6G(SCH_1):PAGE90

M_F_CPU0_SB_DQ<4> @T6G_MB_LIB.T6G(SCH_1):M_F_CPU0_SB_DQ(4)
   U25 CF67 MFB_DATA4 GENOA_SP5-SOCKET6096_13568-001,SMLF,IO,DGA^6000030   I159 @T6G_MB_LIB.T6G(SCH_1):PAGE15
   J23  107  DQ4_B SCONN288_DDR506112002KQ-SCONN288_DDR506112002KQ,SMA   I350 @T6G_MB_LIB.T6G(SCH_1):PAGE90

M_F_CPU0_SB_DQ<5> @T6G_MB_LIB.T6G(SCH_1):M_F_CPU0_SB_DQ(5)
   U25 CG66 MFB_DATA5 GENOA_SP5-SOCKET6096_13568-001,SMLF,IO,DGA^6000030   I159 @T6G_MB_LIB.T6G(SCH_1):PAGE15
   J23  109  DQ5_B SCONN288_DDR506112002KQ-SCONN288_DDR506112002KQ,SMA   I350 @T6G_MB_LIB.T6G(SCH_1):PAGE90

M_F_CPU0_SB_DQ<6> @T6G_MB_LIB.T6G(SCH_1):M_F_CPU0_SB_DQ(6)
   U25 CG67 MFB_DATA6 GENOA_SP5-SOCKET6096_13568-001,SMLF,IO,DGA^6000030   I159 @T6G_MB_LIB.T6G(SCH_1):PAGE15
   J23  252  DQ6_B SCONN288_DDR506112002KQ-SCONN288_DDR506112002KQ,SMA   I350 @T6G_MB_LIB.T6G(SCH_1):PAGE90

M_F_CPU0_SB_DQ<7> @T6G_MB_LIB.T6G(SCH_1):M_F_CPU0_SB_DQ(7)
   U25 CH65 MFB_DATA7 GENOA_SP5-SOCKET6096_13568-001,SMLF,IO,DGA^6000030   I159 @T6G_MB_LIB.T6G(SCH_1):PAGE15
   J23  254  DQ7_B SCONN288_DDR506112002KQ-SCONN288_DDR506112002KQ,SMA   I350 @T6G_MB_LIB.T6G(SCH_1):PAGE90

M_F_CPU0_SB_DQ<8> @T6G_MB_LIB.T6G(SCH_1):M_F_CPU0_SB_DQ(8)
   U25 CH67 MFB_DATA8 GENOA_SP5-SOCKET6096_13568-001,SMLF,IO,DGA^6000030   I159 @T6G_MB_LIB.T6G(SCH_1):PAGE15
   J23  111  DQ8_B SCONN288_DDR506112002KQ-SCONN288_DDR506112002KQ,SMA   I350 @T6G_MB_LIB.T6G(SCH_1):PAGE90

M_F_CPU0_SB_DQ<9> @T6G_MB_LIB.T6G(SCH_1):M_F_CPU0_SB_DQ(9)
   U25 CJ66 MFB_DATA9 GENOA_SP5-SOCKET6096_13568-001,SMLF,IO,DGA^6000030   I159 @T6G_MB_LIB.T6G(SCH_1):PAGE15
   J23  113  DQ9_B SCONN288_DDR506112002KQ-SCONN288_DDR506112002KQ,SMA   I350 @T6G_MB_LIB.T6G(SCH_1):PAGE90

M_F_CPU0_SB_DQS_DN<0> @T6G_MB_LIB.T6G(SCH_1):M_F_CPU0_SB_DQS_DN(0)
   U25 CE67 MFB_DQS_L0 GENOA_SP5-SOCKET6096_13568-001,SMLF,IO,DGA^6000030   I159 @T6G_MB_LIB.T6G(SCH_1):PAGE15
   J23  105 DQS0_B_C SCONN288_DDR506112002KQ-SCONN288_DDR506112002KQ,SMA   I412 @T6G_MB_LIB.T6G(SCH_1):PAGE90

M_F_CPU0_SB_DQS_DN<1> @T6G_MB_LIB.T6G(SCH_1):M_F_CPU0_SB_DQS_DN(1)
   U25 CL67 MFB_DQS_L1 GENOA_SP5-SOCKET6096_13568-001,SMLF,IO,DGA^6000030   I159 @T6G_MB_LIB.T6G(SCH_1):PAGE15
   J23  116 DQS1_B_C SCONN288_DDR506112002KQ-SCONN288_DDR506112002KQ,SMA   I412 @T6G_MB_LIB.T6G(SCH_1):PAGE90

M_F_CPU0_SB_DQS_DN<2> @T6G_MB_LIB.T6G(SCH_1):M_F_CPU0_SB_DQS_DN(2)
   U25 CU67 MFB_DQS_L2 GENOA_SP5-SOCKET6096_13568-001,SMLF,IO,DGA^6000030   I159 @T6G_MB_LIB.T6G(SCH_1):PAGE15
   J23  127 DQS2_B_C SCONN288_DDR506112002KQ-SCONN288_DDR506112002KQ,SMA   I412 @T6G_MB_LIB.T6G(SCH_1):PAGE90

M_F_CPU0_SB_DQS_DN<3> @T6G_MB_LIB.T6G(SCH_1):M_F_CPU0_SB_DQS_DN(3)
   U25 DC67 MFB_DQS_L3 GENOA_SP5-SOCKET6096_13568-001,SMLF,IO,DGA^6000030   I159 @T6G_MB_LIB.T6G(SCH_1):PAGE15
   J23  138 DQS3_B_C SCONN288_DDR506112002KQ-SCONN288_DDR506112002KQ,SMA   I412 @T6G_MB_LIB.T6G(SCH_1):PAGE90

M_F_CPU0_SB_DQS_DN<4> @T6G_MB_LIB.T6G(SCH_1):M_F_CPU0_SB_DQS_DN(4)
   U25 BW66 MFB_DQS_L4 GENOA_SP5-SOCKET6096_13568-001,SMLF,IO,DGA^6000030   I159 @T6G_MB_LIB.T6G(SCH_1):PAGE15
   J23  238 DQS4_B_C SCONN288_DDR506112002KQ-SCONN288_DDR506112002KQ,SMA   I412 @T6G_MB_LIB.T6G(SCH_1):PAGE90

M_F_CPU0_SB_DQS_DN<5> @T6G_MB_LIB.T6G(SCH_1):M_F_CPU0_SB_DQS_DN(5)
   U25 CE66 MFB_DQS_L5 GENOA_SP5-SOCKET6096_13568-001,SMLF,IO,DGA^6000030   I159 @T6G_MB_LIB.T6G(SCH_1):PAGE15
   J23  249 DQS5_B_C||TDQS5_B_C SCONN288_DDR506112002KQ-SCONN288_DDR506112002KQ,SMA   I412 @T6G_MB_LIB.T6G(SCH_1):PAGE90

M_F_CPU0_SB_DQS_DN<6> @T6G_MB_LIB.T6G(SCH_1):M_F_CPU0_SB_DQS_DN(6)
   U25 CL66 MFB_DQS_L6 GENOA_SP5-SOCKET6096_13568-001,SMLF,IO,DGA^6000030   I159 @T6G_MB_LIB.T6G(SCH_1):PAGE15
   J23  260 DQS6_B_C||TDQS6_B_C SCONN288_DDR506112002KQ-SCONN288_DDR506112002KQ,SMA   I412 @T6G_MB_LIB.T6G(SCH_1):PAGE90

M_F_CPU0_SB_DQS_DN<7> @T6G_MB_LIB.T6G(SCH_1):M_F_CPU0_SB_DQS_DN(7)
   U25 CU66 MFB_DQS_L7 GENOA_SP5-SOCKET6096_13568-001,SMLF,IO,DGA^6000030   I159 @T6G_MB_LIB.T6G(SCH_1):PAGE15
   J23  271 DQS7_B_C||TDQS7_B_C SCONN288_DDR506112002KQ-SCONN288_DDR506112002KQ,SMA   I412 @T6G_MB_LIB.T6G(SCH_1):PAGE90

M_F_CPU0_SB_DQS_DN<8> @T6G_MB_LIB.T6G(SCH_1):M_F_CPU0_SB_DQS_DN(8)
   U25 DC66 MFB_DQS_L8 GENOA_SP5-SOCKET6096_13568-001,SMLF,IO,DGA^6000030   I159 @T6G_MB_LIB.T6G(SCH_1):PAGE15
   J23  282 DQS8_B_C||TDQS8_B_C SCONN288_DDR506112002KQ-SCONN288_DDR506112002KQ,SMA   I412 @T6G_MB_LIB.T6G(SCH_1):PAGE90

M_F_CPU0_SB_DQS_DN<9> @T6G_MB_LIB.T6G(SCH_1):M_F_CPU0_SB_DQS_DN(9)
   U25 BW67 MFB_DQS_L9 GENOA_SP5-SOCKET6096_13568-001,SMLF,IO,DGA^6000030   I159 @T6G_MB_LIB.T6G(SCH_1):PAGE15
   J23   94 DQS9_B_C||TDQS9_B_C SCONN288_DDR506112002KQ-SCONN288_DDR506112002KQ,SMA   I412 @T6G_MB_LIB.T6G(SCH_1):PAGE90

M_F_CPU0_SB_DQS_DP<0> @T6G_MB_LIB.T6G(SCH_1):M_F_CPU0_SB_DQS_DP(0)
   U25 CD67 MFB_DQS_H0 GENOA_SP5-SOCKET6096_13568-001,SMLF,IO,DGA^6000030   I159 @T6G_MB_LIB.T6G(SCH_1):PAGE15
   J23  104 DQS0_B_T SCONN288_DDR506112002KQ-SCONN288_DDR506112002KQ,SMA   I412 @T6G_MB_LIB.T6G(SCH_1):PAGE90

M_F_CPU0_SB_DQS_DP<1> @T6G_MB_LIB.T6G(SCH_1):M_F_CPU0_SB_DQS_DP(1)
   U25 CK67 MFB_DQS_H1 GENOA_SP5-SOCKET6096_13568-001,SMLF,IO,DGA^6000030   I159 @T6G_MB_LIB.T6G(SCH_1):PAGE15
   J23  115 DQS1_B_T SCONN288_DDR506112002KQ-SCONN288_DDR506112002KQ,SMA   I412 @T6G_MB_LIB.T6G(SCH_1):PAGE90

M_F_CPU0_SB_DQS_DP<2> @T6G_MB_LIB.T6G(SCH_1):M_F_CPU0_SB_DQS_DP(2)
   U25 CT67 MFB_DQS_H2 GENOA_SP5-SOCKET6096_13568-001,SMLF,IO,DGA^6000030   I159 @T6G_MB_LIB.T6G(SCH_1):PAGE15
   J23  126 DQS2_B_T SCONN288_DDR506112002KQ-SCONN288_DDR506112002KQ,SMA   I412 @T6G_MB_LIB.T6G(SCH_1):PAGE90

M_F_CPU0_SB_DQS_DP<3> @T6G_MB_LIB.T6G(SCH_1):M_F_CPU0_SB_DQS_DP(3)
   U25 DB67 MFB_DQS_H3 GENOA_SP5-SOCKET6096_13568-001,SMLF,IO,DGA^6000030   I159 @T6G_MB_LIB.T6G(SCH_1):PAGE15
   J23  137 DQS3_B_T SCONN288_DDR506112002KQ-SCONN288_DDR506112002KQ,SMA   I412 @T6G_MB_LIB.T6G(SCH_1):PAGE90

M_F_CPU0_SB_DQS_DP<4> @T6G_MB_LIB.T6G(SCH_1):M_F_CPU0_SB_DQS_DP(4)
   U25 BY65 MFB_DQS_H4 GENOA_SP5-SOCKET6096_13568-001,SMLF,IO,DGA^6000030   I159 @T6G_MB_LIB.T6G(SCH_1):PAGE15
   J23  239 DQS4_B_T SCONN288_DDR506112002KQ-SCONN288_DDR506112002KQ,SMA   I412 @T6G_MB_LIB.T6G(SCH_1):PAGE90

M_F_CPU0_SB_DQS_DP<5> @T6G_MB_LIB.T6G(SCH_1):M_F_CPU0_SB_DQS_DP(5)
   U25 CF65 MFB_DQS_H5 GENOA_SP5-SOCKET6096_13568-001,SMLF,IO,DGA^6000030   I159 @T6G_MB_LIB.T6G(SCH_1):PAGE15
   J23  250 DQS5_B_T||TDQS5_B_T SCONN288_DDR506112002KQ-SCONN288_DDR506112002KQ,SMA   I412 @T6G_MB_LIB.T6G(SCH_1):PAGE90

M_F_CPU0_SB_DQS_DP<6> @T6G_MB_LIB.T6G(SCH_1):M_F_CPU0_SB_DQS_DP(6)
   U25 CM65 MFB_DQS_H6 GENOA_SP5-SOCKET6096_13568-001,SMLF,IO,DGA^6000030   I159 @T6G_MB_LIB.T6G(SCH_1):PAGE15
   J23  261 DQS6_B_T||TDQS6_B_T SCONN288_DDR506112002KQ-SCONN288_DDR506112002KQ,SMA   I412 @T6G_MB_LIB.T6G(SCH_1):PAGE90

M_F_CPU0_SB_DQS_DP<7> @T6G_MB_LIB.T6G(SCH_1):M_F_CPU0_SB_DQS_DP(7)
   U25 CV65 MFB_DQS_H7 GENOA_SP5-SOCKET6096_13568-001,SMLF,IO,DGA^6000030   I159 @T6G_MB_LIB.T6G(SCH_1):PAGE15
   J23  272 DQS7_B_T||TDQS7_B_T SCONN288_DDR506112002KQ-SCONN288_DDR506112002KQ,SMA   I412 @T6G_MB_LIB.T6G(SCH_1):PAGE90

M_F_CPU0_SB_DQS_DP<8> @T6G_MB_LIB.T6G(SCH_1):M_F_CPU0_SB_DQS_DP(8)
   U25 DD65 MFB_DQS_H8 GENOA_SP5-SOCKET6096_13568-001,SMLF,IO,DGA^6000030   I159 @T6G_MB_LIB.T6G(SCH_1):PAGE15
   J23  283 DQS8_B_T||TDQS8_B_T SCONN288_DDR506112002KQ-SCONN288_DDR506112002KQ,SMA   I412 @T6G_MB_LIB.T6G(SCH_1):PAGE90

M_F_CPU0_SB_DQS_DP<9> @T6G_MB_LIB.T6G(SCH_1):M_F_CPU0_SB_DQS_DP(9)
   U25 BV67 MFB_DQS_H9 GENOA_SP5-SOCKET6096_13568-001,SMLF,IO,DGA^6000030   I159 @T6G_MB_LIB.T6G(SCH_1):PAGE15
   J23   93 DQS9_B_T||TDQS9_B_T||DBI4_B_N SCONN288_DDR506112002KQ-SCONN288_DDR506112002KQ,SMA   I412 @T6G_MB_LIB.T6G(SCH_1):PAGE90

M_F_CPU0_SB_PAR @T6G_MB_LIB.T6G(SCH_1):M_F_CPU0_SB_PAR
   U25 BL67 MFB_PAR GENOA_SP5-SOCKET6096_13568-001,SMLF,IO,DGA^6000030   I159 @T6G_MB_LIB.T6G(SCH_1):PAGE15
   J23  227  PAR_B SCONN288_DDR506112002KQ-SCONN288_DDR506112002KQ,SMA   I350 @T6G_MB_LIB.T6G(SCH_1):PAGE90

M_F_CPU0_SB_RSP<0> @T6G_MB_LIB.T6G(SCH_1):M_F_CPU0_SB_RSP(0)
   U25 BP67 MFB0_RSP_L GENOA_SP5-SOCKET6096_13568-001,SMLF,IO,DGA^6000030   I159 @T6G_MB_LIB.T6G(SCH_1):PAGE15
   J23   87 LBS||RSP_B_N SCONN288_DDR506112002KQ-SCONN288_DDR506112002KQ,SMA   I350 @T6G_MB_LIB.T6G(SCH_1):PAGE90

M_F_CPU1_ALERT_N @T6G_MB_LIB.T6G(SCH_1):M_F_CPU1_ALERT_N
  R505    1      A Q_RES_0402LF-15,1%,1/16W,CHIP,CS01502FB03   I314 @T6G_MB_LIB.T6G(SCH_1):PAGE42
   J33   62 ALERT_N SCONN288_DDR506112002KQ-SCONN288_DDR506112002KQ,SMA    I22 @T6G_MB_LIB.T6G(SCH_1):PAGE102

M_F_CPU1_ALERT_R_N @T6G_MB_LIB.T6G(SCH_1):M_F_CPU1_ALERT_R_N
   U26 AT65 MF_ALERT_L GENOA_SP5-SOCKET6096_13568-001,SMLF,IO,DGA^6000030   I159 @T6G_MB_LIB.T6G(SCH_1):PAGE42
  R505    2      B Q_RES_0402LF-15,1%,1/16W,CHIP,CS01502FB03   I314 @T6G_MB_LIB.T6G(SCH_1):PAGE42

M_F_CPU1_CLK_DN<0> @T6G_MB_LIB.T6G(SCH_1):M_F_CPU1_CLK_DN(0)
   U26 BD67 MF0_CLK_L GENOA_SP5-SOCKET6096_13568-001,SMLF,IO,DGA^6000030   I159 @T6G_MB_LIB.T6G(SCH_1):PAGE42
   J33  218   CK_C SCONN288_DDR506112002KQ-SCONN288_DDR506112002KQ,SMA    I22 @T6G_MB_LIB.T6G(SCH_1):PAGE102

M_F_CPU1_CLK_DP<0> @T6G_MB_LIB.T6G(SCH_1):M_F_CPU1_CLK_DP(0)
   U26 BC67 MF0_CLK_H GENOA_SP5-SOCKET6096_13568-001,SMLF,IO,DGA^6000030   I159 @T6G_MB_LIB.T6G(SCH_1):PAGE42
   J33  217   CK_T SCONN288_DDR506112002KQ-SCONN288_DDR506112002KQ,SMA    I22 @T6G_MB_LIB.T6G(SCH_1):PAGE102

M_F_CPU1_RESET_N @T6G_MB_LIB.T6G(SCH_1):M_F_CPU1_RESET_N
   U26 AU66 MF_RESET_L GENOA_SP5-SOCKET6096_13568-001,SMLF,IO,DGA^6000030   I159 @T6G_MB_LIB.T6G(SCH_1):PAGE42
   J33  207 RESET_N SCONN288_DDR506112002KQ-SCONN288_DDR506112002KQ,SMA    I22 @T6G_MB_LIB.T6G(SCH_1):PAGE102

M_F_CPU1_SA_CA<0> @T6G_MB_LIB.T6G(SCH_1):M_F_CPU1_SA_CA(0)
   U26 AW67 MFA_CA0 GENOA_SP5-SOCKET6096_13568-001,SMLF,IO,DGA^6000030   I159 @T6G_MB_LIB.T6G(SCH_1):PAGE42
   J33   66  CA0_A SCONN288_DDR506112002KQ-SCONN288_DDR506112002KQ,SMA    I22 @T6G_MB_LIB.T6G(SCH_1):PAGE102

M_F_CPU1_SA_CA<1> @T6G_MB_LIB.T6G(SCH_1):M_F_CPU1_SA_CA(1)
   U26 AY67 MFA_CA1 GENOA_SP5-SOCKET6096_13568-001,SMLF,IO,DGA^6000030   I159 @T6G_MB_LIB.T6G(SCH_1):PAGE42
   J33  211  CA1_A SCONN288_DDR506112002KQ-SCONN288_DDR506112002KQ,SMA    I22 @T6G_MB_LIB.T6G(SCH_1):PAGE102

M_F_CPU1_SA_CA<2> @T6G_MB_LIB.T6G(SCH_1):M_F_CPU1_SA_CA(2)
   U26 AY65 MFA_CA2 GENOA_SP5-SOCKET6096_13568-001,SMLF,IO,DGA^6000030   I159 @T6G_MB_LIB.T6G(SCH_1):PAGE42
   J33   68  CA2_A SCONN288_DDR506112002KQ-SCONN288_DDR506112002KQ,SMA    I22 @T6G_MB_LIB.T6G(SCH_1):PAGE102

M_F_CPU1_SA_CA<3> @T6G_MB_LIB.T6G(SCH_1):M_F_CPU1_SA_CA(3)
   U26 BA66 MFA_CA3 GENOA_SP5-SOCKET6096_13568-001,SMLF,IO,DGA^6000030   I159 @T6G_MB_LIB.T6G(SCH_1):PAGE42
   J33  213  CA3_A SCONN288_DDR506112002KQ-SCONN288_DDR506112002KQ,SMA    I22 @T6G_MB_LIB.T6G(SCH_1):PAGE102

M_F_CPU1_SA_CA<4> @T6G_MB_LIB.T6G(SCH_1):M_F_CPU1_SA_CA(4)
   U26 BA67 MFA_CA4 GENOA_SP5-SOCKET6096_13568-001,SMLF,IO,DGA^6000030   I159 @T6G_MB_LIB.T6G(SCH_1):PAGE42
   J33   70  CA4_A SCONN288_DDR506112002KQ-SCONN288_DDR506112002KQ,SMA    I22 @T6G_MB_LIB.T6G(SCH_1):PAGE102

M_F_CPU1_SA_CA<5> @T6G_MB_LIB.T6G(SCH_1):M_F_CPU1_SA_CA(5)
   U26 BB67 MFA_CA5 GENOA_SP5-SOCKET6096_13568-001,SMLF,IO,DGA^6000030   I159 @T6G_MB_LIB.T6G(SCH_1):PAGE42
   J33  215  CA5_A SCONN288_DDR506112002KQ-SCONN288_DDR506112002KQ,SMA    I22 @T6G_MB_LIB.T6G(SCH_1):PAGE102

M_F_CPU1_SA_CA<6> @T6G_MB_LIB.T6G(SCH_1):M_F_CPU1_SA_CA(6)
   U26 BB65 MFA_CA6 GENOA_SP5-SOCKET6096_13568-001,SMLF,IO,DGA^6000030   I159 @T6G_MB_LIB.T6G(SCH_1):PAGE42
   J33   72  CA6_A SCONN288_DDR506112002KQ-SCONN288_DDR506112002KQ,SMA    I22 @T6G_MB_LIB.T6G(SCH_1):PAGE102

M_F_CPU1_SA_CB<0> @T6G_MB_LIB.T6G(SCH_1):M_F_CPU1_SA_CB(0)
   U26 AJ67 MFA_CHECK0 GENOA_SP5-SOCKET6096_13568-001,SMLF,IO,DGA^6000030   I159 @T6G_MB_LIB.T6G(SCH_1):PAGE42
   J33   51  CB0_A SCONN288_DDR506112002KQ-SCONN288_DDR506112002KQ,SMA    I22 @T6G_MB_LIB.T6G(SCH_1):PAGE102

M_F_CPU1_SA_CB<1> @T6G_MB_LIB.T6G(SCH_1):M_F_CPU1_SA_CB(1)
   U26 AK65 MFA_CHECK1 GENOA_SP5-SOCKET6096_13568-001,SMLF,IO,DGA^6000030   I159 @T6G_MB_LIB.T6G(SCH_1):PAGE42
   J33   53  CB1_A SCONN288_DDR506112002KQ-SCONN288_DDR506112002KQ,SMA    I22 @T6G_MB_LIB.T6G(SCH_1):PAGE102

M_F_CPU1_SA_CB<2> @T6G_MB_LIB.T6G(SCH_1):M_F_CPU1_SA_CB(2)
   U26 AK67 MFA_CHECK2 GENOA_SP5-SOCKET6096_13568-001,SMLF,IO,DGA^6000030   I159 @T6G_MB_LIB.T6G(SCH_1):PAGE42
   J33  196  CB2_A SCONN288_DDR506112002KQ-SCONN288_DDR506112002KQ,SMA    I22 @T6G_MB_LIB.T6G(SCH_1):PAGE102

M_F_CPU1_SA_CB<3> @T6G_MB_LIB.T6G(SCH_1):M_F_CPU1_SA_CB(3)
   U26 AL66 MFA_CHECK3 GENOA_SP5-SOCKET6096_13568-001,SMLF,IO,DGA^6000030   I159 @T6G_MB_LIB.T6G(SCH_1):PAGE42
   J33  198  CB3_A SCONN288_DDR506112002KQ-SCONN288_DDR506112002KQ,SMA    I22 @T6G_MB_LIB.T6G(SCH_1):PAGE102

M_F_CPU1_SA_CB<4> @T6G_MB_LIB.T6G(SCH_1):M_F_CPU1_SA_CB(4)
   U26 AN67 MFA_CHECK4 GENOA_SP5-SOCKET6096_13568-001,SMLF,IO,DGA^6000030   I159 @T6G_MB_LIB.T6G(SCH_1):PAGE42
   J33   58  CB4_A SCONN288_DDR506112002KQ-SCONN288_DDR506112002KQ,SMA    I22 @T6G_MB_LIB.T6G(SCH_1):PAGE102

M_F_CPU1_SA_CB<5> @T6G_MB_LIB.T6G(SCH_1):M_F_CPU1_SA_CB(5)
   U26 AP65 MFA_CHECK5 GENOA_SP5-SOCKET6096_13568-001,SMLF,IO,DGA^6000030   I159 @T6G_MB_LIB.T6G(SCH_1):PAGE42
   J33   60  CB5_A SCONN288_DDR506112002KQ-SCONN288_DDR506112002KQ,SMA    I22 @T6G_MB_LIB.T6G(SCH_1):PAGE102

M_F_CPU1_SA_CB<6> @T6G_MB_LIB.T6G(SCH_1):M_F_CPU1_SA_CB(6)
   U26 AP67 MFA_CHECK6 GENOA_SP5-SOCKET6096_13568-001,SMLF,IO,DGA^6000030   I159 @T6G_MB_LIB.T6G(SCH_1):PAGE42
   J33  203  CB6_A SCONN288_DDR506112002KQ-SCONN288_DDR506112002KQ,SMA    I22 @T6G_MB_LIB.T6G(SCH_1):PAGE102

M_F_CPU1_SA_CB<7> @T6G_MB_LIB.T6G(SCH_1):M_F_CPU1_SA_CB(7)
   U26 AR66 MFA_CHECK7 GENOA_SP5-SOCKET6096_13568-001,SMLF,IO,DGA^6000030   I159 @T6G_MB_LIB.T6G(SCH_1):PAGE42
   J33  205  CB7_A SCONN288_DDR506112002KQ-SCONN288_DDR506112002KQ,SMA    I22 @T6G_MB_LIB.T6G(SCH_1):PAGE102

M_F_CPU1_SA_CS_N<0> @T6G_MB_LIB.T6G(SCH_1):M_F_CPU1_SA_CS_N(0)
   U26 AV67 MFA0_CS_L0 GENOA_SP5-SOCKET6096_13568-001,SMLF,IO,DGA^6000030   I159 @T6G_MB_LIB.T6G(SCH_1):PAGE42
   J33   64 CS0_A_N SCONN288_DDR506112002KQ-SCONN288_DDR506112002KQ,SMA    I22 @T6G_MB_LIB.T6G(SCH_1):PAGE102

M_F_CPU1_SA_CS_N<1> @T6G_MB_LIB.T6G(SCH_1):M_F_CPU1_SA_CS_N(1)
   U26 AW66 MFA0_CS_L1 GENOA_SP5-SOCKET6096_13568-001,SMLF,IO,DGA^6000030   I159 @T6G_MB_LIB.T6G(SCH_1):PAGE42
   J33  209 CS1_A_N SCONN288_DDR506112002KQ-SCONN288_DDR506112002KQ,SMA    I22 @T6G_MB_LIB.T6G(SCH_1):PAGE102

M_F_CPU1_SA_DQ<0> @T6G_MB_LIB.T6G(SCH_1):M_F_CPU1_SA_DQ(0)
   U26  E67 MFA_DATA0 GENOA_SP5-SOCKET6096_13568-001,SMLF,IO,DGA^6000030   I159 @T6G_MB_LIB.T6G(SCH_1):PAGE42
   J33    7  DQ0_A SCONN288_DDR506112002KQ-SCONN288_DDR506112002KQ,SMA    I22 @T6G_MB_LIB.T6G(SCH_1):PAGE102

M_F_CPU1_SA_DQ<10> @T6G_MB_LIB.T6G(SCH_1):M_F_CPU1_SA_DQ(10)
   U26  M67 MFA_DATA10 GENOA_SP5-SOCKET6096_13568-001,SMLF,IO,DGA^6000030   I159 @T6G_MB_LIB.T6G(SCH_1):PAGE42
   J33  163 DQ10_A SCONN288_DDR506112002KQ-SCONN288_DDR506112002KQ,SMA    I22 @T6G_MB_LIB.T6G(SCH_1):PAGE102

M_F_CPU1_SA_DQ<11> @T6G_MB_LIB.T6G(SCH_1):M_F_CPU1_SA_DQ(11)
   U26  N66 MFA_DATA11 GENOA_SP5-SOCKET6096_13568-001,SMLF,IO,DGA^6000030   I159 @T6G_MB_LIB.T6G(SCH_1):PAGE42
   J33  165 DQ11_A SCONN288_DDR506112002KQ-SCONN288_DDR506112002KQ,SMA    I22 @T6G_MB_LIB.T6G(SCH_1):PAGE102

M_F_CPU1_SA_DQ<12> @T6G_MB_LIB.T6G(SCH_1):M_F_CPU1_SA_DQ(12)
   U26  R67 MFA_DATA12 GENOA_SP5-SOCKET6096_13568-001,SMLF,IO,DGA^6000030   I159 @T6G_MB_LIB.T6G(SCH_1):PAGE42
   J33   25 DQ12_A SCONN288_DDR506112002KQ-SCONN288_DDR506112002KQ,SMA    I22 @T6G_MB_LIB.T6G(SCH_1):PAGE102

M_F_CPU1_SA_DQ<13> @T6G_MB_LIB.T6G(SCH_1):M_F_CPU1_SA_DQ(13)
   U26  T65 MFA_DATA13 GENOA_SP5-SOCKET6096_13568-001,SMLF,IO,DGA^6000030   I159 @T6G_MB_LIB.T6G(SCH_1):PAGE42
   J33   27 DQ13_A SCONN288_DDR506112002KQ-SCONN288_DDR506112002KQ,SMA    I22 @T6G_MB_LIB.T6G(SCH_1):PAGE102

M_F_CPU1_SA_DQ<14> @T6G_MB_LIB.T6G(SCH_1):M_F_CPU1_SA_DQ(14)
   U26  T67 MFA_DATA14 GENOA_SP5-SOCKET6096_13568-001,SMLF,IO,DGA^6000030   I159 @T6G_MB_LIB.T6G(SCH_1):PAGE42
   J33  170 DQ14_A SCONN288_DDR506112002KQ-SCONN288_DDR506112002KQ,SMA    I22 @T6G_MB_LIB.T6G(SCH_1):PAGE102

M_F_CPU1_SA_DQ<15> @T6G_MB_LIB.T6G(SCH_1):M_F_CPU1_SA_DQ(15)
   U26  U66 MFA_DATA15 GENOA_SP5-SOCKET6096_13568-001,SMLF,IO,DGA^6000030   I159 @T6G_MB_LIB.T6G(SCH_1):PAGE42
   J33  172 DQ15_A SCONN288_DDR506112002KQ-SCONN288_DDR506112002KQ,SMA    I22 @T6G_MB_LIB.T6G(SCH_1):PAGE102

M_F_CPU1_SA_DQ<16> @T6G_MB_LIB.T6G(SCH_1):M_F_CPU1_SA_DQ(16)
   U26  U67 MFA_DATA16 GENOA_SP5-SOCKET6096_13568-001,SMLF,IO,DGA^6000030   I159 @T6G_MB_LIB.T6G(SCH_1):PAGE42
   J33   29 DQ16_A SCONN288_DDR506112002KQ-SCONN288_DDR506112002KQ,SMA    I22 @T6G_MB_LIB.T6G(SCH_1):PAGE102

M_F_CPU1_SA_DQ<17> @T6G_MB_LIB.T6G(SCH_1):M_F_CPU1_SA_DQ(17)
   U26  V65 MFA_DATA17 GENOA_SP5-SOCKET6096_13568-001,SMLF,IO,DGA^6000030   I159 @T6G_MB_LIB.T6G(SCH_1):PAGE42
   J33   31 DQ17_A SCONN288_DDR506112002KQ-SCONN288_DDR506112002KQ,SMA    I22 @T6G_MB_LIB.T6G(SCH_1):PAGE102

M_F_CPU1_SA_DQ<18> @T6G_MB_LIB.T6G(SCH_1):M_F_CPU1_SA_DQ(18)
   U26  V67 MFA_DATA18 GENOA_SP5-SOCKET6096_13568-001,SMLF,IO,DGA^6000030   I159 @T6G_MB_LIB.T6G(SCH_1):PAGE42
   J33  174 DQ18_A SCONN288_DDR506112002KQ-SCONN288_DDR506112002KQ,SMA    I22 @T6G_MB_LIB.T6G(SCH_1):PAGE102

M_F_CPU1_SA_DQ<19> @T6G_MB_LIB.T6G(SCH_1):M_F_CPU1_SA_DQ(19)
   U26  W66 MFA_DATA19 GENOA_SP5-SOCKET6096_13568-001,SMLF,IO,DGA^6000030   I159 @T6G_MB_LIB.T6G(SCH_1):PAGE42
   J33  176 DQ19_A SCONN288_DDR506112002KQ-SCONN288_DDR506112002KQ,SMA    I22 @T6G_MB_LIB.T6G(SCH_1):PAGE102

M_F_CPU1_SA_DQ<1> @T6G_MB_LIB.T6G(SCH_1):M_F_CPU1_SA_DQ(1)
   U26  F65 MFA_DATA1 GENOA_SP5-SOCKET6096_13568-001,SMLF,IO,DGA^6000030   I159 @T6G_MB_LIB.T6G(SCH_1):PAGE42
   J33    9  DQ1_A SCONN288_DDR506112002KQ-SCONN288_DDR506112002KQ,SMA    I22 @T6G_MB_LIB.T6G(SCH_1):PAGE102

M_F_CPU1_SA_DQ<20> @T6G_MB_LIB.T6G(SCH_1):M_F_CPU1_SA_DQ(20)
   U26 AA67 MFA_DATA20 GENOA_SP5-SOCKET6096_13568-001,SMLF,IO,DGA^6000030   I159 @T6G_MB_LIB.T6G(SCH_1):PAGE42
   J33   36 DQ20_A SCONN288_DDR506112002KQ-SCONN288_DDR506112002KQ,SMA    I22 @T6G_MB_LIB.T6G(SCH_1):PAGE102

M_F_CPU1_SA_DQ<21> @T6G_MB_LIB.T6G(SCH_1):M_F_CPU1_SA_DQ(21)
   U26 AB65 MFA_DATA21 GENOA_SP5-SOCKET6096_13568-001,SMLF,IO,DGA^6000030   I159 @T6G_MB_LIB.T6G(SCH_1):PAGE42
   J33   38 DQ21_A SCONN288_DDR506112002KQ-SCONN288_DDR506112002KQ,SMA    I22 @T6G_MB_LIB.T6G(SCH_1):PAGE102

M_F_CPU1_SA_DQ<22> @T6G_MB_LIB.T6G(SCH_1):M_F_CPU1_SA_DQ(22)
   U26 AB67 MFA_DATA22 GENOA_SP5-SOCKET6096_13568-001,SMLF,IO,DGA^6000030   I159 @T6G_MB_LIB.T6G(SCH_1):PAGE42
   J33  181 DQ22_A SCONN288_DDR506112002KQ-SCONN288_DDR506112002KQ,SMA    I22 @T6G_MB_LIB.T6G(SCH_1):PAGE102

M_F_CPU1_SA_DQ<23> @T6G_MB_LIB.T6G(SCH_1):M_F_CPU1_SA_DQ(23)
   U26 AC66 MFA_DATA23 GENOA_SP5-SOCKET6096_13568-001,SMLF,IO,DGA^6000030   I159 @T6G_MB_LIB.T6G(SCH_1):PAGE42
   J33  183 DQ23_A SCONN288_DDR506112002KQ-SCONN288_DDR506112002KQ,SMA    I22 @T6G_MB_LIB.T6G(SCH_1):PAGE102

M_F_CPU1_SA_DQ<24> @T6G_MB_LIB.T6G(SCH_1):M_F_CPU1_SA_DQ(24)
   U26 AC67 MFA_DATA24 GENOA_SP5-SOCKET6096_13568-001,SMLF,IO,DGA^6000030   I159 @T6G_MB_LIB.T6G(SCH_1):PAGE42
   J33   40 DQ24_A SCONN288_DDR506112002KQ-SCONN288_DDR506112002KQ,SMA    I22 @T6G_MB_LIB.T6G(SCH_1):PAGE102

M_F_CPU1_SA_DQ<25> @T6G_MB_LIB.T6G(SCH_1):M_F_CPU1_SA_DQ(25)
   U26 AD65 MFA_DATA25 GENOA_SP5-SOCKET6096_13568-001,SMLF,IO,DGA^6000030   I159 @T6G_MB_LIB.T6G(SCH_1):PAGE42
   J33   42 DQ25_A SCONN288_DDR506112002KQ-SCONN288_DDR506112002KQ,SMA    I22 @T6G_MB_LIB.T6G(SCH_1):PAGE102

M_F_CPU1_SA_DQ<26> @T6G_MB_LIB.T6G(SCH_1):M_F_CPU1_SA_DQ(26)
   U26 AD67 MFA_DATA26 GENOA_SP5-SOCKET6096_13568-001,SMLF,IO,DGA^6000030   I159 @T6G_MB_LIB.T6G(SCH_1):PAGE42
   J33  185 DQ26_A SCONN288_DDR506112002KQ-SCONN288_DDR506112002KQ,SMA    I22 @T6G_MB_LIB.T6G(SCH_1):PAGE102

M_F_CPU1_SA_DQ<27> @T6G_MB_LIB.T6G(SCH_1):M_F_CPU1_SA_DQ(27)
   U26 AE66 MFA_DATA27 GENOA_SP5-SOCKET6096_13568-001,SMLF,IO,DGA^6000030   I159 @T6G_MB_LIB.T6G(SCH_1):PAGE42
   J33  187 DQ27_A SCONN288_DDR506112002KQ-SCONN288_DDR506112002KQ,SMA    I22 @T6G_MB_LIB.T6G(SCH_1):PAGE102

M_F_CPU1_SA_DQ<28> @T6G_MB_LIB.T6G(SCH_1):M_F_CPU1_SA_DQ(28)
   U26 AG67 MFA_DATA28 GENOA_SP5-SOCKET6096_13568-001,SMLF,IO,DGA^6000030   I159 @T6G_MB_LIB.T6G(SCH_1):PAGE42
   J33   47 DQ28_A SCONN288_DDR506112002KQ-SCONN288_DDR506112002KQ,SMA    I22 @T6G_MB_LIB.T6G(SCH_1):PAGE102

M_F_CPU1_SA_DQ<29> @T6G_MB_LIB.T6G(SCH_1):M_F_CPU1_SA_DQ(29)
   U26 AH65 MFA_DATA29 GENOA_SP5-SOCKET6096_13568-001,SMLF,IO,DGA^6000030   I159 @T6G_MB_LIB.T6G(SCH_1):PAGE42
   J33   49 DQ29_A SCONN288_DDR506112002KQ-SCONN288_DDR506112002KQ,SMA    I22 @T6G_MB_LIB.T6G(SCH_1):PAGE102

M_F_CPU1_SA_DQ<2> @T6G_MB_LIB.T6G(SCH_1):M_F_CPU1_SA_DQ(2)
   U26  F67 MFA_DATA2 GENOA_SP5-SOCKET6096_13568-001,SMLF,IO,DGA^6000030   I159 @T6G_MB_LIB.T6G(SCH_1):PAGE42
   J33  152  DQ2_A SCONN288_DDR506112002KQ-SCONN288_DDR506112002KQ,SMA    I22 @T6G_MB_LIB.T6G(SCH_1):PAGE102

M_F_CPU1_SA_DQ<30> @T6G_MB_LIB.T6G(SCH_1):M_F_CPU1_SA_DQ(30)
   U26 AH67 MFA_DATA30 GENOA_SP5-SOCKET6096_13568-001,SMLF,IO,DGA^6000030   I159 @T6G_MB_LIB.T6G(SCH_1):PAGE42
   J33  192 DQ30_A SCONN288_DDR506112002KQ-SCONN288_DDR506112002KQ,SMA    I22 @T6G_MB_LIB.T6G(SCH_1):PAGE102

M_F_CPU1_SA_DQ<31> @T6G_MB_LIB.T6G(SCH_1):M_F_CPU1_SA_DQ(31)
   U26 AJ66 MFA_DATA31 GENOA_SP5-SOCKET6096_13568-001,SMLF,IO,DGA^6000030   I159 @T6G_MB_LIB.T6G(SCH_1):PAGE42
   J33  194 DQ31_A SCONN288_DDR506112002KQ-SCONN288_DDR506112002KQ,SMA    I22 @T6G_MB_LIB.T6G(SCH_1):PAGE102

M_F_CPU1_SA_DQ<3> @T6G_MB_LIB.T6G(SCH_1):M_F_CPU1_SA_DQ(3)
   U26  G66 MFA_DATA3 GENOA_SP5-SOCKET6096_13568-001,SMLF,IO,DGA^6000030   I159 @T6G_MB_LIB.T6G(SCH_1):PAGE42
   J33  154  DQ3_A SCONN288_DDR506112002KQ-SCONN288_DDR506112002KQ,SMA    I22 @T6G_MB_LIB.T6G(SCH_1):PAGE102

M_F_CPU1_SA_DQ<4> @T6G_MB_LIB.T6G(SCH_1):M_F_CPU1_SA_DQ(4)
   U26  J67 MFA_DATA4 GENOA_SP5-SOCKET6096_13568-001,SMLF,IO,DGA^6000030   I159 @T6G_MB_LIB.T6G(SCH_1):PAGE42
   J33   14  DQ4_A SCONN288_DDR506112002KQ-SCONN288_DDR506112002KQ,SMA    I22 @T6G_MB_LIB.T6G(SCH_1):PAGE102

M_F_CPU1_SA_DQ<5> @T6G_MB_LIB.T6G(SCH_1):M_F_CPU1_SA_DQ(5)
   U26  K65 MFA_DATA5 GENOA_SP5-SOCKET6096_13568-001,SMLF,IO,DGA^6000030   I159 @T6G_MB_LIB.T6G(SCH_1):PAGE42
   J33   16  DQ5_A SCONN288_DDR506112002KQ-SCONN288_DDR506112002KQ,SMA    I22 @T6G_MB_LIB.T6G(SCH_1):PAGE102

M_F_CPU1_SA_DQ<6> @T6G_MB_LIB.T6G(SCH_1):M_F_CPU1_SA_DQ(6)
   U26  K67 MFA_DATA6 GENOA_SP5-SOCKET6096_13568-001,SMLF,IO,DGA^6000030   I159 @T6G_MB_LIB.T6G(SCH_1):PAGE42
   J33  159  DQ6_A SCONN288_DDR506112002KQ-SCONN288_DDR506112002KQ,SMA    I22 @T6G_MB_LIB.T6G(SCH_1):PAGE102

M_F_CPU1_SA_DQ<7> @T6G_MB_LIB.T6G(SCH_1):M_F_CPU1_SA_DQ(7)
   U26  L66 MFA_DATA7 GENOA_SP5-SOCKET6096_13568-001,SMLF,IO,DGA^6000030   I159 @T6G_MB_LIB.T6G(SCH_1):PAGE42
   J33  161  DQ7_A SCONN288_DDR506112002KQ-SCONN288_DDR506112002KQ,SMA    I22 @T6G_MB_LIB.T6G(SCH_1):PAGE102

M_F_CPU1_SA_DQ<8> @T6G_MB_LIB.T6G(SCH_1):M_F_CPU1_SA_DQ(8)
   U26  L67 MFA_DATA8 GENOA_SP5-SOCKET6096_13568-001,SMLF,IO,DGA^6000030   I159 @T6G_MB_LIB.T6G(SCH_1):PAGE42
   J33   18  DQ8_A SCONN288_DDR506112002KQ-SCONN288_DDR506112002KQ,SMA    I22 @T6G_MB_LIB.T6G(SCH_1):PAGE102

M_F_CPU1_SA_DQ<9> @T6G_MB_LIB.T6G(SCH_1):M_F_CPU1_SA_DQ(9)
   U26  M65 MFA_DATA9 GENOA_SP5-SOCKET6096_13568-001,SMLF,IO,DGA^6000030   I159 @T6G_MB_LIB.T6G(SCH_1):PAGE42
   J33   20  DQ9_A SCONN288_DDR506112002KQ-SCONN288_DDR506112002KQ,SMA    I22 @T6G_MB_LIB.T6G(SCH_1):PAGE102

M_F_CPU1_SA_DQS_DN<0> @T6G_MB_LIB.T6G(SCH_1):M_F_CPU1_SA_DQS_DN(0)
   U26  H67 MFA_DQS_L0 GENOA_SP5-SOCKET6096_13568-001,SMLF,IO,DGA^6000030   I159 @T6G_MB_LIB.T6G(SCH_1):PAGE42
   J33   12 DQS0_A_C SCONN288_DDR506112002KQ-SCONN288_DDR506112002KQ,SMA   I236 @T6G_MB_LIB.T6G(SCH_1):PAGE102

M_F_CPU1_SA_DQS_DN<1> @T6G_MB_LIB.T6G(SCH_1):M_F_CPU1_SA_DQS_DN(1)
   U26  P67 MFA_DQS_L1 GENOA_SP5-SOCKET6096_13568-001,SMLF,IO,DGA^6000030   I159 @T6G_MB_LIB.T6G(SCH_1):PAGE42
   J33   23 DQS1_A_C SCONN288_DDR506112002KQ-SCONN288_DDR506112002KQ,SMA   I236 @T6G_MB_LIB.T6G(SCH_1):PAGE102

M_F_CPU1_SA_DQS_DN<2> @T6G_MB_LIB.T6G(SCH_1):M_F_CPU1_SA_DQS_DN(2)
   U26  Y67 MFA_DQS_L2 GENOA_SP5-SOCKET6096_13568-001,SMLF,IO,DGA^6000030   I159 @T6G_MB_LIB.T6G(SCH_1):PAGE42
   J33   34 DQS2_A_C SCONN288_DDR506112002KQ-SCONN288_DDR506112002KQ,SMA   I236 @T6G_MB_LIB.T6G(SCH_1):PAGE102

M_F_CPU1_SA_DQS_DN<3> @T6G_MB_LIB.T6G(SCH_1):M_F_CPU1_SA_DQS_DN(3)
   U26 AF67 MFA_DQS_L3 GENOA_SP5-SOCKET6096_13568-001,SMLF,IO,DGA^6000030   I159 @T6G_MB_LIB.T6G(SCH_1):PAGE42
   J33   45 DQS3_A_C SCONN288_DDR506112002KQ-SCONN288_DDR506112002KQ,SMA   I236 @T6G_MB_LIB.T6G(SCH_1):PAGE102

M_F_CPU1_SA_DQS_DN<4> @T6G_MB_LIB.T6G(SCH_1):M_F_CPU1_SA_DQS_DN(4)
   U26 AM67 MFA_DQS_L4 GENOA_SP5-SOCKET6096_13568-001,SMLF,IO,DGA^6000030   I159 @T6G_MB_LIB.T6G(SCH_1):PAGE42
   J33   56 DQS4_A_C SCONN288_DDR506112002KQ-SCONN288_DDR506112002KQ,SMA   I236 @T6G_MB_LIB.T6G(SCH_1):PAGE102

M_F_CPU1_SA_DQS_DN<5> @T6G_MB_LIB.T6G(SCH_1):M_F_CPU1_SA_DQS_DN(5)
   U26  H65 MFA_DQS_L5 GENOA_SP5-SOCKET6096_13568-001,SMLF,IO,DGA^6000030   I159 @T6G_MB_LIB.T6G(SCH_1):PAGE42
   J33  156 DQS5_A_C||TDQS5_A_C||DQS5_A_T||TDQS5_A_T SCONN288_DDR506112002KQ-SCONN288_DDR506112002KQ,SMA   I236 @T6G_MB_LIB.T6G(SCH_1):PAGE102

M_F_CPU1_SA_DQS_DN<6> @T6G_MB_LIB.T6G(SCH_1):M_F_CPU1_SA_DQS_DN(6)
   U26  P65 MFA_DQS_L6 GENOA_SP5-SOCKET6096_13568-001,SMLF,IO,DGA^6000030   I159 @T6G_MB_LIB.T6G(SCH_1):PAGE42
   J33  167 DQS6_A_C||TDQS6_A_C||DQS6_A_T||TDQS6_A_T SCONN288_DDR506112002KQ-SCONN288_DDR506112002KQ,SMA   I236 @T6G_MB_LIB.T6G(SCH_1):PAGE102

M_F_CPU1_SA_DQS_DN<7> @T6G_MB_LIB.T6G(SCH_1):M_F_CPU1_SA_DQS_DN(7)
   U26  Y65 MFA_DQS_L7 GENOA_SP5-SOCKET6096_13568-001,SMLF,IO,DGA^6000030   I159 @T6G_MB_LIB.T6G(SCH_1):PAGE42
   J33  178 DQS7_A_C||TDQS7_A_C SCONN288_DDR506112002KQ-SCONN288_DDR506112002KQ,SMA   I236 @T6G_MB_LIB.T6G(SCH_1):PAGE102

M_F_CPU1_SA_DQS_DN<8> @T6G_MB_LIB.T6G(SCH_1):M_F_CPU1_SA_DQS_DN(8)
   U26 AF65 MFA_DQS_L8 GENOA_SP5-SOCKET6096_13568-001,SMLF,IO,DGA^6000030   I159 @T6G_MB_LIB.T6G(SCH_1):PAGE42
   J33  189 DQS8_A_C||TDQS8_A_C SCONN288_DDR506112002KQ-SCONN288_DDR506112002KQ,SMA   I236 @T6G_MB_LIB.T6G(SCH_1):PAGE102

M_F_CPU1_SA_DQS_DN<9> @T6G_MB_LIB.T6G(SCH_1):M_F_CPU1_SA_DQS_DN(9)
   U26 AM65 MFA_DQS_L9 GENOA_SP5-SOCKET6096_13568-001,SMLF,IO,DGA^6000030   I159 @T6G_MB_LIB.T6G(SCH_1):PAGE42
   J33  200 DQS9_A_C||TDQS9_A_C SCONN288_DDR506112002KQ-SCONN288_DDR506112002KQ,SMA   I236 @T6G_MB_LIB.T6G(SCH_1):PAGE102

M_F_CPU1_SA_DQS_DP<0> @T6G_MB_LIB.T6G(SCH_1):M_F_CPU1_SA_DQS_DP(0)
   U26  G67 MFA_DQS_H0 GENOA_SP5-SOCKET6096_13568-001,SMLF,IO,DGA^6000030   I159 @T6G_MB_LIB.T6G(SCH_1):PAGE42
   J33   11 DQS0_A_T SCONN288_DDR506112002KQ-SCONN288_DDR506112002KQ,SMA   I236 @T6G_MB_LIB.T6G(SCH_1):PAGE102

M_F_CPU1_SA_DQS_DP<1> @T6G_MB_LIB.T6G(SCH_1):M_F_CPU1_SA_DQS_DP(1)
   U26  N67 MFA_DQS_H1 GENOA_SP5-SOCKET6096_13568-001,SMLF,IO,DGA^6000030   I159 @T6G_MB_LIB.T6G(SCH_1):PAGE42
   J33   22 DQS1_A_T SCONN288_DDR506112002KQ-SCONN288_DDR506112002KQ,SMA   I236 @T6G_MB_LIB.T6G(SCH_1):PAGE102

M_F_CPU1_SA_DQS_DP<2> @T6G_MB_LIB.T6G(SCH_1):M_F_CPU1_SA_DQS_DP(2)
   U26  W67 MFA_DQS_H2 GENOA_SP5-SOCKET6096_13568-001,SMLF,IO,DGA^6000030   I159 @T6G_MB_LIB.T6G(SCH_1):PAGE42
   J33   33 DQS2_A_T SCONN288_DDR506112002KQ-SCONN288_DDR506112002KQ,SMA   I236 @T6G_MB_LIB.T6G(SCH_1):PAGE102

M_F_CPU1_SA_DQS_DP<3> @T6G_MB_LIB.T6G(SCH_1):M_F_CPU1_SA_DQS_DP(3)
   U26 AE67 MFA_DQS_H3 GENOA_SP5-SOCKET6096_13568-001,SMLF,IO,DGA^6000030   I159 @T6G_MB_LIB.T6G(SCH_1):PAGE42
   J33   44 DQS3_A_T SCONN288_DDR506112002KQ-SCONN288_DDR506112002KQ,SMA   I236 @T6G_MB_LIB.T6G(SCH_1):PAGE102

M_F_CPU1_SA_DQS_DP<4> @T6G_MB_LIB.T6G(SCH_1):M_F_CPU1_SA_DQS_DP(4)
   U26 AL67 MFA_DQS_H4 GENOA_SP5-SOCKET6096_13568-001,SMLF,IO,DGA^6000030   I159 @T6G_MB_LIB.T6G(SCH_1):PAGE42
   J33   55 DQS4_A_T SCONN288_DDR506112002KQ-SCONN288_DDR506112002KQ,SMA   I236 @T6G_MB_LIB.T6G(SCH_1):PAGE102

M_F_CPU1_SA_DQS_DP<5> @T6G_MB_LIB.T6G(SCH_1):M_F_CPU1_SA_DQS_DP(5)
   U26  J66 MFA_DQS_H5 GENOA_SP5-SOCKET6096_13568-001,SMLF,IO,DGA^6000030   I159 @T6G_MB_LIB.T6G(SCH_1):PAGE42
   J33  157 DQS5_A_T||TDQS5_A_T SCONN288_DDR506112002KQ-SCONN288_DDR506112002KQ,SMA   I236 @T6G_MB_LIB.T6G(SCH_1):PAGE102

M_F_CPU1_SA_DQS_DP<6> @T6G_MB_LIB.T6G(SCH_1):M_F_CPU1_SA_DQS_DP(6)
   U26  R66 MFA_DQS_H6 GENOA_SP5-SOCKET6096_13568-001,SMLF,IO,DGA^6000030   I159 @T6G_MB_LIB.T6G(SCH_1):PAGE42
   J33  168 DQS6_A_T||TDQS6_A_T SCONN288_DDR506112002KQ-SCONN288_DDR506112002KQ,SMA   I236 @T6G_MB_LIB.T6G(SCH_1):PAGE102

M_F_CPU1_SA_DQS_DP<7> @T6G_MB_LIB.T6G(SCH_1):M_F_CPU1_SA_DQS_DP(7)
   U26 AA66 MFA_DQS_H7 GENOA_SP5-SOCKET6096_13568-001,SMLF,IO,DGA^6000030   I159 @T6G_MB_LIB.T6G(SCH_1):PAGE42
   J33  179 DQS7_A_T||TDQS7_A_T SCONN288_DDR506112002KQ-SCONN288_DDR506112002KQ,SMA   I236 @T6G_MB_LIB.T6G(SCH_1):PAGE102

M_F_CPU1_SA_DQS_DP<8> @T6G_MB_LIB.T6G(SCH_1):M_F_CPU1_SA_DQS_DP(8)
   U26 AG66 MFA_DQS_H8 GENOA_SP5-SOCKET6096_13568-001,SMLF,IO,DGA^6000030   I159 @T6G_MB_LIB.T6G(SCH_1):PAGE42
   J33  190 DQS8_A_T||TDQS8_A_T SCONN288_DDR506112002KQ-SCONN288_DDR506112002KQ,SMA   I236 @T6G_MB_LIB.T6G(SCH_1):PAGE102

M_F_CPU1_SA_DQS_DP<9> @T6G_MB_LIB.T6G(SCH_1):M_F_CPU1_SA_DQS_DP(9)
   U26 AN66 MFA_DQS_H9 GENOA_SP5-SOCKET6096_13568-001,SMLF,IO,DGA^6000030   I159 @T6G_MB_LIB.T6G(SCH_1):PAGE42
   J33  201 DQS9_A_T||TDQS9_A_T SCONN288_DDR506112002KQ-SCONN288_DDR506112002KQ,SMA   I236 @T6G_MB_LIB.T6G(SCH_1):PAGE102

M_F_CPU1_SA_PAR @T6G_MB_LIB.T6G(SCH_1):M_F_CPU1_SA_PAR
   U26 BC66 MFA_PAR GENOA_SP5-SOCKET6096_13568-001,SMLF,IO,DGA^6000030   I159 @T6G_MB_LIB.T6G(SCH_1):PAGE42
   J33   74  PAR_A SCONN288_DDR506112002KQ-SCONN288_DDR506112002KQ,SMA    I22 @T6G_MB_LIB.T6G(SCH_1):PAGE102

M_F_CPU1_SA_RSP<0> @T6G_MB_LIB.T6G(SCH_1):M_F_CPU1_SA_RSP(0)
   U26 BN66 MFA0_RSP_L GENOA_SP5-SOCKET6096_13568-001,SMLF,IO,DGA^6000030   I159 @T6G_MB_LIB.T6G(SCH_1):PAGE42
   J33   86 LBD||RSP_A_N SCONN288_DDR506112002KQ-SCONN288_DDR506112002KQ,SMA    I22 @T6G_MB_LIB.T6G(SCH_1):PAGE102

M_F_CPU1_SB_CA<0> @T6G_MB_LIB.T6G(SCH_1):M_F_CPU1_SB_CA(0)
   U26 BG66 MFB_CA0 GENOA_SP5-SOCKET6096_13568-001,SMLF,IO,DGA^6000030   I159 @T6G_MB_LIB.T6G(SCH_1):PAGE42
   J33   76  CA0_B SCONN288_DDR506112002KQ-SCONN288_DDR506112002KQ,SMA    I22 @T6G_MB_LIB.T6G(SCH_1):PAGE102

M_F_CPU1_SB_CA<1> @T6G_MB_LIB.T6G(SCH_1):M_F_CPU1_SB_CA(1)
   U26 BH65 MFB_CA1 GENOA_SP5-SOCKET6096_13568-001,SMLF,IO,DGA^6000030   I159 @T6G_MB_LIB.T6G(SCH_1):PAGE42
   J33  221  CA1_B SCONN288_DDR506112002KQ-SCONN288_DDR506112002KQ,SMA    I22 @T6G_MB_LIB.T6G(SCH_1):PAGE102

M_F_CPU1_SB_CA<2> @T6G_MB_LIB.T6G(SCH_1):M_F_CPU1_SB_CA(2)
   U26 BH67 MFB_CA2 GENOA_SP5-SOCKET6096_13568-001,SMLF,IO,DGA^6000030   I159 @T6G_MB_LIB.T6G(SCH_1):PAGE42
   J33   78  CA2_B SCONN288_DDR506112002KQ-SCONN288_DDR506112002KQ,SMA    I22 @T6G_MB_LIB.T6G(SCH_1):PAGE102

M_F_CPU1_SB_CA<3> @T6G_MB_LIB.T6G(SCH_1):M_F_CPU1_SB_CA(3)
   U26 BJ67 MFB_CA3 GENOA_SP5-SOCKET6096_13568-001,SMLF,IO,DGA^6000030   I159 @T6G_MB_LIB.T6G(SCH_1):PAGE42
   J33  223  CA3_B SCONN288_DDR506112002KQ-SCONN288_DDR506112002KQ,SMA    I22 @T6G_MB_LIB.T6G(SCH_1):PAGE102

M_F_CPU1_SB_CA<4> @T6G_MB_LIB.T6G(SCH_1):M_F_CPU1_SB_CA(4)
   U26 BJ66 MFB_CA4 GENOA_SP5-SOCKET6096_13568-001,SMLF,IO,DGA^6000030   I159 @T6G_MB_LIB.T6G(SCH_1):PAGE42
   J33   80  CA4_B SCONN288_DDR506112002KQ-SCONN288_DDR506112002KQ,SMA    I22 @T6G_MB_LIB.T6G(SCH_1):PAGE102

M_F_CPU1_SB_CA<5> @T6G_MB_LIB.T6G(SCH_1):M_F_CPU1_SB_CA(5)
   U26 BK65 MFB_CA5 GENOA_SP5-SOCKET6096_13568-001,SMLF,IO,DGA^6000030   I159 @T6G_MB_LIB.T6G(SCH_1):PAGE42
   J33  225  CA5_B SCONN288_DDR506112002KQ-SCONN288_DDR506112002KQ,SMA    I22 @T6G_MB_LIB.T6G(SCH_1):PAGE102

M_F_CPU1_SB_CA<6> @T6G_MB_LIB.T6G(SCH_1):M_F_CPU1_SB_CA(6)
   U26 BK67 MFB_CA6 GENOA_SP5-SOCKET6096_13568-001,SMLF,IO,DGA^6000030   I159 @T6G_MB_LIB.T6G(SCH_1):PAGE42
   J33   82  CA6_B SCONN288_DDR506112002KQ-SCONN288_DDR506112002KQ,SMA    I22 @T6G_MB_LIB.T6G(SCH_1):PAGE102

M_F_CPU1_SB_CB<0> @T6G_MB_LIB.T6G(SCH_1):M_F_CPU1_SB_CB(0)
   U26 BY67 MFB_CHECK0 GENOA_SP5-SOCKET6096_13568-001,SMLF,IO,DGA^6000030   I159 @T6G_MB_LIB.T6G(SCH_1):PAGE42
   J33   96  CB0_B SCONN288_DDR506112002KQ-SCONN288_DDR506112002KQ,SMA    I22 @T6G_MB_LIB.T6G(SCH_1):PAGE102

M_F_CPU1_SB_CB<1> @T6G_MB_LIB.T6G(SCH_1):M_F_CPU1_SB_CB(1)
   U26 CA66 MFB_CHECK1 GENOA_SP5-SOCKET6096_13568-001,SMLF,IO,DGA^6000030   I159 @T6G_MB_LIB.T6G(SCH_1):PAGE42
   J33   98  CB1_B SCONN288_DDR506112002KQ-SCONN288_DDR506112002KQ,SMA    I22 @T6G_MB_LIB.T6G(SCH_1):PAGE102

M_F_CPU1_SB_CB<2> @T6G_MB_LIB.T6G(SCH_1):M_F_CPU1_SB_CB(2)
   U26 CA67 MFB_CHECK2 GENOA_SP5-SOCKET6096_13568-001,SMLF,IO,DGA^6000030   I159 @T6G_MB_LIB.T6G(SCH_1):PAGE42
   J33  241  CB2_B SCONN288_DDR506112002KQ-SCONN288_DDR506112002KQ,SMA    I22 @T6G_MB_LIB.T6G(SCH_1):PAGE102

M_F_CPU1_SB_CB<3> @T6G_MB_LIB.T6G(SCH_1):M_F_CPU1_SB_CB(3)
   U26 CB65 MFB_CHECK3 GENOA_SP5-SOCKET6096_13568-001,SMLF,IO,DGA^6000030   I159 @T6G_MB_LIB.T6G(SCH_1):PAGE42
   J33  243  CB3_B SCONN288_DDR506112002KQ-SCONN288_DDR506112002KQ,SMA    I22 @T6G_MB_LIB.T6G(SCH_1):PAGE102

M_F_CPU1_SB_CB<4> @T6G_MB_LIB.T6G(SCH_1):M_F_CPU1_SB_CB(4)
   U26 BT67 MFB_CHECK4 GENOA_SP5-SOCKET6096_13568-001,SMLF,IO,DGA^6000030   I159 @T6G_MB_LIB.T6G(SCH_1):PAGE42
   J33   89  CB4_B SCONN288_DDR506112002KQ-SCONN288_DDR506112002KQ,SMA    I22 @T6G_MB_LIB.T6G(SCH_1):PAGE102

M_F_CPU1_SB_CB<5> @T6G_MB_LIB.T6G(SCH_1):M_F_CPU1_SB_CB(5)
   U26 BU66 MFB_CHECK5 GENOA_SP5-SOCKET6096_13568-001,SMLF,IO,DGA^6000030   I159 @T6G_MB_LIB.T6G(SCH_1):PAGE42
   J33   91  CB5_B SCONN288_DDR506112002KQ-SCONN288_DDR506112002KQ,SMA    I22 @T6G_MB_LIB.T6G(SCH_1):PAGE102

M_F_CPU1_SB_CB<6> @T6G_MB_LIB.T6G(SCH_1):M_F_CPU1_SB_CB(6)
   U26 BU67 MFB_CHECK6 GENOA_SP5-SOCKET6096_13568-001,SMLF,IO,DGA^6000030   I159 @T6G_MB_LIB.T6G(SCH_1):PAGE42
   J33  234  CB6_B SCONN288_DDR506112002KQ-SCONN288_DDR506112002KQ,SMA    I22 @T6G_MB_LIB.T6G(SCH_1):PAGE102

M_F_CPU1_SB_CB<7> @T6G_MB_LIB.T6G(SCH_1):M_F_CPU1_SB_CB(7)
   U26 BV65 MFB_CHECK7 GENOA_SP5-SOCKET6096_13568-001,SMLF,IO,DGA^6000030   I159 @T6G_MB_LIB.T6G(SCH_1):PAGE42
   J33  236  CB7_B SCONN288_DDR506112002KQ-SCONN288_DDR506112002KQ,SMA    I22 @T6G_MB_LIB.T6G(SCH_1):PAGE102

M_F_CPU1_SB_CS_N<0> @T6G_MB_LIB.T6G(SCH_1):M_F_CPU1_SB_CS_N(0)
   U26 BM65 MFB0_CS_L0 GENOA_SP5-SOCKET6096_13568-001,SMLF,IO,DGA^6000030   I159 @T6G_MB_LIB.T6G(SCH_1):PAGE42
   J33   84 CS0_B_N SCONN288_DDR506112002KQ-SCONN288_DDR506112002KQ,SMA    I22 @T6G_MB_LIB.T6G(SCH_1):PAGE102

M_F_CPU1_SB_CS_N<1> @T6G_MB_LIB.T6G(SCH_1):M_F_CPU1_SB_CS_N(1)
   U26 BN67 MFB0_CS_L1 GENOA_SP5-SOCKET6096_13568-001,SMLF,IO,DGA^6000030   I159 @T6G_MB_LIB.T6G(SCH_1):PAGE42
   J33  229 CS1_B_N SCONN288_DDR506112002KQ-SCONN288_DDR506112002KQ,SMA    I22 @T6G_MB_LIB.T6G(SCH_1):PAGE102

M_F_CPU1_SB_DQ<0> @T6G_MB_LIB.T6G(SCH_1):M_F_CPU1_SB_DQ(0)
   U26 CB67 MFB_DATA0 GENOA_SP5-SOCKET6096_13568-001,SMLF,IO,DGA^6000030   I159 @T6G_MB_LIB.T6G(SCH_1):PAGE42
   J33  100  DQ0_B SCONN288_DDR506112002KQ-SCONN288_DDR506112002KQ,SMA    I22 @T6G_MB_LIB.T6G(SCH_1):PAGE102

M_F_CPU1_SB_DQ<10> @T6G_MB_LIB.T6G(SCH_1):M_F_CPU1_SB_DQ(10)
   U26 CJ67 MFB_DATA10 GENOA_SP5-SOCKET6096_13568-001,SMLF,IO,DGA^6000030   I159 @T6G_MB_LIB.T6G(SCH_1):PAGE42
   J33  256 DQ10_B SCONN288_DDR506112002KQ-SCONN288_DDR506112002KQ,SMA    I22 @T6G_MB_LIB.T6G(SCH_1):PAGE102

M_F_CPU1_SB_DQ<11> @T6G_MB_LIB.T6G(SCH_1):M_F_CPU1_SB_DQ(11)
   U26 CK65 MFB_DATA11 GENOA_SP5-SOCKET6096_13568-001,SMLF,IO,DGA^6000030   I159 @T6G_MB_LIB.T6G(SCH_1):PAGE42
   J33  258 DQ11_B SCONN288_DDR506112002KQ-SCONN288_DDR506112002KQ,SMA    I22 @T6G_MB_LIB.T6G(SCH_1):PAGE102

M_F_CPU1_SB_DQ<12> @T6G_MB_LIB.T6G(SCH_1):M_F_CPU1_SB_DQ(12)
   U26 CM67 MFB_DATA12 GENOA_SP5-SOCKET6096_13568-001,SMLF,IO,DGA^6000030   I159 @T6G_MB_LIB.T6G(SCH_1):PAGE42
   J33  118 DQ12_B SCONN288_DDR506112002KQ-SCONN288_DDR506112002KQ,SMA    I22 @T6G_MB_LIB.T6G(SCH_1):PAGE102

M_F_CPU1_SB_DQ<13> @T6G_MB_LIB.T6G(SCH_1):M_F_CPU1_SB_DQ(13)
   U26 CN66 MFB_DATA13 GENOA_SP5-SOCKET6096_13568-001,SMLF,IO,DGA^6000030   I159 @T6G_MB_LIB.T6G(SCH_1):PAGE42
   J33  120 DQ13_B SCONN288_DDR506112002KQ-SCONN288_DDR506112002KQ,SMA    I22 @T6G_MB_LIB.T6G(SCH_1):PAGE102

M_F_CPU1_SB_DQ<14> @T6G_MB_LIB.T6G(SCH_1):M_F_CPU1_SB_DQ(14)
   U26 CN67 MFB_DATA14 GENOA_SP5-SOCKET6096_13568-001,SMLF,IO,DGA^6000030   I159 @T6G_MB_LIB.T6G(SCH_1):PAGE42
   J33  263 DQ14_B SCONN288_DDR506112002KQ-SCONN288_DDR506112002KQ,SMA    I22 @T6G_MB_LIB.T6G(SCH_1):PAGE102

M_F_CPU1_SB_DQ<15> @T6G_MB_LIB.T6G(SCH_1):M_F_CPU1_SB_DQ(15)
   U26 CP65 MFB_DATA15 GENOA_SP5-SOCKET6096_13568-001,SMLF,IO,DGA^6000030   I159 @T6G_MB_LIB.T6G(SCH_1):PAGE42
   J33  265 DQ15_B SCONN288_DDR506112002KQ-SCONN288_DDR506112002KQ,SMA    I22 @T6G_MB_LIB.T6G(SCH_1):PAGE102

M_F_CPU1_SB_DQ<16> @T6G_MB_LIB.T6G(SCH_1):M_F_CPU1_SB_DQ(16)
   U26 CP67 MFB_DATA16 GENOA_SP5-SOCKET6096_13568-001,SMLF,IO,DGA^6000030   I159 @T6G_MB_LIB.T6G(SCH_1):PAGE42
   J33  122 DQ16_B SCONN288_DDR506112002KQ-SCONN288_DDR506112002KQ,SMA    I22 @T6G_MB_LIB.T6G(SCH_1):PAGE102

M_F_CPU1_SB_DQ<17> @T6G_MB_LIB.T6G(SCH_1):M_F_CPU1_SB_DQ(17)
   U26 CR66 MFB_DATA17 GENOA_SP5-SOCKET6096_13568-001,SMLF,IO,DGA^6000030   I159 @T6G_MB_LIB.T6G(SCH_1):PAGE42
   J33  124 DQ17_B SCONN288_DDR506112002KQ-SCONN288_DDR506112002KQ,SMA    I22 @T6G_MB_LIB.T6G(SCH_1):PAGE102

M_F_CPU1_SB_DQ<18> @T6G_MB_LIB.T6G(SCH_1):M_F_CPU1_SB_DQ(18)
   U26 CR67 MFB_DATA18 GENOA_SP5-SOCKET6096_13568-001,SMLF,IO,DGA^6000030   I159 @T6G_MB_LIB.T6G(SCH_1):PAGE42
   J33  267 DQ18_B SCONN288_DDR506112002KQ-SCONN288_DDR506112002KQ,SMA    I22 @T6G_MB_LIB.T6G(SCH_1):PAGE102

M_F_CPU1_SB_DQ<19> @T6G_MB_LIB.T6G(SCH_1):M_F_CPU1_SB_DQ(19)
   U26 CT65 MFB_DATA19 GENOA_SP5-SOCKET6096_13568-001,SMLF,IO,DGA^6000030   I159 @T6G_MB_LIB.T6G(SCH_1):PAGE42
   J33  269 DQ19_B SCONN288_DDR506112002KQ-SCONN288_DDR506112002KQ,SMA    I22 @T6G_MB_LIB.T6G(SCH_1):PAGE102

M_F_CPU1_SB_DQ<1> @T6G_MB_LIB.T6G(SCH_1):M_F_CPU1_SB_DQ(1)
   U26 CC66 MFB_DATA1 GENOA_SP5-SOCKET6096_13568-001,SMLF,IO,DGA^6000030   I159 @T6G_MB_LIB.T6G(SCH_1):PAGE42
   J33  102  DQ1_B SCONN288_DDR506112002KQ-SCONN288_DDR506112002KQ,SMA    I22 @T6G_MB_LIB.T6G(SCH_1):PAGE102

M_F_CPU1_SB_DQ<20> @T6G_MB_LIB.T6G(SCH_1):M_F_CPU1_SB_DQ(20)
   U26 CV67 MFB_DATA20 GENOA_SP5-SOCKET6096_13568-001,SMLF,IO,DGA^6000030   I159 @T6G_MB_LIB.T6G(SCH_1):PAGE42
   J33  129 DQ20_B SCONN288_DDR506112002KQ-SCONN288_DDR506112002KQ,SMA    I22 @T6G_MB_LIB.T6G(SCH_1):PAGE102

M_F_CPU1_SB_DQ<21> @T6G_MB_LIB.T6G(SCH_1):M_F_CPU1_SB_DQ(21)
   U26 CW66 MFB_DATA21 GENOA_SP5-SOCKET6096_13568-001,SMLF,IO,DGA^6000030   I159 @T6G_MB_LIB.T6G(SCH_1):PAGE42
   J33  131 DQ21_B SCONN288_DDR506112002KQ-SCONN288_DDR506112002KQ,SMA    I22 @T6G_MB_LIB.T6G(SCH_1):PAGE102

M_F_CPU1_SB_DQ<22> @T6G_MB_LIB.T6G(SCH_1):M_F_CPU1_SB_DQ(22)
   U26 CW67 MFB_DATA22 GENOA_SP5-SOCKET6096_13568-001,SMLF,IO,DGA^6000030   I159 @T6G_MB_LIB.T6G(SCH_1):PAGE42
   J33  274 DQ22_B SCONN288_DDR506112002KQ-SCONN288_DDR506112002KQ,SMA    I22 @T6G_MB_LIB.T6G(SCH_1):PAGE102

M_F_CPU1_SB_DQ<23> @T6G_MB_LIB.T6G(SCH_1):M_F_CPU1_SB_DQ(23)
   U26 CY65 MFB_DATA23 GENOA_SP5-SOCKET6096_13568-001,SMLF,IO,DGA^6000030   I159 @T6G_MB_LIB.T6G(SCH_1):PAGE42
   J33  276 DQ23_B SCONN288_DDR506112002KQ-SCONN288_DDR506112002KQ,SMA    I22 @T6G_MB_LIB.T6G(SCH_1):PAGE102

M_F_CPU1_SB_DQ<24> @T6G_MB_LIB.T6G(SCH_1):M_F_CPU1_SB_DQ(24)
   U26 CY67 MFB_DATA24 GENOA_SP5-SOCKET6096_13568-001,SMLF,IO,DGA^6000030   I159 @T6G_MB_LIB.T6G(SCH_1):PAGE42
   J33  133 DQ24_B SCONN288_DDR506112002KQ-SCONN288_DDR506112002KQ,SMA    I22 @T6G_MB_LIB.T6G(SCH_1):PAGE102

M_F_CPU1_SB_DQ<25> @T6G_MB_LIB.T6G(SCH_1):M_F_CPU1_SB_DQ(25)
   U26 DA66 MFB_DATA25 GENOA_SP5-SOCKET6096_13568-001,SMLF,IO,DGA^6000030   I159 @T6G_MB_LIB.T6G(SCH_1):PAGE42
   J33  135 DQ25_B SCONN288_DDR506112002KQ-SCONN288_DDR506112002KQ,SMA    I22 @T6G_MB_LIB.T6G(SCH_1):PAGE102

M_F_CPU1_SB_DQ<26> @T6G_MB_LIB.T6G(SCH_1):M_F_CPU1_SB_DQ(26)
   U26 DA67 MFB_DATA26 GENOA_SP5-SOCKET6096_13568-001,SMLF,IO,DGA^6000030   I159 @T6G_MB_LIB.T6G(SCH_1):PAGE42
   J33  278 DQ26_B SCONN288_DDR506112002KQ-SCONN288_DDR506112002KQ,SMA    I22 @T6G_MB_LIB.T6G(SCH_1):PAGE102

M_F_CPU1_SB_DQ<27> @T6G_MB_LIB.T6G(SCH_1):M_F_CPU1_SB_DQ(27)
   U26 DB65 MFB_DATA27 GENOA_SP5-SOCKET6096_13568-001,SMLF,IO,DGA^6000030   I159 @T6G_MB_LIB.T6G(SCH_1):PAGE42
   J33  280 DQ27_B SCONN288_DDR506112002KQ-SCONN288_DDR506112002KQ,SMA    I22 @T6G_MB_LIB.T6G(SCH_1):PAGE102

M_F_CPU1_SB_DQ<28> @T6G_MB_LIB.T6G(SCH_1):M_F_CPU1_SB_DQ(28)
   U26 DD67 MFB_DATA28 GENOA_SP5-SOCKET6096_13568-001,SMLF,IO,DGA^6000030   I159 @T6G_MB_LIB.T6G(SCH_1):PAGE42
   J33  140 DQ28_B SCONN288_DDR506112002KQ-SCONN288_DDR506112002KQ,SMA    I22 @T6G_MB_LIB.T6G(SCH_1):PAGE102

M_F_CPU1_SB_DQ<29> @T6G_MB_LIB.T6G(SCH_1):M_F_CPU1_SB_DQ(29)
   U26 DE66 MFB_DATA29 GENOA_SP5-SOCKET6096_13568-001,SMLF,IO,DGA^6000030   I159 @T6G_MB_LIB.T6G(SCH_1):PAGE42
   J33  142 DQ29_B SCONN288_DDR506112002KQ-SCONN288_DDR506112002KQ,SMA    I22 @T6G_MB_LIB.T6G(SCH_1):PAGE102

M_F_CPU1_SB_DQ<2> @T6G_MB_LIB.T6G(SCH_1):M_F_CPU1_SB_DQ(2)
   U26 CC67 MFB_DATA2 GENOA_SP5-SOCKET6096_13568-001,SMLF,IO,DGA^6000030   I159 @T6G_MB_LIB.T6G(SCH_1):PAGE42
   J33  245  DQ2_B SCONN288_DDR506112002KQ-SCONN288_DDR506112002KQ,SMA    I22 @T6G_MB_LIB.T6G(SCH_1):PAGE102

M_F_CPU1_SB_DQ<30> @T6G_MB_LIB.T6G(SCH_1):M_F_CPU1_SB_DQ(30)
   U26 DE67 MFB_DATA30 GENOA_SP5-SOCKET6096_13568-001,SMLF,IO,DGA^6000030   I159 @T6G_MB_LIB.T6G(SCH_1):PAGE42
   J33  285 DQ30_B SCONN288_DDR506112002KQ-SCONN288_DDR506112002KQ,SMA    I22 @T6G_MB_LIB.T6G(SCH_1):PAGE102

M_F_CPU1_SB_DQ<31> @T6G_MB_LIB.T6G(SCH_1):M_F_CPU1_SB_DQ(31)
   U26 DF67 MFB_DATA31 GENOA_SP5-SOCKET6096_13568-001,SMLF,IO,DGA^6000030   I159 @T6G_MB_LIB.T6G(SCH_1):PAGE42
   J33  287 DQ31_B SCONN288_DDR506112002KQ-SCONN288_DDR506112002KQ,SMA    I22 @T6G_MB_LIB.T6G(SCH_1):PAGE102

M_F_CPU1_SB_DQ<3> @T6G_MB_LIB.T6G(SCH_1):M_F_CPU1_SB_DQ(3)
   U26 CD65 MFB_DATA3 GENOA_SP5-SOCKET6096_13568-001,SMLF,IO,DGA^6000030   I159 @T6G_MB_LIB.T6G(SCH_1):PAGE42
   J33  247  DQ3_B SCONN288_DDR506112002KQ-SCONN288_DDR506112002KQ,SMA    I22 @T6G_MB_LIB.T6G(SCH_1):PAGE102

M_F_CPU1_SB_DQ<4> @T6G_MB_LIB.T6G(SCH_1):M_F_CPU1_SB_DQ(4)
   U26 CF67 MFB_DATA4 GENOA_SP5-SOCKET6096_13568-001,SMLF,IO,DGA^6000030   I159 @T6G_MB_LIB.T6G(SCH_1):PAGE42
   J33  107  DQ4_B SCONN288_DDR506112002KQ-SCONN288_DDR506112002KQ,SMA    I22 @T6G_MB_LIB.T6G(SCH_1):PAGE102

M_F_CPU1_SB_DQ<5> @T6G_MB_LIB.T6G(SCH_1):M_F_CPU1_SB_DQ(5)
   U26 CG66 MFB_DATA5 GENOA_SP5-SOCKET6096_13568-001,SMLF,IO,DGA^6000030   I159 @T6G_MB_LIB.T6G(SCH_1):PAGE42
   J33  109  DQ5_B SCONN288_DDR506112002KQ-SCONN288_DDR506112002KQ,SMA    I22 @T6G_MB_LIB.T6G(SCH_1):PAGE102

M_F_CPU1_SB_DQ<6> @T6G_MB_LIB.T6G(SCH_1):M_F_CPU1_SB_DQ(6)
   U26 CG67 MFB_DATA6 GENOA_SP5-SOCKET6096_13568-001,SMLF,IO,DGA^6000030   I159 @T6G_MB_LIB.T6G(SCH_1):PAGE42
   J33  252  DQ6_B SCONN288_DDR506112002KQ-SCONN288_DDR506112002KQ,SMA    I22 @T6G_MB_LIB.T6G(SCH_1):PAGE102

M_F_CPU1_SB_DQ<7> @T6G_MB_LIB.T6G(SCH_1):M_F_CPU1_SB_DQ(7)
   U26 CH65 MFB_DATA7 GENOA_SP5-SOCKET6096_13568-001,SMLF,IO,DGA^6000030   I159 @T6G_MB_LIB.T6G(SCH_1):PAGE42
   J33  254  DQ7_B SCONN288_DDR506112002KQ-SCONN288_DDR506112002KQ,SMA    I22 @T6G_MB_LIB.T6G(SCH_1):PAGE102

M_F_CPU1_SB_DQ<8> @T6G_MB_LIB.T6G(SCH_1):M_F_CPU1_SB_DQ(8)
   U26 CH67 MFB_DATA8 GENOA_SP5-SOCKET6096_13568-001,SMLF,IO,DGA^6000030   I159 @T6G_MB_LIB.T6G(SCH_1):PAGE42
   J33  111  DQ8_B SCONN288_DDR506112002KQ-SCONN288_DDR506112002KQ,SMA    I22 @T6G_MB_LIB.T6G(SCH_1):PAGE102

M_F_CPU1_SB_DQ<9> @T6G_MB_LIB.T6G(SCH_1):M_F_CPU1_SB_DQ(9)
   U26 CJ66 MFB_DATA9 GENOA_SP5-SOCKET6096_13568-001,SMLF,IO,DGA^6000030   I159 @T6G_MB_LIB.T6G(SCH_1):PAGE42
   J33  113  DQ9_B SCONN288_DDR506112002KQ-SCONN288_DDR506112002KQ,SMA    I22 @T6G_MB_LIB.T6G(SCH_1):PAGE102

M_F_CPU1_SB_DQS_DN<0> @T6G_MB_LIB.T6G(SCH_1):M_F_CPU1_SB_DQS_DN(0)
   U26 CE67 MFB_DQS_L0 GENOA_SP5-SOCKET6096_13568-001,SMLF,IO,DGA^6000030   I159 @T6G_MB_LIB.T6G(SCH_1):PAGE42
   J33  105 DQS0_B_C SCONN288_DDR506112002KQ-SCONN288_DDR506112002KQ,SMA   I236 @T6G_MB_LIB.T6G(SCH_1):PAGE102

M_F_CPU1_SB_DQS_DN<1> @T6G_MB_LIB.T6G(SCH_1):M_F_CPU1_SB_DQS_DN(1)
   U26 CL67 MFB_DQS_L1 GENOA_SP5-SOCKET6096_13568-001,SMLF,IO,DGA^6000030   I159 @T6G_MB_LIB.T6G(SCH_1):PAGE42
   J33  116 DQS1_B_C SCONN288_DDR506112002KQ-SCONN288_DDR506112002KQ,SMA   I236 @T6G_MB_LIB.T6G(SCH_1):PAGE102

M_F_CPU1_SB_DQS_DN<2> @T6G_MB_LIB.T6G(SCH_1):M_F_CPU1_SB_DQS_DN(2)
   U26 CU67 MFB_DQS_L2 GENOA_SP5-SOCKET6096_13568-001,SMLF,IO,DGA^6000030   I159 @T6G_MB_LIB.T6G(SCH_1):PAGE42
   J33  127 DQS2_B_C SCONN288_DDR506112002KQ-SCONN288_DDR506112002KQ,SMA   I236 @T6G_MB_LIB.T6G(SCH_1):PAGE102

M_F_CPU1_SB_DQS_DN<3> @T6G_MB_LIB.T6G(SCH_1):M_F_CPU1_SB_DQS_DN(3)
   U26 DC67 MFB_DQS_L3 GENOA_SP5-SOCKET6096_13568-001,SMLF,IO,DGA^6000030   I159 @T6G_MB_LIB.T6G(SCH_1):PAGE42
   J33  138 DQS3_B_C SCONN288_DDR506112002KQ-SCONN288_DDR506112002KQ,SMA   I236 @T6G_MB_LIB.T6G(SCH_1):PAGE102

M_F_CPU1_SB_DQS_DN<4> @T6G_MB_LIB.T6G(SCH_1):M_F_CPU1_SB_DQS_DN(4)
   U26 BW66 MFB_DQS_L4 GENOA_SP5-SOCKET6096_13568-001,SMLF,IO,DGA^6000030   I159 @T6G_MB_LIB.T6G(SCH_1):PAGE42
   J33  238 DQS4_B_C SCONN288_DDR506112002KQ-SCONN288_DDR506112002KQ,SMA   I236 @T6G_MB_LIB.T6G(SCH_1):PAGE102

M_F_CPU1_SB_DQS_DN<5> @T6G_MB_LIB.T6G(SCH_1):M_F_CPU1_SB_DQS_DN(5)
   U26 CE66 MFB_DQS_L5 GENOA_SP5-SOCKET6096_13568-001,SMLF,IO,DGA^6000030   I159 @T6G_MB_LIB.T6G(SCH_1):PAGE42
   J33  249 DQS5_B_C||TDQS5_B_C SCONN288_DDR506112002KQ-SCONN288_DDR506112002KQ,SMA   I236 @T6G_MB_LIB.T6G(SCH_1):PAGE102

M_F_CPU1_SB_DQS_DN<6> @T6G_MB_LIB.T6G(SCH_1):M_F_CPU1_SB_DQS_DN(6)
   U26 CL66 MFB_DQS_L6 GENOA_SP5-SOCKET6096_13568-001,SMLF,IO,DGA^6000030   I159 @T6G_MB_LIB.T6G(SCH_1):PAGE42
   J33  260 DQS6_B_C||TDQS6_B_C SCONN288_DDR506112002KQ-SCONN288_DDR506112002KQ,SMA   I236 @T6G_MB_LIB.T6G(SCH_1):PAGE102

M_F_CPU1_SB_DQS_DN<7> @T6G_MB_LIB.T6G(SCH_1):M_F_CPU1_SB_DQS_DN(7)
   U26 CU66 MFB_DQS_L7 GENOA_SP5-SOCKET6096_13568-001,SMLF,IO,DGA^6000030   I159 @T6G_MB_LIB.T6G(SCH_1):PAGE42
   J33  271 DQS7_B_C||TDQS7_B_C SCONN288_DDR506112002KQ-SCONN288_DDR506112002KQ,SMA   I236 @T6G_MB_LIB.T6G(SCH_1):PAGE102

M_F_CPU1_SB_DQS_DN<8> @T6G_MB_LIB.T6G(SCH_1):M_F_CPU1_SB_DQS_DN(8)
   U26 DC66 MFB_DQS_L8 GENOA_SP5-SOCKET6096_13568-001,SMLF,IO,DGA^6000030   I159 @T6G_MB_LIB.T6G(SCH_1):PAGE42
   J33  282 DQS8_B_C||TDQS8_B_C SCONN288_DDR506112002KQ-SCONN288_DDR506112002KQ,SMA   I236 @T6G_MB_LIB.T6G(SCH_1):PAGE102

M_F_CPU1_SB_DQS_DN<9> @T6G_MB_LIB.T6G(SCH_1):M_F_CPU1_SB_DQS_DN(9)
   U26 BW67 MFB_DQS_L9 GENOA_SP5-SOCKET6096_13568-001,SMLF,IO,DGA^6000030   I159 @T6G_MB_LIB.T6G(SCH_1):PAGE42
   J33   94 DQS9_B_C||TDQS9_B_C SCONN288_DDR506112002KQ-SCONN288_DDR506112002KQ,SMA   I236 @T6G_MB_LIB.T6G(SCH_1):PAGE102

M_F_CPU1_SB_DQS_DP<0> @T6G_MB_LIB.T6G(SCH_1):M_F_CPU1_SB_DQS_DP(0)
   U26 CD67 MFB_DQS_H0 GENOA_SP5-SOCKET6096_13568-001,SMLF,IO,DGA^6000030   I159 @T6G_MB_LIB.T6G(SCH_1):PAGE42
   J33  104 DQS0_B_T SCONN288_DDR506112002KQ-SCONN288_DDR506112002KQ,SMA   I236 @T6G_MB_LIB.T6G(SCH_1):PAGE102

M_F_CPU1_SB_DQS_DP<1> @T6G_MB_LIB.T6G(SCH_1):M_F_CPU1_SB_DQS_DP(1)
   U26 CK67 MFB_DQS_H1 GENOA_SP5-SOCKET6096_13568-001,SMLF,IO,DGA^6000030   I159 @T6G_MB_LIB.T6G(SCH_1):PAGE42
   J33  115 DQS1_B_T SCONN288_DDR506112002KQ-SCONN288_DDR506112002KQ,SMA   I236 @T6G_MB_LIB.T6G(SCH_1):PAGE102

M_F_CPU1_SB_DQS_DP<2> @T6G_MB_LIB.T6G(SCH_1):M_F_CPU1_SB_DQS_DP(2)
   U26 CT67 MFB_DQS_H2 GENOA_SP5-SOCKET6096_13568-001,SMLF,IO,DGA^6000030   I159 @T6G_MB_LIB.T6G(SCH_1):PAGE42
   J33  126 DQS2_B_T SCONN288_DDR506112002KQ-SCONN288_DDR506112002KQ,SMA   I236 @T6G_MB_LIB.T6G(SCH_1):PAGE102

M_F_CPU1_SB_DQS_DP<3> @T6G_MB_LIB.T6G(SCH_1):M_F_CPU1_SB_DQS_DP(3)
   U26 DB67 MFB_DQS_H3 GENOA_SP5-SOCKET6096_13568-001,SMLF,IO,DGA^6000030   I159 @T6G_MB_LIB.T6G(SCH_1):PAGE42
   J33  137 DQS3_B_T SCONN288_DDR506112002KQ-SCONN288_DDR506112002KQ,SMA   I236 @T6G_MB_LIB.T6G(SCH_1):PAGE102

M_F_CPU1_SB_DQS_DP<4> @T6G_MB_LIB.T6G(SCH_1):M_F_CPU1_SB_DQS_DP(4)
   U26 BY65 MFB_DQS_H4 GENOA_SP5-SOCKET6096_13568-001,SMLF,IO,DGA^6000030   I159 @T6G_MB_LIB.T6G(SCH_1):PAGE42
   J33  239 DQS4_B_T SCONN288_DDR506112002KQ-SCONN288_DDR506112002KQ,SMA   I236 @T6G_MB_LIB.T6G(SCH_1):PAGE102

M_F_CPU1_SB_DQS_DP<5> @T6G_MB_LIB.T6G(SCH_1):M_F_CPU1_SB_DQS_DP(5)
   U26 CF65 MFB_DQS_H5 GENOA_SP5-SOCKET6096_13568-001,SMLF,IO,DGA^6000030   I159 @T6G_MB_LIB.T6G(SCH_1):PAGE42
   J33  250 DQS5_B_T||TDQS5_B_T SCONN288_DDR506112002KQ-SCONN288_DDR506112002KQ,SMA   I236 @T6G_MB_LIB.T6G(SCH_1):PAGE102

M_F_CPU1_SB_DQS_DP<6> @T6G_MB_LIB.T6G(SCH_1):M_F_CPU1_SB_DQS_DP(6)
   U26 CM65 MFB_DQS_H6 GENOA_SP5-SOCKET6096_13568-001,SMLF,IO,DGA^6000030   I159 @T6G_MB_LIB.T6G(SCH_1):PAGE42
   J33  261 DQS6_B_T||TDQS6_B_T SCONN288_DDR506112002KQ-SCONN288_DDR506112002KQ,SMA   I236 @T6G_MB_LIB.T6G(SCH_1):PAGE102

M_F_CPU1_SB_DQS_DP<7> @T6G_MB_LIB.T6G(SCH_1):M_F_CPU1_SB_DQS_DP(7)
   U26 CV65 MFB_DQS_H7 GENOA_SP5-SOCKET6096_13568-001,SMLF,IO,DGA^6000030   I159 @T6G_MB_LIB.T6G(SCH_1):PAGE42
   J33  272 DQS7_B_T||TDQS7_B_T SCONN288_DDR506112002KQ-SCONN288_DDR506112002KQ,SMA   I236 @T6G_MB_LIB.T6G(SCH_1):PAGE102

M_F_CPU1_SB_DQS_DP<8> @T6G_MB_LIB.T6G(SCH_1):M_F_CPU1_SB_DQS_DP(8)
   U26 DD65 MFB_DQS_H8 GENOA_SP5-SOCKET6096_13568-001,SMLF,IO,DGA^6000030   I159 @T6G_MB_LIB.T6G(SCH_1):PAGE42
   J33  283 DQS8_B_T||TDQS8_B_T SCONN288_DDR506112002KQ-SCONN288_DDR506112002KQ,SMA   I236 @T6G_MB_LIB.T6G(SCH_1):PAGE102

M_F_CPU1_SB_DQS_DP<9> @T6G_MB_LIB.T6G(SCH_1):M_F_CPU1_SB_DQS_DP(9)
   U26 BV67 MFB_DQS_H9 GENOA_SP5-SOCKET6096_13568-001,SMLF,IO,DGA^6000030   I159 @T6G_MB_LIB.T6G(SCH_1):PAGE42
   J33   93 DQS9_B_T||TDQS9_B_T||DBI4_B_N SCONN288_DDR506112002KQ-SCONN288_DDR506112002KQ,SMA   I236 @T6G_MB_LIB.T6G(SCH_1):PAGE102

M_F_CPU1_SB_PAR @T6G_MB_LIB.T6G(SCH_1):M_F_CPU1_SB_PAR
   U26 BL67 MFB_PAR GENOA_SP5-SOCKET6096_13568-001,SMLF,IO,DGA^6000030   I159 @T6G_MB_LIB.T6G(SCH_1):PAGE42
   J33  227  PAR_B SCONN288_DDR506112002KQ-SCONN288_DDR506112002KQ,SMA    I22 @T6G_MB_LIB.T6G(SCH_1):PAGE102

M_F_CPU1_SB_RSP<0> @T6G_MB_LIB.T6G(SCH_1):M_F_CPU1_SB_RSP(0)
   U26 BP67 MFB0_RSP_L GENOA_SP5-SOCKET6096_13568-001,SMLF,IO,DGA^6000030   I159 @T6G_MB_LIB.T6G(SCH_1):PAGE42
   J33   87 LBS||RSP_B_N SCONN288_DDR506112002KQ-SCONN288_DDR506112002KQ,SMA    I22 @T6G_MB_LIB.T6G(SCH_1):PAGE102

M_G_CPU0_ALERT_N @T6G_MB_LIB.T6G(SCH_1):M_G_CPU0_ALERT_N
  R381    1      A Q_RES_0402LF-15,1%,1/16W,CHIP,CS01502FB03   I323 @T6G_MB_LIB.T6G(SCH_1):PAGE16
   J16   62 ALERT_N SCONN288_DDR506112002KQ-SCONN288_DDR506112002KQ,SMA    I22 @T6G_MB_LIB.T6G(SCH_1):PAGE91

M_G_CPU0_ALERT_R_N @T6G_MB_LIB.T6G(SCH_1):M_G_CPU0_ALERT_R_N
   U25  AR2 MG_ALERT_L GENOA_SP5-SOCKET6096_13568-001,SMLF,IO,DGA^6000030   I167 @T6G_MB_LIB.T6G(SCH_1):PAGE16
  R381    2      B Q_RES_0402LF-15,1%,1/16W,CHIP,CS01502FB03   I323 @T6G_MB_LIB.T6G(SCH_1):PAGE16

M_G_CPU0_CLK_DN<0> @T6G_MB_LIB.T6G(SCH_1):M_G_CPU0_CLK_DN(0)
   U25  BD2 MG0_CLK_L GENOA_SP5-SOCKET6096_13568-001,SMLF,IO,DGA^6000030   I167 @T6G_MB_LIB.T6G(SCH_1):PAGE16
   J16  218   CK_C SCONN288_DDR506112002KQ-SCONN288_DDR506112002KQ,SMA    I22 @T6G_MB_LIB.T6G(SCH_1):PAGE91

M_G_CPU0_CLK_DP<0> @T6G_MB_LIB.T6G(SCH_1):M_G_CPU0_CLK_DP(0)
   U25  BC2 MG0_CLK_H GENOA_SP5-SOCKET6096_13568-001,SMLF,IO,DGA^6000030   I167 @T6G_MB_LIB.T6G(SCH_1):PAGE16
   J16  217   CK_T SCONN288_DDR506112002KQ-SCONN288_DDR506112002KQ,SMA    I22 @T6G_MB_LIB.T6G(SCH_1):PAGE91

M_G_CPU0_RESET_N @T6G_MB_LIB.T6G(SCH_1):M_G_CPU0_RESET_N
   U25  AT2 MG_RESET_L GENOA_SP5-SOCKET6096_13568-001,SMLF,IO,DGA^6000030   I167 @T6G_MB_LIB.T6G(SCH_1):PAGE16
   J16  207 RESET_N SCONN288_DDR506112002KQ-SCONN288_DDR506112002KQ,SMA    I22 @T6G_MB_LIB.T6G(SCH_1):PAGE91

M_G_CPU0_SA_CA<0> @T6G_MB_LIB.T6G(SCH_1):M_G_CPU0_SA_CA(0)
   U25  AW2 MGA_CA0 GENOA_SP5-SOCKET6096_13568-001,SMLF,IO,DGA^6000030   I167 @T6G_MB_LIB.T6G(SCH_1):PAGE16
   J16   66  CA0_A SCONN288_DDR506112002KQ-SCONN288_DDR506112002KQ,SMA    I22 @T6G_MB_LIB.T6G(SCH_1):PAGE91

M_G_CPU0_SA_CA<1> @T6G_MB_LIB.T6G(SCH_1):M_G_CPU0_SA_CA(1)
   U25  AY2 MGA_CA1 GENOA_SP5-SOCKET6096_13568-001,SMLF,IO,DGA^6000030   I167 @T6G_MB_LIB.T6G(SCH_1):PAGE16
   J16  211  CA1_A SCONN288_DDR506112002KQ-SCONN288_DDR506112002KQ,SMA    I22 @T6G_MB_LIB.T6G(SCH_1):PAGE91

M_G_CPU0_SA_CA<2> @T6G_MB_LIB.T6G(SCH_1):M_G_CPU0_SA_CA(2)
   U25  AY4 MGA_CA2 GENOA_SP5-SOCKET6096_13568-001,SMLF,IO,DGA^6000030   I167 @T6G_MB_LIB.T6G(SCH_1):PAGE16
   J16   68  CA2_A SCONN288_DDR506112002KQ-SCONN288_DDR506112002KQ,SMA    I22 @T6G_MB_LIB.T6G(SCH_1):PAGE91

M_G_CPU0_SA_CA<3> @T6G_MB_LIB.T6G(SCH_1):M_G_CPU0_SA_CA(3)
   U25  BA3 MGA_CA3 GENOA_SP5-SOCKET6096_13568-001,SMLF,IO,DGA^6000030   I167 @T6G_MB_LIB.T6G(SCH_1):PAGE16
   J16  213  CA3_A SCONN288_DDR506112002KQ-SCONN288_DDR506112002KQ,SMA    I22 @T6G_MB_LIB.T6G(SCH_1):PAGE91

M_G_CPU0_SA_CA<4> @T6G_MB_LIB.T6G(SCH_1):M_G_CPU0_SA_CA(4)
   U25  BA2 MGA_CA4 GENOA_SP5-SOCKET6096_13568-001,SMLF,IO,DGA^6000030   I167 @T6G_MB_LIB.T6G(SCH_1):PAGE16
   J16   70  CA4_A SCONN288_DDR506112002KQ-SCONN288_DDR506112002KQ,SMA    I22 @T6G_MB_LIB.T6G(SCH_1):PAGE91

M_G_CPU0_SA_CA<5> @T6G_MB_LIB.T6G(SCH_1):M_G_CPU0_SA_CA(5)
   U25  BB2 MGA_CA5 GENOA_SP5-SOCKET6096_13568-001,SMLF,IO,DGA^6000030   I167 @T6G_MB_LIB.T6G(SCH_1):PAGE16
   J16  215  CA5_A SCONN288_DDR506112002KQ-SCONN288_DDR506112002KQ,SMA    I22 @T6G_MB_LIB.T6G(SCH_1):PAGE91

M_G_CPU0_SA_CA<6> @T6G_MB_LIB.T6G(SCH_1):M_G_CPU0_SA_CA(6)
   U25  BB4 MGA_CA6 GENOA_SP5-SOCKET6096_13568-001,SMLF,IO,DGA^6000030   I167 @T6G_MB_LIB.T6G(SCH_1):PAGE16
   J16   72  CA6_A SCONN288_DDR506112002KQ-SCONN288_DDR506112002KQ,SMA    I22 @T6G_MB_LIB.T6G(SCH_1):PAGE91

M_G_CPU0_SA_CB<0> @T6G_MB_LIB.T6G(SCH_1):M_G_CPU0_SA_CB(0)
   U25  AJ2 MGA_CHECK0 GENOA_SP5-SOCKET6096_13568-001,SMLF,IO,DGA^6000030   I167 @T6G_MB_LIB.T6G(SCH_1):PAGE16
   J16   51  CB0_A SCONN288_DDR506112002KQ-SCONN288_DDR506112002KQ,SMA    I22 @T6G_MB_LIB.T6G(SCH_1):PAGE91

M_G_CPU0_SA_CB<1> @T6G_MB_LIB.T6G(SCH_1):M_G_CPU0_SA_CB(1)
   U25  AK4 MGA_CHECK1 GENOA_SP5-SOCKET6096_13568-001,SMLF,IO,DGA^6000030   I167 @T6G_MB_LIB.T6G(SCH_1):PAGE16
   J16   53  CB1_A SCONN288_DDR506112002KQ-SCONN288_DDR506112002KQ,SMA    I22 @T6G_MB_LIB.T6G(SCH_1):PAGE91

M_G_CPU0_SA_CB<2> @T6G_MB_LIB.T6G(SCH_1):M_G_CPU0_SA_CB(2)
   U25  AK2 MGA_CHECK2 GENOA_SP5-SOCKET6096_13568-001,SMLF,IO,DGA^6000030   I167 @T6G_MB_LIB.T6G(SCH_1):PAGE16
   J16  196  CB2_A SCONN288_DDR506112002KQ-SCONN288_DDR506112002KQ,SMA    I22 @T6G_MB_LIB.T6G(SCH_1):PAGE91

M_G_CPU0_SA_CB<3> @T6G_MB_LIB.T6G(SCH_1):M_G_CPU0_SA_CB(3)
   U25  AL3 MGA_CHECK3 GENOA_SP5-SOCKET6096_13568-001,SMLF,IO,DGA^6000030   I167 @T6G_MB_LIB.T6G(SCH_1):PAGE16
   J16  198  CB3_A SCONN288_DDR506112002KQ-SCONN288_DDR506112002KQ,SMA    I22 @T6G_MB_LIB.T6G(SCH_1):PAGE91

M_G_CPU0_SA_CB<4> @T6G_MB_LIB.T6G(SCH_1):M_G_CPU0_SA_CB(4)
   U25  AN2 MGA_CHECK4 GENOA_SP5-SOCKET6096_13568-001,SMLF,IO,DGA^6000030   I167 @T6G_MB_LIB.T6G(SCH_1):PAGE16
   J16   58  CB4_A SCONN288_DDR506112002KQ-SCONN288_DDR506112002KQ,SMA    I22 @T6G_MB_LIB.T6G(SCH_1):PAGE91

M_G_CPU0_SA_CB<5> @T6G_MB_LIB.T6G(SCH_1):M_G_CPU0_SA_CB(5)
   U25  AP4 MGA_CHECK5 GENOA_SP5-SOCKET6096_13568-001,SMLF,IO,DGA^6000030   I167 @T6G_MB_LIB.T6G(SCH_1):PAGE16
   J16   60  CB5_A SCONN288_DDR506112002KQ-SCONN288_DDR506112002KQ,SMA    I22 @T6G_MB_LIB.T6G(SCH_1):PAGE91

M_G_CPU0_SA_CB<6> @T6G_MB_LIB.T6G(SCH_1):M_G_CPU0_SA_CB(6)
   U25  AP2 MGA_CHECK6 GENOA_SP5-SOCKET6096_13568-001,SMLF,IO,DGA^6000030   I167 @T6G_MB_LIB.T6G(SCH_1):PAGE16
   J16  203  CB6_A SCONN288_DDR506112002KQ-SCONN288_DDR506112002KQ,SMA    I22 @T6G_MB_LIB.T6G(SCH_1):PAGE91

M_G_CPU0_SA_CB<7> @T6G_MB_LIB.T6G(SCH_1):M_G_CPU0_SA_CB(7)
   U25  AR3 MGA_CHECK7 GENOA_SP5-SOCKET6096_13568-001,SMLF,IO,DGA^6000030   I167 @T6G_MB_LIB.T6G(SCH_1):PAGE16
   J16  205  CB7_A SCONN288_DDR506112002KQ-SCONN288_DDR506112002KQ,SMA    I22 @T6G_MB_LIB.T6G(SCH_1):PAGE91

M_G_CPU0_SA_CS_N<0> @T6G_MB_LIB.T6G(SCH_1):M_G_CPU0_SA_CS_N(0)
   U25  AU2 MGA0_CS_L0 GENOA_SP5-SOCKET6096_13568-001,SMLF,IO,DGA^6000030   I167 @T6G_MB_LIB.T6G(SCH_1):PAGE16
   J16   64 CS0_A_N SCONN288_DDR506112002KQ-SCONN288_DDR506112002KQ,SMA    I22 @T6G_MB_LIB.T6G(SCH_1):PAGE91

M_G_CPU0_SA_CS_N<1> @T6G_MB_LIB.T6G(SCH_1):M_G_CPU0_SA_CS_N(1)
   U25  AV4 MGA0_CS_L1 GENOA_SP5-SOCKET6096_13568-001,SMLF,IO,DGA^6000030   I167 @T6G_MB_LIB.T6G(SCH_1):PAGE16
   J16  209 CS1_A_N SCONN288_DDR506112002KQ-SCONN288_DDR506112002KQ,SMA    I22 @T6G_MB_LIB.T6G(SCH_1):PAGE91

M_G_CPU0_SA_DQ<0> @T6G_MB_LIB.T6G(SCH_1):M_G_CPU0_SA_DQ(0)
   U25   E2 MGA_DATA0 GENOA_SP5-SOCKET6096_13568-001,SMLF,IO,DGA^6000030   I167 @T6G_MB_LIB.T6G(SCH_1):PAGE16
   J16    7  DQ0_A SCONN288_DDR506112002KQ-SCONN288_DDR506112002KQ,SMA    I22 @T6G_MB_LIB.T6G(SCH_1):PAGE91

M_G_CPU0_SA_DQ<10> @T6G_MB_LIB.T6G(SCH_1):M_G_CPU0_SA_DQ(10)
   U25   M2 MGA_DATA10 GENOA_SP5-SOCKET6096_13568-001,SMLF,IO,DGA^6000030   I167 @T6G_MB_LIB.T6G(SCH_1):PAGE16
   J16  163 DQ10_A SCONN288_DDR506112002KQ-SCONN288_DDR506112002KQ,SMA    I22 @T6G_MB_LIB.T6G(SCH_1):PAGE91

M_G_CPU0_SA_DQ<11> @T6G_MB_LIB.T6G(SCH_1):M_G_CPU0_SA_DQ(11)
   U25   N3 MGA_DATA11 GENOA_SP5-SOCKET6096_13568-001,SMLF,IO,DGA^6000030   I167 @T6G_MB_LIB.T6G(SCH_1):PAGE16
   J16  165 DQ11_A SCONN288_DDR506112002KQ-SCONN288_DDR506112002KQ,SMA    I22 @T6G_MB_LIB.T6G(SCH_1):PAGE91

M_G_CPU0_SA_DQ<12> @T6G_MB_LIB.T6G(SCH_1):M_G_CPU0_SA_DQ(12)
   U25   R2 MGA_DATA12 GENOA_SP5-SOCKET6096_13568-001,SMLF,IO,DGA^6000030   I167 @T6G_MB_LIB.T6G(SCH_1):PAGE16
   J16   25 DQ12_A SCONN288_DDR506112002KQ-SCONN288_DDR506112002KQ,SMA    I22 @T6G_MB_LIB.T6G(SCH_1):PAGE91

M_G_CPU0_SA_DQ<13> @T6G_MB_LIB.T6G(SCH_1):M_G_CPU0_SA_DQ(13)
   U25   T4 MGA_DATA13 GENOA_SP5-SOCKET6096_13568-001,SMLF,IO,DGA^6000030   I167 @T6G_MB_LIB.T6G(SCH_1):PAGE16
   J16   27 DQ13_A SCONN288_DDR506112002KQ-SCONN288_DDR506112002KQ,SMA    I22 @T6G_MB_LIB.T6G(SCH_1):PAGE91

M_G_CPU0_SA_DQ<14> @T6G_MB_LIB.T6G(SCH_1):M_G_CPU0_SA_DQ(14)
   U25   T2 MGA_DATA14 GENOA_SP5-SOCKET6096_13568-001,SMLF,IO,DGA^6000030   I167 @T6G_MB_LIB.T6G(SCH_1):PAGE16
   J16  170 DQ14_A SCONN288_DDR506112002KQ-SCONN288_DDR506112002KQ,SMA    I22 @T6G_MB_LIB.T6G(SCH_1):PAGE91

M_G_CPU0_SA_DQ<15> @T6G_MB_LIB.T6G(SCH_1):M_G_CPU0_SA_DQ(15)
   U25   U3 MGA_DATA15 GENOA_SP5-SOCKET6096_13568-001,SMLF,IO,DGA^6000030   I167 @T6G_MB_LIB.T6G(SCH_1):PAGE16
   J16  172 DQ15_A SCONN288_DDR506112002KQ-SCONN288_DDR506112002KQ,SMA    I22 @T6G_MB_LIB.T6G(SCH_1):PAGE91

M_G_CPU0_SA_DQ<16> @T6G_MB_LIB.T6G(SCH_1):M_G_CPU0_SA_DQ(16)
   U25   U2 MGA_DATA16 GENOA_SP5-SOCKET6096_13568-001,SMLF,IO,DGA^6000030   I167 @T6G_MB_LIB.T6G(SCH_1):PAGE16
   J16   29 DQ16_A SCONN288_DDR506112002KQ-SCONN288_DDR506112002KQ,SMA    I22 @T6G_MB_LIB.T6G(SCH_1):PAGE91

M_G_CPU0_SA_DQ<17> @T6G_MB_LIB.T6G(SCH_1):M_G_CPU0_SA_DQ(17)
   U25   V4 MGA_DATA17 GENOA_SP5-SOCKET6096_13568-001,SMLF,IO,DGA^6000030   I167 @T6G_MB_LIB.T6G(SCH_1):PAGE16
   J16   31 DQ17_A SCONN288_DDR506112002KQ-SCONN288_DDR506112002KQ,SMA    I22 @T6G_MB_LIB.T6G(SCH_1):PAGE91

M_G_CPU0_SA_DQ<18> @T6G_MB_LIB.T6G(SCH_1):M_G_CPU0_SA_DQ(18)
   U25   V2 MGA_DATA18 GENOA_SP5-SOCKET6096_13568-001,SMLF,IO,DGA^6000030   I167 @T6G_MB_LIB.T6G(SCH_1):PAGE16
   J16  174 DQ18_A SCONN288_DDR506112002KQ-SCONN288_DDR506112002KQ,SMA    I22 @T6G_MB_LIB.T6G(SCH_1):PAGE91

M_G_CPU0_SA_DQ<19> @T6G_MB_LIB.T6G(SCH_1):M_G_CPU0_SA_DQ(19)
   U25   W3 MGA_DATA19 GENOA_SP5-SOCKET6096_13568-001,SMLF,IO,DGA^6000030   I167 @T6G_MB_LIB.T6G(SCH_1):PAGE16
   J16  176 DQ19_A SCONN288_DDR506112002KQ-SCONN288_DDR506112002KQ,SMA    I22 @T6G_MB_LIB.T6G(SCH_1):PAGE91

M_G_CPU0_SA_DQ<1> @T6G_MB_LIB.T6G(SCH_1):M_G_CPU0_SA_DQ(1)
   U25   F4 MGA_DATA1 GENOA_SP5-SOCKET6096_13568-001,SMLF,IO,DGA^6000030   I167 @T6G_MB_LIB.T6G(SCH_1):PAGE16
   J16    9  DQ1_A SCONN288_DDR506112002KQ-SCONN288_DDR506112002KQ,SMA    I22 @T6G_MB_LIB.T6G(SCH_1):PAGE91

M_G_CPU0_SA_DQ<20> @T6G_MB_LIB.T6G(SCH_1):M_G_CPU0_SA_DQ(20)
   U25  AA2 MGA_DATA20 GENOA_SP5-SOCKET6096_13568-001,SMLF,IO,DGA^6000030   I167 @T6G_MB_LIB.T6G(SCH_1):PAGE16
   J16   36 DQ20_A SCONN288_DDR506112002KQ-SCONN288_DDR506112002KQ,SMA    I22 @T6G_MB_LIB.T6G(SCH_1):PAGE91

M_G_CPU0_SA_DQ<21> @T6G_MB_LIB.T6G(SCH_1):M_G_CPU0_SA_DQ(21)
   U25  AB4 MGA_DATA21 GENOA_SP5-SOCKET6096_13568-001,SMLF,IO,DGA^6000030   I167 @T6G_MB_LIB.T6G(SCH_1):PAGE16
   J16   38 DQ21_A SCONN288_DDR506112002KQ-SCONN288_DDR506112002KQ,SMA    I22 @T6G_MB_LIB.T6G(SCH_1):PAGE91

M_G_CPU0_SA_DQ<22> @T6G_MB_LIB.T6G(SCH_1):M_G_CPU0_SA_DQ(22)
   U25  AB2 MGA_DATA22 GENOA_SP5-SOCKET6096_13568-001,SMLF,IO,DGA^6000030   I167 @T6G_MB_LIB.T6G(SCH_1):PAGE16
   J16  181 DQ22_A SCONN288_DDR506112002KQ-SCONN288_DDR506112002KQ,SMA    I22 @T6G_MB_LIB.T6G(SCH_1):PAGE91

M_G_CPU0_SA_DQ<23> @T6G_MB_LIB.T6G(SCH_1):M_G_CPU0_SA_DQ(23)
   U25  AC3 MGA_DATA23 GENOA_SP5-SOCKET6096_13568-001,SMLF,IO,DGA^6000030   I167 @T6G_MB_LIB.T6G(SCH_1):PAGE16
   J16  183 DQ23_A SCONN288_DDR506112002KQ-SCONN288_DDR506112002KQ,SMA    I22 @T6G_MB_LIB.T6G(SCH_1):PAGE91

M_G_CPU0_SA_DQ<24> @T6G_MB_LIB.T6G(SCH_1):M_G_CPU0_SA_DQ(24)
   U25  AC2 MGA_DATA24 GENOA_SP5-SOCKET6096_13568-001,SMLF,IO,DGA^6000030   I167 @T6G_MB_LIB.T6G(SCH_1):PAGE16
   J16   40 DQ24_A SCONN288_DDR506112002KQ-SCONN288_DDR506112002KQ,SMA    I22 @T6G_MB_LIB.T6G(SCH_1):PAGE91

M_G_CPU0_SA_DQ<25> @T6G_MB_LIB.T6G(SCH_1):M_G_CPU0_SA_DQ(25)
   U25  AD4 MGA_DATA25 GENOA_SP5-SOCKET6096_13568-001,SMLF,IO,DGA^6000030   I167 @T6G_MB_LIB.T6G(SCH_1):PAGE16
   J16   42 DQ25_A SCONN288_DDR506112002KQ-SCONN288_DDR506112002KQ,SMA    I22 @T6G_MB_LIB.T6G(SCH_1):PAGE91

M_G_CPU0_SA_DQ<26> @T6G_MB_LIB.T6G(SCH_1):M_G_CPU0_SA_DQ(26)
   U25  AD2 MGA_DATA26 GENOA_SP5-SOCKET6096_13568-001,SMLF,IO,DGA^6000030   I167 @T6G_MB_LIB.T6G(SCH_1):PAGE16
   J16  185 DQ26_A SCONN288_DDR506112002KQ-SCONN288_DDR506112002KQ,SMA    I22 @T6G_MB_LIB.T6G(SCH_1):PAGE91

M_G_CPU0_SA_DQ<27> @T6G_MB_LIB.T6G(SCH_1):M_G_CPU0_SA_DQ(27)
   U25  AE3 MGA_DATA27 GENOA_SP5-SOCKET6096_13568-001,SMLF,IO,DGA^6000030   I167 @T6G_MB_LIB.T6G(SCH_1):PAGE16
   J16  187 DQ27_A SCONN288_DDR506112002KQ-SCONN288_DDR506112002KQ,SMA    I22 @T6G_MB_LIB.T6G(SCH_1):PAGE91

M_G_CPU0_SA_DQ<28> @T6G_MB_LIB.T6G(SCH_1):M_G_CPU0_SA_DQ(28)
   U25  AG2 MGA_DATA28 GENOA_SP5-SOCKET6096_13568-001,SMLF,IO,DGA^6000030   I167 @T6G_MB_LIB.T6G(SCH_1):PAGE16
   J16   47 DQ28_A SCONN288_DDR506112002KQ-SCONN288_DDR506112002KQ,SMA    I22 @T6G_MB_LIB.T6G(SCH_1):PAGE91

M_G_CPU0_SA_DQ<29> @T6G_MB_LIB.T6G(SCH_1):M_G_CPU0_SA_DQ(29)
   U25  AH4 MGA_DATA29 GENOA_SP5-SOCKET6096_13568-001,SMLF,IO,DGA^6000030   I167 @T6G_MB_LIB.T6G(SCH_1):PAGE16
   J16   49 DQ29_A SCONN288_DDR506112002KQ-SCONN288_DDR506112002KQ,SMA    I22 @T6G_MB_LIB.T6G(SCH_1):PAGE91

M_G_CPU0_SA_DQ<2> @T6G_MB_LIB.T6G(SCH_1):M_G_CPU0_SA_DQ(2)
   U25   F2 MGA_DATA2 GENOA_SP5-SOCKET6096_13568-001,SMLF,IO,DGA^6000030   I167 @T6G_MB_LIB.T6G(SCH_1):PAGE16
   J16  152  DQ2_A SCONN288_DDR506112002KQ-SCONN288_DDR506112002KQ,SMA    I22 @T6G_MB_LIB.T6G(SCH_1):PAGE91

M_G_CPU0_SA_DQ<30> @T6G_MB_LIB.T6G(SCH_1):M_G_CPU0_SA_DQ(30)
   U25  AH2 MGA_DATA30 GENOA_SP5-SOCKET6096_13568-001,SMLF,IO,DGA^6000030   I167 @T6G_MB_LIB.T6G(SCH_1):PAGE16
   J16  192 DQ30_A SCONN288_DDR506112002KQ-SCONN288_DDR506112002KQ,SMA    I22 @T6G_MB_LIB.T6G(SCH_1):PAGE91

M_G_CPU0_SA_DQ<31> @T6G_MB_LIB.T6G(SCH_1):M_G_CPU0_SA_DQ(31)
   U25  AJ3 MGA_DATA31 GENOA_SP5-SOCKET6096_13568-001,SMLF,IO,DGA^6000030   I167 @T6G_MB_LIB.T6G(SCH_1):PAGE16
   J16  194 DQ31_A SCONN288_DDR506112002KQ-SCONN288_DDR506112002KQ,SMA    I22 @T6G_MB_LIB.T6G(SCH_1):PAGE91

M_G_CPU0_SA_DQ<3> @T6G_MB_LIB.T6G(SCH_1):M_G_CPU0_SA_DQ(3)
   U25   G3 MGA_DATA3 GENOA_SP5-SOCKET6096_13568-001,SMLF,IO,DGA^6000030   I167 @T6G_MB_LIB.T6G(SCH_1):PAGE16
   J16  154  DQ3_A SCONN288_DDR506112002KQ-SCONN288_DDR506112002KQ,SMA    I22 @T6G_MB_LIB.T6G(SCH_1):PAGE91

M_G_CPU0_SA_DQ<4> @T6G_MB_LIB.T6G(SCH_1):M_G_CPU0_SA_DQ(4)
   U25   J2 MGA_DATA4 GENOA_SP5-SOCKET6096_13568-001,SMLF,IO,DGA^6000030   I167 @T6G_MB_LIB.T6G(SCH_1):PAGE16
   J16   14  DQ4_A SCONN288_DDR506112002KQ-SCONN288_DDR506112002KQ,SMA    I22 @T6G_MB_LIB.T6G(SCH_1):PAGE91

M_G_CPU0_SA_DQ<5> @T6G_MB_LIB.T6G(SCH_1):M_G_CPU0_SA_DQ(5)
   U25   K4 MGA_DATA5 GENOA_SP5-SOCKET6096_13568-001,SMLF,IO,DGA^6000030   I167 @T6G_MB_LIB.T6G(SCH_1):PAGE16
   J16   16  DQ5_A SCONN288_DDR506112002KQ-SCONN288_DDR506112002KQ,SMA    I22 @T6G_MB_LIB.T6G(SCH_1):PAGE91

M_G_CPU0_SA_DQ<6> @T6G_MB_LIB.T6G(SCH_1):M_G_CPU0_SA_DQ(6)
   U25   K2 MGA_DATA6 GENOA_SP5-SOCKET6096_13568-001,SMLF,IO,DGA^6000030   I167 @T6G_MB_LIB.T6G(SCH_1):PAGE16
   J16  159  DQ6_A SCONN288_DDR506112002KQ-SCONN288_DDR506112002KQ,SMA    I22 @T6G_MB_LIB.T6G(SCH_1):PAGE91

M_G_CPU0_SA_DQ<7> @T6G_MB_LIB.T6G(SCH_1):M_G_CPU0_SA_DQ(7)
   U25   L3 MGA_DATA7 GENOA_SP5-SOCKET6096_13568-001,SMLF,IO,DGA^6000030   I167 @T6G_MB_LIB.T6G(SCH_1):PAGE16
   J16  161  DQ7_A SCONN288_DDR506112002KQ-SCONN288_DDR506112002KQ,SMA    I22 @T6G_MB_LIB.T6G(SCH_1):PAGE91

M_G_CPU0_SA_DQ<8> @T6G_MB_LIB.T6G(SCH_1):M_G_CPU0_SA_DQ(8)
   U25   L2 MGA_DATA8 GENOA_SP5-SOCKET6096_13568-001,SMLF,IO,DGA^6000030   I167 @T6G_MB_LIB.T6G(SCH_1):PAGE16
   J16   18  DQ8_A SCONN288_DDR506112002KQ-SCONN288_DDR506112002KQ,SMA    I22 @T6G_MB_LIB.T6G(SCH_1):PAGE91

M_G_CPU0_SA_DQ<9> @T6G_MB_LIB.T6G(SCH_1):M_G_CPU0_SA_DQ(9)
   U25   M4 MGA_DATA9 GENOA_SP5-SOCKET6096_13568-001,SMLF,IO,DGA^6000030   I167 @T6G_MB_LIB.T6G(SCH_1):PAGE16
   J16   20  DQ9_A SCONN288_DDR506112002KQ-SCONN288_DDR506112002KQ,SMA    I22 @T6G_MB_LIB.T6G(SCH_1):PAGE91

M_G_CPU0_SA_DQS_DN<0> @T6G_MB_LIB.T6G(SCH_1):M_G_CPU0_SA_DQS_DN(0)
   U25   H2 MGA_DQS_L0 GENOA_SP5-SOCKET6096_13568-001,SMLF,IO,DGA^6000030   I167 @T6G_MB_LIB.T6G(SCH_1):PAGE16
   J16   12 DQS0_A_C SCONN288_DDR506112002KQ-SCONN288_DDR506112002KQ,SMA   I236 @T6G_MB_LIB.T6G(SCH_1):PAGE91

M_G_CPU0_SA_DQS_DN<1> @T6G_MB_LIB.T6G(SCH_1):M_G_CPU0_SA_DQS_DN(1)
   U25   P2 MGA_DQS_L1 GENOA_SP5-SOCKET6096_13568-001,SMLF,IO,DGA^6000030   I167 @T6G_MB_LIB.T6G(SCH_1):PAGE16
   J16   23 DQS1_A_C SCONN288_DDR506112002KQ-SCONN288_DDR506112002KQ,SMA   I236 @T6G_MB_LIB.T6G(SCH_1):PAGE91

M_G_CPU0_SA_DQS_DN<2> @T6G_MB_LIB.T6G(SCH_1):M_G_CPU0_SA_DQS_DN(2)
   U25   Y2 MGA_DQS_L2 GENOA_SP5-SOCKET6096_13568-001,SMLF,IO,DGA^6000030   I167 @T6G_MB_LIB.T6G(SCH_1):PAGE16
   J16   34 DQS2_A_C SCONN288_DDR506112002KQ-SCONN288_DDR506112002KQ,SMA   I236 @T6G_MB_LIB.T6G(SCH_1):PAGE91

M_G_CPU0_SA_DQS_DN<3> @T6G_MB_LIB.T6G(SCH_1):M_G_CPU0_SA_DQS_DN(3)
   U25  AF2 MGA_DQS_L3 GENOA_SP5-SOCKET6096_13568-001,SMLF,IO,DGA^6000030   I167 @T6G_MB_LIB.T6G(SCH_1):PAGE16
   J16   45 DQS3_A_C SCONN288_DDR506112002KQ-SCONN288_DDR506112002KQ,SMA   I236 @T6G_MB_LIB.T6G(SCH_1):PAGE91

M_G_CPU0_SA_DQS_DN<4> @T6G_MB_LIB.T6G(SCH_1):M_G_CPU0_SA_DQS_DN(4)
   U25  AM2 MGA_DQS_L4 GENOA_SP5-SOCKET6096_13568-001,SMLF,IO,DGA^6000030   I167 @T6G_MB_LIB.T6G(SCH_1):PAGE16
   J16   56 DQS4_A_C SCONN288_DDR506112002KQ-SCONN288_DDR506112002KQ,SMA   I236 @T6G_MB_LIB.T6G(SCH_1):PAGE91

M_G_CPU0_SA_DQS_DN<5> @T6G_MB_LIB.T6G(SCH_1):M_G_CPU0_SA_DQS_DN(5)
   U25   H4 MGA_DQS_L5 GENOA_SP5-SOCKET6096_13568-001,SMLF,IO,DGA^6000030   I167 @T6G_MB_LIB.T6G(SCH_1):PAGE16
   J16  156 DQS5_A_C||TDQS5_A_C||DQS5_A_T||TDQS5_A_T SCONN288_DDR506112002KQ-SCONN288_DDR506112002KQ,SMA   I236 @T6G_MB_LIB.T6G(SCH_1):PAGE91

M_G_CPU0_SA_DQS_DN<6> @T6G_MB_LIB.T6G(SCH_1):M_G_CPU0_SA_DQS_DN(6)
   U25   P4 MGA_DQS_L6 GENOA_SP5-SOCKET6096_13568-001,SMLF,IO,DGA^6000030   I167 @T6G_MB_LIB.T6G(SCH_1):PAGE16
   J16  167 DQS6_A_C||TDQS6_A_C||DQS6_A_T||TDQS6_A_T SCONN288_DDR506112002KQ-SCONN288_DDR506112002KQ,SMA   I236 @T6G_MB_LIB.T6G(SCH_1):PAGE91

M_G_CPU0_SA_DQS_DN<7> @T6G_MB_LIB.T6G(SCH_1):M_G_CPU0_SA_DQS_DN(7)
   U25   Y4 MGA_DQS_L7 GENOA_SP5-SOCKET6096_13568-001,SMLF,IO,DGA^6000030   I167 @T6G_MB_LIB.T6G(SCH_1):PAGE16
   J16  178 DQS7_A_C||TDQS7_A_C SCONN288_DDR506112002KQ-SCONN288_DDR506112002KQ,SMA   I236 @T6G_MB_LIB.T6G(SCH_1):PAGE91

M_G_CPU0_SA_DQS_DN<8> @T6G_MB_LIB.T6G(SCH_1):M_G_CPU0_SA_DQS_DN(8)
   U25  AF4 MGA_DQS_L8 GENOA_SP5-SOCKET6096_13568-001,SMLF,IO,DGA^6000030   I167 @T6G_MB_LIB.T6G(SCH_1):PAGE16
   J16  189 DQS8_A_C||TDQS8_A_C SCONN288_DDR506112002KQ-SCONN288_DDR506112002KQ,SMA   I236 @T6G_MB_LIB.T6G(SCH_1):PAGE91

M_G_CPU0_SA_DQS_DN<9> @T6G_MB_LIB.T6G(SCH_1):M_G_CPU0_SA_DQS_DN(9)
   U25  AM4 MGA_DQS_L9 GENOA_SP5-SOCKET6096_13568-001,SMLF,IO,DGA^6000030   I167 @T6G_MB_LIB.T6G(SCH_1):PAGE16
   J16  200 DQS9_A_C||TDQS9_A_C SCONN288_DDR506112002KQ-SCONN288_DDR506112002KQ,SMA   I236 @T6G_MB_LIB.T6G(SCH_1):PAGE91

M_G_CPU0_SA_DQS_DP<0> @T6G_MB_LIB.T6G(SCH_1):M_G_CPU0_SA_DQS_DP(0)
   U25   G2 MGA_DQS_H0 GENOA_SP5-SOCKET6096_13568-001,SMLF,IO,DGA^6000030   I167 @T6G_MB_LIB.T6G(SCH_1):PAGE16
   J16   11 DQS0_A_T SCONN288_DDR506112002KQ-SCONN288_DDR506112002KQ,SMA   I236 @T6G_MB_LIB.T6G(SCH_1):PAGE91

M_G_CPU0_SA_DQS_DP<1> @T6G_MB_LIB.T6G(SCH_1):M_G_CPU0_SA_DQS_DP(1)
   U25   N2 MGA_DQS_H1 GENOA_SP5-SOCKET6096_13568-001,SMLF,IO,DGA^6000030   I167 @T6G_MB_LIB.T6G(SCH_1):PAGE16
   J16   22 DQS1_A_T SCONN288_DDR506112002KQ-SCONN288_DDR506112002KQ,SMA   I236 @T6G_MB_LIB.T6G(SCH_1):PAGE91

M_G_CPU0_SA_DQS_DP<2> @T6G_MB_LIB.T6G(SCH_1):M_G_CPU0_SA_DQS_DP(2)
   U25   W2 MGA_DQS_H2 GENOA_SP5-SOCKET6096_13568-001,SMLF,IO,DGA^6000030   I167 @T6G_MB_LIB.T6G(SCH_1):PAGE16
   J16   33 DQS2_A_T SCONN288_DDR506112002KQ-SCONN288_DDR506112002KQ,SMA   I236 @T6G_MB_LIB.T6G(SCH_1):PAGE91

M_G_CPU0_SA_DQS_DP<3> @T6G_MB_LIB.T6G(SCH_1):M_G_CPU0_SA_DQS_DP(3)
   U25  AE2 MGA_DQS_H3 GENOA_SP5-SOCKET6096_13568-001,SMLF,IO,DGA^6000030   I167 @T6G_MB_LIB.T6G(SCH_1):PAGE16
   J16   44 DQS3_A_T SCONN288_DDR506112002KQ-SCONN288_DDR506112002KQ,SMA   I236 @T6G_MB_LIB.T6G(SCH_1):PAGE91

M_G_CPU0_SA_DQS_DP<4> @T6G_MB_LIB.T6G(SCH_1):M_G_CPU0_SA_DQS_DP(4)
   U25  AL2 MGA_DQS_H4 GENOA_SP5-SOCKET6096_13568-001,SMLF,IO,DGA^6000030   I167 @T6G_MB_LIB.T6G(SCH_1):PAGE16
   J16   55 DQS4_A_T SCONN288_DDR506112002KQ-SCONN288_DDR506112002KQ,SMA   I236 @T6G_MB_LIB.T6G(SCH_1):PAGE91

M_G_CPU0_SA_DQS_DP<5> @T6G_MB_LIB.T6G(SCH_1):M_G_CPU0_SA_DQS_DP(5)
   U25   J3 MGA_DQS_H5 GENOA_SP5-SOCKET6096_13568-001,SMLF,IO,DGA^6000030   I167 @T6G_MB_LIB.T6G(SCH_1):PAGE16
   J16  157 DQS5_A_T||TDQS5_A_T SCONN288_DDR506112002KQ-SCONN288_DDR506112002KQ,SMA   I236 @T6G_MB_LIB.T6G(SCH_1):PAGE91

M_G_CPU0_SA_DQS_DP<6> @T6G_MB_LIB.T6G(SCH_1):M_G_CPU0_SA_DQS_DP(6)
   U25   R3 MGA_DQS_H6 GENOA_SP5-SOCKET6096_13568-001,SMLF,IO,DGA^6000030   I167 @T6G_MB_LIB.T6G(SCH_1):PAGE16
   J16  168 DQS6_A_T||TDQS6_A_T SCONN288_DDR506112002KQ-SCONN288_DDR506112002KQ,SMA   I236 @T6G_MB_LIB.T6G(SCH_1):PAGE91

M_G_CPU0_SA_DQS_DP<7> @T6G_MB_LIB.T6G(SCH_1):M_G_CPU0_SA_DQS_DP(7)
   U25  AA3 MGA_DQS_H7 GENOA_SP5-SOCKET6096_13568-001,SMLF,IO,DGA^6000030   I167 @T6G_MB_LIB.T6G(SCH_1):PAGE16
   J16  179 DQS7_A_T||TDQS7_A_T SCONN288_DDR506112002KQ-SCONN288_DDR506112002KQ,SMA   I236 @T6G_MB_LIB.T6G(SCH_1):PAGE91

M_G_CPU0_SA_DQS_DP<8> @T6G_MB_LIB.T6G(SCH_1):M_G_CPU0_SA_DQS_DP(8)
   U25  AG3 MGA_DQS_H8 GENOA_SP5-SOCKET6096_13568-001,SMLF,IO,DGA^6000030   I167 @T6G_MB_LIB.T6G(SCH_1):PAGE16
   J16  190 DQS8_A_T||TDQS8_A_T SCONN288_DDR506112002KQ-SCONN288_DDR506112002KQ,SMA   I236 @T6G_MB_LIB.T6G(SCH_1):PAGE91

M_G_CPU0_SA_DQS_DP<9> @T6G_MB_LIB.T6G(SCH_1):M_G_CPU0_SA_DQS_DP(9)
   U25  AN3 MGA_DQS_H9 GENOA_SP5-SOCKET6096_13568-001,SMLF,IO,DGA^6000030   I167 @T6G_MB_LIB.T6G(SCH_1):PAGE16
   J16  201 DQS9_A_T||TDQS9_A_T SCONN288_DDR506112002KQ-SCONN288_DDR506112002KQ,SMA   I236 @T6G_MB_LIB.T6G(SCH_1):PAGE91

M_G_CPU0_SA_PAR @T6G_MB_LIB.T6G(SCH_1):M_G_CPU0_SA_PAR
   U25  BC3 MGA_PAR GENOA_SP5-SOCKET6096_13568-001,SMLF,IO,DGA^6000030   I167 @T6G_MB_LIB.T6G(SCH_1):PAGE16
   J16   74  PAR_A SCONN288_DDR506112002KQ-SCONN288_DDR506112002KQ,SMA    I22 @T6G_MB_LIB.T6G(SCH_1):PAGE91

M_G_CPU0_SA_RSP<0> @T6G_MB_LIB.T6G(SCH_1):M_G_CPU0_SA_RSP(0)
   U25  BN3 MGA0_RSP_L GENOA_SP5-SOCKET6096_13568-001,SMLF,IO,DGA^6000030   I167 @T6G_MB_LIB.T6G(SCH_1):PAGE16
   J16   86 LBD||RSP_A_N SCONN288_DDR506112002KQ-SCONN288_DDR506112002KQ,SMA    I22 @T6G_MB_LIB.T6G(SCH_1):PAGE91

M_G_CPU0_SB_CA<0> @T6G_MB_LIB.T6G(SCH_1):M_G_CPU0_SB_CA(0)
   U25  BG3 MGB_CA0 GENOA_SP5-SOCKET6096_13568-001,SMLF,IO,DGA^6000030   I167 @T6G_MB_LIB.T6G(SCH_1):PAGE16
   J16   76  CA0_B SCONN288_DDR506112002KQ-SCONN288_DDR506112002KQ,SMA    I22 @T6G_MB_LIB.T6G(SCH_1):PAGE91

M_G_CPU0_SB_CA<1> @T6G_MB_LIB.T6G(SCH_1):M_G_CPU0_SB_CA(1)
   U25  BH4 MGB_CA1 GENOA_SP5-SOCKET6096_13568-001,SMLF,IO,DGA^6000030   I167 @T6G_MB_LIB.T6G(SCH_1):PAGE16
   J16  221  CA1_B SCONN288_DDR506112002KQ-SCONN288_DDR506112002KQ,SMA    I22 @T6G_MB_LIB.T6G(SCH_1):PAGE91

M_G_CPU0_SB_CA<2> @T6G_MB_LIB.T6G(SCH_1):M_G_CPU0_SB_CA(2)
   U25  BH2 MGB_CA2 GENOA_SP5-SOCKET6096_13568-001,SMLF,IO,DGA^6000030   I167 @T6G_MB_LIB.T6G(SCH_1):PAGE16
   J16   78  CA2_B SCONN288_DDR506112002KQ-SCONN288_DDR506112002KQ,SMA    I22 @T6G_MB_LIB.T6G(SCH_1):PAGE91

M_G_CPU0_SB_CA<3> @T6G_MB_LIB.T6G(SCH_1):M_G_CPU0_SB_CA(3)
   U25  BJ2 MGB_CA3 GENOA_SP5-SOCKET6096_13568-001,SMLF,IO,DGA^6000030   I167 @T6G_MB_LIB.T6G(SCH_1):PAGE16
   J16  223  CA3_B SCONN288_DDR506112002KQ-SCONN288_DDR506112002KQ,SMA    I22 @T6G_MB_LIB.T6G(SCH_1):PAGE91

M_G_CPU0_SB_CA<4> @T6G_MB_LIB.T6G(SCH_1):M_G_CPU0_SB_CA(4)
   U25  BJ3 MGB_CA4 GENOA_SP5-SOCKET6096_13568-001,SMLF,IO,DGA^6000030   I167 @T6G_MB_LIB.T6G(SCH_1):PAGE16
   J16   80  CA4_B SCONN288_DDR506112002KQ-SCONN288_DDR506112002KQ,SMA    I22 @T6G_MB_LIB.T6G(SCH_1):PAGE91

M_G_CPU0_SB_CA<5> @T6G_MB_LIB.T6G(SCH_1):M_G_CPU0_SB_CA(5)
   U25  BK4 MGB_CA5 GENOA_SP5-SOCKET6096_13568-001,SMLF,IO,DGA^6000030   I167 @T6G_MB_LIB.T6G(SCH_1):PAGE16
   J16  225  CA5_B SCONN288_DDR506112002KQ-SCONN288_DDR506112002KQ,SMA    I22 @T6G_MB_LIB.T6G(SCH_1):PAGE91

M_G_CPU0_SB_CA<6> @T6G_MB_LIB.T6G(SCH_1):M_G_CPU0_SB_CA(6)
   U25  BK2 MGB_CA6 GENOA_SP5-SOCKET6096_13568-001,SMLF,IO,DGA^6000030   I167 @T6G_MB_LIB.T6G(SCH_1):PAGE16
   J16   82  CA6_B SCONN288_DDR506112002KQ-SCONN288_DDR506112002KQ,SMA    I22 @T6G_MB_LIB.T6G(SCH_1):PAGE91

M_G_CPU0_SB_CB<0> @T6G_MB_LIB.T6G(SCH_1):M_G_CPU0_SB_CB(0)
   U25  BY2 MGB_CHECK0 GENOA_SP5-SOCKET6096_13568-001,SMLF,IO,DGA^6000030   I167 @T6G_MB_LIB.T6G(SCH_1):PAGE16
   J16   96  CB0_B SCONN288_DDR506112002KQ-SCONN288_DDR506112002KQ,SMA    I22 @T6G_MB_LIB.T6G(SCH_1):PAGE91

M_G_CPU0_SB_CB<1> @T6G_MB_LIB.T6G(SCH_1):M_G_CPU0_SB_CB(1)
   U25  CA3 MGB_CHECK1 GENOA_SP5-SOCKET6096_13568-001,SMLF,IO,DGA^6000030   I167 @T6G_MB_LIB.T6G(SCH_1):PAGE16
   J16   98  CB1_B SCONN288_DDR506112002KQ-SCONN288_DDR506112002KQ,SMA    I22 @T6G_MB_LIB.T6G(SCH_1):PAGE91

M_G_CPU0_SB_CB<2> @T6G_MB_LIB.T6G(SCH_1):M_G_CPU0_SB_CB(2)
   U25  CA2 MGB_CHECK2 GENOA_SP5-SOCKET6096_13568-001,SMLF,IO,DGA^6000030   I167 @T6G_MB_LIB.T6G(SCH_1):PAGE16
   J16  241  CB2_B SCONN288_DDR506112002KQ-SCONN288_DDR506112002KQ,SMA    I22 @T6G_MB_LIB.T6G(SCH_1):PAGE91

M_G_CPU0_SB_CB<3> @T6G_MB_LIB.T6G(SCH_1):M_G_CPU0_SB_CB(3)
   U25  CB4 MGB_CHECK3 GENOA_SP5-SOCKET6096_13568-001,SMLF,IO,DGA^6000030   I167 @T6G_MB_LIB.T6G(SCH_1):PAGE16
   J16  243  CB3_B SCONN288_DDR506112002KQ-SCONN288_DDR506112002KQ,SMA    I22 @T6G_MB_LIB.T6G(SCH_1):PAGE91

M_G_CPU0_SB_CB<4> @T6G_MB_LIB.T6G(SCH_1):M_G_CPU0_SB_CB(4)
   U25  BT2 MGB_CHECK4 GENOA_SP5-SOCKET6096_13568-001,SMLF,IO,DGA^6000030   I167 @T6G_MB_LIB.T6G(SCH_1):PAGE16
   J16   89  CB4_B SCONN288_DDR506112002KQ-SCONN288_DDR506112002KQ,SMA    I22 @T6G_MB_LIB.T6G(SCH_1):PAGE91

M_G_CPU0_SB_CB<5> @T6G_MB_LIB.T6G(SCH_1):M_G_CPU0_SB_CB(5)
   U25  BU3 MGB_CHECK5 GENOA_SP5-SOCKET6096_13568-001,SMLF,IO,DGA^6000030   I167 @T6G_MB_LIB.T6G(SCH_1):PAGE16
   J16   91  CB5_B SCONN288_DDR506112002KQ-SCONN288_DDR506112002KQ,SMA    I22 @T6G_MB_LIB.T6G(SCH_1):PAGE91

M_G_CPU0_SB_CB<6> @T6G_MB_LIB.T6G(SCH_1):M_G_CPU0_SB_CB(6)
   U25  BU2 MGB_CHECK6 GENOA_SP5-SOCKET6096_13568-001,SMLF,IO,DGA^6000030   I167 @T6G_MB_LIB.T6G(SCH_1):PAGE16
   J16  234  CB6_B SCONN288_DDR506112002KQ-SCONN288_DDR506112002KQ,SMA    I22 @T6G_MB_LIB.T6G(SCH_1):PAGE91

M_G_CPU0_SB_CB<7> @T6G_MB_LIB.T6G(SCH_1):M_G_CPU0_SB_CB(7)
   U25  BV4 MGB_CHECK7 GENOA_SP5-SOCKET6096_13568-001,SMLF,IO,DGA^6000030   I167 @T6G_MB_LIB.T6G(SCH_1):PAGE16
   J16  236  CB7_B SCONN288_DDR506112002KQ-SCONN288_DDR506112002KQ,SMA    I22 @T6G_MB_LIB.T6G(SCH_1):PAGE91

M_G_CPU0_SB_CS_N<0> @T6G_MB_LIB.T6G(SCH_1):M_G_CPU0_SB_CS_N(0)
   U25  BM4 MGB0_CS_L0 GENOA_SP5-SOCKET6096_13568-001,SMLF,IO,DGA^6000030   I167 @T6G_MB_LIB.T6G(SCH_1):PAGE16
   J16   84 CS0_B_N SCONN288_DDR506112002KQ-SCONN288_DDR506112002KQ,SMA    I22 @T6G_MB_LIB.T6G(SCH_1):PAGE91

M_G_CPU0_SB_CS_N<1> @T6G_MB_LIB.T6G(SCH_1):M_G_CPU0_SB_CS_N(1)
   U25  BN2 MGB0_CS_L1 GENOA_SP5-SOCKET6096_13568-001,SMLF,IO,DGA^6000030   I167 @T6G_MB_LIB.T6G(SCH_1):PAGE16
   J16  229 CS1_B_N SCONN288_DDR506112002KQ-SCONN288_DDR506112002KQ,SMA    I22 @T6G_MB_LIB.T6G(SCH_1):PAGE91

M_G_CPU0_SB_DQ<0> @T6G_MB_LIB.T6G(SCH_1):M_G_CPU0_SB_DQ(0)
   U25  CB2 MGB_DATA0 GENOA_SP5-SOCKET6096_13568-001,SMLF,IO,DGA^6000030   I167 @T6G_MB_LIB.T6G(SCH_1):PAGE16
   J16  100  DQ0_B SCONN288_DDR506112002KQ-SCONN288_DDR506112002KQ,SMA    I22 @T6G_MB_LIB.T6G(SCH_1):PAGE91

M_G_CPU0_SB_DQ<10> @T6G_MB_LIB.T6G(SCH_1):M_G_CPU0_SB_DQ(10)
   U25  CJ2 MGB_DATA10 GENOA_SP5-SOCKET6096_13568-001,SMLF,IO,DGA^6000030   I167 @T6G_MB_LIB.T6G(SCH_1):PAGE16
   J16  256 DQ10_B SCONN288_DDR506112002KQ-SCONN288_DDR506112002KQ,SMA    I22 @T6G_MB_LIB.T6G(SCH_1):PAGE91

M_G_CPU0_SB_DQ<11> @T6G_MB_LIB.T6G(SCH_1):M_G_CPU0_SB_DQ(11)
   U25  CK4 MGB_DATA11 GENOA_SP5-SOCKET6096_13568-001,SMLF,IO,DGA^6000030   I167 @T6G_MB_LIB.T6G(SCH_1):PAGE16
   J16  258 DQ11_B SCONN288_DDR506112002KQ-SCONN288_DDR506112002KQ,SMA    I22 @T6G_MB_LIB.T6G(SCH_1):PAGE91

M_G_CPU0_SB_DQ<12> @T6G_MB_LIB.T6G(SCH_1):M_G_CPU0_SB_DQ(12)
   U25  CM2 MGB_DATA12 GENOA_SP5-SOCKET6096_13568-001,SMLF,IO,DGA^6000030   I167 @T6G_MB_LIB.T6G(SCH_1):PAGE16
   J16  118 DQ12_B SCONN288_DDR506112002KQ-SCONN288_DDR506112002KQ,SMA    I22 @T6G_MB_LIB.T6G(SCH_1):PAGE91

M_G_CPU0_SB_DQ<13> @T6G_MB_LIB.T6G(SCH_1):M_G_CPU0_SB_DQ(13)
   U25  CN3 MGB_DATA13 GENOA_SP5-SOCKET6096_13568-001,SMLF,IO,DGA^6000030   I167 @T6G_MB_LIB.T6G(SCH_1):PAGE16
   J16  120 DQ13_B SCONN288_DDR506112002KQ-SCONN288_DDR506112002KQ,SMA    I22 @T6G_MB_LIB.T6G(SCH_1):PAGE91

M_G_CPU0_SB_DQ<14> @T6G_MB_LIB.T6G(SCH_1):M_G_CPU0_SB_DQ(14)
   U25  CN2 MGB_DATA14 GENOA_SP5-SOCKET6096_13568-001,SMLF,IO,DGA^6000030   I167 @T6G_MB_LIB.T6G(SCH_1):PAGE16
   J16  263 DQ14_B SCONN288_DDR506112002KQ-SCONN288_DDR506112002KQ,SMA    I22 @T6G_MB_LIB.T6G(SCH_1):PAGE91

M_G_CPU0_SB_DQ<15> @T6G_MB_LIB.T6G(SCH_1):M_G_CPU0_SB_DQ(15)
   U25  CP4 MGB_DATA15 GENOA_SP5-SOCKET6096_13568-001,SMLF,IO,DGA^6000030   I167 @T6G_MB_LIB.T6G(SCH_1):PAGE16
   J16  265 DQ15_B SCONN288_DDR506112002KQ-SCONN288_DDR506112002KQ,SMA    I22 @T6G_MB_LIB.T6G(SCH_1):PAGE91

M_G_CPU0_SB_DQ<16> @T6G_MB_LIB.T6G(SCH_1):M_G_CPU0_SB_DQ(16)
   U25  CP2 MGB_DATA16 GENOA_SP5-SOCKET6096_13568-001,SMLF,IO,DGA^6000030   I167 @T6G_MB_LIB.T6G(SCH_1):PAGE16
   J16  122 DQ16_B SCONN288_DDR506112002KQ-SCONN288_DDR506112002KQ,SMA    I22 @T6G_MB_LIB.T6G(SCH_1):PAGE91

M_G_CPU0_SB_DQ<17> @T6G_MB_LIB.T6G(SCH_1):M_G_CPU0_SB_DQ(17)
   U25  CR3 MGB_DATA17 GENOA_SP5-SOCKET6096_13568-001,SMLF,IO,DGA^6000030   I167 @T6G_MB_LIB.T6G(SCH_1):PAGE16
   J16  124 DQ17_B SCONN288_DDR506112002KQ-SCONN288_DDR506112002KQ,SMA    I22 @T6G_MB_LIB.T6G(SCH_1):PAGE91

M_G_CPU0_SB_DQ<18> @T6G_MB_LIB.T6G(SCH_1):M_G_CPU0_SB_DQ(18)
   U25  CR2 MGB_DATA18 GENOA_SP5-SOCKET6096_13568-001,SMLF,IO,DGA^6000030   I167 @T6G_MB_LIB.T6G(SCH_1):PAGE16
   J16  267 DQ18_B SCONN288_DDR506112002KQ-SCONN288_DDR506112002KQ,SMA    I22 @T6G_MB_LIB.T6G(SCH_1):PAGE91

M_G_CPU0_SB_DQ<19> @T6G_MB_LIB.T6G(SCH_1):M_G_CPU0_SB_DQ(19)
   U25  CT4 MGB_DATA19 GENOA_SP5-SOCKET6096_13568-001,SMLF,IO,DGA^6000030   I167 @T6G_MB_LIB.T6G(SCH_1):PAGE16
   J16  269 DQ19_B SCONN288_DDR506112002KQ-SCONN288_DDR506112002KQ,SMA    I22 @T6G_MB_LIB.T6G(SCH_1):PAGE91

M_G_CPU0_SB_DQ<1> @T6G_MB_LIB.T6G(SCH_1):M_G_CPU0_SB_DQ(1)
   U25  CC3 MGB_DATA1 GENOA_SP5-SOCKET6096_13568-001,SMLF,IO,DGA^6000030   I167 @T6G_MB_LIB.T6G(SCH_1):PAGE16
   J16  102  DQ1_B SCONN288_DDR506112002KQ-SCONN288_DDR506112002KQ,SMA    I22 @T6G_MB_LIB.T6G(SCH_1):PAGE91

M_G_CPU0_SB_DQ<20> @T6G_MB_LIB.T6G(SCH_1):M_G_CPU0_SB_DQ(20)
   U25  CV2 MGB_DATA20 GENOA_SP5-SOCKET6096_13568-001,SMLF,IO,DGA^6000030   I167 @T6G_MB_LIB.T6G(SCH_1):PAGE16
   J16  129 DQ20_B SCONN288_DDR506112002KQ-SCONN288_DDR506112002KQ,SMA    I22 @T6G_MB_LIB.T6G(SCH_1):PAGE91

M_G_CPU0_SB_DQ<21> @T6G_MB_LIB.T6G(SCH_1):M_G_CPU0_SB_DQ(21)
   U25  CW3 MGB_DATA21 GENOA_SP5-SOCKET6096_13568-001,SMLF,IO,DGA^6000030   I167 @T6G_MB_LIB.T6G(SCH_1):PAGE16
   J16  131 DQ21_B SCONN288_DDR506112002KQ-SCONN288_DDR506112002KQ,SMA    I22 @T6G_MB_LIB.T6G(SCH_1):PAGE91

M_G_CPU0_SB_DQ<22> @T6G_MB_LIB.T6G(SCH_1):M_G_CPU0_SB_DQ(22)
   U25  CW2 MGB_DATA22 GENOA_SP5-SOCKET6096_13568-001,SMLF,IO,DGA^6000030   I167 @T6G_MB_LIB.T6G(SCH_1):PAGE16
   J16  274 DQ22_B SCONN288_DDR506112002KQ-SCONN288_DDR506112002KQ,SMA    I22 @T6G_MB_LIB.T6G(SCH_1):PAGE91

M_G_CPU0_SB_DQ<23> @T6G_MB_LIB.T6G(SCH_1):M_G_CPU0_SB_DQ(23)
   U25  CY4 MGB_DATA23 GENOA_SP5-SOCKET6096_13568-001,SMLF,IO,DGA^6000030   I167 @T6G_MB_LIB.T6G(SCH_1):PAGE16
   J16  276 DQ23_B SCONN288_DDR506112002KQ-SCONN288_DDR506112002KQ,SMA    I22 @T6G_MB_LIB.T6G(SCH_1):PAGE91

M_G_CPU0_SB_DQ<24> @T6G_MB_LIB.T6G(SCH_1):M_G_CPU0_SB_DQ(24)
   U25  CY2 MGB_DATA24 GENOA_SP5-SOCKET6096_13568-001,SMLF,IO,DGA^6000030   I167 @T6G_MB_LIB.T6G(SCH_1):PAGE16
   J16  133 DQ24_B SCONN288_DDR506112002KQ-SCONN288_DDR506112002KQ,SMA    I22 @T6G_MB_LIB.T6G(SCH_1):PAGE91

M_G_CPU0_SB_DQ<25> @T6G_MB_LIB.T6G(SCH_1):M_G_CPU0_SB_DQ(25)
   U25  DA3 MGB_DATA25 GENOA_SP5-SOCKET6096_13568-001,SMLF,IO,DGA^6000030   I167 @T6G_MB_LIB.T6G(SCH_1):PAGE16
   J16  135 DQ25_B SCONN288_DDR506112002KQ-SCONN288_DDR506112002KQ,SMA    I22 @T6G_MB_LIB.T6G(SCH_1):PAGE91

M_G_CPU0_SB_DQ<26> @T6G_MB_LIB.T6G(SCH_1):M_G_CPU0_SB_DQ(26)
   U25  DA2 MGB_DATA26 GENOA_SP5-SOCKET6096_13568-001,SMLF,IO,DGA^6000030   I167 @T6G_MB_LIB.T6G(SCH_1):PAGE16
   J16  278 DQ26_B SCONN288_DDR506112002KQ-SCONN288_DDR506112002KQ,SMA    I22 @T6G_MB_LIB.T6G(SCH_1):PAGE91

M_G_CPU0_SB_DQ<27> @T6G_MB_LIB.T6G(SCH_1):M_G_CPU0_SB_DQ(27)
   U25  DB4 MGB_DATA27 GENOA_SP5-SOCKET6096_13568-001,SMLF,IO,DGA^6000030   I167 @T6G_MB_LIB.T6G(SCH_1):PAGE16
   J16  280 DQ27_B SCONN288_DDR506112002KQ-SCONN288_DDR506112002KQ,SMA    I22 @T6G_MB_LIB.T6G(SCH_1):PAGE91

M_G_CPU0_SB_DQ<28> @T6G_MB_LIB.T6G(SCH_1):M_G_CPU0_SB_DQ(28)
   U25  DD2 MGB_DATA28 GENOA_SP5-SOCKET6096_13568-001,SMLF,IO,DGA^6000030   I167 @T6G_MB_LIB.T6G(SCH_1):PAGE16
   J16  140 DQ28_B SCONN288_DDR506112002KQ-SCONN288_DDR506112002KQ,SMA    I22 @T6G_MB_LIB.T6G(SCH_1):PAGE91

M_G_CPU0_SB_DQ<29> @T6G_MB_LIB.T6G(SCH_1):M_G_CPU0_SB_DQ(29)
   U25  DE3 MGB_DATA29 GENOA_SP5-SOCKET6096_13568-001,SMLF,IO,DGA^6000030   I167 @T6G_MB_LIB.T6G(SCH_1):PAGE16
   J16  142 DQ29_B SCONN288_DDR506112002KQ-SCONN288_DDR506112002KQ,SMA    I22 @T6G_MB_LIB.T6G(SCH_1):PAGE91

M_G_CPU0_SB_DQ<2> @T6G_MB_LIB.T6G(SCH_1):M_G_CPU0_SB_DQ(2)
   U25  CC2 MGB_DATA2 GENOA_SP5-SOCKET6096_13568-001,SMLF,IO,DGA^6000030   I167 @T6G_MB_LIB.T6G(SCH_1):PAGE16
   J16  245  DQ2_B SCONN288_DDR506112002KQ-SCONN288_DDR506112002KQ,SMA    I22 @T6G_MB_LIB.T6G(SCH_1):PAGE91

M_G_CPU0_SB_DQ<30> @T6G_MB_LIB.T6G(SCH_1):M_G_CPU0_SB_DQ(30)
   U25  DE2 MGB_DATA30 GENOA_SP5-SOCKET6096_13568-001,SMLF,IO,DGA^6000030   I167 @T6G_MB_LIB.T6G(SCH_1):PAGE16
   J16  285 DQ30_B SCONN288_DDR506112002KQ-SCONN288_DDR506112002KQ,SMA    I22 @T6G_MB_LIB.T6G(SCH_1):PAGE91

M_G_CPU0_SB_DQ<31> @T6G_MB_LIB.T6G(SCH_1):M_G_CPU0_SB_DQ(31)
   U25  DF2 MGB_DATA31 GENOA_SP5-SOCKET6096_13568-001,SMLF,IO,DGA^6000030   I167 @T6G_MB_LIB.T6G(SCH_1):PAGE16
   J16  287 DQ31_B SCONN288_DDR506112002KQ-SCONN288_DDR506112002KQ,SMA    I22 @T6G_MB_LIB.T6G(SCH_1):PAGE91

M_G_CPU0_SB_DQ<3> @T6G_MB_LIB.T6G(SCH_1):M_G_CPU0_SB_DQ(3)
   U25  CD4 MGB_DATA3 GENOA_SP5-SOCKET6096_13568-001,SMLF,IO,DGA^6000030   I167 @T6G_MB_LIB.T6G(SCH_1):PAGE16
   J16  247  DQ3_B SCONN288_DDR506112002KQ-SCONN288_DDR506112002KQ,SMA    I22 @T6G_MB_LIB.T6G(SCH_1):PAGE91

M_G_CPU0_SB_DQ<4> @T6G_MB_LIB.T6G(SCH_1):M_G_CPU0_SB_DQ(4)
   U25  CF2 MGB_DATA4 GENOA_SP5-SOCKET6096_13568-001,SMLF,IO,DGA^6000030   I167 @T6G_MB_LIB.T6G(SCH_1):PAGE16
   J16  107  DQ4_B SCONN288_DDR506112002KQ-SCONN288_DDR506112002KQ,SMA    I22 @T6G_MB_LIB.T6G(SCH_1):PAGE91

M_G_CPU0_SB_DQ<5> @T6G_MB_LIB.T6G(SCH_1):M_G_CPU0_SB_DQ(5)
   U25  CG3 MGB_DATA5 GENOA_SP5-SOCKET6096_13568-001,SMLF,IO,DGA^6000030   I167 @T6G_MB_LIB.T6G(SCH_1):PAGE16
   J16  109  DQ5_B SCONN288_DDR506112002KQ-SCONN288_DDR506112002KQ,SMA    I22 @T6G_MB_LIB.T6G(SCH_1):PAGE91

M_G_CPU0_SB_DQ<6> @T6G_MB_LIB.T6G(SCH_1):M_G_CPU0_SB_DQ(6)
   U25  CG2 MGB_DATA6 GENOA_SP5-SOCKET6096_13568-001,SMLF,IO,DGA^6000030   I167 @T6G_MB_LIB.T6G(SCH_1):PAGE16
   J16  252  DQ6_B SCONN288_DDR506112002KQ-SCONN288_DDR506112002KQ,SMA    I22 @T6G_MB_LIB.T6G(SCH_1):PAGE91

M_G_CPU0_SB_DQ<7> @T6G_MB_LIB.T6G(SCH_1):M_G_CPU0_SB_DQ(7)
   U25  CH4 MGB_DATA7 GENOA_SP5-SOCKET6096_13568-001,SMLF,IO,DGA^6000030   I167 @T6G_MB_LIB.T6G(SCH_1):PAGE16
   J16  254  DQ7_B SCONN288_DDR506112002KQ-SCONN288_DDR506112002KQ,SMA    I22 @T6G_MB_LIB.T6G(SCH_1):PAGE91

M_G_CPU0_SB_DQ<8> @T6G_MB_LIB.T6G(SCH_1):M_G_CPU0_SB_DQ(8)
   U25  CH2 MGB_DATA8 GENOA_SP5-SOCKET6096_13568-001,SMLF,IO,DGA^6000030   I167 @T6G_MB_LIB.T6G(SCH_1):PAGE16
   J16  111  DQ8_B SCONN288_DDR506112002KQ-SCONN288_DDR506112002KQ,SMA    I22 @T6G_MB_LIB.T6G(SCH_1):PAGE91

M_G_CPU0_SB_DQ<9> @T6G_MB_LIB.T6G(SCH_1):M_G_CPU0_SB_DQ(9)
   U25  CJ3 MGB_DATA9 GENOA_SP5-SOCKET6096_13568-001,SMLF,IO,DGA^6000030   I167 @T6G_MB_LIB.T6G(SCH_1):PAGE16
   J16  113  DQ9_B SCONN288_DDR506112002KQ-SCONN288_DDR506112002KQ,SMA    I22 @T6G_MB_LIB.T6G(SCH_1):PAGE91

M_G_CPU0_SB_DQS_DN<0> @T6G_MB_LIB.T6G(SCH_1):M_G_CPU0_SB_DQS_DN(0)
   U25  CE2 MGB_DQS_L0 GENOA_SP5-SOCKET6096_13568-001,SMLF,IO,DGA^6000030   I167 @T6G_MB_LIB.T6G(SCH_1):PAGE16
   J16  105 DQS0_B_C SCONN288_DDR506112002KQ-SCONN288_DDR506112002KQ,SMA   I236 @T6G_MB_LIB.T6G(SCH_1):PAGE91

M_G_CPU0_SB_DQS_DN<1> @T6G_MB_LIB.T6G(SCH_1):M_G_CPU0_SB_DQS_DN(1)
   U25  CL2 MGB_DQS_L1 GENOA_SP5-SOCKET6096_13568-001,SMLF,IO,DGA^6000030   I167 @T6G_MB_LIB.T6G(SCH_1):PAGE16
   J16  116 DQS1_B_C SCONN288_DDR506112002KQ-SCONN288_DDR506112002KQ,SMA   I236 @T6G_MB_LIB.T6G(SCH_1):PAGE91

M_G_CPU0_SB_DQS_DN<2> @T6G_MB_LIB.T6G(SCH_1):M_G_CPU0_SB_DQS_DN(2)
   U25  CU2 MGB_DQS_L2 GENOA_SP5-SOCKET6096_13568-001,SMLF,IO,DGA^6000030   I167 @T6G_MB_LIB.T6G(SCH_1):PAGE16
   J16  127 DQS2_B_C SCONN288_DDR506112002KQ-SCONN288_DDR506112002KQ,SMA   I236 @T6G_MB_LIB.T6G(SCH_1):PAGE91

M_G_CPU0_SB_DQS_DN<3> @T6G_MB_LIB.T6G(SCH_1):M_G_CPU0_SB_DQS_DN(3)
   U25  DC2 MGB_DQS_L3 GENOA_SP5-SOCKET6096_13568-001,SMLF,IO,DGA^6000030   I167 @T6G_MB_LIB.T6G(SCH_1):PAGE16
   J16  138 DQS3_B_C SCONN288_DDR506112002KQ-SCONN288_DDR506112002KQ,SMA   I236 @T6G_MB_LIB.T6G(SCH_1):PAGE91

M_G_CPU0_SB_DQS_DN<4> @T6G_MB_LIB.T6G(SCH_1):M_G_CPU0_SB_DQS_DN(4)
   U25  BW3 MGB_DQS_L4 GENOA_SP5-SOCKET6096_13568-001,SMLF,IO,DGA^6000030   I167 @T6G_MB_LIB.T6G(SCH_1):PAGE16
   J16  238 DQS4_B_C SCONN288_DDR506112002KQ-SCONN288_DDR506112002KQ,SMA   I236 @T6G_MB_LIB.T6G(SCH_1):PAGE91

M_G_CPU0_SB_DQS_DN<5> @T6G_MB_LIB.T6G(SCH_1):M_G_CPU0_SB_DQS_DN(5)
   U25  CE3 MGB_DQS_L5 GENOA_SP5-SOCKET6096_13568-001,SMLF,IO,DGA^6000030   I167 @T6G_MB_LIB.T6G(SCH_1):PAGE16
   J16  249 DQS5_B_C||TDQS5_B_C SCONN288_DDR506112002KQ-SCONN288_DDR506112002KQ,SMA   I236 @T6G_MB_LIB.T6G(SCH_1):PAGE91

M_G_CPU0_SB_DQS_DN<6> @T6G_MB_LIB.T6G(SCH_1):M_G_CPU0_SB_DQS_DN(6)
   U25  CL3 MGB_DQS_L6 GENOA_SP5-SOCKET6096_13568-001,SMLF,IO,DGA^6000030   I167 @T6G_MB_LIB.T6G(SCH_1):PAGE16
   J16  260 DQS6_B_C||TDQS6_B_C SCONN288_DDR506112002KQ-SCONN288_DDR506112002KQ,SMA   I236 @T6G_MB_LIB.T6G(SCH_1):PAGE91

M_G_CPU0_SB_DQS_DN<7> @T6G_MB_LIB.T6G(SCH_1):M_G_CPU0_SB_DQS_DN(7)
   U25  CU3 MGB_DQS_L7 GENOA_SP5-SOCKET6096_13568-001,SMLF,IO,DGA^6000030   I167 @T6G_MB_LIB.T6G(SCH_1):PAGE16
   J16  271 DQS7_B_C||TDQS7_B_C SCONN288_DDR506112002KQ-SCONN288_DDR506112002KQ,SMA   I236 @T6G_MB_LIB.T6G(SCH_1):PAGE91

M_G_CPU0_SB_DQS_DN<8> @T6G_MB_LIB.T6G(SCH_1):M_G_CPU0_SB_DQS_DN(8)
   U25  DC3 MGB_DQS_L8 GENOA_SP5-SOCKET6096_13568-001,SMLF,IO,DGA^6000030   I167 @T6G_MB_LIB.T6G(SCH_1):PAGE16
   J16  282 DQS8_B_C||TDQS8_B_C SCONN288_DDR506112002KQ-SCONN288_DDR506112002KQ,SMA   I236 @T6G_MB_LIB.T6G(SCH_1):PAGE91

M_G_CPU0_SB_DQS_DN<9> @T6G_MB_LIB.T6G(SCH_1):M_G_CPU0_SB_DQS_DN(9)
   U25  BW2 MGB_DQS_L9 GENOA_SP5-SOCKET6096_13568-001,SMLF,IO,DGA^6000030   I167 @T6G_MB_LIB.T6G(SCH_1):PAGE16
   J16   94 DQS9_B_C||TDQS9_B_C SCONN288_DDR506112002KQ-SCONN288_DDR506112002KQ,SMA   I236 @T6G_MB_LIB.T6G(SCH_1):PAGE91

M_G_CPU0_SB_DQS_DP<0> @T6G_MB_LIB.T6G(SCH_1):M_G_CPU0_SB_DQS_DP(0)
   U25  CD2 MGB_DQS_H0 GENOA_SP5-SOCKET6096_13568-001,SMLF,IO,DGA^6000030   I167 @T6G_MB_LIB.T6G(SCH_1):PAGE16
   J16  104 DQS0_B_T SCONN288_DDR506112002KQ-SCONN288_DDR506112002KQ,SMA   I236 @T6G_MB_LIB.T6G(SCH_1):PAGE91

M_G_CPU0_SB_DQS_DP<1> @T6G_MB_LIB.T6G(SCH_1):M_G_CPU0_SB_DQS_DP(1)
   U25  CK2 MGB_DQS_H1 GENOA_SP5-SOCKET6096_13568-001,SMLF,IO,DGA^6000030   I167 @T6G_MB_LIB.T6G(SCH_1):PAGE16
   J16  115 DQS1_B_T SCONN288_DDR506112002KQ-SCONN288_DDR506112002KQ,SMA   I236 @T6G_MB_LIB.T6G(SCH_1):PAGE91

M_G_CPU0_SB_DQS_DP<2> @T6G_MB_LIB.T6G(SCH_1):M_G_CPU0_SB_DQS_DP(2)
   U25  CT2 MGB_DQS_H2 GENOA_SP5-SOCKET6096_13568-001,SMLF,IO,DGA^6000030   I167 @T6G_MB_LIB.T6G(SCH_1):PAGE16
   J16  126 DQS2_B_T SCONN288_DDR506112002KQ-SCONN288_DDR506112002KQ,SMA   I236 @T6G_MB_LIB.T6G(SCH_1):PAGE91

M_G_CPU0_SB_DQS_DP<3> @T6G_MB_LIB.T6G(SCH_1):M_G_CPU0_SB_DQS_DP(3)
   U25  DB2 MGB_DQS_H3 GENOA_SP5-SOCKET6096_13568-001,SMLF,IO,DGA^6000030   I167 @T6G_MB_LIB.T6G(SCH_1):PAGE16
   J16  137 DQS3_B_T SCONN288_DDR506112002KQ-SCONN288_DDR506112002KQ,SMA   I236 @T6G_MB_LIB.T6G(SCH_1):PAGE91

M_G_CPU0_SB_DQS_DP<4> @T6G_MB_LIB.T6G(SCH_1):M_G_CPU0_SB_DQS_DP(4)
   U25  BY4 MGB_DQS_H4 GENOA_SP5-SOCKET6096_13568-001,SMLF,IO,DGA^6000030   I167 @T6G_MB_LIB.T6G(SCH_1):PAGE16
   J16  239 DQS4_B_T SCONN288_DDR506112002KQ-SCONN288_DDR506112002KQ,SMA   I236 @T6G_MB_LIB.T6G(SCH_1):PAGE91

M_G_CPU0_SB_DQS_DP<5> @T6G_MB_LIB.T6G(SCH_1):M_G_CPU0_SB_DQS_DP(5)
   U25  CF4 MGB_DQS_H5 GENOA_SP5-SOCKET6096_13568-001,SMLF,IO,DGA^6000030   I167 @T6G_MB_LIB.T6G(SCH_1):PAGE16
   J16  250 DQS5_B_T||TDQS5_B_T SCONN288_DDR506112002KQ-SCONN288_DDR506112002KQ,SMA   I236 @T6G_MB_LIB.T6G(SCH_1):PAGE91

M_G_CPU0_SB_DQS_DP<6> @T6G_MB_LIB.T6G(SCH_1):M_G_CPU0_SB_DQS_DP(6)
   U25  CM4 MGB_DQS_H6 GENOA_SP5-SOCKET6096_13568-001,SMLF,IO,DGA^6000030   I167 @T6G_MB_LIB.T6G(SCH_1):PAGE16
   J16  261 DQS6_B_T||TDQS6_B_T SCONN288_DDR506112002KQ-SCONN288_DDR506112002KQ,SMA   I236 @T6G_MB_LIB.T6G(SCH_1):PAGE91

M_G_CPU0_SB_DQS_DP<7> @T6G_MB_LIB.T6G(SCH_1):M_G_CPU0_SB_DQS_DP(7)
   U25  CV4 MGB_DQS_H7 GENOA_SP5-SOCKET6096_13568-001,SMLF,IO,DGA^6000030   I167 @T6G_MB_LIB.T6G(SCH_1):PAGE16
   J16  272 DQS7_B_T||TDQS7_B_T SCONN288_DDR506112002KQ-SCONN288_DDR506112002KQ,SMA   I236 @T6G_MB_LIB.T6G(SCH_1):PAGE91

M_G_CPU0_SB_DQS_DP<8> @T6G_MB_LIB.T6G(SCH_1):M_G_CPU0_SB_DQS_DP(8)
   U25  DD4 MGB_DQS_H8 GENOA_SP5-SOCKET6096_13568-001,SMLF,IO,DGA^6000030   I167 @T6G_MB_LIB.T6G(SCH_1):PAGE16
   J16  283 DQS8_B_T||TDQS8_B_T SCONN288_DDR506112002KQ-SCONN288_DDR506112002KQ,SMA   I236 @T6G_MB_LIB.T6G(SCH_1):PAGE91

M_G_CPU0_SB_DQS_DP<9> @T6G_MB_LIB.T6G(SCH_1):M_G_CPU0_SB_DQS_DP(9)
   U25  BV2 MGB_DQS_H9 GENOA_SP5-SOCKET6096_13568-001,SMLF,IO,DGA^6000030   I167 @T6G_MB_LIB.T6G(SCH_1):PAGE16
   J16   93 DQS9_B_T||TDQS9_B_T||DBI4_B_N SCONN288_DDR506112002KQ-SCONN288_DDR506112002KQ,SMA   I236 @T6G_MB_LIB.T6G(SCH_1):PAGE91

M_G_CPU0_SB_PAR @T6G_MB_LIB.T6G(SCH_1):M_G_CPU0_SB_PAR
   U25  BL3 MGB_PAR GENOA_SP5-SOCKET6096_13568-001,SMLF,IO,DGA^6000030   I167 @T6G_MB_LIB.T6G(SCH_1):PAGE16
   J16  227  PAR_B SCONN288_DDR506112002KQ-SCONN288_DDR506112002KQ,SMA    I22 @T6G_MB_LIB.T6G(SCH_1):PAGE91

M_G_CPU0_SB_RSP<0> @T6G_MB_LIB.T6G(SCH_1):M_G_CPU0_SB_RSP(0)
   U25  BP2 MGB0_RSP_L GENOA_SP5-SOCKET6096_13568-001,SMLF,IO,DGA^6000030   I167 @T6G_MB_LIB.T6G(SCH_1):PAGE16
   J16   87 LBS||RSP_B_N SCONN288_DDR506112002KQ-SCONN288_DDR506112002KQ,SMA    I22 @T6G_MB_LIB.T6G(SCH_1):PAGE91

M_G_CPU1_ALERT_N @T6G_MB_LIB.T6G(SCH_1):M_G_CPU1_ALERT_N
  R506    1      A Q_RES_0402LF-15,1%,1/16W,CHIP,CS01502FB03   I322 @T6G_MB_LIB.T6G(SCH_1):PAGE43
  J102   62 ALERT_N SCONN288_DDR506112002KQ-SCONN288_DDR506112002KQ,SMA    I22 @T6G_MB_LIB.T6G(SCH_1):PAGE103

M_G_CPU1_ALERT_R_N @T6G_MB_LIB.T6G(SCH_1):M_G_CPU1_ALERT_R_N
   U26  AR2 MG_ALERT_L GENOA_SP5-SOCKET6096_13568-001,SMLF,IO,DGA^6000030   I167 @T6G_MB_LIB.T6G(SCH_1):PAGE43
  R506    2      B Q_RES_0402LF-15,1%,1/16W,CHIP,CS01502FB03   I322 @T6G_MB_LIB.T6G(SCH_1):PAGE43

M_G_CPU1_CLK_DN<0> @T6G_MB_LIB.T6G(SCH_1):M_G_CPU1_CLK_DN(0)
   U26  BD2 MG0_CLK_L GENOA_SP5-SOCKET6096_13568-001,SMLF,IO,DGA^6000030   I167 @T6G_MB_LIB.T6G(SCH_1):PAGE43
  J102  218   CK_C SCONN288_DDR506112002KQ-SCONN288_DDR506112002KQ,SMA    I22 @T6G_MB_LIB.T6G(SCH_1):PAGE103

M_G_CPU1_CLK_DP<0> @T6G_MB_LIB.T6G(SCH_1):M_G_CPU1_CLK_DP(0)
   U26  BC2 MG0_CLK_H GENOA_SP5-SOCKET6096_13568-001,SMLF,IO,DGA^6000030   I167 @T6G_MB_LIB.T6G(SCH_1):PAGE43
  J102  217   CK_T SCONN288_DDR506112002KQ-SCONN288_DDR506112002KQ,SMA    I22 @T6G_MB_LIB.T6G(SCH_1):PAGE103

M_G_CPU1_RESET_N @T6G_MB_LIB.T6G(SCH_1):M_G_CPU1_RESET_N
   U26  AT2 MG_RESET_L GENOA_SP5-SOCKET6096_13568-001,SMLF,IO,DGA^6000030   I167 @T6G_MB_LIB.T6G(SCH_1):PAGE43
  J102  207 RESET_N SCONN288_DDR506112002KQ-SCONN288_DDR506112002KQ,SMA    I22 @T6G_MB_LIB.T6G(SCH_1):PAGE103

M_G_CPU1_SA_CA<0> @T6G_MB_LIB.T6G(SCH_1):M_G_CPU1_SA_CA(0)
   U26  AW2 MGA_CA0 GENOA_SP5-SOCKET6096_13568-001,SMLF,IO,DGA^6000030   I167 @T6G_MB_LIB.T6G(SCH_1):PAGE43
  J102   66  CA0_A SCONN288_DDR506112002KQ-SCONN288_DDR506112002KQ,SMA    I22 @T6G_MB_LIB.T6G(SCH_1):PAGE103

M_G_CPU1_SA_CA<1> @T6G_MB_LIB.T6G(SCH_1):M_G_CPU1_SA_CA(1)
   U26  AY2 MGA_CA1 GENOA_SP5-SOCKET6096_13568-001,SMLF,IO,DGA^6000030   I167 @T6G_MB_LIB.T6G(SCH_1):PAGE43
  J102  211  CA1_A SCONN288_DDR506112002KQ-SCONN288_DDR506112002KQ,SMA    I22 @T6G_MB_LIB.T6G(SCH_1):PAGE103

M_G_CPU1_SA_CA<2> @T6G_MB_LIB.T6G(SCH_1):M_G_CPU1_SA_CA(2)
   U26  AY4 MGA_CA2 GENOA_SP5-SOCKET6096_13568-001,SMLF,IO,DGA^6000030   I167 @T6G_MB_LIB.T6G(SCH_1):PAGE43
  J102   68  CA2_A SCONN288_DDR506112002KQ-SCONN288_DDR506112002KQ,SMA    I22 @T6G_MB_LIB.T6G(SCH_1):PAGE103

M_G_CPU1_SA_CA<3> @T6G_MB_LIB.T6G(SCH_1):M_G_CPU1_SA_CA(3)
   U26  BA3 MGA_CA3 GENOA_SP5-SOCKET6096_13568-001,SMLF,IO,DGA^6000030   I167 @T6G_MB_LIB.T6G(SCH_1):PAGE43
  J102  213  CA3_A SCONN288_DDR506112002KQ-SCONN288_DDR506112002KQ,SMA    I22 @T6G_MB_LIB.T6G(SCH_1):PAGE103

M_G_CPU1_SA_CA<4> @T6G_MB_LIB.T6G(SCH_1):M_G_CPU1_SA_CA(4)
   U26  BA2 MGA_CA4 GENOA_SP5-SOCKET6096_13568-001,SMLF,IO,DGA^6000030   I167 @T6G_MB_LIB.T6G(SCH_1):PAGE43
  J102   70  CA4_A SCONN288_DDR506112002KQ-SCONN288_DDR506112002KQ,SMA    I22 @T6G_MB_LIB.T6G(SCH_1):PAGE103

M_G_CPU1_SA_CA<5> @T6G_MB_LIB.T6G(SCH_1):M_G_CPU1_SA_CA(5)
   U26  BB2 MGA_CA5 GENOA_SP5-SOCKET6096_13568-001,SMLF,IO,DGA^6000030   I167 @T6G_MB_LIB.T6G(SCH_1):PAGE43
  J102  215  CA5_A SCONN288_DDR506112002KQ-SCONN288_DDR506112002KQ,SMA    I22 @T6G_MB_LIB.T6G(SCH_1):PAGE103

M_G_CPU1_SA_CA<6> @T6G_MB_LIB.T6G(SCH_1):M_G_CPU1_SA_CA(6)
   U26  BB4 MGA_CA6 GENOA_SP5-SOCKET6096_13568-001,SMLF,IO,DGA^6000030   I167 @T6G_MB_LIB.T6G(SCH_1):PAGE43
  J102   72  CA6_A SCONN288_DDR506112002KQ-SCONN288_DDR506112002KQ,SMA    I22 @T6G_MB_LIB.T6G(SCH_1):PAGE103

M_G_CPU1_SA_CB<0> @T6G_MB_LIB.T6G(SCH_1):M_G_CPU1_SA_CB(0)
   U26  AJ2 MGA_CHECK0 GENOA_SP5-SOCKET6096_13568-001,SMLF,IO,DGA^6000030   I167 @T6G_MB_LIB.T6G(SCH_1):PAGE43
  J102   51  CB0_A SCONN288_DDR506112002KQ-SCONN288_DDR506112002KQ,SMA    I22 @T6G_MB_LIB.T6G(SCH_1):PAGE103

M_G_CPU1_SA_CB<1> @T6G_MB_LIB.T6G(SCH_1):M_G_CPU1_SA_CB(1)
   U26  AK4 MGA_CHECK1 GENOA_SP5-SOCKET6096_13568-001,SMLF,IO,DGA^6000030   I167 @T6G_MB_LIB.T6G(SCH_1):PAGE43
  J102   53  CB1_A SCONN288_DDR506112002KQ-SCONN288_DDR506112002KQ,SMA    I22 @T6G_MB_LIB.T6G(SCH_1):PAGE103

M_G_CPU1_SA_CB<2> @T6G_MB_LIB.T6G(SCH_1):M_G_CPU1_SA_CB(2)
   U26  AK2 MGA_CHECK2 GENOA_SP5-SOCKET6096_13568-001,SMLF,IO,DGA^6000030   I167 @T6G_MB_LIB.T6G(SCH_1):PAGE43
  J102  196  CB2_A SCONN288_DDR506112002KQ-SCONN288_DDR506112002KQ,SMA    I22 @T6G_MB_LIB.T6G(SCH_1):PAGE103

M_G_CPU1_SA_CB<3> @T6G_MB_LIB.T6G(SCH_1):M_G_CPU1_SA_CB(3)
   U26  AL3 MGA_CHECK3 GENOA_SP5-SOCKET6096_13568-001,SMLF,IO,DGA^6000030   I167 @T6G_MB_LIB.T6G(SCH_1):PAGE43
  J102  198  CB3_A SCONN288_DDR506112002KQ-SCONN288_DDR506112002KQ,SMA    I22 @T6G_MB_LIB.T6G(SCH_1):PAGE103

M_G_CPU1_SA_CB<4> @T6G_MB_LIB.T6G(SCH_1):M_G_CPU1_SA_CB(4)
   U26  AN2 MGA_CHECK4 GENOA_SP5-SOCKET6096_13568-001,SMLF,IO,DGA^6000030   I167 @T6G_MB_LIB.T6G(SCH_1):PAGE43
  J102   58  CB4_A SCONN288_DDR506112002KQ-SCONN288_DDR506112002KQ,SMA    I22 @T6G_MB_LIB.T6G(SCH_1):PAGE103

M_G_CPU1_SA_CB<5> @T6G_MB_LIB.T6G(SCH_1):M_G_CPU1_SA_CB(5)
   U26  AP4 MGA_CHECK5 GENOA_SP5-SOCKET6096_13568-001,SMLF,IO,DGA^6000030   I167 @T6G_MB_LIB.T6G(SCH_1):PAGE43
  J102   60  CB5_A SCONN288_DDR506112002KQ-SCONN288_DDR506112002KQ,SMA    I22 @T6G_MB_LIB.T6G(SCH_1):PAGE103

M_G_CPU1_SA_CB<6> @T6G_MB_LIB.T6G(SCH_1):M_G_CPU1_SA_CB(6)
   U26  AP2 MGA_CHECK6 GENOA_SP5-SOCKET6096_13568-001,SMLF,IO,DGA^6000030   I167 @T6G_MB_LIB.T6G(SCH_1):PAGE43
  J102  203  CB6_A SCONN288_DDR506112002KQ-SCONN288_DDR506112002KQ,SMA    I22 @T6G_MB_LIB.T6G(SCH_1):PAGE103

M_G_CPU1_SA_CB<7> @T6G_MB_LIB.T6G(SCH_1):M_G_CPU1_SA_CB(7)
   U26  AR3 MGA_CHECK7 GENOA_SP5-SOCKET6096_13568-001,SMLF,IO,DGA^6000030   I167 @T6G_MB_LIB.T6G(SCH_1):PAGE43
  J102  205  CB7_A SCONN288_DDR506112002KQ-SCONN288_DDR506112002KQ,SMA    I22 @T6G_MB_LIB.T6G(SCH_1):PAGE103

M_G_CPU1_SA_CS_N<0> @T6G_MB_LIB.T6G(SCH_1):M_G_CPU1_SA_CS_N(0)
   U26  AU2 MGA0_CS_L0 GENOA_SP5-SOCKET6096_13568-001,SMLF,IO,DGA^6000030   I167 @T6G_MB_LIB.T6G(SCH_1):PAGE43
  J102   64 CS0_A_N SCONN288_DDR506112002KQ-SCONN288_DDR506112002KQ,SMA    I22 @T6G_MB_LIB.T6G(SCH_1):PAGE103

M_G_CPU1_SA_CS_N<1> @T6G_MB_LIB.T6G(SCH_1):M_G_CPU1_SA_CS_N(1)
   U26  AV4 MGA0_CS_L1 GENOA_SP5-SOCKET6096_13568-001,SMLF,IO,DGA^6000030   I167 @T6G_MB_LIB.T6G(SCH_1):PAGE43
  J102  209 CS1_A_N SCONN288_DDR506112002KQ-SCONN288_DDR506112002KQ,SMA    I22 @T6G_MB_LIB.T6G(SCH_1):PAGE103

M_G_CPU1_SA_DQ<0> @T6G_MB_LIB.T6G(SCH_1):M_G_CPU1_SA_DQ(0)
   U26   E2 MGA_DATA0 GENOA_SP5-SOCKET6096_13568-001,SMLF,IO,DGA^6000030   I167 @T6G_MB_LIB.T6G(SCH_1):PAGE43
  J102    7  DQ0_A SCONN288_DDR506112002KQ-SCONN288_DDR506112002KQ,SMA    I22 @T6G_MB_LIB.T6G(SCH_1):PAGE103

M_G_CPU1_SA_DQ<10> @T6G_MB_LIB.T6G(SCH_1):M_G_CPU1_SA_DQ(10)
   U26   M2 MGA_DATA10 GENOA_SP5-SOCKET6096_13568-001,SMLF,IO,DGA^6000030   I167 @T6G_MB_LIB.T6G(SCH_1):PAGE43
  J102  163 DQ10_A SCONN288_DDR506112002KQ-SCONN288_DDR506112002KQ,SMA    I22 @T6G_MB_LIB.T6G(SCH_1):PAGE103

M_G_CPU1_SA_DQ<11> @T6G_MB_LIB.T6G(SCH_1):M_G_CPU1_SA_DQ(11)
   U26   N3 MGA_DATA11 GENOA_SP5-SOCKET6096_13568-001,SMLF,IO,DGA^6000030   I167 @T6G_MB_LIB.T6G(SCH_1):PAGE43
  J102  165 DQ11_A SCONN288_DDR506112002KQ-SCONN288_DDR506112002KQ,SMA    I22 @T6G_MB_LIB.T6G(SCH_1):PAGE103

M_G_CPU1_SA_DQ<12> @T6G_MB_LIB.T6G(SCH_1):M_G_CPU1_SA_DQ(12)
   U26   R2 MGA_DATA12 GENOA_SP5-SOCKET6096_13568-001,SMLF,IO,DGA^6000030   I167 @T6G_MB_LIB.T6G(SCH_1):PAGE43
  J102   25 DQ12_A SCONN288_DDR506112002KQ-SCONN288_DDR506112002KQ,SMA    I22 @T6G_MB_LIB.T6G(SCH_1):PAGE103

M_G_CPU1_SA_DQ<13> @T6G_MB_LIB.T6G(SCH_1):M_G_CPU1_SA_DQ(13)
   U26   T4 MGA_DATA13 GENOA_SP5-SOCKET6096_13568-001,SMLF,IO,DGA^6000030   I167 @T6G_MB_LIB.T6G(SCH_1):PAGE43
  J102   27 DQ13_A SCONN288_DDR506112002KQ-SCONN288_DDR506112002KQ,SMA    I22 @T6G_MB_LIB.T6G(SCH_1):PAGE103

M_G_CPU1_SA_DQ<14> @T6G_MB_LIB.T6G(SCH_1):M_G_CPU1_SA_DQ(14)
   U26   T2 MGA_DATA14 GENOA_SP5-SOCKET6096_13568-001,SMLF,IO,DGA^6000030   I167 @T6G_MB_LIB.T6G(SCH_1):PAGE43
  J102  170 DQ14_A SCONN288_DDR506112002KQ-SCONN288_DDR506112002KQ,SMA    I22 @T6G_MB_LIB.T6G(SCH_1):PAGE103

M_G_CPU1_SA_DQ<15> @T6G_MB_LIB.T6G(SCH_1):M_G_CPU1_SA_DQ(15)
   U26   U3 MGA_DATA15 GENOA_SP5-SOCKET6096_13568-001,SMLF,IO,DGA^6000030   I167 @T6G_MB_LIB.T6G(SCH_1):PAGE43
  J102  172 DQ15_A SCONN288_DDR506112002KQ-SCONN288_DDR506112002KQ,SMA    I22 @T6G_MB_LIB.T6G(SCH_1):PAGE103

M_G_CPU1_SA_DQ<16> @T6G_MB_LIB.T6G(SCH_1):M_G_CPU1_SA_DQ(16)
   U26   U2 MGA_DATA16 GENOA_SP5-SOCKET6096_13568-001,SMLF,IO,DGA^6000030   I167 @T6G_MB_LIB.T6G(SCH_1):PAGE43
  J102   29 DQ16_A SCONN288_DDR506112002KQ-SCONN288_DDR506112002KQ,SMA    I22 @T6G_MB_LIB.T6G(SCH_1):PAGE103

M_G_CPU1_SA_DQ<17> @T6G_MB_LIB.T6G(SCH_1):M_G_CPU1_SA_DQ(17)
   U26   V4 MGA_DATA17 GENOA_SP5-SOCKET6096_13568-001,SMLF,IO,DGA^6000030   I167 @T6G_MB_LIB.T6G(SCH_1):PAGE43
  J102   31 DQ17_A SCONN288_DDR506112002KQ-SCONN288_DDR506112002KQ,SMA    I22 @T6G_MB_LIB.T6G(SCH_1):PAGE103

M_G_CPU1_SA_DQ<18> @T6G_MB_LIB.T6G(SCH_1):M_G_CPU1_SA_DQ(18)
   U26   V2 MGA_DATA18 GENOA_SP5-SOCKET6096_13568-001,SMLF,IO,DGA^6000030   I167 @T6G_MB_LIB.T6G(SCH_1):PAGE43
  J102  174 DQ18_A SCONN288_DDR506112002KQ-SCONN288_DDR506112002KQ,SMA    I22 @T6G_MB_LIB.T6G(SCH_1):PAGE103

M_G_CPU1_SA_DQ<19> @T6G_MB_LIB.T6G(SCH_1):M_G_CPU1_SA_DQ(19)
   U26   W3 MGA_DATA19 GENOA_SP5-SOCKET6096_13568-001,SMLF,IO,DGA^6000030   I167 @T6G_MB_LIB.T6G(SCH_1):PAGE43
  J102  176 DQ19_A SCONN288_DDR506112002KQ-SCONN288_DDR506112002KQ,SMA    I22 @T6G_MB_LIB.T6G(SCH_1):PAGE103

M_G_CPU1_SA_DQ<1> @T6G_MB_LIB.T6G(SCH_1):M_G_CPU1_SA_DQ(1)
   U26   F4 MGA_DATA1 GENOA_SP5-SOCKET6096_13568-001,SMLF,IO,DGA^6000030   I167 @T6G_MB_LIB.T6G(SCH_1):PAGE43
  J102    9  DQ1_A SCONN288_DDR506112002KQ-SCONN288_DDR506112002KQ,SMA    I22 @T6G_MB_LIB.T6G(SCH_1):PAGE103

M_G_CPU1_SA_DQ<20> @T6G_MB_LIB.T6G(SCH_1):M_G_CPU1_SA_DQ(20)
   U26  AA2 MGA_DATA20 GENOA_SP5-SOCKET6096_13568-001,SMLF,IO,DGA^6000030   I167 @T6G_MB_LIB.T6G(SCH_1):PAGE43
  J102   36 DQ20_A SCONN288_DDR506112002KQ-SCONN288_DDR506112002KQ,SMA    I22 @T6G_MB_LIB.T6G(SCH_1):PAGE103

M_G_CPU1_SA_DQ<21> @T6G_MB_LIB.T6G(SCH_1):M_G_CPU1_SA_DQ(21)
   U26  AB4 MGA_DATA21 GENOA_SP5-SOCKET6096_13568-001,SMLF,IO,DGA^6000030   I167 @T6G_MB_LIB.T6G(SCH_1):PAGE43
  J102   38 DQ21_A SCONN288_DDR506112002KQ-SCONN288_DDR506112002KQ,SMA    I22 @T6G_MB_LIB.T6G(SCH_1):PAGE103

M_G_CPU1_SA_DQ<22> @T6G_MB_LIB.T6G(SCH_1):M_G_CPU1_SA_DQ(22)
   U26  AB2 MGA_DATA22 GENOA_SP5-SOCKET6096_13568-001,SMLF,IO,DGA^6000030   I167 @T6G_MB_LIB.T6G(SCH_1):PAGE43
  J102  181 DQ22_A SCONN288_DDR506112002KQ-SCONN288_DDR506112002KQ,SMA    I22 @T6G_MB_LIB.T6G(SCH_1):PAGE103

M_G_CPU1_SA_DQ<23> @T6G_MB_LIB.T6G(SCH_1):M_G_CPU1_SA_DQ(23)
   U26  AC3 MGA_DATA23 GENOA_SP5-SOCKET6096_13568-001,SMLF,IO,DGA^6000030   I167 @T6G_MB_LIB.T6G(SCH_1):PAGE43
  J102  183 DQ23_A SCONN288_DDR506112002KQ-SCONN288_DDR506112002KQ,SMA    I22 @T6G_MB_LIB.T6G(SCH_1):PAGE103

M_G_CPU1_SA_DQ<24> @T6G_MB_LIB.T6G(SCH_1):M_G_CPU1_SA_DQ(24)
   U26  AC2 MGA_DATA24 GENOA_SP5-SOCKET6096_13568-001,SMLF,IO,DGA^6000030   I167 @T6G_MB_LIB.T6G(SCH_1):PAGE43
  J102   40 DQ24_A SCONN288_DDR506112002KQ-SCONN288_DDR506112002KQ,SMA    I22 @T6G_MB_LIB.T6G(SCH_1):PAGE103

M_G_CPU1_SA_DQ<25> @T6G_MB_LIB.T6G(SCH_1):M_G_CPU1_SA_DQ(25)
   U26  AD4 MGA_DATA25 GENOA_SP5-SOCKET6096_13568-001,SMLF,IO,DGA^6000030   I167 @T6G_MB_LIB.T6G(SCH_1):PAGE43
  J102   42 DQ25_A SCONN288_DDR506112002KQ-SCONN288_DDR506112002KQ,SMA    I22 @T6G_MB_LIB.T6G(SCH_1):PAGE103

M_G_CPU1_SA_DQ<26> @T6G_MB_LIB.T6G(SCH_1):M_G_CPU1_SA_DQ(26)
   U26  AD2 MGA_DATA26 GENOA_SP5-SOCKET6096_13568-001,SMLF,IO,DGA^6000030   I167 @T6G_MB_LIB.T6G(SCH_1):PAGE43
  J102  185 DQ26_A SCONN288_DDR506112002KQ-SCONN288_DDR506112002KQ,SMA    I22 @T6G_MB_LIB.T6G(SCH_1):PAGE103

M_G_CPU1_SA_DQ<27> @T6G_MB_LIB.T6G(SCH_1):M_G_CPU1_SA_DQ(27)
   U26  AE3 MGA_DATA27 GENOA_SP5-SOCKET6096_13568-001,SMLF,IO,DGA^6000030   I167 @T6G_MB_LIB.T6G(SCH_1):PAGE43
  J102  187 DQ27_A SCONN288_DDR506112002KQ-SCONN288_DDR506112002KQ,SMA    I22 @T6G_MB_LIB.T6G(SCH_1):PAGE103

M_G_CPU1_SA_DQ<28> @T6G_MB_LIB.T6G(SCH_1):M_G_CPU1_SA_DQ(28)
   U26  AG2 MGA_DATA28 GENOA_SP5-SOCKET6096_13568-001,SMLF,IO,DGA^6000030   I167 @T6G_MB_LIB.T6G(SCH_1):PAGE43
  J102   47 DQ28_A SCONN288_DDR506112002KQ-SCONN288_DDR506112002KQ,SMA    I22 @T6G_MB_LIB.T6G(SCH_1):PAGE103

M_G_CPU1_SA_DQ<29> @T6G_MB_LIB.T6G(SCH_1):M_G_CPU1_SA_DQ(29)
   U26  AH4 MGA_DATA29 GENOA_SP5-SOCKET6096_13568-001,SMLF,IO,DGA^6000030   I167 @T6G_MB_LIB.T6G(SCH_1):PAGE43
  J102   49 DQ29_A SCONN288_DDR506112002KQ-SCONN288_DDR506112002KQ,SMA    I22 @T6G_MB_LIB.T6G(SCH_1):PAGE103

M_G_CPU1_SA_DQ<2> @T6G_MB_LIB.T6G(SCH_1):M_G_CPU1_SA_DQ(2)
   U26   F2 MGA_DATA2 GENOA_SP5-SOCKET6096_13568-001,SMLF,IO,DGA^6000030   I167 @T6G_MB_LIB.T6G(SCH_1):PAGE43
  J102  152  DQ2_A SCONN288_DDR506112002KQ-SCONN288_DDR506112002KQ,SMA    I22 @T6G_MB_LIB.T6G(SCH_1):PAGE103

M_G_CPU1_SA_DQ<30> @T6G_MB_LIB.T6G(SCH_1):M_G_CPU1_SA_DQ(30)
   U26  AH2 MGA_DATA30 GENOA_SP5-SOCKET6096_13568-001,SMLF,IO,DGA^6000030   I167 @T6G_MB_LIB.T6G(SCH_1):PAGE43
  J102  192 DQ30_A SCONN288_DDR506112002KQ-SCONN288_DDR506112002KQ,SMA    I22 @T6G_MB_LIB.T6G(SCH_1):PAGE103

M_G_CPU1_SA_DQ<31> @T6G_MB_LIB.T6G(SCH_1):M_G_CPU1_SA_DQ(31)
   U26  AJ3 MGA_DATA31 GENOA_SP5-SOCKET6096_13568-001,SMLF,IO,DGA^6000030   I167 @T6G_MB_LIB.T6G(SCH_1):PAGE43
  J102  194 DQ31_A SCONN288_DDR506112002KQ-SCONN288_DDR506112002KQ,SMA    I22 @T6G_MB_LIB.T6G(SCH_1):PAGE103

M_G_CPU1_SA_DQ<3> @T6G_MB_LIB.T6G(SCH_1):M_G_CPU1_SA_DQ(3)
   U26   G3 MGA_DATA3 GENOA_SP5-SOCKET6096_13568-001,SMLF,IO,DGA^6000030   I167 @T6G_MB_LIB.T6G(SCH_1):PAGE43
  J102  154  DQ3_A SCONN288_DDR506112002KQ-SCONN288_DDR506112002KQ,SMA    I22 @T6G_MB_LIB.T6G(SCH_1):PAGE103

M_G_CPU1_SA_DQ<4> @T6G_MB_LIB.T6G(SCH_1):M_G_CPU1_SA_DQ(4)
   U26   J2 MGA_DATA4 GENOA_SP5-SOCKET6096_13568-001,SMLF,IO,DGA^6000030   I167 @T6G_MB_LIB.T6G(SCH_1):PAGE43
  J102   14  DQ4_A SCONN288_DDR506112002KQ-SCONN288_DDR506112002KQ,SMA    I22 @T6G_MB_LIB.T6G(SCH_1):PAGE103

M_G_CPU1_SA_DQ<5> @T6G_MB_LIB.T6G(SCH_1):M_G_CPU1_SA_DQ(5)
   U26   K4 MGA_DATA5 GENOA_SP5-SOCKET6096_13568-001,SMLF,IO,DGA^6000030   I167 @T6G_MB_LIB.T6G(SCH_1):PAGE43
  J102   16  DQ5_A SCONN288_DDR506112002KQ-SCONN288_DDR506112002KQ,SMA    I22 @T6G_MB_LIB.T6G(SCH_1):PAGE103

M_G_CPU1_SA_DQ<6> @T6G_MB_LIB.T6G(SCH_1):M_G_CPU1_SA_DQ(6)
   U26   K2 MGA_DATA6 GENOA_SP5-SOCKET6096_13568-001,SMLF,IO,DGA^6000030   I167 @T6G_MB_LIB.T6G(SCH_1):PAGE43
  J102  159  DQ6_A SCONN288_DDR506112002KQ-SCONN288_DDR506112002KQ,SMA    I22 @T6G_MB_LIB.T6G(SCH_1):PAGE103

M_G_CPU1_SA_DQ<7> @T6G_MB_LIB.T6G(SCH_1):M_G_CPU1_SA_DQ(7)
   U26   L3 MGA_DATA7 GENOA_SP5-SOCKET6096_13568-001,SMLF,IO,DGA^6000030   I167 @T6G_MB_LIB.T6G(SCH_1):PAGE43
  J102  161  DQ7_A SCONN288_DDR506112002KQ-SCONN288_DDR506112002KQ,SMA    I22 @T6G_MB_LIB.T6G(SCH_1):PAGE103

M_G_CPU1_SA_DQ<8> @T6G_MB_LIB.T6G(SCH_1):M_G_CPU1_SA_DQ(8)
   U26   L2 MGA_DATA8 GENOA_SP5-SOCKET6096_13568-001,SMLF,IO,DGA^6000030   I167 @T6G_MB_LIB.T6G(SCH_1):PAGE43
  J102   18  DQ8_A SCONN288_DDR506112002KQ-SCONN288_DDR506112002KQ,SMA    I22 @T6G_MB_LIB.T6G(SCH_1):PAGE103

M_G_CPU1_SA_DQ<9> @T6G_MB_LIB.T6G(SCH_1):M_G_CPU1_SA_DQ(9)
   U26   M4 MGA_DATA9 GENOA_SP5-SOCKET6096_13568-001,SMLF,IO,DGA^6000030   I167 @T6G_MB_LIB.T6G(SCH_1):PAGE43
  J102   20  DQ9_A SCONN288_DDR506112002KQ-SCONN288_DDR506112002KQ,SMA    I22 @T6G_MB_LIB.T6G(SCH_1):PAGE103

M_G_CPU1_SA_DQS_DN<0> @T6G_MB_LIB.T6G(SCH_1):M_G_CPU1_SA_DQS_DN(0)
   U26   H2 MGA_DQS_L0 GENOA_SP5-SOCKET6096_13568-001,SMLF,IO,DGA^6000030   I167 @T6G_MB_LIB.T6G(SCH_1):PAGE43
  J102   12 DQS0_A_C SCONN288_DDR506112002KQ-SCONN288_DDR506112002KQ,SMA   I238 @T6G_MB_LIB.T6G(SCH_1):PAGE103

M_G_CPU1_SA_DQS_DN<1> @T6G_MB_LIB.T6G(SCH_1):M_G_CPU1_SA_DQS_DN(1)
   U26   P2 MGA_DQS_L1 GENOA_SP5-SOCKET6096_13568-001,SMLF,IO,DGA^6000030   I167 @T6G_MB_LIB.T6G(SCH_1):PAGE43
  J102   23 DQS1_A_C SCONN288_DDR506112002KQ-SCONN288_DDR506112002KQ,SMA   I238 @T6G_MB_LIB.T6G(SCH_1):PAGE103

M_G_CPU1_SA_DQS_DN<2> @T6G_MB_LIB.T6G(SCH_1):M_G_CPU1_SA_DQS_DN(2)
   U26   Y2 MGA_DQS_L2 GENOA_SP5-SOCKET6096_13568-001,SMLF,IO,DGA^6000030   I167 @T6G_MB_LIB.T6G(SCH_1):PAGE43
  J102   34 DQS2_A_C SCONN288_DDR506112002KQ-SCONN288_DDR506112002KQ,SMA   I238 @T6G_MB_LIB.T6G(SCH_1):PAGE103

M_G_CPU1_SA_DQS_DN<3> @T6G_MB_LIB.T6G(SCH_1):M_G_CPU1_SA_DQS_DN(3)
   U26  AF2 MGA_DQS_L3 GENOA_SP5-SOCKET6096_13568-001,SMLF,IO,DGA^6000030   I167 @T6G_MB_LIB.T6G(SCH_1):PAGE43
  J102   45 DQS3_A_C SCONN288_DDR506112002KQ-SCONN288_DDR506112002KQ,SMA   I238 @T6G_MB_LIB.T6G(SCH_1):PAGE103

M_G_CPU1_SA_DQS_DN<4> @T6G_MB_LIB.T6G(SCH_1):M_G_CPU1_SA_DQS_DN(4)
   U26  AM2 MGA_DQS_L4 GENOA_SP5-SOCKET6096_13568-001,SMLF,IO,DGA^6000030   I167 @T6G_MB_LIB.T6G(SCH_1):PAGE43
  J102   56 DQS4_A_C SCONN288_DDR506112002KQ-SCONN288_DDR506112002KQ,SMA   I238 @T6G_MB_LIB.T6G(SCH_1):PAGE103

M_G_CPU1_SA_DQS_DN<5> @T6G_MB_LIB.T6G(SCH_1):M_G_CPU1_SA_DQS_DN(5)
   U26   H4 MGA_DQS_L5 GENOA_SP5-SOCKET6096_13568-001,SMLF,IO,DGA^6000030   I167 @T6G_MB_LIB.T6G(SCH_1):PAGE43
  J102  156 DQS5_A_C||TDQS5_A_C||DQS5_A_T||TDQS5_A_T SCONN288_DDR506112002KQ-SCONN288_DDR506112002KQ,SMA   I238 @T6G_MB_LIB.T6G(SCH_1):PAGE103

M_G_CPU1_SA_DQS_DN<6> @T6G_MB_LIB.T6G(SCH_1):M_G_CPU1_SA_DQS_DN(6)
   U26   P4 MGA_DQS_L6 GENOA_SP5-SOCKET6096_13568-001,SMLF,IO,DGA^6000030   I167 @T6G_MB_LIB.T6G(SCH_1):PAGE43
  J102  167 DQS6_A_C||TDQS6_A_C||DQS6_A_T||TDQS6_A_T SCONN288_DDR506112002KQ-SCONN288_DDR506112002KQ,SMA   I238 @T6G_MB_LIB.T6G(SCH_1):PAGE103

M_G_CPU1_SA_DQS_DN<7> @T6G_MB_LIB.T6G(SCH_1):M_G_CPU1_SA_DQS_DN(7)
   U26   Y4 MGA_DQS_L7 GENOA_SP5-SOCKET6096_13568-001,SMLF,IO,DGA^6000030   I167 @T6G_MB_LIB.T6G(SCH_1):PAGE43
  J102  178 DQS7_A_C||TDQS7_A_C SCONN288_DDR506112002KQ-SCONN288_DDR506112002KQ,SMA   I238 @T6G_MB_LIB.T6G(SCH_1):PAGE103

M_G_CPU1_SA_DQS_DN<8> @T6G_MB_LIB.T6G(SCH_1):M_G_CPU1_SA_DQS_DN(8)
   U26  AF4 MGA_DQS_L8 GENOA_SP5-SOCKET6096_13568-001,SMLF,IO,DGA^6000030   I167 @T6G_MB_LIB.T6G(SCH_1):PAGE43
  J102  189 DQS8_A_C||TDQS8_A_C SCONN288_DDR506112002KQ-SCONN288_DDR506112002KQ,SMA   I238 @T6G_MB_LIB.T6G(SCH_1):PAGE103

M_G_CPU1_SA_DQS_DN<9> @T6G_MB_LIB.T6G(SCH_1):M_G_CPU1_SA_DQS_DN(9)
   U26  AM4 MGA_DQS_L9 GENOA_SP5-SOCKET6096_13568-001,SMLF,IO,DGA^6000030   I167 @T6G_MB_LIB.T6G(SCH_1):PAGE43
  J102  200 DQS9_A_C||TDQS9_A_C SCONN288_DDR506112002KQ-SCONN288_DDR506112002KQ,SMA   I238 @T6G_MB_LIB.T6G(SCH_1):PAGE103

M_G_CPU1_SA_DQS_DP<0> @T6G_MB_LIB.T6G(SCH_1):M_G_CPU1_SA_DQS_DP(0)
   U26   G2 MGA_DQS_H0 GENOA_SP5-SOCKET6096_13568-001,SMLF,IO,DGA^6000030   I167 @T6G_MB_LIB.T6G(SCH_1):PAGE43
  J102   11 DQS0_A_T SCONN288_DDR506112002KQ-SCONN288_DDR506112002KQ,SMA   I238 @T6G_MB_LIB.T6G(SCH_1):PAGE103

M_G_CPU1_SA_DQS_DP<1> @T6G_MB_LIB.T6G(SCH_1):M_G_CPU1_SA_DQS_DP(1)
   U26   N2 MGA_DQS_H1 GENOA_SP5-SOCKET6096_13568-001,SMLF,IO,DGA^6000030   I167 @T6G_MB_LIB.T6G(SCH_1):PAGE43
  J102   22 DQS1_A_T SCONN288_DDR506112002KQ-SCONN288_DDR506112002KQ,SMA   I238 @T6G_MB_LIB.T6G(SCH_1):PAGE103

M_G_CPU1_SA_DQS_DP<2> @T6G_MB_LIB.T6G(SCH_1):M_G_CPU1_SA_DQS_DP(2)
   U26   W2 MGA_DQS_H2 GENOA_SP5-SOCKET6096_13568-001,SMLF,IO,DGA^6000030   I167 @T6G_MB_LIB.T6G(SCH_1):PAGE43
  J102   33 DQS2_A_T SCONN288_DDR506112002KQ-SCONN288_DDR506112002KQ,SMA   I238 @T6G_MB_LIB.T6G(SCH_1):PAGE103

M_G_CPU1_SA_DQS_DP<3> @T6G_MB_LIB.T6G(SCH_1):M_G_CPU1_SA_DQS_DP(3)
   U26  AE2 MGA_DQS_H3 GENOA_SP5-SOCKET6096_13568-001,SMLF,IO,DGA^6000030   I167 @T6G_MB_LIB.T6G(SCH_1):PAGE43
  J102   44 DQS3_A_T SCONN288_DDR506112002KQ-SCONN288_DDR506112002KQ,SMA   I238 @T6G_MB_LIB.T6G(SCH_1):PAGE103

M_G_CPU1_SA_DQS_DP<4> @T6G_MB_LIB.T6G(SCH_1):M_G_CPU1_SA_DQS_DP(4)
   U26  AL2 MGA_DQS_H4 GENOA_SP5-SOCKET6096_13568-001,SMLF,IO,DGA^6000030   I167 @T6G_MB_LIB.T6G(SCH_1):PAGE43
  J102   55 DQS4_A_T SCONN288_DDR506112002KQ-SCONN288_DDR506112002KQ,SMA   I238 @T6G_MB_LIB.T6G(SCH_1):PAGE103

M_G_CPU1_SA_DQS_DP<5> @T6G_MB_LIB.T6G(SCH_1):M_G_CPU1_SA_DQS_DP(5)
   U26   J3 MGA_DQS_H5 GENOA_SP5-SOCKET6096_13568-001,SMLF,IO,DGA^6000030   I167 @T6G_MB_LIB.T6G(SCH_1):PAGE43
  J102  157 DQS5_A_T||TDQS5_A_T SCONN288_DDR506112002KQ-SCONN288_DDR506112002KQ,SMA   I238 @T6G_MB_LIB.T6G(SCH_1):PAGE103

M_G_CPU1_SA_DQS_DP<6> @T6G_MB_LIB.T6G(SCH_1):M_G_CPU1_SA_DQS_DP(6)
   U26   R3 MGA_DQS_H6 GENOA_SP5-SOCKET6096_13568-001,SMLF,IO,DGA^6000030   I167 @T6G_MB_LIB.T6G(SCH_1):PAGE43
  J102  168 DQS6_A_T||TDQS6_A_T SCONN288_DDR506112002KQ-SCONN288_DDR506112002KQ,SMA   I238 @T6G_MB_LIB.T6G(SCH_1):PAGE103

M_G_CPU1_SA_DQS_DP<7> @T6G_MB_LIB.T6G(SCH_1):M_G_CPU1_SA_DQS_DP(7)
   U26  AA3 MGA_DQS_H7 GENOA_SP5-SOCKET6096_13568-001,SMLF,IO,DGA^6000030   I167 @T6G_MB_LIB.T6G(SCH_1):PAGE43
  J102  179 DQS7_A_T||TDQS7_A_T SCONN288_DDR506112002KQ-SCONN288_DDR506112002KQ,SMA   I238 @T6G_MB_LIB.T6G(SCH_1):PAGE103

M_G_CPU1_SA_DQS_DP<8> @T6G_MB_LIB.T6G(SCH_1):M_G_CPU1_SA_DQS_DP(8)
   U26  AG3 MGA_DQS_H8 GENOA_SP5-SOCKET6096_13568-001,SMLF,IO,DGA^6000030   I167 @T6G_MB_LIB.T6G(SCH_1):PAGE43
  J102  190 DQS8_A_T||TDQS8_A_T SCONN288_DDR506112002KQ-SCONN288_DDR506112002KQ,SMA   I238 @T6G_MB_LIB.T6G(SCH_1):PAGE103

M_G_CPU1_SA_DQS_DP<9> @T6G_MB_LIB.T6G(SCH_1):M_G_CPU1_SA_DQS_DP(9)
   U26  AN3 MGA_DQS_H9 GENOA_SP5-SOCKET6096_13568-001,SMLF,IO,DGA^6000030   I167 @T6G_MB_LIB.T6G(SCH_1):PAGE43
  J102  201 DQS9_A_T||TDQS9_A_T SCONN288_DDR506112002KQ-SCONN288_DDR506112002KQ,SMA   I238 @T6G_MB_LIB.T6G(SCH_1):PAGE103

M_G_CPU1_SA_PAR @T6G_MB_LIB.T6G(SCH_1):M_G_CPU1_SA_PAR
   U26  BC3 MGA_PAR GENOA_SP5-SOCKET6096_13568-001,SMLF,IO,DGA^6000030   I167 @T6G_MB_LIB.T6G(SCH_1):PAGE43
  J102   74  PAR_A SCONN288_DDR506112002KQ-SCONN288_DDR506112002KQ,SMA    I22 @T6G_MB_LIB.T6G(SCH_1):PAGE103

M_G_CPU1_SA_RSP<0> @T6G_MB_LIB.T6G(SCH_1):M_G_CPU1_SA_RSP(0)
   U26  BN3 MGA0_RSP_L GENOA_SP5-SOCKET6096_13568-001,SMLF,IO,DGA^6000030   I167 @T6G_MB_LIB.T6G(SCH_1):PAGE43
  J102   86 LBD||RSP_A_N SCONN288_DDR506112002KQ-SCONN288_DDR506112002KQ,SMA    I22 @T6G_MB_LIB.T6G(SCH_1):PAGE103

M_G_CPU1_SB_CA<0> @T6G_MB_LIB.T6G(SCH_1):M_G_CPU1_SB_CA(0)
   U26  BG3 MGB_CA0 GENOA_SP5-SOCKET6096_13568-001,SMLF,IO,DGA^6000030   I167 @T6G_MB_LIB.T6G(SCH_1):PAGE43
  J102   76  CA0_B SCONN288_DDR506112002KQ-SCONN288_DDR506112002KQ,SMA    I22 @T6G_MB_LIB.T6G(SCH_1):PAGE103

M_G_CPU1_SB_CA<1> @T6G_MB_LIB.T6G(SCH_1):M_G_CPU1_SB_CA(1)
   U26  BH4 MGB_CA1 GENOA_SP5-SOCKET6096_13568-001,SMLF,IO,DGA^6000030   I167 @T6G_MB_LIB.T6G(SCH_1):PAGE43
  J102  221  CA1_B SCONN288_DDR506112002KQ-SCONN288_DDR506112002KQ,SMA    I22 @T6G_MB_LIB.T6G(SCH_1):PAGE103

M_G_CPU1_SB_CA<2> @T6G_MB_LIB.T6G(SCH_1):M_G_CPU1_SB_CA(2)
   U26  BH2 MGB_CA2 GENOA_SP5-SOCKET6096_13568-001,SMLF,IO,DGA^6000030   I167 @T6G_MB_LIB.T6G(SCH_1):PAGE43
  J102   78  CA2_B SCONN288_DDR506112002KQ-SCONN288_DDR506112002KQ,SMA    I22 @T6G_MB_LIB.T6G(SCH_1):PAGE103

M_G_CPU1_SB_CA<3> @T6G_MB_LIB.T6G(SCH_1):M_G_CPU1_SB_CA(3)
   U26  BJ2 MGB_CA3 GENOA_SP5-SOCKET6096_13568-001,SMLF,IO,DGA^6000030   I167 @T6G_MB_LIB.T6G(SCH_1):PAGE43
  J102  223  CA3_B SCONN288_DDR506112002KQ-SCONN288_DDR506112002KQ,SMA    I22 @T6G_MB_LIB.T6G(SCH_1):PAGE103

M_G_CPU1_SB_CA<4> @T6G_MB_LIB.T6G(SCH_1):M_G_CPU1_SB_CA(4)
   U26  BJ3 MGB_CA4 GENOA_SP5-SOCKET6096_13568-001,SMLF,IO,DGA^6000030   I167 @T6G_MB_LIB.T6G(SCH_1):PAGE43
  J102   80  CA4_B SCONN288_DDR506112002KQ-SCONN288_DDR506112002KQ,SMA    I22 @T6G_MB_LIB.T6G(SCH_1):PAGE103

M_G_CPU1_SB_CA<5> @T6G_MB_LIB.T6G(SCH_1):M_G_CPU1_SB_CA(5)
   U26  BK4 MGB_CA5 GENOA_SP5-SOCKET6096_13568-001,SMLF,IO,DGA^6000030   I167 @T6G_MB_LIB.T6G(SCH_1):PAGE43
  J102  225  CA5_B SCONN288_DDR506112002KQ-SCONN288_DDR506112002KQ,SMA    I22 @T6G_MB_LIB.T6G(SCH_1):PAGE103

M_G_CPU1_SB_CA<6> @T6G_MB_LIB.T6G(SCH_1):M_G_CPU1_SB_CA(6)
   U26  BK2 MGB_CA6 GENOA_SP5-SOCKET6096_13568-001,SMLF,IO,DGA^6000030   I167 @T6G_MB_LIB.T6G(SCH_1):PAGE43
  J102   82  CA6_B SCONN288_DDR506112002KQ-SCONN288_DDR506112002KQ,SMA    I22 @T6G_MB_LIB.T6G(SCH_1):PAGE103

M_G_CPU1_SB_CB<0> @T6G_MB_LIB.T6G(SCH_1):M_G_CPU1_SB_CB(0)
   U26  BY2 MGB_CHECK0 GENOA_SP5-SOCKET6096_13568-001,SMLF,IO,DGA^6000030   I167 @T6G_MB_LIB.T6G(SCH_1):PAGE43
  J102   96  CB0_B SCONN288_DDR506112002KQ-SCONN288_DDR506112002KQ,SMA    I22 @T6G_MB_LIB.T6G(SCH_1):PAGE103

M_G_CPU1_SB_CB<1> @T6G_MB_LIB.T6G(SCH_1):M_G_CPU1_SB_CB(1)
   U26  CA3 MGB_CHECK1 GENOA_SP5-SOCKET6096_13568-001,SMLF,IO,DGA^6000030   I167 @T6G_MB_LIB.T6G(SCH_1):PAGE43
  J102   98  CB1_B SCONN288_DDR506112002KQ-SCONN288_DDR506112002KQ,SMA    I22 @T6G_MB_LIB.T6G(SCH_1):PAGE103

M_G_CPU1_SB_CB<2> @T6G_MB_LIB.T6G(SCH_1):M_G_CPU1_SB_CB(2)
   U26  CA2 MGB_CHECK2 GENOA_SP5-SOCKET6096_13568-001,SMLF,IO,DGA^6000030   I167 @T6G_MB_LIB.T6G(SCH_1):PAGE43
  J102  241  CB2_B SCONN288_DDR506112002KQ-SCONN288_DDR506112002KQ,SMA    I22 @T6G_MB_LIB.T6G(SCH_1):PAGE103

M_G_CPU1_SB_CB<3> @T6G_MB_LIB.T6G(SCH_1):M_G_CPU1_SB_CB(3)
   U26  CB4 MGB_CHECK3 GENOA_SP5-SOCKET6096_13568-001,SMLF,IO,DGA^6000030   I167 @T6G_MB_LIB.T6G(SCH_1):PAGE43
  J102  243  CB3_B SCONN288_DDR506112002KQ-SCONN288_DDR506112002KQ,SMA    I22 @T6G_MB_LIB.T6G(SCH_1):PAGE103

M_G_CPU1_SB_CB<4> @T6G_MB_LIB.T6G(SCH_1):M_G_CPU1_SB_CB(4)
   U26  BT2 MGB_CHECK4 GENOA_SP5-SOCKET6096_13568-001,SMLF,IO,DGA^6000030   I167 @T6G_MB_LIB.T6G(SCH_1):PAGE43
  J102   89  CB4_B SCONN288_DDR506112002KQ-SCONN288_DDR506112002KQ,SMA    I22 @T6G_MB_LIB.T6G(SCH_1):PAGE103

M_G_CPU1_SB_CB<5> @T6G_MB_LIB.T6G(SCH_1):M_G_CPU1_SB_CB(5)
   U26  BU3 MGB_CHECK5 GENOA_SP5-SOCKET6096_13568-001,SMLF,IO,DGA^6000030   I167 @T6G_MB_LIB.T6G(SCH_1):PAGE43
  J102   91  CB5_B SCONN288_DDR506112002KQ-SCONN288_DDR506112002KQ,SMA    I22 @T6G_MB_LIB.T6G(SCH_1):PAGE103

M_G_CPU1_SB_CB<6> @T6G_MB_LIB.T6G(SCH_1):M_G_CPU1_SB_CB(6)
   U26  BU2 MGB_CHECK6 GENOA_SP5-SOCKET6096_13568-001,SMLF,IO,DGA^6000030   I167 @T6G_MB_LIB.T6G(SCH_1):PAGE43
  J102  234  CB6_B SCONN288_DDR506112002KQ-SCONN288_DDR506112002KQ,SMA    I22 @T6G_MB_LIB.T6G(SCH_1):PAGE103

M_G_CPU1_SB_CB<7> @T6G_MB_LIB.T6G(SCH_1):M_G_CPU1_SB_CB(7)
   U26  BV4 MGB_CHECK7 GENOA_SP5-SOCKET6096_13568-001,SMLF,IO,DGA^6000030   I167 @T6G_MB_LIB.T6G(SCH_1):PAGE43
  J102  236  CB7_B SCONN288_DDR506112002KQ-SCONN288_DDR506112002KQ,SMA    I22 @T6G_MB_LIB.T6G(SCH_1):PAGE103

M_G_CPU1_SB_CS_N<0> @T6G_MB_LIB.T6G(SCH_1):M_G_CPU1_SB_CS_N(0)
   U26  BM4 MGB0_CS_L0 GENOA_SP5-SOCKET6096_13568-001,SMLF,IO,DGA^6000030   I167 @T6G_MB_LIB.T6G(SCH_1):PAGE43
  J102   84 CS0_B_N SCONN288_DDR506112002KQ-SCONN288_DDR506112002KQ,SMA    I22 @T6G_MB_LIB.T6G(SCH_1):PAGE103

M_G_CPU1_SB_CS_N<1> @T6G_MB_LIB.T6G(SCH_1):M_G_CPU1_SB_CS_N(1)
   U26  BN2 MGB0_CS_L1 GENOA_SP5-SOCKET6096_13568-001,SMLF,IO,DGA^6000030   I167 @T6G_MB_LIB.T6G(SCH_1):PAGE43
  J102  229 CS1_B_N SCONN288_DDR506112002KQ-SCONN288_DDR506112002KQ,SMA    I22 @T6G_MB_LIB.T6G(SCH_1):PAGE103

M_G_CPU1_SB_DQ<0> @T6G_MB_LIB.T6G(SCH_1):M_G_CPU1_SB_DQ(0)
   U26  CB2 MGB_DATA0 GENOA_SP5-SOCKET6096_13568-001,SMLF,IO,DGA^6000030   I167 @T6G_MB_LIB.T6G(SCH_1):PAGE43
  J102  100  DQ0_B SCONN288_DDR506112002KQ-SCONN288_DDR506112002KQ,SMA    I22 @T6G_MB_LIB.T6G(SCH_1):PAGE103

M_G_CPU1_SB_DQ<10> @T6G_MB_LIB.T6G(SCH_1):M_G_CPU1_SB_DQ(10)
   U26  CJ2 MGB_DATA10 GENOA_SP5-SOCKET6096_13568-001,SMLF,IO,DGA^6000030   I167 @T6G_MB_LIB.T6G(SCH_1):PAGE43
  J102  256 DQ10_B SCONN288_DDR506112002KQ-SCONN288_DDR506112002KQ,SMA    I22 @T6G_MB_LIB.T6G(SCH_1):PAGE103

M_G_CPU1_SB_DQ<11> @T6G_MB_LIB.T6G(SCH_1):M_G_CPU1_SB_DQ(11)
   U26  CK4 MGB_DATA11 GENOA_SP5-SOCKET6096_13568-001,SMLF,IO,DGA^6000030   I167 @T6G_MB_LIB.T6G(SCH_1):PAGE43
  J102  258 DQ11_B SCONN288_DDR506112002KQ-SCONN288_DDR506112002KQ,SMA    I22 @T6G_MB_LIB.T6G(SCH_1):PAGE103

M_G_CPU1_SB_DQ<12> @T6G_MB_LIB.T6G(SCH_1):M_G_CPU1_SB_DQ(12)
   U26  CM2 MGB_DATA12 GENOA_SP5-SOCKET6096_13568-001,SMLF,IO,DGA^6000030   I167 @T6G_MB_LIB.T6G(SCH_1):PAGE43
  J102  118 DQ12_B SCONN288_DDR506112002KQ-SCONN288_DDR506112002KQ,SMA    I22 @T6G_MB_LIB.T6G(SCH_1):PAGE103

M_G_CPU1_SB_DQ<13> @T6G_MB_LIB.T6G(SCH_1):M_G_CPU1_SB_DQ(13)
   U26  CN3 MGB_DATA13 GENOA_SP5-SOCKET6096_13568-001,SMLF,IO,DGA^6000030   I167 @T6G_MB_LIB.T6G(SCH_1):PAGE43
  J102  120 DQ13_B SCONN288_DDR506112002KQ-SCONN288_DDR506112002KQ,SMA    I22 @T6G_MB_LIB.T6G(SCH_1):PAGE103

M_G_CPU1_SB_DQ<14> @T6G_MB_LIB.T6G(SCH_1):M_G_CPU1_SB_DQ(14)
   U26  CN2 MGB_DATA14 GENOA_SP5-SOCKET6096_13568-001,SMLF,IO,DGA^6000030   I167 @T6G_MB_LIB.T6G(SCH_1):PAGE43
  J102  263 DQ14_B SCONN288_DDR506112002KQ-SCONN288_DDR506112002KQ,SMA    I22 @T6G_MB_LIB.T6G(SCH_1):PAGE103

M_G_CPU1_SB_DQ<15> @T6G_MB_LIB.T6G(SCH_1):M_G_CPU1_SB_DQ(15)
   U26  CP4 MGB_DATA15 GENOA_SP5-SOCKET6096_13568-001,SMLF,IO,DGA^6000030   I167 @T6G_MB_LIB.T6G(SCH_1):PAGE43
  J102  265 DQ15_B SCONN288_DDR506112002KQ-SCONN288_DDR506112002KQ,SMA    I22 @T6G_MB_LIB.T6G(SCH_1):PAGE103

M_G_CPU1_SB_DQ<16> @T6G_MB_LIB.T6G(SCH_1):M_G_CPU1_SB_DQ(16)
   U26  CP2 MGB_DATA16 GENOA_SP5-SOCKET6096_13568-001,SMLF,IO,DGA^6000030   I167 @T6G_MB_LIB.T6G(SCH_1):PAGE43
  J102  122 DQ16_B SCONN288_DDR506112002KQ-SCONN288_DDR506112002KQ,SMA    I22 @T6G_MB_LIB.T6G(SCH_1):PAGE103

M_G_CPU1_SB_DQ<17> @T6G_MB_LIB.T6G(SCH_1):M_G_CPU1_SB_DQ(17)
   U26  CR3 MGB_DATA17 GENOA_SP5-SOCKET6096_13568-001,SMLF,IO,DGA^6000030   I167 @T6G_MB_LIB.T6G(SCH_1):PAGE43
  J102  124 DQ17_B SCONN288_DDR506112002KQ-SCONN288_DDR506112002KQ,SMA    I22 @T6G_MB_LIB.T6G(SCH_1):PAGE103

M_G_CPU1_SB_DQ<18> @T6G_MB_LIB.T6G(SCH_1):M_G_CPU1_SB_DQ(18)
   U26  CR2 MGB_DATA18 GENOA_SP5-SOCKET6096_13568-001,SMLF,IO,DGA^6000030   I167 @T6G_MB_LIB.T6G(SCH_1):PAGE43
  J102  267 DQ18_B SCONN288_DDR506112002KQ-SCONN288_DDR506112002KQ,SMA    I22 @T6G_MB_LIB.T6G(SCH_1):PAGE103

M_G_CPU1_SB_DQ<19> @T6G_MB_LIB.T6G(SCH_1):M_G_CPU1_SB_DQ(19)
   U26  CT4 MGB_DATA19 GENOA_SP5-SOCKET6096_13568-001,SMLF,IO,DGA^6000030   I167 @T6G_MB_LIB.T6G(SCH_1):PAGE43
  J102  269 DQ19_B SCONN288_DDR506112002KQ-SCONN288_DDR506112002KQ,SMA    I22 @T6G_MB_LIB.T6G(SCH_1):PAGE103

M_G_CPU1_SB_DQ<1> @T6G_MB_LIB.T6G(SCH_1):M_G_CPU1_SB_DQ(1)
   U26  CC3 MGB_DATA1 GENOA_SP5-SOCKET6096_13568-001,SMLF,IO,DGA^6000030   I167 @T6G_MB_LIB.T6G(SCH_1):PAGE43
  J102  102  DQ1_B SCONN288_DDR506112002KQ-SCONN288_DDR506112002KQ,SMA    I22 @T6G_MB_LIB.T6G(SCH_1):PAGE103

M_G_CPU1_SB_DQ<20> @T6G_MB_LIB.T6G(SCH_1):M_G_CPU1_SB_DQ(20)
   U26  CV2 MGB_DATA20 GENOA_SP5-SOCKET6096_13568-001,SMLF,IO,DGA^6000030   I167 @T6G_MB_LIB.T6G(SCH_1):PAGE43
  J102  129 DQ20_B SCONN288_DDR506112002KQ-SCONN288_DDR506112002KQ,SMA    I22 @T6G_MB_LIB.T6G(SCH_1):PAGE103

M_G_CPU1_SB_DQ<21> @T6G_MB_LIB.T6G(SCH_1):M_G_CPU1_SB_DQ(21)
   U26  CW3 MGB_DATA21 GENOA_SP5-SOCKET6096_13568-001,SMLF,IO,DGA^6000030   I167 @T6G_MB_LIB.T6G(SCH_1):PAGE43
  J102  131 DQ21_B SCONN288_DDR506112002KQ-SCONN288_DDR506112002KQ,SMA    I22 @T6G_MB_LIB.T6G(SCH_1):PAGE103

M_G_CPU1_SB_DQ<22> @T6G_MB_LIB.T6G(SCH_1):M_G_CPU1_SB_DQ(22)
   U26  CW2 MGB_DATA22 GENOA_SP5-SOCKET6096_13568-001,SMLF,IO,DGA^6000030   I167 @T6G_MB_LIB.T6G(SCH_1):PAGE43
  J102  274 DQ22_B SCONN288_DDR506112002KQ-SCONN288_DDR506112002KQ,SMA    I22 @T6G_MB_LIB.T6G(SCH_1):PAGE103

M_G_CPU1_SB_DQ<23> @T6G_MB_LIB.T6G(SCH_1):M_G_CPU1_SB_DQ(23)
   U26  CY4 MGB_DATA23 GENOA_SP5-SOCKET6096_13568-001,SMLF,IO,DGA^6000030   I167 @T6G_MB_LIB.T6G(SCH_1):PAGE43
  J102  276 DQ23_B SCONN288_DDR506112002KQ-SCONN288_DDR506112002KQ,SMA    I22 @T6G_MB_LIB.T6G(SCH_1):PAGE103

M_G_CPU1_SB_DQ<24> @T6G_MB_LIB.T6G(SCH_1):M_G_CPU1_SB_DQ(24)
   U26  CY2 MGB_DATA24 GENOA_SP5-SOCKET6096_13568-001,SMLF,IO,DGA^6000030   I167 @T6G_MB_LIB.T6G(SCH_1):PAGE43
  J102  133 DQ24_B SCONN288_DDR506112002KQ-SCONN288_DDR506112002KQ,SMA    I22 @T6G_MB_LIB.T6G(SCH_1):PAGE103

M_G_CPU1_SB_DQ<25> @T6G_MB_LIB.T6G(SCH_1):M_G_CPU1_SB_DQ(25)
   U26  DA3 MGB_DATA25 GENOA_SP5-SOCKET6096_13568-001,SMLF,IO,DGA^6000030   I167 @T6G_MB_LIB.T6G(SCH_1):PAGE43
  J102  135 DQ25_B SCONN288_DDR506112002KQ-SCONN288_DDR506112002KQ,SMA    I22 @T6G_MB_LIB.T6G(SCH_1):PAGE103

M_G_CPU1_SB_DQ<26> @T6G_MB_LIB.T6G(SCH_1):M_G_CPU1_SB_DQ(26)
   U26  DA2 MGB_DATA26 GENOA_SP5-SOCKET6096_13568-001,SMLF,IO,DGA^6000030   I167 @T6G_MB_LIB.T6G(SCH_1):PAGE43
  J102  278 DQ26_B SCONN288_DDR506112002KQ-SCONN288_DDR506112002KQ,SMA    I22 @T6G_MB_LIB.T6G(SCH_1):PAGE103

M_G_CPU1_SB_DQ<27> @T6G_MB_LIB.T6G(SCH_1):M_G_CPU1_SB_DQ(27)
   U26  DB4 MGB_DATA27 GENOA_SP5-SOCKET6096_13568-001,SMLF,IO,DGA^6000030   I167 @T6G_MB_LIB.T6G(SCH_1):PAGE43
  J102  280 DQ27_B SCONN288_DDR506112002KQ-SCONN288_DDR506112002KQ,SMA    I22 @T6G_MB_LIB.T6G(SCH_1):PAGE103

M_G_CPU1_SB_DQ<28> @T6G_MB_LIB.T6G(SCH_1):M_G_CPU1_SB_DQ(28)
   U26  DD2 MGB_DATA28 GENOA_SP5-SOCKET6096_13568-001,SMLF,IO,DGA^6000030   I167 @T6G_MB_LIB.T6G(SCH_1):PAGE43
  J102  140 DQ28_B SCONN288_DDR506112002KQ-SCONN288_DDR506112002KQ,SMA    I22 @T6G_MB_LIB.T6G(SCH_1):PAGE103

M_G_CPU1_SB_DQ<29> @T6G_MB_LIB.T6G(SCH_1):M_G_CPU1_SB_DQ(29)
   U26  DE3 MGB_DATA29 GENOA_SP5-SOCKET6096_13568-001,SMLF,IO,DGA^6000030   I167 @T6G_MB_LIB.T6G(SCH_1):PAGE43
  J102  142 DQ29_B SCONN288_DDR506112002KQ-SCONN288_DDR506112002KQ,SMA    I22 @T6G_MB_LIB.T6G(SCH_1):PAGE103

M_G_CPU1_SB_DQ<2> @T6G_MB_LIB.T6G(SCH_1):M_G_CPU1_SB_DQ(2)
   U26  CC2 MGB_DATA2 GENOA_SP5-SOCKET6096_13568-001,SMLF,IO,DGA^6000030   I167 @T6G_MB_LIB.T6G(SCH_1):PAGE43
  J102  245  DQ2_B SCONN288_DDR506112002KQ-SCONN288_DDR506112002KQ,SMA    I22 @T6G_MB_LIB.T6G(SCH_1):PAGE103

M_G_CPU1_SB_DQ<30> @T6G_MB_LIB.T6G(SCH_1):M_G_CPU1_SB_DQ(30)
   U26  DE2 MGB_DATA30 GENOA_SP5-SOCKET6096_13568-001,SMLF,IO,DGA^6000030   I167 @T6G_MB_LIB.T6G(SCH_1):PAGE43
  J102  285 DQ30_B SCONN288_DDR506112002KQ-SCONN288_DDR506112002KQ,SMA    I22 @T6G_MB_LIB.T6G(SCH_1):PAGE103

M_G_CPU1_SB_DQ<31> @T6G_MB_LIB.T6G(SCH_1):M_G_CPU1_SB_DQ(31)
   U26  DF2 MGB_DATA31 GENOA_SP5-SOCKET6096_13568-001,SMLF,IO,DGA^6000030   I167 @T6G_MB_LIB.T6G(SCH_1):PAGE43
  J102  287 DQ31_B SCONN288_DDR506112002KQ-SCONN288_DDR506112002KQ,SMA    I22 @T6G_MB_LIB.T6G(SCH_1):PAGE103

M_G_CPU1_SB_DQ<3> @T6G_MB_LIB.T6G(SCH_1):M_G_CPU1_SB_DQ(3)
   U26  CD4 MGB_DATA3 GENOA_SP5-SOCKET6096_13568-001,SMLF,IO,DGA^6000030   I167 @T6G_MB_LIB.T6G(SCH_1):PAGE43
  J102  247  DQ3_B SCONN288_DDR506112002KQ-SCONN288_DDR506112002KQ,SMA    I22 @T6G_MB_LIB.T6G(SCH_1):PAGE103

M_G_CPU1_SB_DQ<4> @T6G_MB_LIB.T6G(SCH_1):M_G_CPU1_SB_DQ(4)
   U26  CF2 MGB_DATA4 GENOA_SP5-SOCKET6096_13568-001,SMLF,IO,DGA^6000030   I167 @T6G_MB_LIB.T6G(SCH_1):PAGE43
  J102  107  DQ4_B SCONN288_DDR506112002KQ-SCONN288_DDR506112002KQ,SMA    I22 @T6G_MB_LIB.T6G(SCH_1):PAGE103

M_G_CPU1_SB_DQ<5> @T6G_MB_LIB.T6G(SCH_1):M_G_CPU1_SB_DQ(5)
   U26  CG3 MGB_DATA5 GENOA_SP5-SOCKET6096_13568-001,SMLF,IO,DGA^6000030   I167 @T6G_MB_LIB.T6G(SCH_1):PAGE43
  J102  109  DQ5_B SCONN288_DDR506112002KQ-SCONN288_DDR506112002KQ,SMA    I22 @T6G_MB_LIB.T6G(SCH_1):PAGE103

M_G_CPU1_SB_DQ<6> @T6G_MB_LIB.T6G(SCH_1):M_G_CPU1_SB_DQ(6)
   U26  CG2 MGB_DATA6 GENOA_SP5-SOCKET6096_13568-001,SMLF,IO,DGA^6000030   I167 @T6G_MB_LIB.T6G(SCH_1):PAGE43
  J102  252  DQ6_B SCONN288_DDR506112002KQ-SCONN288_DDR506112002KQ,SMA    I22 @T6G_MB_LIB.T6G(SCH_1):PAGE103

M_G_CPU1_SB_DQ<7> @T6G_MB_LIB.T6G(SCH_1):M_G_CPU1_SB_DQ(7)
   U26  CH4 MGB_DATA7 GENOA_SP5-SOCKET6096_13568-001,SMLF,IO,DGA^6000030   I167 @T6G_MB_LIB.T6G(SCH_1):PAGE43
  J102  254  DQ7_B SCONN288_DDR506112002KQ-SCONN288_DDR506112002KQ,SMA    I22 @T6G_MB_LIB.T6G(SCH_1):PAGE103

M_G_CPU1_SB_DQ<8> @T6G_MB_LIB.T6G(SCH_1):M_G_CPU1_SB_DQ(8)
   U26  CH2 MGB_DATA8 GENOA_SP5-SOCKET6096_13568-001,SMLF,IO,DGA^6000030   I167 @T6G_MB_LIB.T6G(SCH_1):PAGE43
  J102  111  DQ8_B SCONN288_DDR506112002KQ-SCONN288_DDR506112002KQ,SMA    I22 @T6G_MB_LIB.T6G(SCH_1):PAGE103

M_G_CPU1_SB_DQ<9> @T6G_MB_LIB.T6G(SCH_1):M_G_CPU1_SB_DQ(9)
   U26  CJ3 MGB_DATA9 GENOA_SP5-SOCKET6096_13568-001,SMLF,IO,DGA^6000030   I167 @T6G_MB_LIB.T6G(SCH_1):PAGE43
  J102  113  DQ9_B SCONN288_DDR506112002KQ-SCONN288_DDR506112002KQ,SMA    I22 @T6G_MB_LIB.T6G(SCH_1):PAGE103

M_G_CPU1_SB_DQS_DN<0> @T6G_MB_LIB.T6G(SCH_1):M_G_CPU1_SB_DQS_DN(0)
   U26  CE2 MGB_DQS_L0 GENOA_SP5-SOCKET6096_13568-001,SMLF,IO,DGA^6000030   I167 @T6G_MB_LIB.T6G(SCH_1):PAGE43
  J102  105 DQS0_B_C SCONN288_DDR506112002KQ-SCONN288_DDR506112002KQ,SMA   I238 @T6G_MB_LIB.T6G(SCH_1):PAGE103

M_G_CPU1_SB_DQS_DN<1> @T6G_MB_LIB.T6G(SCH_1):M_G_CPU1_SB_DQS_DN(1)
   U26  CL2 MGB_DQS_L1 GENOA_SP5-SOCKET6096_13568-001,SMLF,IO,DGA^6000030   I167 @T6G_MB_LIB.T6G(SCH_1):PAGE43
  J102  116 DQS1_B_C SCONN288_DDR506112002KQ-SCONN288_DDR506112002KQ,SMA   I238 @T6G_MB_LIB.T6G(SCH_1):PAGE103

M_G_CPU1_SB_DQS_DN<2> @T6G_MB_LIB.T6G(SCH_1):M_G_CPU1_SB_DQS_DN(2)
   U26  CU2 MGB_DQS_L2 GENOA_SP5-SOCKET6096_13568-001,SMLF,IO,DGA^6000030   I167 @T6G_MB_LIB.T6G(SCH_1):PAGE43
  J102  127 DQS2_B_C SCONN288_DDR506112002KQ-SCONN288_DDR506112002KQ,SMA   I238 @T6G_MB_LIB.T6G(SCH_1):PAGE103

M_G_CPU1_SB_DQS_DN<3> @T6G_MB_LIB.T6G(SCH_1):M_G_CPU1_SB_DQS_DN(3)
   U26  DC2 MGB_DQS_L3 GENOA_SP5-SOCKET6096_13568-001,SMLF,IO,DGA^6000030   I167 @T6G_MB_LIB.T6G(SCH_1):PAGE43
  J102  138 DQS3_B_C SCONN288_DDR506112002KQ-SCONN288_DDR506112002KQ,SMA   I238 @T6G_MB_LIB.T6G(SCH_1):PAGE103

M_G_CPU1_SB_DQS_DN<4> @T6G_MB_LIB.T6G(SCH_1):M_G_CPU1_SB_DQS_DN(4)
   U26  BW3 MGB_DQS_L4 GENOA_SP5-SOCKET6096_13568-001,SMLF,IO,DGA^6000030   I167 @T6G_MB_LIB.T6G(SCH_1):PAGE43
  J102  238 DQS4_B_C SCONN288_DDR506112002KQ-SCONN288_DDR506112002KQ,SMA   I238 @T6G_MB_LIB.T6G(SCH_1):PAGE103

M_G_CPU1_SB_DQS_DN<5> @T6G_MB_LIB.T6G(SCH_1):M_G_CPU1_SB_DQS_DN(5)
   U26  CE3 MGB_DQS_L5 GENOA_SP5-SOCKET6096_13568-001,SMLF,IO,DGA^6000030   I167 @T6G_MB_LIB.T6G(SCH_1):PAGE43
  J102  249 DQS5_B_C||TDQS5_B_C SCONN288_DDR506112002KQ-SCONN288_DDR506112002KQ,SMA   I238 @T6G_MB_LIB.T6G(SCH_1):PAGE103

M_G_CPU1_SB_DQS_DN<6> @T6G_MB_LIB.T6G(SCH_1):M_G_CPU1_SB_DQS_DN(6)
   U26  CL3 MGB_DQS_L6 GENOA_SP5-SOCKET6096_13568-001,SMLF,IO,DGA^6000030   I167 @T6G_MB_LIB.T6G(SCH_1):PAGE43
  J102  260 DQS6_B_C||TDQS6_B_C SCONN288_DDR506112002KQ-SCONN288_DDR506112002KQ,SMA   I238 @T6G_MB_LIB.T6G(SCH_1):PAGE103

M_G_CPU1_SB_DQS_DN<7> @T6G_MB_LIB.T6G(SCH_1):M_G_CPU1_SB_DQS_DN(7)
   U26  CU3 MGB_DQS_L7 GENOA_SP5-SOCKET6096_13568-001,SMLF,IO,DGA^6000030   I167 @T6G_MB_LIB.T6G(SCH_1):PAGE43
  J102  271 DQS7_B_C||TDQS7_B_C SCONN288_DDR506112002KQ-SCONN288_DDR506112002KQ,SMA   I238 @T6G_MB_LIB.T6G(SCH_1):PAGE103

M_G_CPU1_SB_DQS_DN<8> @T6G_MB_LIB.T6G(SCH_1):M_G_CPU1_SB_DQS_DN(8)
   U26  DC3 MGB_DQS_L8 GENOA_SP5-SOCKET6096_13568-001,SMLF,IO,DGA^6000030   I167 @T6G_MB_LIB.T6G(SCH_1):PAGE43
  J102  282 DQS8_B_C||TDQS8_B_C SCONN288_DDR506112002KQ-SCONN288_DDR506112002KQ,SMA   I238 @T6G_MB_LIB.T6G(SCH_1):PAGE103

M_G_CPU1_SB_DQS_DN<9> @T6G_MB_LIB.T6G(SCH_1):M_G_CPU1_SB_DQS_DN(9)
   U26  BW2 MGB_DQS_L9 GENOA_SP5-SOCKET6096_13568-001,SMLF,IO,DGA^6000030   I167 @T6G_MB_LIB.T6G(SCH_1):PAGE43
  J102   94 DQS9_B_C||TDQS9_B_C SCONN288_DDR506112002KQ-SCONN288_DDR506112002KQ,SMA   I238 @T6G_MB_LIB.T6G(SCH_1):PAGE103

M_G_CPU1_SB_DQS_DP<0> @T6G_MB_LIB.T6G(SCH_1):M_G_CPU1_SB_DQS_DP(0)
   U26  CD2 MGB_DQS_H0 GENOA_SP5-SOCKET6096_13568-001,SMLF,IO,DGA^6000030   I167 @T6G_MB_LIB.T6G(SCH_1):PAGE43
  J102  104 DQS0_B_T SCONN288_DDR506112002KQ-SCONN288_DDR506112002KQ,SMA   I238 @T6G_MB_LIB.T6G(SCH_1):PAGE103

M_G_CPU1_SB_DQS_DP<1> @T6G_MB_LIB.T6G(SCH_1):M_G_CPU1_SB_DQS_DP(1)
   U26  CK2 MGB_DQS_H1 GENOA_SP5-SOCKET6096_13568-001,SMLF,IO,DGA^6000030   I167 @T6G_MB_LIB.T6G(SCH_1):PAGE43
  J102  115 DQS1_B_T SCONN288_DDR506112002KQ-SCONN288_DDR506112002KQ,SMA   I238 @T6G_MB_LIB.T6G(SCH_1):PAGE103

M_G_CPU1_SB_DQS_DP<2> @T6G_MB_LIB.T6G(SCH_1):M_G_CPU1_SB_DQS_DP(2)
   U26  CT2 MGB_DQS_H2 GENOA_SP5-SOCKET6096_13568-001,SMLF,IO,DGA^6000030   I167 @T6G_MB_LIB.T6G(SCH_1):PAGE43
  J102  126 DQS2_B_T SCONN288_DDR506112002KQ-SCONN288_DDR506112002KQ,SMA   I238 @T6G_MB_LIB.T6G(SCH_1):PAGE103

M_G_CPU1_SB_DQS_DP<3> @T6G_MB_LIB.T6G(SCH_1):M_G_CPU1_SB_DQS_DP(3)
   U26  DB2 MGB_DQS_H3 GENOA_SP5-SOCKET6096_13568-001,SMLF,IO,DGA^6000030   I167 @T6G_MB_LIB.T6G(SCH_1):PAGE43
  J102  137 DQS3_B_T SCONN288_DDR506112002KQ-SCONN288_DDR506112002KQ,SMA   I238 @T6G_MB_LIB.T6G(SCH_1):PAGE103

M_G_CPU1_SB_DQS_DP<4> @T6G_MB_LIB.T6G(SCH_1):M_G_CPU1_SB_DQS_DP(4)
   U26  BY4 MGB_DQS_H4 GENOA_SP5-SOCKET6096_13568-001,SMLF,IO,DGA^6000030   I167 @T6G_MB_LIB.T6G(SCH_1):PAGE43
  J102  239 DQS4_B_T SCONN288_DDR506112002KQ-SCONN288_DDR506112002KQ,SMA   I238 @T6G_MB_LIB.T6G(SCH_1):PAGE103

M_G_CPU1_SB_DQS_DP<5> @T6G_MB_LIB.T6G(SCH_1):M_G_CPU1_SB_DQS_DP(5)
   U26  CF4 MGB_DQS_H5 GENOA_SP5-SOCKET6096_13568-001,SMLF,IO,DGA^6000030   I167 @T6G_MB_LIB.T6G(SCH_1):PAGE43
  J102  250 DQS5_B_T||TDQS5_B_T SCONN288_DDR506112002KQ-SCONN288_DDR506112002KQ,SMA   I238 @T6G_MB_LIB.T6G(SCH_1):PAGE103

M_G_CPU1_SB_DQS_DP<6> @T6G_MB_LIB.T6G(SCH_1):M_G_CPU1_SB_DQS_DP(6)
   U26  CM4 MGB_DQS_H6 GENOA_SP5-SOCKET6096_13568-001,SMLF,IO,DGA^6000030   I167 @T6G_MB_LIB.T6G(SCH_1):PAGE43
  J102  261 DQS6_B_T||TDQS6_B_T SCONN288_DDR506112002KQ-SCONN288_DDR506112002KQ,SMA   I238 @T6G_MB_LIB.T6G(SCH_1):PAGE103

M_G_CPU1_SB_DQS_DP<7> @T6G_MB_LIB.T6G(SCH_1):M_G_CPU1_SB_DQS_DP(7)
   U26  CV4 MGB_DQS_H7 GENOA_SP5-SOCKET6096_13568-001,SMLF,IO,DGA^6000030   I167 @T6G_MB_LIB.T6G(SCH_1):PAGE43
  J102  272 DQS7_B_T||TDQS7_B_T SCONN288_DDR506112002KQ-SCONN288_DDR506112002KQ,SMA   I238 @T6G_MB_LIB.T6G(SCH_1):PAGE103

M_G_CPU1_SB_DQS_DP<8> @T6G_MB_LIB.T6G(SCH_1):M_G_CPU1_SB_DQS_DP(8)
   U26  DD4 MGB_DQS_H8 GENOA_SP5-SOCKET6096_13568-001,SMLF,IO,DGA^6000030   I167 @T6G_MB_LIB.T6G(SCH_1):PAGE43
  J102  283 DQS8_B_T||TDQS8_B_T SCONN288_DDR506112002KQ-SCONN288_DDR506112002KQ,SMA   I238 @T6G_MB_LIB.T6G(SCH_1):PAGE103

M_G_CPU1_SB_DQS_DP<9> @T6G_MB_LIB.T6G(SCH_1):M_G_CPU1_SB_DQS_DP(9)
   U26  BV2 MGB_DQS_H9 GENOA_SP5-SOCKET6096_13568-001,SMLF,IO,DGA^6000030   I167 @T6G_MB_LIB.T6G(SCH_1):PAGE43
  J102   93 DQS9_B_T||TDQS9_B_T||DBI4_B_N SCONN288_DDR506112002KQ-SCONN288_DDR506112002KQ,SMA   I238 @T6G_MB_LIB.T6G(SCH_1):PAGE103

M_G_CPU1_SB_PAR @T6G_MB_LIB.T6G(SCH_1):M_G_CPU1_SB_PAR
   U26  BL3 MGB_PAR GENOA_SP5-SOCKET6096_13568-001,SMLF,IO,DGA^6000030   I167 @T6G_MB_LIB.T6G(SCH_1):PAGE43
  J102  227  PAR_B SCONN288_DDR506112002KQ-SCONN288_DDR506112002KQ,SMA    I22 @T6G_MB_LIB.T6G(SCH_1):PAGE103

M_G_CPU1_SB_RSP<0> @T6G_MB_LIB.T6G(SCH_1):M_G_CPU1_SB_RSP(0)
   U26  BP2 MGB0_RSP_L GENOA_SP5-SOCKET6096_13568-001,SMLF,IO,DGA^6000030   I167 @T6G_MB_LIB.T6G(SCH_1):PAGE43
  J102   87 LBS||RSP_B_N SCONN288_DDR506112002KQ-SCONN288_DDR506112002KQ,SMA    I22 @T6G_MB_LIB.T6G(SCH_1):PAGE103

M_H_CPU0_ALERT_N @T6G_MB_LIB.T6G(SCH_1):M_H_CPU0_ALERT_N
  R382    1      A Q_RES_0402LF-15,1%,1/16W,CHIP,CS01502FB03   I314 @T6G_MB_LIB.T6G(SCH_1):PAGE17
   J69   62 ALERT_N SCONN288_DDR506112002KQ-SCONN288_DDR506112002KQ,SMA    I22 @T6G_MB_LIB.T6G(SCH_1):PAGE92

M_H_CPU0_ALERT_R_N @T6G_MB_LIB.T6G(SCH_1):M_H_CPU0_ALERT_R_N
   U25 AT14 MH_ALERT_L GENOA_SP5-SOCKET6096_13568-001,SMLF,IO,DGA^6000030   I159 @T6G_MB_LIB.T6G(SCH_1):PAGE17
  R382    2      B Q_RES_0402LF-15,1%,1/16W,CHIP,CS01502FB03   I314 @T6G_MB_LIB.T6G(SCH_1):PAGE17

M_H_CPU0_CLK_DN<0> @T6G_MB_LIB.T6G(SCH_1):M_H_CPU0_CLK_DN(0)
   U25 BD13 MH0_CLK_L GENOA_SP5-SOCKET6096_13568-001,SMLF,IO,DGA^6000030   I159 @T6G_MB_LIB.T6G(SCH_1):PAGE17
   J69  218   CK_C SCONN288_DDR506112002KQ-SCONN288_DDR506112002KQ,SMA    I22 @T6G_MB_LIB.T6G(SCH_1):PAGE92

M_H_CPU0_CLK_DP<0> @T6G_MB_LIB.T6G(SCH_1):M_H_CPU0_CLK_DP(0)
   U25 BC12 MH0_CLK_H GENOA_SP5-SOCKET6096_13568-001,SMLF,IO,DGA^6000030   I159 @T6G_MB_LIB.T6G(SCH_1):PAGE17
   J69  217   CK_T SCONN288_DDR506112002KQ-SCONN288_DDR506112002KQ,SMA    I22 @T6G_MB_LIB.T6G(SCH_1):PAGE92

M_H_CPU0_RESET_N @T6G_MB_LIB.T6G(SCH_1):M_H_CPU0_RESET_N
   U25 AU14 MH_RESET_L GENOA_SP5-SOCKET6096_13568-001,SMLF,IO,DGA^6000030   I159 @T6G_MB_LIB.T6G(SCH_1):PAGE17
   J69  207 RESET_N SCONN288_DDR506112002KQ-SCONN288_DDR506112002KQ,SMA    I22 @T6G_MB_LIB.T6G(SCH_1):PAGE92

M_H_CPU0_SA_CA<0> @T6G_MB_LIB.T6G(SCH_1):M_H_CPU0_SA_CA(0)
   U25 AW12 MHA_CA0 GENOA_SP5-SOCKET6096_13568-001,SMLF,IO,DGA^6000030   I159 @T6G_MB_LIB.T6G(SCH_1):PAGE17
   J69   66  CA0_A SCONN288_DDR506112002KQ-SCONN288_DDR506112002KQ,SMA    I22 @T6G_MB_LIB.T6G(SCH_1):PAGE92

M_H_CPU0_SA_CA<1> @T6G_MB_LIB.T6G(SCH_1):M_H_CPU0_SA_CA(1)
   U25 AY13 MHA_CA1 GENOA_SP5-SOCKET6096_13568-001,SMLF,IO,DGA^6000030   I159 @T6G_MB_LIB.T6G(SCH_1):PAGE17
   J69  211  CA1_A SCONN288_DDR506112002KQ-SCONN288_DDR506112002KQ,SMA    I22 @T6G_MB_LIB.T6G(SCH_1):PAGE92

M_H_CPU0_SA_CA<2> @T6G_MB_LIB.T6G(SCH_1):M_H_CPU0_SA_CA(2)
   U25 AY14 MHA_CA2 GENOA_SP5-SOCKET6096_13568-001,SMLF,IO,DGA^6000030   I159 @T6G_MB_LIB.T6G(SCH_1):PAGE17
   J69   68  CA2_A SCONN288_DDR506112002KQ-SCONN288_DDR506112002KQ,SMA    I22 @T6G_MB_LIB.T6G(SCH_1):PAGE92

M_H_CPU0_SA_CA<3> @T6G_MB_LIB.T6G(SCH_1):M_H_CPU0_SA_CA(3)
   U25 BA14 MHA_CA3 GENOA_SP5-SOCKET6096_13568-001,SMLF,IO,DGA^6000030   I159 @T6G_MB_LIB.T6G(SCH_1):PAGE17
   J69  213  CA3_A SCONN288_DDR506112002KQ-SCONN288_DDR506112002KQ,SMA    I22 @T6G_MB_LIB.T6G(SCH_1):PAGE92

M_H_CPU0_SA_CA<4> @T6G_MB_LIB.T6G(SCH_1):M_H_CPU0_SA_CA(4)
   U25 BA12 MHA_CA4 GENOA_SP5-SOCKET6096_13568-001,SMLF,IO,DGA^6000030   I159 @T6G_MB_LIB.T6G(SCH_1):PAGE17
   J69   70  CA4_A SCONN288_DDR506112002KQ-SCONN288_DDR506112002KQ,SMA    I22 @T6G_MB_LIB.T6G(SCH_1):PAGE92

M_H_CPU0_SA_CA<5> @T6G_MB_LIB.T6G(SCH_1):M_H_CPU0_SA_CA(5)
   U25 BB13 MHA_CA5 GENOA_SP5-SOCKET6096_13568-001,SMLF,IO,DGA^6000030   I159 @T6G_MB_LIB.T6G(SCH_1):PAGE17
   J69  215  CA5_A SCONN288_DDR506112002KQ-SCONN288_DDR506112002KQ,SMA    I22 @T6G_MB_LIB.T6G(SCH_1):PAGE92

M_H_CPU0_SA_CA<6> @T6G_MB_LIB.T6G(SCH_1):M_H_CPU0_SA_CA(6)
   U25 BB14 MHA_CA6 GENOA_SP5-SOCKET6096_13568-001,SMLF,IO,DGA^6000030   I159 @T6G_MB_LIB.T6G(SCH_1):PAGE17
   J69   72  CA6_A SCONN288_DDR506112002KQ-SCONN288_DDR506112002KQ,SMA    I22 @T6G_MB_LIB.T6G(SCH_1):PAGE92

M_H_CPU0_SA_CB<0> @T6G_MB_LIB.T6G(SCH_1):M_H_CPU0_SA_CB(0)
   U25 AJ12 MHA_CHECK0 GENOA_SP5-SOCKET6096_13568-001,SMLF,IO,DGA^6000030   I159 @T6G_MB_LIB.T6G(SCH_1):PAGE17
   J69   51  CB0_A SCONN288_DDR506112002KQ-SCONN288_DDR506112002KQ,SMA    I22 @T6G_MB_LIB.T6G(SCH_1):PAGE92

M_H_CPU0_SA_CB<1> @T6G_MB_LIB.T6G(SCH_1):M_H_CPU0_SA_CB(1)
   U25 AK14 MHA_CHECK1 GENOA_SP5-SOCKET6096_13568-001,SMLF,IO,DGA^6000030   I159 @T6G_MB_LIB.T6G(SCH_1):PAGE17
   J69   53  CB1_A SCONN288_DDR506112002KQ-SCONN288_DDR506112002KQ,SMA    I22 @T6G_MB_LIB.T6G(SCH_1):PAGE92

M_H_CPU0_SA_CB<2> @T6G_MB_LIB.T6G(SCH_1):M_H_CPU0_SA_CB(2)
   U25 AK13 MHA_CHECK2 GENOA_SP5-SOCKET6096_13568-001,SMLF,IO,DGA^6000030   I159 @T6G_MB_LIB.T6G(SCH_1):PAGE17
   J69  196  CB2_A SCONN288_DDR506112002KQ-SCONN288_DDR506112002KQ,SMA    I22 @T6G_MB_LIB.T6G(SCH_1):PAGE92

M_H_CPU0_SA_CB<3> @T6G_MB_LIB.T6G(SCH_1):M_H_CPU0_SA_CB(3)
   U25 AL14 MHA_CHECK3 GENOA_SP5-SOCKET6096_13568-001,SMLF,IO,DGA^6000030   I159 @T6G_MB_LIB.T6G(SCH_1):PAGE17
   J69  198  CB3_A SCONN288_DDR506112002KQ-SCONN288_DDR506112002KQ,SMA    I22 @T6G_MB_LIB.T6G(SCH_1):PAGE92

M_H_CPU0_SA_CB<4> @T6G_MB_LIB.T6G(SCH_1):M_H_CPU0_SA_CB(4)
   U25 AN12 MHA_CHECK4 GENOA_SP5-SOCKET6096_13568-001,SMLF,IO,DGA^6000030   I159 @T6G_MB_LIB.T6G(SCH_1):PAGE17
   J69   58  CB4_A SCONN288_DDR506112002KQ-SCONN288_DDR506112002KQ,SMA    I22 @T6G_MB_LIB.T6G(SCH_1):PAGE92

M_H_CPU0_SA_CB<5> @T6G_MB_LIB.T6G(SCH_1):M_H_CPU0_SA_CB(5)
   U25 AP14 MHA_CHECK5 GENOA_SP5-SOCKET6096_13568-001,SMLF,IO,DGA^6000030   I159 @T6G_MB_LIB.T6G(SCH_1):PAGE17
   J69   60  CB5_A SCONN288_DDR506112002KQ-SCONN288_DDR506112002KQ,SMA    I22 @T6G_MB_LIB.T6G(SCH_1):PAGE92

M_H_CPU0_SA_CB<6> @T6G_MB_LIB.T6G(SCH_1):M_H_CPU0_SA_CB(6)
   U25 AP13 MHA_CHECK6 GENOA_SP5-SOCKET6096_13568-001,SMLF,IO,DGA^6000030   I159 @T6G_MB_LIB.T6G(SCH_1):PAGE17
   J69  203  CB6_A SCONN288_DDR506112002KQ-SCONN288_DDR506112002KQ,SMA    I22 @T6G_MB_LIB.T6G(SCH_1):PAGE92

M_H_CPU0_SA_CB<7> @T6G_MB_LIB.T6G(SCH_1):M_H_CPU0_SA_CB(7)
   U25 AR14 MHA_CHECK7 GENOA_SP5-SOCKET6096_13568-001,SMLF,IO,DGA^6000030   I159 @T6G_MB_LIB.T6G(SCH_1):PAGE17
   J69  205  CB7_A SCONN288_DDR506112002KQ-SCONN288_DDR506112002KQ,SMA    I22 @T6G_MB_LIB.T6G(SCH_1):PAGE92

M_H_CPU0_SA_CS_N<0> @T6G_MB_LIB.T6G(SCH_1):M_H_CPU0_SA_CS_N(0)
   U25 AU12 MHA0_CS_L0 GENOA_SP5-SOCKET6096_13568-001,SMLF,IO,DGA^6000030   I159 @T6G_MB_LIB.T6G(SCH_1):PAGE17
   J69   64 CS0_A_N SCONN288_DDR506112002KQ-SCONN288_DDR506112002KQ,SMA    I22 @T6G_MB_LIB.T6G(SCH_1):PAGE92

M_H_CPU0_SA_CS_N<1> @T6G_MB_LIB.T6G(SCH_1):M_H_CPU0_SA_CS_N(1)
   U25 AV14 MHA0_CS_L1 GENOA_SP5-SOCKET6096_13568-001,SMLF,IO,DGA^6000030   I159 @T6G_MB_LIB.T6G(SCH_1):PAGE17
   J69  209 CS1_A_N SCONN288_DDR506112002KQ-SCONN288_DDR506112002KQ,SMA    I22 @T6G_MB_LIB.T6G(SCH_1):PAGE92

M_H_CPU0_SA_DQ<0> @T6G_MB_LIB.T6G(SCH_1):M_H_CPU0_SA_DQ(0)
   U25  E12 MHA_DATA0 GENOA_SP5-SOCKET6096_13568-001,SMLF,IO,DGA^6000030   I159 @T6G_MB_LIB.T6G(SCH_1):PAGE17
   J69    7  DQ0_A SCONN288_DDR506112002KQ-SCONN288_DDR506112002KQ,SMA    I22 @T6G_MB_LIB.T6G(SCH_1):PAGE92

M_H_CPU0_SA_DQ<10> @T6G_MB_LIB.T6G(SCH_1):M_H_CPU0_SA_DQ(10)
   U25  M13 MHA_DATA10 GENOA_SP5-SOCKET6096_13568-001,SMLF,IO,DGA^6000030   I159 @T6G_MB_LIB.T6G(SCH_1):PAGE17
   J69  163 DQ10_A SCONN288_DDR506112002KQ-SCONN288_DDR506112002KQ,SMA    I22 @T6G_MB_LIB.T6G(SCH_1):PAGE92

M_H_CPU0_SA_DQ<11> @T6G_MB_LIB.T6G(SCH_1):M_H_CPU0_SA_DQ(11)
   U25  N14 MHA_DATA11 GENOA_SP5-SOCKET6096_13568-001,SMLF,IO,DGA^6000030   I159 @T6G_MB_LIB.T6G(SCH_1):PAGE17
   J69  165 DQ11_A SCONN288_DDR506112002KQ-SCONN288_DDR506112002KQ,SMA    I22 @T6G_MB_LIB.T6G(SCH_1):PAGE92

M_H_CPU0_SA_DQ<12> @T6G_MB_LIB.T6G(SCH_1):M_H_CPU0_SA_DQ(12)
   U25  R12 MHA_DATA12 GENOA_SP5-SOCKET6096_13568-001,SMLF,IO,DGA^6000030   I159 @T6G_MB_LIB.T6G(SCH_1):PAGE17
   J69   25 DQ12_A SCONN288_DDR506112002KQ-SCONN288_DDR506112002KQ,SMA    I22 @T6G_MB_LIB.T6G(SCH_1):PAGE92

M_H_CPU0_SA_DQ<13> @T6G_MB_LIB.T6G(SCH_1):M_H_CPU0_SA_DQ(13)
   U25  T14 MHA_DATA13 GENOA_SP5-SOCKET6096_13568-001,SMLF,IO,DGA^6000030   I159 @T6G_MB_LIB.T6G(SCH_1):PAGE17
   J69   27 DQ13_A SCONN288_DDR506112002KQ-SCONN288_DDR506112002KQ,SMA    I22 @T6G_MB_LIB.T6G(SCH_1):PAGE92

M_H_CPU0_SA_DQ<14> @T6G_MB_LIB.T6G(SCH_1):M_H_CPU0_SA_DQ(14)
   U25  T13 MHA_DATA14 GENOA_SP5-SOCKET6096_13568-001,SMLF,IO,DGA^6000030   I159 @T6G_MB_LIB.T6G(SCH_1):PAGE17
   J69  170 DQ14_A SCONN288_DDR506112002KQ-SCONN288_DDR506112002KQ,SMA    I22 @T6G_MB_LIB.T6G(SCH_1):PAGE92

M_H_CPU0_SA_DQ<15> @T6G_MB_LIB.T6G(SCH_1):M_H_CPU0_SA_DQ(15)
   U25  U14 MHA_DATA15 GENOA_SP5-SOCKET6096_13568-001,SMLF,IO,DGA^6000030   I159 @T6G_MB_LIB.T6G(SCH_1):PAGE17
   J69  172 DQ15_A SCONN288_DDR506112002KQ-SCONN288_DDR506112002KQ,SMA    I22 @T6G_MB_LIB.T6G(SCH_1):PAGE92

M_H_CPU0_SA_DQ<16> @T6G_MB_LIB.T6G(SCH_1):M_H_CPU0_SA_DQ(16)
   U25  U12 MHA_DATA16 GENOA_SP5-SOCKET6096_13568-001,SMLF,IO,DGA^6000030   I159 @T6G_MB_LIB.T6G(SCH_1):PAGE17
   J69   29 DQ16_A SCONN288_DDR506112002KQ-SCONN288_DDR506112002KQ,SMA    I22 @T6G_MB_LIB.T6G(SCH_1):PAGE92

M_H_CPU0_SA_DQ<17> @T6G_MB_LIB.T6G(SCH_1):M_H_CPU0_SA_DQ(17)
   U25  V14 MHA_DATA17 GENOA_SP5-SOCKET6096_13568-001,SMLF,IO,DGA^6000030   I159 @T6G_MB_LIB.T6G(SCH_1):PAGE17
   J69   31 DQ17_A SCONN288_DDR506112002KQ-SCONN288_DDR506112002KQ,SMA    I22 @T6G_MB_LIB.T6G(SCH_1):PAGE92

M_H_CPU0_SA_DQ<18> @T6G_MB_LIB.T6G(SCH_1):M_H_CPU0_SA_DQ(18)
   U25  V13 MHA_DATA18 GENOA_SP5-SOCKET6096_13568-001,SMLF,IO,DGA^6000030   I159 @T6G_MB_LIB.T6G(SCH_1):PAGE17
   J69  174 DQ18_A SCONN288_DDR506112002KQ-SCONN288_DDR506112002KQ,SMA    I22 @T6G_MB_LIB.T6G(SCH_1):PAGE92

M_H_CPU0_SA_DQ<19> @T6G_MB_LIB.T6G(SCH_1):M_H_CPU0_SA_DQ(19)
   U25  W14 MHA_DATA19 GENOA_SP5-SOCKET6096_13568-001,SMLF,IO,DGA^6000030   I159 @T6G_MB_LIB.T6G(SCH_1):PAGE17
   J69  176 DQ19_A SCONN288_DDR506112002KQ-SCONN288_DDR506112002KQ,SMA    I22 @T6G_MB_LIB.T6G(SCH_1):PAGE92

M_H_CPU0_SA_DQ<1> @T6G_MB_LIB.T6G(SCH_1):M_H_CPU0_SA_DQ(1)
   U25  F14 MHA_DATA1 GENOA_SP5-SOCKET6096_13568-001,SMLF,IO,DGA^6000030   I159 @T6G_MB_LIB.T6G(SCH_1):PAGE17
   J69    9  DQ1_A SCONN288_DDR506112002KQ-SCONN288_DDR506112002KQ,SMA    I22 @T6G_MB_LIB.T6G(SCH_1):PAGE92

M_H_CPU0_SA_DQ<20> @T6G_MB_LIB.T6G(SCH_1):M_H_CPU0_SA_DQ(20)
   U25 AA12 MHA_DATA20 GENOA_SP5-SOCKET6096_13568-001,SMLF,IO,DGA^6000030   I159 @T6G_MB_LIB.T6G(SCH_1):PAGE17
   J69   36 DQ20_A SCONN288_DDR506112002KQ-SCONN288_DDR506112002KQ,SMA    I22 @T6G_MB_LIB.T6G(SCH_1):PAGE92

M_H_CPU0_SA_DQ<21> @T6G_MB_LIB.T6G(SCH_1):M_H_CPU0_SA_DQ(21)
   U25 AB14 MHA_DATA21 GENOA_SP5-SOCKET6096_13568-001,SMLF,IO,DGA^6000030   I159 @T6G_MB_LIB.T6G(SCH_1):PAGE17
   J69   38 DQ21_A SCONN288_DDR506112002KQ-SCONN288_DDR506112002KQ,SMA    I22 @T6G_MB_LIB.T6G(SCH_1):PAGE92

M_H_CPU0_SA_DQ<22> @T6G_MB_LIB.T6G(SCH_1):M_H_CPU0_SA_DQ(22)
   U25 AB13 MHA_DATA22 GENOA_SP5-SOCKET6096_13568-001,SMLF,IO,DGA^6000030   I159 @T6G_MB_LIB.T6G(SCH_1):PAGE17
   J69  181 DQ22_A SCONN288_DDR506112002KQ-SCONN288_DDR506112002KQ,SMA    I22 @T6G_MB_LIB.T6G(SCH_1):PAGE92

M_H_CPU0_SA_DQ<23> @T6G_MB_LIB.T6G(SCH_1):M_H_CPU0_SA_DQ(23)
   U25 AC14 MHA_DATA23 GENOA_SP5-SOCKET6096_13568-001,SMLF,IO,DGA^6000030   I159 @T6G_MB_LIB.T6G(SCH_1):PAGE17
   J69  183 DQ23_A SCONN288_DDR506112002KQ-SCONN288_DDR506112002KQ,SMA    I22 @T6G_MB_LIB.T6G(SCH_1):PAGE92

M_H_CPU0_SA_DQ<24> @T6G_MB_LIB.T6G(SCH_1):M_H_CPU0_SA_DQ(24)
   U25 AC12 MHA_DATA24 GENOA_SP5-SOCKET6096_13568-001,SMLF,IO,DGA^6000030   I159 @T6G_MB_LIB.T6G(SCH_1):PAGE17
   J69   40 DQ24_A SCONN288_DDR506112002KQ-SCONN288_DDR506112002KQ,SMA    I22 @T6G_MB_LIB.T6G(SCH_1):PAGE92

M_H_CPU0_SA_DQ<25> @T6G_MB_LIB.T6G(SCH_1):M_H_CPU0_SA_DQ(25)
   U25 AD14 MHA_DATA25 GENOA_SP5-SOCKET6096_13568-001,SMLF,IO,DGA^6000030   I159 @T6G_MB_LIB.T6G(SCH_1):PAGE17
   J69   42 DQ25_A SCONN288_DDR506112002KQ-SCONN288_DDR506112002KQ,SMA    I22 @T6G_MB_LIB.T6G(SCH_1):PAGE92

M_H_CPU0_SA_DQ<26> @T6G_MB_LIB.T6G(SCH_1):M_H_CPU0_SA_DQ(26)
   U25 AD13 MHA_DATA26 GENOA_SP5-SOCKET6096_13568-001,SMLF,IO,DGA^6000030   I159 @T6G_MB_LIB.T6G(SCH_1):PAGE17
   J69  185 DQ26_A SCONN288_DDR506112002KQ-SCONN288_DDR506112002KQ,SMA    I22 @T6G_MB_LIB.T6G(SCH_1):PAGE92

M_H_CPU0_SA_DQ<27> @T6G_MB_LIB.T6G(SCH_1):M_H_CPU0_SA_DQ(27)
   U25 AE14 MHA_DATA27 GENOA_SP5-SOCKET6096_13568-001,SMLF,IO,DGA^6000030   I159 @T6G_MB_LIB.T6G(SCH_1):PAGE17
   J69  187 DQ27_A SCONN288_DDR506112002KQ-SCONN288_DDR506112002KQ,SMA    I22 @T6G_MB_LIB.T6G(SCH_1):PAGE92

M_H_CPU0_SA_DQ<28> @T6G_MB_LIB.T6G(SCH_1):M_H_CPU0_SA_DQ(28)
   U25 AG12 MHA_DATA28 GENOA_SP5-SOCKET6096_13568-001,SMLF,IO,DGA^6000030   I159 @T6G_MB_LIB.T6G(SCH_1):PAGE17
   J69   47 DQ28_A SCONN288_DDR506112002KQ-SCONN288_DDR506112002KQ,SMA    I22 @T6G_MB_LIB.T6G(SCH_1):PAGE92

M_H_CPU0_SA_DQ<29> @T6G_MB_LIB.T6G(SCH_1):M_H_CPU0_SA_DQ(29)
   U25 AH14 MHA_DATA29 GENOA_SP5-SOCKET6096_13568-001,SMLF,IO,DGA^6000030   I159 @T6G_MB_LIB.T6G(SCH_1):PAGE17
   J69   49 DQ29_A SCONN288_DDR506112002KQ-SCONN288_DDR506112002KQ,SMA    I22 @T6G_MB_LIB.T6G(SCH_1):PAGE92

M_H_CPU0_SA_DQ<2> @T6G_MB_LIB.T6G(SCH_1):M_H_CPU0_SA_DQ(2)
   U25  F13 MHA_DATA2 GENOA_SP5-SOCKET6096_13568-001,SMLF,IO,DGA^6000030   I159 @T6G_MB_LIB.T6G(SCH_1):PAGE17
   J69  152  DQ2_A SCONN288_DDR506112002KQ-SCONN288_DDR506112002KQ,SMA    I22 @T6G_MB_LIB.T6G(SCH_1):PAGE92

M_H_CPU0_SA_DQ<30> @T6G_MB_LIB.T6G(SCH_1):M_H_CPU0_SA_DQ(30)
   U25 AH13 MHA_DATA30 GENOA_SP5-SOCKET6096_13568-001,SMLF,IO,DGA^6000030   I159 @T6G_MB_LIB.T6G(SCH_1):PAGE17
   J69  192 DQ30_A SCONN288_DDR506112002KQ-SCONN288_DDR506112002KQ,SMA    I22 @T6G_MB_LIB.T6G(SCH_1):PAGE92

M_H_CPU0_SA_DQ<31> @T6G_MB_LIB.T6G(SCH_1):M_H_CPU0_SA_DQ(31)
   U25 AJ14 MHA_DATA31 GENOA_SP5-SOCKET6096_13568-001,SMLF,IO,DGA^6000030   I159 @T6G_MB_LIB.T6G(SCH_1):PAGE17
   J69  194 DQ31_A SCONN288_DDR506112002KQ-SCONN288_DDR506112002KQ,SMA    I22 @T6G_MB_LIB.T6G(SCH_1):PAGE92

M_H_CPU0_SA_DQ<3> @T6G_MB_LIB.T6G(SCH_1):M_H_CPU0_SA_DQ(3)
   U25  G14 MHA_DATA3 GENOA_SP5-SOCKET6096_13568-001,SMLF,IO,DGA^6000030   I159 @T6G_MB_LIB.T6G(SCH_1):PAGE17
   J69  154  DQ3_A SCONN288_DDR506112002KQ-SCONN288_DDR506112002KQ,SMA    I22 @T6G_MB_LIB.T6G(SCH_1):PAGE92

M_H_CPU0_SA_DQ<4> @T6G_MB_LIB.T6G(SCH_1):M_H_CPU0_SA_DQ(4)
   U25  J12 MHA_DATA4 GENOA_SP5-SOCKET6096_13568-001,SMLF,IO,DGA^6000030   I159 @T6G_MB_LIB.T6G(SCH_1):PAGE17
   J69   14  DQ4_A SCONN288_DDR506112002KQ-SCONN288_DDR506112002KQ,SMA    I22 @T6G_MB_LIB.T6G(SCH_1):PAGE92

M_H_CPU0_SA_DQ<5> @T6G_MB_LIB.T6G(SCH_1):M_H_CPU0_SA_DQ(5)
   U25  K14 MHA_DATA5 GENOA_SP5-SOCKET6096_13568-001,SMLF,IO,DGA^6000030   I159 @T6G_MB_LIB.T6G(SCH_1):PAGE17
   J69   16  DQ5_A SCONN288_DDR506112002KQ-SCONN288_DDR506112002KQ,SMA    I22 @T6G_MB_LIB.T6G(SCH_1):PAGE92

M_H_CPU0_SA_DQ<6> @T6G_MB_LIB.T6G(SCH_1):M_H_CPU0_SA_DQ(6)
   U25  K13 MHA_DATA6 GENOA_SP5-SOCKET6096_13568-001,SMLF,IO,DGA^6000030   I159 @T6G_MB_LIB.T6G(SCH_1):PAGE17
   J69  159  DQ6_A SCONN288_DDR506112002KQ-SCONN288_DDR506112002KQ,SMA    I22 @T6G_MB_LIB.T6G(SCH_1):PAGE92

M_H_CPU0_SA_DQ<7> @T6G_MB_LIB.T6G(SCH_1):M_H_CPU0_SA_DQ(7)
   U25  L14 MHA_DATA7 GENOA_SP5-SOCKET6096_13568-001,SMLF,IO,DGA^6000030   I159 @T6G_MB_LIB.T6G(SCH_1):PAGE17
   J69  161  DQ7_A SCONN288_DDR506112002KQ-SCONN288_DDR506112002KQ,SMA    I22 @T6G_MB_LIB.T6G(SCH_1):PAGE92

M_H_CPU0_SA_DQ<8> @T6G_MB_LIB.T6G(SCH_1):M_H_CPU0_SA_DQ(8)
   U25  L12 MHA_DATA8 GENOA_SP5-SOCKET6096_13568-001,SMLF,IO,DGA^6000030   I159 @T6G_MB_LIB.T6G(SCH_1):PAGE17
   J69   18  DQ8_A SCONN288_DDR506112002KQ-SCONN288_DDR506112002KQ,SMA    I22 @T6G_MB_LIB.T6G(SCH_1):PAGE92

M_H_CPU0_SA_DQ<9> @T6G_MB_LIB.T6G(SCH_1):M_H_CPU0_SA_DQ(9)
   U25  M14 MHA_DATA9 GENOA_SP5-SOCKET6096_13568-001,SMLF,IO,DGA^6000030   I159 @T6G_MB_LIB.T6G(SCH_1):PAGE17
   J69   20  DQ9_A SCONN288_DDR506112002KQ-SCONN288_DDR506112002KQ,SMA    I22 @T6G_MB_LIB.T6G(SCH_1):PAGE92

M_H_CPU0_SA_DQS_DN<0> @T6G_MB_LIB.T6G(SCH_1):M_H_CPU0_SA_DQS_DN(0)
   U25  H13 MHA_DQS_L0 GENOA_SP5-SOCKET6096_13568-001,SMLF,IO,DGA^6000030   I159 @T6G_MB_LIB.T6G(SCH_1):PAGE17
   J69   12 DQS0_A_C SCONN288_DDR506112002KQ-SCONN288_DDR506112002KQ,SMA   I237 @T6G_MB_LIB.T6G(SCH_1):PAGE92

M_H_CPU0_SA_DQS_DN<1> @T6G_MB_LIB.T6G(SCH_1):M_H_CPU0_SA_DQS_DN(1)
   U25  P13 MHA_DQS_L1 GENOA_SP5-SOCKET6096_13568-001,SMLF,IO,DGA^6000030   I159 @T6G_MB_LIB.T6G(SCH_1):PAGE17
   J69   23 DQS1_A_C SCONN288_DDR506112002KQ-SCONN288_DDR506112002KQ,SMA   I237 @T6G_MB_LIB.T6G(SCH_1):PAGE92

M_H_CPU0_SA_DQS_DN<2> @T6G_MB_LIB.T6G(SCH_1):M_H_CPU0_SA_DQS_DN(2)
   U25  Y13 MHA_DQS_L2 GENOA_SP5-SOCKET6096_13568-001,SMLF,IO,DGA^6000030   I159 @T6G_MB_LIB.T6G(SCH_1):PAGE17
   J69   34 DQS2_A_C SCONN288_DDR506112002KQ-SCONN288_DDR506112002KQ,SMA   I237 @T6G_MB_LIB.T6G(SCH_1):PAGE92

M_H_CPU0_SA_DQS_DN<3> @T6G_MB_LIB.T6G(SCH_1):M_H_CPU0_SA_DQS_DN(3)
   U25 AF13 MHA_DQS_L3 GENOA_SP5-SOCKET6096_13568-001,SMLF,IO,DGA^6000030   I159 @T6G_MB_LIB.T6G(SCH_1):PAGE17
   J69   45 DQS3_A_C SCONN288_DDR506112002KQ-SCONN288_DDR506112002KQ,SMA   I237 @T6G_MB_LIB.T6G(SCH_1):PAGE92

M_H_CPU0_SA_DQS_DN<4> @T6G_MB_LIB.T6G(SCH_1):M_H_CPU0_SA_DQS_DN(4)
   U25 AM13 MHA_DQS_L4 GENOA_SP5-SOCKET6096_13568-001,SMLF,IO,DGA^6000030   I159 @T6G_MB_LIB.T6G(SCH_1):PAGE17
   J69   56 DQS4_A_C SCONN288_DDR506112002KQ-SCONN288_DDR506112002KQ,SMA   I237 @T6G_MB_LIB.T6G(SCH_1):PAGE92

M_H_CPU0_SA_DQS_DN<5> @T6G_MB_LIB.T6G(SCH_1):M_H_CPU0_SA_DQS_DN(5)
   U25  H14 MHA_DQS_L5 GENOA_SP5-SOCKET6096_13568-001,SMLF,IO,DGA^6000030   I159 @T6G_MB_LIB.T6G(SCH_1):PAGE17
   J69  156 DQS5_A_C||TDQS5_A_C||DQS5_A_T||TDQS5_A_T SCONN288_DDR506112002KQ-SCONN288_DDR506112002KQ,SMA   I237 @T6G_MB_LIB.T6G(SCH_1):PAGE92

M_H_CPU0_SA_DQS_DN<6> @T6G_MB_LIB.T6G(SCH_1):M_H_CPU0_SA_DQS_DN(6)
   U25  P14 MHA_DQS_L6 GENOA_SP5-SOCKET6096_13568-001,SMLF,IO,DGA^6000030   I159 @T6G_MB_LIB.T6G(SCH_1):PAGE17
   J69  167 DQS6_A_C||TDQS6_A_C||DQS6_A_T||TDQS6_A_T SCONN288_DDR506112002KQ-SCONN288_DDR506112002KQ,SMA   I237 @T6G_MB_LIB.T6G(SCH_1):PAGE92

M_H_CPU0_SA_DQS_DN<7> @T6G_MB_LIB.T6G(SCH_1):M_H_CPU0_SA_DQS_DN(7)
   U25  Y14 MHA_DQS_L7 GENOA_SP5-SOCKET6096_13568-001,SMLF,IO,DGA^6000030   I159 @T6G_MB_LIB.T6G(SCH_1):PAGE17
   J69  178 DQS7_A_C||TDQS7_A_C SCONN288_DDR506112002KQ-SCONN288_DDR506112002KQ,SMA   I237 @T6G_MB_LIB.T6G(SCH_1):PAGE92

M_H_CPU0_SA_DQS_DN<8> @T6G_MB_LIB.T6G(SCH_1):M_H_CPU0_SA_DQS_DN(8)
   U25 AF14 MHA_DQS_L8 GENOA_SP5-SOCKET6096_13568-001,SMLF,IO,DGA^6000030   I159 @T6G_MB_LIB.T6G(SCH_1):PAGE17
   J69  189 DQS8_A_C||TDQS8_A_C SCONN288_DDR506112002KQ-SCONN288_DDR506112002KQ,SMA   I237 @T6G_MB_LIB.T6G(SCH_1):PAGE92

M_H_CPU0_SA_DQS_DN<9> @T6G_MB_LIB.T6G(SCH_1):M_H_CPU0_SA_DQS_DN(9)
   U25 AM14 MHA_DQS_L9 GENOA_SP5-SOCKET6096_13568-001,SMLF,IO,DGA^6000030   I159 @T6G_MB_LIB.T6G(SCH_1):PAGE17
   J69  200 DQS9_A_C||TDQS9_A_C SCONN288_DDR506112002KQ-SCONN288_DDR506112002KQ,SMA   I237 @T6G_MB_LIB.T6G(SCH_1):PAGE92

M_H_CPU0_SA_DQS_DP<0> @T6G_MB_LIB.T6G(SCH_1):M_H_CPU0_SA_DQS_DP(0)
   U25  G12 MHA_DQS_H0 GENOA_SP5-SOCKET6096_13568-001,SMLF,IO,DGA^6000030   I159 @T6G_MB_LIB.T6G(SCH_1):PAGE17
   J69   11 DQS0_A_T SCONN288_DDR506112002KQ-SCONN288_DDR506112002KQ,SMA   I237 @T6G_MB_LIB.T6G(SCH_1):PAGE92

M_H_CPU0_SA_DQS_DP<1> @T6G_MB_LIB.T6G(SCH_1):M_H_CPU0_SA_DQS_DP(1)
   U25  N12 MHA_DQS_H1 GENOA_SP5-SOCKET6096_13568-001,SMLF,IO,DGA^6000030   I159 @T6G_MB_LIB.T6G(SCH_1):PAGE17
   J69   22 DQS1_A_T SCONN288_DDR506112002KQ-SCONN288_DDR506112002KQ,SMA   I237 @T6G_MB_LIB.T6G(SCH_1):PAGE92

M_H_CPU0_SA_DQS_DP<2> @T6G_MB_LIB.T6G(SCH_1):M_H_CPU0_SA_DQS_DP(2)
   U25  W12 MHA_DQS_H2 GENOA_SP5-SOCKET6096_13568-001,SMLF,IO,DGA^6000030   I159 @T6G_MB_LIB.T6G(SCH_1):PAGE17
   J69   33 DQS2_A_T SCONN288_DDR506112002KQ-SCONN288_DDR506112002KQ,SMA   I237 @T6G_MB_LIB.T6G(SCH_1):PAGE92

M_H_CPU0_SA_DQS_DP<3> @T6G_MB_LIB.T6G(SCH_1):M_H_CPU0_SA_DQS_DP(3)
   U25 AE12 MHA_DQS_H3 GENOA_SP5-SOCKET6096_13568-001,SMLF,IO,DGA^6000030   I159 @T6G_MB_LIB.T6G(SCH_1):PAGE17
   J69   44 DQS3_A_T SCONN288_DDR506112002KQ-SCONN288_DDR506112002KQ,SMA   I237 @T6G_MB_LIB.T6G(SCH_1):PAGE92

M_H_CPU0_SA_DQS_DP<4> @T6G_MB_LIB.T6G(SCH_1):M_H_CPU0_SA_DQS_DP(4)
   U25 AL12 MHA_DQS_H4 GENOA_SP5-SOCKET6096_13568-001,SMLF,IO,DGA^6000030   I159 @T6G_MB_LIB.T6G(SCH_1):PAGE17
   J69   55 DQS4_A_T SCONN288_DDR506112002KQ-SCONN288_DDR506112002KQ,SMA   I237 @T6G_MB_LIB.T6G(SCH_1):PAGE92

M_H_CPU0_SA_DQS_DP<5> @T6G_MB_LIB.T6G(SCH_1):M_H_CPU0_SA_DQS_DP(5)
   U25  J14 MHA_DQS_H5 GENOA_SP5-SOCKET6096_13568-001,SMLF,IO,DGA^6000030   I159 @T6G_MB_LIB.T6G(SCH_1):PAGE17
   J69  157 DQS5_A_T||TDQS5_A_T SCONN288_DDR506112002KQ-SCONN288_DDR506112002KQ,SMA   I237 @T6G_MB_LIB.T6G(SCH_1):PAGE92

M_H_CPU0_SA_DQS_DP<6> @T6G_MB_LIB.T6G(SCH_1):M_H_CPU0_SA_DQS_DP(6)
   U25  R14 MHA_DQS_H6 GENOA_SP5-SOCKET6096_13568-001,SMLF,IO,DGA^6000030   I159 @T6G_MB_LIB.T6G(SCH_1):PAGE17
   J69  168 DQS6_A_T||TDQS6_A_T SCONN288_DDR506112002KQ-SCONN288_DDR506112002KQ,SMA   I237 @T6G_MB_LIB.T6G(SCH_1):PAGE92

M_H_CPU0_SA_DQS_DP<7> @T6G_MB_LIB.T6G(SCH_1):M_H_CPU0_SA_DQS_DP(7)
   U25 AA14 MHA_DQS_H7 GENOA_SP5-SOCKET6096_13568-001,SMLF,IO,DGA^6000030   I159 @T6G_MB_LIB.T6G(SCH_1):PAGE17
   J69  179 DQS7_A_T||TDQS7_A_T SCONN288_DDR506112002KQ-SCONN288_DDR506112002KQ,SMA   I237 @T6G_MB_LIB.T6G(SCH_1):PAGE92

M_H_CPU0_SA_DQS_DP<8> @T6G_MB_LIB.T6G(SCH_1):M_H_CPU0_SA_DQS_DP(8)
   U25 AG14 MHA_DQS_H8 GENOA_SP5-SOCKET6096_13568-001,SMLF,IO,DGA^6000030   I159 @T6G_MB_LIB.T6G(SCH_1):PAGE17
   J69  190 DQS8_A_T||TDQS8_A_T SCONN288_DDR506112002KQ-SCONN288_DDR506112002KQ,SMA   I237 @T6G_MB_LIB.T6G(SCH_1):PAGE92

M_H_CPU0_SA_DQS_DP<9> @T6G_MB_LIB.T6G(SCH_1):M_H_CPU0_SA_DQS_DP(9)
   U25 AN14 MHA_DQS_H9 GENOA_SP5-SOCKET6096_13568-001,SMLF,IO,DGA^6000030   I159 @T6G_MB_LIB.T6G(SCH_1):PAGE17
   J69  201 DQS9_A_T||TDQS9_A_T SCONN288_DDR506112002KQ-SCONN288_DDR506112002KQ,SMA   I237 @T6G_MB_LIB.T6G(SCH_1):PAGE92

M_H_CPU0_SA_PAR @T6G_MB_LIB.T6G(SCH_1):M_H_CPU0_SA_PAR
   U25 BC14 MHA_PAR GENOA_SP5-SOCKET6096_13568-001,SMLF,IO,DGA^6000030   I159 @T6G_MB_LIB.T6G(SCH_1):PAGE17
   J69   74  PAR_A SCONN288_DDR506112002KQ-SCONN288_DDR506112002KQ,SMA    I22 @T6G_MB_LIB.T6G(SCH_1):PAGE92

M_H_CPU0_SA_RSP<0> @T6G_MB_LIB.T6G(SCH_1):M_H_CPU0_SA_RSP(0)
   U25 BN14 MHA0_RSP_L GENOA_SP5-SOCKET6096_13568-001,SMLF,IO,DGA^6000030   I159 @T6G_MB_LIB.T6G(SCH_1):PAGE17
   J69   86 LBD||RSP_A_N SCONN288_DDR506112002KQ-SCONN288_DDR506112002KQ,SMA    I22 @T6G_MB_LIB.T6G(SCH_1):PAGE92

M_H_CPU0_SB_CA<0> @T6G_MB_LIB.T6G(SCH_1):M_H_CPU0_SB_CA(0)
   U25 BG14 MHB_CA0 GENOA_SP5-SOCKET6096_13568-001,SMLF,IO,DGA^6000030   I159 @T6G_MB_LIB.T6G(SCH_1):PAGE17
   J69   76  CA0_B SCONN288_DDR506112002KQ-SCONN288_DDR506112002KQ,SMA    I22 @T6G_MB_LIB.T6G(SCH_1):PAGE92

M_H_CPU0_SB_CA<1> @T6G_MB_LIB.T6G(SCH_1):M_H_CPU0_SB_CA(1)
   U25 BH14 MHB_CA1 GENOA_SP5-SOCKET6096_13568-001,SMLF,IO,DGA^6000030   I159 @T6G_MB_LIB.T6G(SCH_1):PAGE17
   J69  221  CA1_B SCONN288_DDR506112002KQ-SCONN288_DDR506112002KQ,SMA    I22 @T6G_MB_LIB.T6G(SCH_1):PAGE92

M_H_CPU0_SB_CA<2> @T6G_MB_LIB.T6G(SCH_1):M_H_CPU0_SB_CA(2)
   U25 BH13 MHB_CA2 GENOA_SP5-SOCKET6096_13568-001,SMLF,IO,DGA^6000030   I159 @T6G_MB_LIB.T6G(SCH_1):PAGE17
   J69   78  CA2_B SCONN288_DDR506112002KQ-SCONN288_DDR506112002KQ,SMA    I22 @T6G_MB_LIB.T6G(SCH_1):PAGE92

M_H_CPU0_SB_CA<3> @T6G_MB_LIB.T6G(SCH_1):M_H_CPU0_SB_CA(3)
   U25 BJ12 MHB_CA3 GENOA_SP5-SOCKET6096_13568-001,SMLF,IO,DGA^6000030   I159 @T6G_MB_LIB.T6G(SCH_1):PAGE17
   J69  223  CA3_B SCONN288_DDR506112002KQ-SCONN288_DDR506112002KQ,SMA    I22 @T6G_MB_LIB.T6G(SCH_1):PAGE92

M_H_CPU0_SB_CA<4> @T6G_MB_LIB.T6G(SCH_1):M_H_CPU0_SB_CA(4)
   U25 BJ14 MHB_CA4 GENOA_SP5-SOCKET6096_13568-001,SMLF,IO,DGA^6000030   I159 @T6G_MB_LIB.T6G(SCH_1):PAGE17
   J69   80  CA4_B SCONN288_DDR506112002KQ-SCONN288_DDR506112002KQ,SMA    I22 @T6G_MB_LIB.T6G(SCH_1):PAGE92

M_H_CPU0_SB_CA<5> @T6G_MB_LIB.T6G(SCH_1):M_H_CPU0_SB_CA(5)
   U25 BK14 MHB_CA5 GENOA_SP5-SOCKET6096_13568-001,SMLF,IO,DGA^6000030   I159 @T6G_MB_LIB.T6G(SCH_1):PAGE17
   J69  225  CA5_B SCONN288_DDR506112002KQ-SCONN288_DDR506112002KQ,SMA    I22 @T6G_MB_LIB.T6G(SCH_1):PAGE92

M_H_CPU0_SB_CA<6> @T6G_MB_LIB.T6G(SCH_1):M_H_CPU0_SB_CA(6)
   U25 BK13 MHB_CA6 GENOA_SP5-SOCKET6096_13568-001,SMLF,IO,DGA^6000030   I159 @T6G_MB_LIB.T6G(SCH_1):PAGE17
   J69   82  CA6_B SCONN288_DDR506112002KQ-SCONN288_DDR506112002KQ,SMA    I22 @T6G_MB_LIB.T6G(SCH_1):PAGE92

M_H_CPU0_SB_CB<0> @T6G_MB_LIB.T6G(SCH_1):M_H_CPU0_SB_CB(0)
   U25 BY13 MHB_CHECK0 GENOA_SP5-SOCKET6096_13568-001,SMLF,IO,DGA^6000030   I159 @T6G_MB_LIB.T6G(SCH_1):PAGE17
   J69   96  CB0_B SCONN288_DDR506112002KQ-SCONN288_DDR506112002KQ,SMA    I22 @T6G_MB_LIB.T6G(SCH_1):PAGE92

M_H_CPU0_SB_CB<1> @T6G_MB_LIB.T6G(SCH_1):M_H_CPU0_SB_CB(1)
   U25 CA14 MHB_CHECK1 GENOA_SP5-SOCKET6096_13568-001,SMLF,IO,DGA^6000030   I159 @T6G_MB_LIB.T6G(SCH_1):PAGE17
   J69   98  CB1_B SCONN288_DDR506112002KQ-SCONN288_DDR506112002KQ,SMA    I22 @T6G_MB_LIB.T6G(SCH_1):PAGE92

M_H_CPU0_SB_CB<2> @T6G_MB_LIB.T6G(SCH_1):M_H_CPU0_SB_CB(2)
   U25 CA12 MHB_CHECK2 GENOA_SP5-SOCKET6096_13568-001,SMLF,IO,DGA^6000030   I159 @T6G_MB_LIB.T6G(SCH_1):PAGE17
   J69  241  CB2_B SCONN288_DDR506112002KQ-SCONN288_DDR506112002KQ,SMA    I22 @T6G_MB_LIB.T6G(SCH_1):PAGE92

M_H_CPU0_SB_CB<3> @T6G_MB_LIB.T6G(SCH_1):M_H_CPU0_SB_CB(3)
   U25 CB14 MHB_CHECK3 GENOA_SP5-SOCKET6096_13568-001,SMLF,IO,DGA^6000030   I159 @T6G_MB_LIB.T6G(SCH_1):PAGE17
   J69  243  CB3_B SCONN288_DDR506112002KQ-SCONN288_DDR506112002KQ,SMA    I22 @T6G_MB_LIB.T6G(SCH_1):PAGE92

M_H_CPU0_SB_CB<4> @T6G_MB_LIB.T6G(SCH_1):M_H_CPU0_SB_CB(4)
   U25 BT13 MHB_CHECK4 GENOA_SP5-SOCKET6096_13568-001,SMLF,IO,DGA^6000030   I159 @T6G_MB_LIB.T6G(SCH_1):PAGE17
   J69   89  CB4_B SCONN288_DDR506112002KQ-SCONN288_DDR506112002KQ,SMA    I22 @T6G_MB_LIB.T6G(SCH_1):PAGE92

M_H_CPU0_SB_CB<5> @T6G_MB_LIB.T6G(SCH_1):M_H_CPU0_SB_CB(5)
   U25 BU14 MHB_CHECK5 GENOA_SP5-SOCKET6096_13568-001,SMLF,IO,DGA^6000030   I159 @T6G_MB_LIB.T6G(SCH_1):PAGE17
   J69   91  CB5_B SCONN288_DDR506112002KQ-SCONN288_DDR506112002KQ,SMA    I22 @T6G_MB_LIB.T6G(SCH_1):PAGE92

M_H_CPU0_SB_CB<6> @T6G_MB_LIB.T6G(SCH_1):M_H_CPU0_SB_CB(6)
   U25 BU12 MHB_CHECK6 GENOA_SP5-SOCKET6096_13568-001,SMLF,IO,DGA^6000030   I159 @T6G_MB_LIB.T6G(SCH_1):PAGE17
   J69  234  CB6_B SCONN288_DDR506112002KQ-SCONN288_DDR506112002KQ,SMA    I22 @T6G_MB_LIB.T6G(SCH_1):PAGE92

M_H_CPU0_SB_CB<7> @T6G_MB_LIB.T6G(SCH_1):M_H_CPU0_SB_CB(7)
   U25 BV14 MHB_CHECK7 GENOA_SP5-SOCKET6096_13568-001,SMLF,IO,DGA^6000030   I159 @T6G_MB_LIB.T6G(SCH_1):PAGE17
   J69  236  CB7_B SCONN288_DDR506112002KQ-SCONN288_DDR506112002KQ,SMA    I22 @T6G_MB_LIB.T6G(SCH_1):PAGE92

M_H_CPU0_SB_CS_N<0> @T6G_MB_LIB.T6G(SCH_1):M_H_CPU0_SB_CS_N(0)
   U25 BM14 MHB0_CS_L0 GENOA_SP5-SOCKET6096_13568-001,SMLF,IO,DGA^6000030   I159 @T6G_MB_LIB.T6G(SCH_1):PAGE17
   J69   84 CS0_B_N SCONN288_DDR506112002KQ-SCONN288_DDR506112002KQ,SMA    I22 @T6G_MB_LIB.T6G(SCH_1):PAGE92

M_H_CPU0_SB_CS_N<1> @T6G_MB_LIB.T6G(SCH_1):M_H_CPU0_SB_CS_N(1)
   U25 BN12 MHB0_CS_L1 GENOA_SP5-SOCKET6096_13568-001,SMLF,IO,DGA^6000030   I159 @T6G_MB_LIB.T6G(SCH_1):PAGE17
   J69  229 CS1_B_N SCONN288_DDR506112002KQ-SCONN288_DDR506112002KQ,SMA    I22 @T6G_MB_LIB.T6G(SCH_1):PAGE92

M_H_CPU0_SB_DQ<0> @T6G_MB_LIB.T6G(SCH_1):M_H_CPU0_SB_DQ(0)
   U25 CB13 MHB_DATA0 GENOA_SP5-SOCKET6096_13568-001,SMLF,IO,DGA^6000030   I159 @T6G_MB_LIB.T6G(SCH_1):PAGE17
   J69  100  DQ0_B SCONN288_DDR506112002KQ-SCONN288_DDR506112002KQ,SMA    I22 @T6G_MB_LIB.T6G(SCH_1):PAGE92

M_H_CPU0_SB_DQ<10> @T6G_MB_LIB.T6G(SCH_1):M_H_CPU0_SB_DQ(10)
   U25 CJ12 MHB_DATA10 GENOA_SP5-SOCKET6096_13568-001,SMLF,IO,DGA^6000030   I159 @T6G_MB_LIB.T6G(SCH_1):PAGE17
   J69  256 DQ10_B SCONN288_DDR506112002KQ-SCONN288_DDR506112002KQ,SMA    I22 @T6G_MB_LIB.T6G(SCH_1):PAGE92

M_H_CPU0_SB_DQ<11> @T6G_MB_LIB.T6G(SCH_1):M_H_CPU0_SB_DQ(11)
   U25 CK14 MHB_DATA11 GENOA_SP5-SOCKET6096_13568-001,SMLF,IO,DGA^6000030   I159 @T6G_MB_LIB.T6G(SCH_1):PAGE17
   J69  258 DQ11_B SCONN288_DDR506112002KQ-SCONN288_DDR506112002KQ,SMA    I22 @T6G_MB_LIB.T6G(SCH_1):PAGE92

M_H_CPU0_SB_DQ<12> @T6G_MB_LIB.T6G(SCH_1):M_H_CPU0_SB_DQ(12)
   U25 CM13 MHB_DATA12 GENOA_SP5-SOCKET6096_13568-001,SMLF,IO,DGA^6000030   I159 @T6G_MB_LIB.T6G(SCH_1):PAGE17
   J69  118 DQ12_B SCONN288_DDR506112002KQ-SCONN288_DDR506112002KQ,SMA    I22 @T6G_MB_LIB.T6G(SCH_1):PAGE92

M_H_CPU0_SB_DQ<13> @T6G_MB_LIB.T6G(SCH_1):M_H_CPU0_SB_DQ(13)
   U25 CN14 MHB_DATA13 GENOA_SP5-SOCKET6096_13568-001,SMLF,IO,DGA^6000030   I159 @T6G_MB_LIB.T6G(SCH_1):PAGE17
   J69  120 DQ13_B SCONN288_DDR506112002KQ-SCONN288_DDR506112002KQ,SMA    I22 @T6G_MB_LIB.T6G(SCH_1):PAGE92

M_H_CPU0_SB_DQ<14> @T6G_MB_LIB.T6G(SCH_1):M_H_CPU0_SB_DQ(14)
   U25 CN12 MHB_DATA14 GENOA_SP5-SOCKET6096_13568-001,SMLF,IO,DGA^6000030   I159 @T6G_MB_LIB.T6G(SCH_1):PAGE17
   J69  263 DQ14_B SCONN288_DDR506112002KQ-SCONN288_DDR506112002KQ,SMA    I22 @T6G_MB_LIB.T6G(SCH_1):PAGE92

M_H_CPU0_SB_DQ<15> @T6G_MB_LIB.T6G(SCH_1):M_H_CPU0_SB_DQ(15)
   U25 CP14 MHB_DATA15 GENOA_SP5-SOCKET6096_13568-001,SMLF,IO,DGA^6000030   I159 @T6G_MB_LIB.T6G(SCH_1):PAGE17
   J69  265 DQ15_B SCONN288_DDR506112002KQ-SCONN288_DDR506112002KQ,SMA    I22 @T6G_MB_LIB.T6G(SCH_1):PAGE92

M_H_CPU0_SB_DQ<16> @T6G_MB_LIB.T6G(SCH_1):M_H_CPU0_SB_DQ(16)
   U25 CP13 MHB_DATA16 GENOA_SP5-SOCKET6096_13568-001,SMLF,IO,DGA^6000030   I159 @T6G_MB_LIB.T6G(SCH_1):PAGE17
   J69  122 DQ16_B SCONN288_DDR506112002KQ-SCONN288_DDR506112002KQ,SMA    I22 @T6G_MB_LIB.T6G(SCH_1):PAGE92

M_H_CPU0_SB_DQ<17> @T6G_MB_LIB.T6G(SCH_1):M_H_CPU0_SB_DQ(17)
   U25 CR14 MHB_DATA17 GENOA_SP5-SOCKET6096_13568-001,SMLF,IO,DGA^6000030   I159 @T6G_MB_LIB.T6G(SCH_1):PAGE17
   J69  124 DQ17_B SCONN288_DDR506112002KQ-SCONN288_DDR506112002KQ,SMA    I22 @T6G_MB_LIB.T6G(SCH_1):PAGE92

M_H_CPU0_SB_DQ<18> @T6G_MB_LIB.T6G(SCH_1):M_H_CPU0_SB_DQ(18)
   U25 CR12 MHB_DATA18 GENOA_SP5-SOCKET6096_13568-001,SMLF,IO,DGA^6000030   I159 @T6G_MB_LIB.T6G(SCH_1):PAGE17
   J69  267 DQ18_B SCONN288_DDR506112002KQ-SCONN288_DDR506112002KQ,SMA    I22 @T6G_MB_LIB.T6G(SCH_1):PAGE92

M_H_CPU0_SB_DQ<19> @T6G_MB_LIB.T6G(SCH_1):M_H_CPU0_SB_DQ(19)
   U25 CT14 MHB_DATA19 GENOA_SP5-SOCKET6096_13568-001,SMLF,IO,DGA^6000030   I159 @T6G_MB_LIB.T6G(SCH_1):PAGE17
   J69  269 DQ19_B SCONN288_DDR506112002KQ-SCONN288_DDR506112002KQ,SMA    I22 @T6G_MB_LIB.T6G(SCH_1):PAGE92

M_H_CPU0_SB_DQ<1> @T6G_MB_LIB.T6G(SCH_1):M_H_CPU0_SB_DQ(1)
   U25 CC14 MHB_DATA1 GENOA_SP5-SOCKET6096_13568-001,SMLF,IO,DGA^6000030   I159 @T6G_MB_LIB.T6G(SCH_1):PAGE17
   J69  102  DQ1_B SCONN288_DDR506112002KQ-SCONN288_DDR506112002KQ,SMA    I22 @T6G_MB_LIB.T6G(SCH_1):PAGE92

M_H_CPU0_SB_DQ<20> @T6G_MB_LIB.T6G(SCH_1):M_H_CPU0_SB_DQ(20)
   U25 CV13 MHB_DATA20 GENOA_SP5-SOCKET6096_13568-001,SMLF,IO,DGA^6000030   I159 @T6G_MB_LIB.T6G(SCH_1):PAGE17
   J69  129 DQ20_B SCONN288_DDR506112002KQ-SCONN288_DDR506112002KQ,SMA    I22 @T6G_MB_LIB.T6G(SCH_1):PAGE92

M_H_CPU0_SB_DQ<21> @T6G_MB_LIB.T6G(SCH_1):M_H_CPU0_SB_DQ(21)
   U25 CW14 MHB_DATA21 GENOA_SP5-SOCKET6096_13568-001,SMLF,IO,DGA^6000030   I159 @T6G_MB_LIB.T6G(SCH_1):PAGE17
   J69  131 DQ21_B SCONN288_DDR506112002KQ-SCONN288_DDR506112002KQ,SMA    I22 @T6G_MB_LIB.T6G(SCH_1):PAGE92

M_H_CPU0_SB_DQ<22> @T6G_MB_LIB.T6G(SCH_1):M_H_CPU0_SB_DQ(22)
   U25 CW12 MHB_DATA22 GENOA_SP5-SOCKET6096_13568-001,SMLF,IO,DGA^6000030   I159 @T6G_MB_LIB.T6G(SCH_1):PAGE17
   J69  274 DQ22_B SCONN288_DDR506112002KQ-SCONN288_DDR506112002KQ,SMA    I22 @T6G_MB_LIB.T6G(SCH_1):PAGE92

M_H_CPU0_SB_DQ<23> @T6G_MB_LIB.T6G(SCH_1):M_H_CPU0_SB_DQ(23)
   U25 CY14 MHB_DATA23 GENOA_SP5-SOCKET6096_13568-001,SMLF,IO,DGA^6000030   I159 @T6G_MB_LIB.T6G(SCH_1):PAGE17
   J69  276 DQ23_B SCONN288_DDR506112002KQ-SCONN288_DDR506112002KQ,SMA    I22 @T6G_MB_LIB.T6G(SCH_1):PAGE92

M_H_CPU0_SB_DQ<24> @T6G_MB_LIB.T6G(SCH_1):M_H_CPU0_SB_DQ(24)
   U25 CY13 MHB_DATA24 GENOA_SP5-SOCKET6096_13568-001,SMLF,IO,DGA^6000030   I159 @T6G_MB_LIB.T6G(SCH_1):PAGE17
   J69  133 DQ24_B SCONN288_DDR506112002KQ-SCONN288_DDR506112002KQ,SMA    I22 @T6G_MB_LIB.T6G(SCH_1):PAGE92

M_H_CPU0_SB_DQ<25> @T6G_MB_LIB.T6G(SCH_1):M_H_CPU0_SB_DQ(25)
   U25 DA14 MHB_DATA25 GENOA_SP5-SOCKET6096_13568-001,SMLF,IO,DGA^6000030   I159 @T6G_MB_LIB.T6G(SCH_1):PAGE17
   J69  135 DQ25_B SCONN288_DDR506112002KQ-SCONN288_DDR506112002KQ,SMA    I22 @T6G_MB_LIB.T6G(SCH_1):PAGE92

M_H_CPU0_SB_DQ<26> @T6G_MB_LIB.T6G(SCH_1):M_H_CPU0_SB_DQ(26)
   U25 DA12 MHB_DATA26 GENOA_SP5-SOCKET6096_13568-001,SMLF,IO,DGA^6000030   I159 @T6G_MB_LIB.T6G(SCH_1):PAGE17
   J69  278 DQ26_B SCONN288_DDR506112002KQ-SCONN288_DDR506112002KQ,SMA    I22 @T6G_MB_LIB.T6G(SCH_1):PAGE92

M_H_CPU0_SB_DQ<27> @T6G_MB_LIB.T6G(SCH_1):M_H_CPU0_SB_DQ(27)
   U25 DB14 MHB_DATA27 GENOA_SP5-SOCKET6096_13568-001,SMLF,IO,DGA^6000030   I159 @T6G_MB_LIB.T6G(SCH_1):PAGE17
   J69  280 DQ27_B SCONN288_DDR506112002KQ-SCONN288_DDR506112002KQ,SMA    I22 @T6G_MB_LIB.T6G(SCH_1):PAGE92

M_H_CPU0_SB_DQ<28> @T6G_MB_LIB.T6G(SCH_1):M_H_CPU0_SB_DQ(28)
   U25 DD13 MHB_DATA28 GENOA_SP5-SOCKET6096_13568-001,SMLF,IO,DGA^6000030   I159 @T6G_MB_LIB.T6G(SCH_1):PAGE17
   J69  140 DQ28_B SCONN288_DDR506112002KQ-SCONN288_DDR506112002KQ,SMA    I22 @T6G_MB_LIB.T6G(SCH_1):PAGE92

M_H_CPU0_SB_DQ<29> @T6G_MB_LIB.T6G(SCH_1):M_H_CPU0_SB_DQ(29)
   U25 DE14 MHB_DATA29 GENOA_SP5-SOCKET6096_13568-001,SMLF,IO,DGA^6000030   I159 @T6G_MB_LIB.T6G(SCH_1):PAGE17
   J69  142 DQ29_B SCONN288_DDR506112002KQ-SCONN288_DDR506112002KQ,SMA    I22 @T6G_MB_LIB.T6G(SCH_1):PAGE92

M_H_CPU0_SB_DQ<2> @T6G_MB_LIB.T6G(SCH_1):M_H_CPU0_SB_DQ(2)
   U25 CC12 MHB_DATA2 GENOA_SP5-SOCKET6096_13568-001,SMLF,IO,DGA^6000030   I159 @T6G_MB_LIB.T6G(SCH_1):PAGE17
   J69  245  DQ2_B SCONN288_DDR506112002KQ-SCONN288_DDR506112002KQ,SMA    I22 @T6G_MB_LIB.T6G(SCH_1):PAGE92

M_H_CPU0_SB_DQ<30> @T6G_MB_LIB.T6G(SCH_1):M_H_CPU0_SB_DQ(30)
   U25 DE12 MHB_DATA30 GENOA_SP5-SOCKET6096_13568-001,SMLF,IO,DGA^6000030   I159 @T6G_MB_LIB.T6G(SCH_1):PAGE17
   J69  285 DQ30_B SCONN288_DDR506112002KQ-SCONN288_DDR506112002KQ,SMA    I22 @T6G_MB_LIB.T6G(SCH_1):PAGE92

M_H_CPU0_SB_DQ<31> @T6G_MB_LIB.T6G(SCH_1):M_H_CPU0_SB_DQ(31)
   U25 DF14 MHB_DATA31 GENOA_SP5-SOCKET6096_13568-001,SMLF,IO,DGA^6000030   I159 @T6G_MB_LIB.T6G(SCH_1):PAGE17
   J69  287 DQ31_B SCONN288_DDR506112002KQ-SCONN288_DDR506112002KQ,SMA    I22 @T6G_MB_LIB.T6G(SCH_1):PAGE92

M_H_CPU0_SB_DQ<3> @T6G_MB_LIB.T6G(SCH_1):M_H_CPU0_SB_DQ(3)
   U25 CD14 MHB_DATA3 GENOA_SP5-SOCKET6096_13568-001,SMLF,IO,DGA^6000030   I159 @T6G_MB_LIB.T6G(SCH_1):PAGE17
   J69  247  DQ3_B SCONN288_DDR506112002KQ-SCONN288_DDR506112002KQ,SMA    I22 @T6G_MB_LIB.T6G(SCH_1):PAGE92

M_H_CPU0_SB_DQ<4> @T6G_MB_LIB.T6G(SCH_1):M_H_CPU0_SB_DQ(4)
   U25 CF13 MHB_DATA4 GENOA_SP5-SOCKET6096_13568-001,SMLF,IO,DGA^6000030   I159 @T6G_MB_LIB.T6G(SCH_1):PAGE17
   J69  107  DQ4_B SCONN288_DDR506112002KQ-SCONN288_DDR506112002KQ,SMA    I22 @T6G_MB_LIB.T6G(SCH_1):PAGE92

M_H_CPU0_SB_DQ<5> @T6G_MB_LIB.T6G(SCH_1):M_H_CPU0_SB_DQ(5)
   U25 CG14 MHB_DATA5 GENOA_SP5-SOCKET6096_13568-001,SMLF,IO,DGA^6000030   I159 @T6G_MB_LIB.T6G(SCH_1):PAGE17
   J69  109  DQ5_B SCONN288_DDR506112002KQ-SCONN288_DDR506112002KQ,SMA    I22 @T6G_MB_LIB.T6G(SCH_1):PAGE92

M_H_CPU0_SB_DQ<6> @T6G_MB_LIB.T6G(SCH_1):M_H_CPU0_SB_DQ(6)
   U25 CG12 MHB_DATA6 GENOA_SP5-SOCKET6096_13568-001,SMLF,IO,DGA^6000030   I159 @T6G_MB_LIB.T6G(SCH_1):PAGE17
   J69  252  DQ6_B SCONN288_DDR506112002KQ-SCONN288_DDR506112002KQ,SMA    I22 @T6G_MB_LIB.T6G(SCH_1):PAGE92

M_H_CPU0_SB_DQ<7> @T6G_MB_LIB.T6G(SCH_1):M_H_CPU0_SB_DQ(7)
   U25 CH14 MHB_DATA7 GENOA_SP5-SOCKET6096_13568-001,SMLF,IO,DGA^6000030   I159 @T6G_MB_LIB.T6G(SCH_1):PAGE17
   J69  254  DQ7_B SCONN288_DDR506112002KQ-SCONN288_DDR506112002KQ,SMA    I22 @T6G_MB_LIB.T6G(SCH_1):PAGE92

M_H_CPU0_SB_DQ<8> @T6G_MB_LIB.T6G(SCH_1):M_H_CPU0_SB_DQ(8)
   U25 CH13 MHB_DATA8 GENOA_SP5-SOCKET6096_13568-001,SMLF,IO,DGA^6000030   I159 @T6G_MB_LIB.T6G(SCH_1):PAGE17
   J69  111  DQ8_B SCONN288_DDR506112002KQ-SCONN288_DDR506112002KQ,SMA    I22 @T6G_MB_LIB.T6G(SCH_1):PAGE92

M_H_CPU0_SB_DQ<9> @T6G_MB_LIB.T6G(SCH_1):M_H_CPU0_SB_DQ(9)
   U25 CJ14 MHB_DATA9 GENOA_SP5-SOCKET6096_13568-001,SMLF,IO,DGA^6000030   I159 @T6G_MB_LIB.T6G(SCH_1):PAGE17
   J69  113  DQ9_B SCONN288_DDR506112002KQ-SCONN288_DDR506112002KQ,SMA    I22 @T6G_MB_LIB.T6G(SCH_1):PAGE92

M_H_CPU0_SB_DQS_DN<0> @T6G_MB_LIB.T6G(SCH_1):M_H_CPU0_SB_DQS_DN(0)
   U25 CE12 MHB_DQS_L0 GENOA_SP5-SOCKET6096_13568-001,SMLF,IO,DGA^6000030   I159 @T6G_MB_LIB.T6G(SCH_1):PAGE17
   J69  105 DQS0_B_C SCONN288_DDR506112002KQ-SCONN288_DDR506112002KQ,SMA   I237 @T6G_MB_LIB.T6G(SCH_1):PAGE92

M_H_CPU0_SB_DQS_DN<1> @T6G_MB_LIB.T6G(SCH_1):M_H_CPU0_SB_DQS_DN(1)
   U25 CL12 MHB_DQS_L1 GENOA_SP5-SOCKET6096_13568-001,SMLF,IO,DGA^6000030   I159 @T6G_MB_LIB.T6G(SCH_1):PAGE17
   J69  116 DQS1_B_C SCONN288_DDR506112002KQ-SCONN288_DDR506112002KQ,SMA   I237 @T6G_MB_LIB.T6G(SCH_1):PAGE92

M_H_CPU0_SB_DQS_DN<2> @T6G_MB_LIB.T6G(SCH_1):M_H_CPU0_SB_DQS_DN(2)
   U25 CU12 MHB_DQS_L2 GENOA_SP5-SOCKET6096_13568-001,SMLF,IO,DGA^6000030   I159 @T6G_MB_LIB.T6G(SCH_1):PAGE17
   J69  127 DQS2_B_C SCONN288_DDR506112002KQ-SCONN288_DDR506112002KQ,SMA   I237 @T6G_MB_LIB.T6G(SCH_1):PAGE92

M_H_CPU0_SB_DQS_DN<3> @T6G_MB_LIB.T6G(SCH_1):M_H_CPU0_SB_DQS_DN(3)
   U25 DC12 MHB_DQS_L3 GENOA_SP5-SOCKET6096_13568-001,SMLF,IO,DGA^6000030   I159 @T6G_MB_LIB.T6G(SCH_1):PAGE17
   J69  138 DQS3_B_C SCONN288_DDR506112002KQ-SCONN288_DDR506112002KQ,SMA   I237 @T6G_MB_LIB.T6G(SCH_1):PAGE92

M_H_CPU0_SB_DQS_DN<4> @T6G_MB_LIB.T6G(SCH_1):M_H_CPU0_SB_DQS_DN(4)
   U25 BW14 MHB_DQS_L4 GENOA_SP5-SOCKET6096_13568-001,SMLF,IO,DGA^6000030   I159 @T6G_MB_LIB.T6G(SCH_1):PAGE17
   J69  238 DQS4_B_C SCONN288_DDR506112002KQ-SCONN288_DDR506112002KQ,SMA   I237 @T6G_MB_LIB.T6G(SCH_1):PAGE92

M_H_CPU0_SB_DQS_DN<5> @T6G_MB_LIB.T6G(SCH_1):M_H_CPU0_SB_DQS_DN(5)
   U25 CE14 MHB_DQS_L5 GENOA_SP5-SOCKET6096_13568-001,SMLF,IO,DGA^6000030   I159 @T6G_MB_LIB.T6G(SCH_1):PAGE17
   J69  249 DQS5_B_C||TDQS5_B_C SCONN288_DDR506112002KQ-SCONN288_DDR506112002KQ,SMA   I237 @T6G_MB_LIB.T6G(SCH_1):PAGE92

M_H_CPU0_SB_DQS_DN<6> @T6G_MB_LIB.T6G(SCH_1):M_H_CPU0_SB_DQS_DN(6)
   U25 CL14 MHB_DQS_L6 GENOA_SP5-SOCKET6096_13568-001,SMLF,IO,DGA^6000030   I159 @T6G_MB_LIB.T6G(SCH_1):PAGE17
   J69  260 DQS6_B_C||TDQS6_B_C SCONN288_DDR506112002KQ-SCONN288_DDR506112002KQ,SMA   I237 @T6G_MB_LIB.T6G(SCH_1):PAGE92

M_H_CPU0_SB_DQS_DN<7> @T6G_MB_LIB.T6G(SCH_1):M_H_CPU0_SB_DQS_DN(7)
   U25 CU14 MHB_DQS_L7 GENOA_SP5-SOCKET6096_13568-001,SMLF,IO,DGA^6000030   I159 @T6G_MB_LIB.T6G(SCH_1):PAGE17
   J69  271 DQS7_B_C||TDQS7_B_C SCONN288_DDR506112002KQ-SCONN288_DDR506112002KQ,SMA   I237 @T6G_MB_LIB.T6G(SCH_1):PAGE92

M_H_CPU0_SB_DQS_DN<8> @T6G_MB_LIB.T6G(SCH_1):M_H_CPU0_SB_DQS_DN(8)
   U25 DC14 MHB_DQS_L8 GENOA_SP5-SOCKET6096_13568-001,SMLF,IO,DGA^6000030   I159 @T6G_MB_LIB.T6G(SCH_1):PAGE17
   J69  282 DQS8_B_C||TDQS8_B_C SCONN288_DDR506112002KQ-SCONN288_DDR506112002KQ,SMA   I237 @T6G_MB_LIB.T6G(SCH_1):PAGE92

M_H_CPU0_SB_DQS_DN<9> @T6G_MB_LIB.T6G(SCH_1):M_H_CPU0_SB_DQS_DN(9)
   U25 BW12 MHB_DQS_L9 GENOA_SP5-SOCKET6096_13568-001,SMLF,IO,DGA^6000030   I159 @T6G_MB_LIB.T6G(SCH_1):PAGE17
   J69   94 DQS9_B_C||TDQS9_B_C SCONN288_DDR506112002KQ-SCONN288_DDR506112002KQ,SMA   I237 @T6G_MB_LIB.T6G(SCH_1):PAGE92

M_H_CPU0_SB_DQS_DP<0> @T6G_MB_LIB.T6G(SCH_1):M_H_CPU0_SB_DQS_DP(0)
   U25 CD13 MHB_DQS_H0 GENOA_SP5-SOCKET6096_13568-001,SMLF,IO,DGA^6000030   I159 @T6G_MB_LIB.T6G(SCH_1):PAGE17
   J69  104 DQS0_B_T SCONN288_DDR506112002KQ-SCONN288_DDR506112002KQ,SMA   I237 @T6G_MB_LIB.T6G(SCH_1):PAGE92

M_H_CPU0_SB_DQS_DP<1> @T6G_MB_LIB.T6G(SCH_1):M_H_CPU0_SB_DQS_DP(1)
   U25 CK13 MHB_DQS_H1 GENOA_SP5-SOCKET6096_13568-001,SMLF,IO,DGA^6000030   I159 @T6G_MB_LIB.T6G(SCH_1):PAGE17
   J69  115 DQS1_B_T SCONN288_DDR506112002KQ-SCONN288_DDR506112002KQ,SMA   I237 @T6G_MB_LIB.T6G(SCH_1):PAGE92

M_H_CPU0_SB_DQS_DP<2> @T6G_MB_LIB.T6G(SCH_1):M_H_CPU0_SB_DQS_DP(2)
   U25 CT13 MHB_DQS_H2 GENOA_SP5-SOCKET6096_13568-001,SMLF,IO,DGA^6000030   I159 @T6G_MB_LIB.T6G(SCH_1):PAGE17
   J69  126 DQS2_B_T SCONN288_DDR506112002KQ-SCONN288_DDR506112002KQ,SMA   I237 @T6G_MB_LIB.T6G(SCH_1):PAGE92

M_H_CPU0_SB_DQS_DP<3> @T6G_MB_LIB.T6G(SCH_1):M_H_CPU0_SB_DQS_DP(3)
   U25 DB13 MHB_DQS_H3 GENOA_SP5-SOCKET6096_13568-001,SMLF,IO,DGA^6000030   I159 @T6G_MB_LIB.T6G(SCH_1):PAGE17
   J69  137 DQS3_B_T SCONN288_DDR506112002KQ-SCONN288_DDR506112002KQ,SMA   I237 @T6G_MB_LIB.T6G(SCH_1):PAGE92

M_H_CPU0_SB_DQS_DP<4> @T6G_MB_LIB.T6G(SCH_1):M_H_CPU0_SB_DQS_DP(4)
   U25 BY14 MHB_DQS_H4 GENOA_SP5-SOCKET6096_13568-001,SMLF,IO,DGA^6000030   I159 @T6G_MB_LIB.T6G(SCH_1):PAGE17
   J69  239 DQS4_B_T SCONN288_DDR506112002KQ-SCONN288_DDR506112002KQ,SMA   I237 @T6G_MB_LIB.T6G(SCH_1):PAGE92

M_H_CPU0_SB_DQS_DP<5> @T6G_MB_LIB.T6G(SCH_1):M_H_CPU0_SB_DQS_DP(5)
   U25 CF14 MHB_DQS_H5 GENOA_SP5-SOCKET6096_13568-001,SMLF,IO,DGA^6000030   I159 @T6G_MB_LIB.T6G(SCH_1):PAGE17
   J69  250 DQS5_B_T||TDQS5_B_T SCONN288_DDR506112002KQ-SCONN288_DDR506112002KQ,SMA   I237 @T6G_MB_LIB.T6G(SCH_1):PAGE92

M_H_CPU0_SB_DQS_DP<6> @T6G_MB_LIB.T6G(SCH_1):M_H_CPU0_SB_DQS_DP(6)
   U25 CM14 MHB_DQS_H6 GENOA_SP5-SOCKET6096_13568-001,SMLF,IO,DGA^6000030   I159 @T6G_MB_LIB.T6G(SCH_1):PAGE17
   J69  261 DQS6_B_T||TDQS6_B_T SCONN288_DDR506112002KQ-SCONN288_DDR506112002KQ,SMA   I237 @T6G_MB_LIB.T6G(SCH_1):PAGE92

M_H_CPU0_SB_DQS_DP<7> @T6G_MB_LIB.T6G(SCH_1):M_H_CPU0_SB_DQS_DP(7)
   U25 CV14 MHB_DQS_H7 GENOA_SP5-SOCKET6096_13568-001,SMLF,IO,DGA^6000030   I159 @T6G_MB_LIB.T6G(SCH_1):PAGE17
   J69  272 DQS7_B_T||TDQS7_B_T SCONN288_DDR506112002KQ-SCONN288_DDR506112002KQ,SMA   I237 @T6G_MB_LIB.T6G(SCH_1):PAGE92

M_H_CPU0_SB_DQS_DP<8> @T6G_MB_LIB.T6G(SCH_1):M_H_CPU0_SB_DQS_DP(8)
   U25 DD14 MHB_DQS_H8 GENOA_SP5-SOCKET6096_13568-001,SMLF,IO,DGA^6000030   I159 @T6G_MB_LIB.T6G(SCH_1):PAGE17
   J69  283 DQS8_B_T||TDQS8_B_T SCONN288_DDR506112002KQ-SCONN288_DDR506112002KQ,SMA   I237 @T6G_MB_LIB.T6G(SCH_1):PAGE92

M_H_CPU0_SB_DQS_DP<9> @T6G_MB_LIB.T6G(SCH_1):M_H_CPU0_SB_DQS_DP(9)
   U25 BV13 MHB_DQS_H9 GENOA_SP5-SOCKET6096_13568-001,SMLF,IO,DGA^6000030   I159 @T6G_MB_LIB.T6G(SCH_1):PAGE17
   J69   93 DQS9_B_T||TDQS9_B_T||DBI4_B_N SCONN288_DDR506112002KQ-SCONN288_DDR506112002KQ,SMA   I237 @T6G_MB_LIB.T6G(SCH_1):PAGE92

M_H_CPU0_SB_PAR @T6G_MB_LIB.T6G(SCH_1):M_H_CPU0_SB_PAR
   U25 BL14 MHB_PAR GENOA_SP5-SOCKET6096_13568-001,SMLF,IO,DGA^6000030   I159 @T6G_MB_LIB.T6G(SCH_1):PAGE17
   J69  227  PAR_B SCONN288_DDR506112002KQ-SCONN288_DDR506112002KQ,SMA    I22 @T6G_MB_LIB.T6G(SCH_1):PAGE92

M_H_CPU0_SB_RSP<0> @T6G_MB_LIB.T6G(SCH_1):M_H_CPU0_SB_RSP(0)
   U25 BP13 MHB0_RSP_L GENOA_SP5-SOCKET6096_13568-001,SMLF,IO,DGA^6000030   I159 @T6G_MB_LIB.T6G(SCH_1):PAGE17
   J69   87 LBS||RSP_B_N SCONN288_DDR506112002KQ-SCONN288_DDR506112002KQ,SMA    I22 @T6G_MB_LIB.T6G(SCH_1):PAGE92

M_H_CPU1_ALERT_N @T6G_MB_LIB.T6G(SCH_1):M_H_CPU1_ALERT_N
  R507    1      A Q_RES_0402LF-15,1%,1/16W,CHIP,CS01502FB03   I314 @T6G_MB_LIB.T6G(SCH_1):PAGE44
   J27   62 ALERT_N SCONN288_DDR506112002KQ-SCONN288_DDR506112002KQ,SMA    I22 @T6G_MB_LIB.T6G(SCH_1):PAGE104

M_H_CPU1_ALERT_R_N @T6G_MB_LIB.T6G(SCH_1):M_H_CPU1_ALERT_R_N
   U26 AT14 MH_ALERT_L GENOA_SP5-SOCKET6096_13568-001,SMLF,IO,DGA^6000030   I159 @T6G_MB_LIB.T6G(SCH_1):PAGE44
  R507    2      B Q_RES_0402LF-15,1%,1/16W,CHIP,CS01502FB03   I314 @T6G_MB_LIB.T6G(SCH_1):PAGE44

M_H_CPU1_CLK_DN<0> @T6G_MB_LIB.T6G(SCH_1):M_H_CPU1_CLK_DN(0)
   U26 BD13 MH0_CLK_L GENOA_SP5-SOCKET6096_13568-001,SMLF,IO,DGA^6000030   I159 @T6G_MB_LIB.T6G(SCH_1):PAGE44
   J27  218   CK_C SCONN288_DDR506112002KQ-SCONN288_DDR506112002KQ,SMA    I22 @T6G_MB_LIB.T6G(SCH_1):PAGE104

M_H_CPU1_CLK_DP<0> @T6G_MB_LIB.T6G(SCH_1):M_H_CPU1_CLK_DP(0)
   U26 BC12 MH0_CLK_H GENOA_SP5-SOCKET6096_13568-001,SMLF,IO,DGA^6000030   I159 @T6G_MB_LIB.T6G(SCH_1):PAGE44
   J27  217   CK_T SCONN288_DDR506112002KQ-SCONN288_DDR506112002KQ,SMA    I22 @T6G_MB_LIB.T6G(SCH_1):PAGE104

M_H_CPU1_RESET_N @T6G_MB_LIB.T6G(SCH_1):M_H_CPU1_RESET_N
   U26 AU14 MH_RESET_L GENOA_SP5-SOCKET6096_13568-001,SMLF,IO,DGA^6000030   I159 @T6G_MB_LIB.T6G(SCH_1):PAGE44
   J27  207 RESET_N SCONN288_DDR506112002KQ-SCONN288_DDR506112002KQ,SMA    I22 @T6G_MB_LIB.T6G(SCH_1):PAGE104

M_H_CPU1_SA_CA<0> @T6G_MB_LIB.T6G(SCH_1):M_H_CPU1_SA_CA(0)
   U26 AW12 MHA_CA0 GENOA_SP5-SOCKET6096_13568-001,SMLF,IO,DGA^6000030   I159 @T6G_MB_LIB.T6G(SCH_1):PAGE44
   J27   66  CA0_A SCONN288_DDR506112002KQ-SCONN288_DDR506112002KQ,SMA    I22 @T6G_MB_LIB.T6G(SCH_1):PAGE104

M_H_CPU1_SA_CA<1> @T6G_MB_LIB.T6G(SCH_1):M_H_CPU1_SA_CA(1)
   U26 AY13 MHA_CA1 GENOA_SP5-SOCKET6096_13568-001,SMLF,IO,DGA^6000030   I159 @T6G_MB_LIB.T6G(SCH_1):PAGE44
   J27  211  CA1_A SCONN288_DDR506112002KQ-SCONN288_DDR506112002KQ,SMA    I22 @T6G_MB_LIB.T6G(SCH_1):PAGE104

M_H_CPU1_SA_CA<2> @T6G_MB_LIB.T6G(SCH_1):M_H_CPU1_SA_CA(2)
   U26 AY14 MHA_CA2 GENOA_SP5-SOCKET6096_13568-001,SMLF,IO,DGA^6000030   I159 @T6G_MB_LIB.T6G(SCH_1):PAGE44
   J27   68  CA2_A SCONN288_DDR506112002KQ-SCONN288_DDR506112002KQ,SMA    I22 @T6G_MB_LIB.T6G(SCH_1):PAGE104

M_H_CPU1_SA_CA<3> @T6G_MB_LIB.T6G(SCH_1):M_H_CPU1_SA_CA(3)
   U26 BA14 MHA_CA3 GENOA_SP5-SOCKET6096_13568-001,SMLF,IO,DGA^6000030   I159 @T6G_MB_LIB.T6G(SCH_1):PAGE44
   J27  213  CA3_A SCONN288_DDR506112002KQ-SCONN288_DDR506112002KQ,SMA    I22 @T6G_MB_LIB.T6G(SCH_1):PAGE104

M_H_CPU1_SA_CA<4> @T6G_MB_LIB.T6G(SCH_1):M_H_CPU1_SA_CA(4)
   U26 BA12 MHA_CA4 GENOA_SP5-SOCKET6096_13568-001,SMLF,IO,DGA^6000030   I159 @T6G_MB_LIB.T6G(SCH_1):PAGE44
   J27   70  CA4_A SCONN288_DDR506112002KQ-SCONN288_DDR506112002KQ,SMA    I22 @T6G_MB_LIB.T6G(SCH_1):PAGE104

M_H_CPU1_SA_CA<5> @T6G_MB_LIB.T6G(SCH_1):M_H_CPU1_SA_CA(5)
   U26 BB13 MHA_CA5 GENOA_SP5-SOCKET6096_13568-001,SMLF,IO,DGA^6000030   I159 @T6G_MB_LIB.T6G(SCH_1):PAGE44
   J27  215  CA5_A SCONN288_DDR506112002KQ-SCONN288_DDR506112002KQ,SMA    I22 @T6G_MB_LIB.T6G(SCH_1):PAGE104

M_H_CPU1_SA_CA<6> @T6G_MB_LIB.T6G(SCH_1):M_H_CPU1_SA_CA(6)
   U26 BB14 MHA_CA6 GENOA_SP5-SOCKET6096_13568-001,SMLF,IO,DGA^6000030   I159 @T6G_MB_LIB.T6G(SCH_1):PAGE44
   J27   72  CA6_A SCONN288_DDR506112002KQ-SCONN288_DDR506112002KQ,SMA    I22 @T6G_MB_LIB.T6G(SCH_1):PAGE104

M_H_CPU1_SA_CB<0> @T6G_MB_LIB.T6G(SCH_1):M_H_CPU1_SA_CB(0)
   U26 AJ12 MHA_CHECK0 GENOA_SP5-SOCKET6096_13568-001,SMLF,IO,DGA^6000030   I159 @T6G_MB_LIB.T6G(SCH_1):PAGE44
   J27   51  CB0_A SCONN288_DDR506112002KQ-SCONN288_DDR506112002KQ,SMA    I22 @T6G_MB_LIB.T6G(SCH_1):PAGE104

M_H_CPU1_SA_CB<1> @T6G_MB_LIB.T6G(SCH_1):M_H_CPU1_SA_CB(1)
   U26 AK14 MHA_CHECK1 GENOA_SP5-SOCKET6096_13568-001,SMLF,IO,DGA^6000030   I159 @T6G_MB_LIB.T6G(SCH_1):PAGE44
   J27   53  CB1_A SCONN288_DDR506112002KQ-SCONN288_DDR506112002KQ,SMA    I22 @T6G_MB_LIB.T6G(SCH_1):PAGE104

M_H_CPU1_SA_CB<2> @T6G_MB_LIB.T6G(SCH_1):M_H_CPU1_SA_CB(2)
   U26 AK13 MHA_CHECK2 GENOA_SP5-SOCKET6096_13568-001,SMLF,IO,DGA^6000030   I159 @T6G_MB_LIB.T6G(SCH_1):PAGE44
   J27  196  CB2_A SCONN288_DDR506112002KQ-SCONN288_DDR506112002KQ,SMA    I22 @T6G_MB_LIB.T6G(SCH_1):PAGE104

M_H_CPU1_SA_CB<3> @T6G_MB_LIB.T6G(SCH_1):M_H_CPU1_SA_CB(3)
   U26 AL14 MHA_CHECK3 GENOA_SP5-SOCKET6096_13568-001,SMLF,IO,DGA^6000030   I159 @T6G_MB_LIB.T6G(SCH_1):PAGE44
   J27  198  CB3_A SCONN288_DDR506112002KQ-SCONN288_DDR506112002KQ,SMA    I22 @T6G_MB_LIB.T6G(SCH_1):PAGE104

M_H_CPU1_SA_CB<4> @T6G_MB_LIB.T6G(SCH_1):M_H_CPU1_SA_CB(4)
   U26 AN12 MHA_CHECK4 GENOA_SP5-SOCKET6096_13568-001,SMLF,IO,DGA^6000030   I159 @T6G_MB_LIB.T6G(SCH_1):PAGE44
   J27   58  CB4_A SCONN288_DDR506112002KQ-SCONN288_DDR506112002KQ,SMA    I22 @T6G_MB_LIB.T6G(SCH_1):PAGE104

M_H_CPU1_SA_CB<5> @T6G_MB_LIB.T6G(SCH_1):M_H_CPU1_SA_CB(5)
   U26 AP14 MHA_CHECK5 GENOA_SP5-SOCKET6096_13568-001,SMLF,IO,DGA^6000030   I159 @T6G_MB_LIB.T6G(SCH_1):PAGE44
   J27   60  CB5_A SCONN288_DDR506112002KQ-SCONN288_DDR506112002KQ,SMA    I22 @T6G_MB_LIB.T6G(SCH_1):PAGE104

M_H_CPU1_SA_CB<6> @T6G_MB_LIB.T6G(SCH_1):M_H_CPU1_SA_CB(6)
   U26 AP13 MHA_CHECK6 GENOA_SP5-SOCKET6096_13568-001,SMLF,IO,DGA^6000030   I159 @T6G_MB_LIB.T6G(SCH_1):PAGE44
   J27  203  CB6_A SCONN288_DDR506112002KQ-SCONN288_DDR506112002KQ,SMA    I22 @T6G_MB_LIB.T6G(SCH_1):PAGE104

M_H_CPU1_SA_CB<7> @T6G_MB_LIB.T6G(SCH_1):M_H_CPU1_SA_CB(7)
   U26 AR14 MHA_CHECK7 GENOA_SP5-SOCKET6096_13568-001,SMLF,IO,DGA^6000030   I159 @T6G_MB_LIB.T6G(SCH_1):PAGE44
   J27  205  CB7_A SCONN288_DDR506112002KQ-SCONN288_DDR506112002KQ,SMA    I22 @T6G_MB_LIB.T6G(SCH_1):PAGE104

M_H_CPU1_SA_CS_N<0> @T6G_MB_LIB.T6G(SCH_1):M_H_CPU1_SA_CS_N(0)
   U26 AU12 MHA0_CS_L0 GENOA_SP5-SOCKET6096_13568-001,SMLF,IO,DGA^6000030   I159 @T6G_MB_LIB.T6G(SCH_1):PAGE44
   J27   64 CS0_A_N SCONN288_DDR506112002KQ-SCONN288_DDR506112002KQ,SMA    I22 @T6G_MB_LIB.T6G(SCH_1):PAGE104

M_H_CPU1_SA_CS_N<1> @T6G_MB_LIB.T6G(SCH_1):M_H_CPU1_SA_CS_N(1)
   U26 AV14 MHA0_CS_L1 GENOA_SP5-SOCKET6096_13568-001,SMLF,IO,DGA^6000030   I159 @T6G_MB_LIB.T6G(SCH_1):PAGE44
   J27  209 CS1_A_N SCONN288_DDR506112002KQ-SCONN288_DDR506112002KQ,SMA    I22 @T6G_MB_LIB.T6G(SCH_1):PAGE104

M_H_CPU1_SA_DQ<0> @T6G_MB_LIB.T6G(SCH_1):M_H_CPU1_SA_DQ(0)
   U26  E12 MHA_DATA0 GENOA_SP5-SOCKET6096_13568-001,SMLF,IO,DGA^6000030   I159 @T6G_MB_LIB.T6G(SCH_1):PAGE44
   J27    7  DQ0_A SCONN288_DDR506112002KQ-SCONN288_DDR506112002KQ,SMA    I22 @T6G_MB_LIB.T6G(SCH_1):PAGE104

M_H_CPU1_SA_DQ<10> @T6G_MB_LIB.T6G(SCH_1):M_H_CPU1_SA_DQ(10)
   U26  M13 MHA_DATA10 GENOA_SP5-SOCKET6096_13568-001,SMLF,IO,DGA^6000030   I159 @T6G_MB_LIB.T6G(SCH_1):PAGE44
   J27  163 DQ10_A SCONN288_DDR506112002KQ-SCONN288_DDR506112002KQ,SMA    I22 @T6G_MB_LIB.T6G(SCH_1):PAGE104

M_H_CPU1_SA_DQ<11> @T6G_MB_LIB.T6G(SCH_1):M_H_CPU1_SA_DQ(11)
   U26  N14 MHA_DATA11 GENOA_SP5-SOCKET6096_13568-001,SMLF,IO,DGA^6000030   I159 @T6G_MB_LIB.T6G(SCH_1):PAGE44
   J27  165 DQ11_A SCONN288_DDR506112002KQ-SCONN288_DDR506112002KQ,SMA    I22 @T6G_MB_LIB.T6G(SCH_1):PAGE104

M_H_CPU1_SA_DQ<12> @T6G_MB_LIB.T6G(SCH_1):M_H_CPU1_SA_DQ(12)
   U26  R12 MHA_DATA12 GENOA_SP5-SOCKET6096_13568-001,SMLF,IO,DGA^6000030   I159 @T6G_MB_LIB.T6G(SCH_1):PAGE44
   J27   25 DQ12_A SCONN288_DDR506112002KQ-SCONN288_DDR506112002KQ,SMA    I22 @T6G_MB_LIB.T6G(SCH_1):PAGE104

M_H_CPU1_SA_DQ<13> @T6G_MB_LIB.T6G(SCH_1):M_H_CPU1_SA_DQ(13)
   U26  T14 MHA_DATA13 GENOA_SP5-SOCKET6096_13568-001,SMLF,IO,DGA^6000030   I159 @T6G_MB_LIB.T6G(SCH_1):PAGE44
   J27   27 DQ13_A SCONN288_DDR506112002KQ-SCONN288_DDR506112002KQ,SMA    I22 @T6G_MB_LIB.T6G(SCH_1):PAGE104

M_H_CPU1_SA_DQ<14> @T6G_MB_LIB.T6G(SCH_1):M_H_CPU1_SA_DQ(14)
   U26  T13 MHA_DATA14 GENOA_SP5-SOCKET6096_13568-001,SMLF,IO,DGA^6000030   I159 @T6G_MB_LIB.T6G(SCH_1):PAGE44
   J27  170 DQ14_A SCONN288_DDR506112002KQ-SCONN288_DDR506112002KQ,SMA    I22 @T6G_MB_LIB.T6G(SCH_1):PAGE104

M_H_CPU1_SA_DQ<15> @T6G_MB_LIB.T6G(SCH_1):M_H_CPU1_SA_DQ(15)
   U26  U14 MHA_DATA15 GENOA_SP5-SOCKET6096_13568-001,SMLF,IO,DGA^6000030   I159 @T6G_MB_LIB.T6G(SCH_1):PAGE44
   J27  172 DQ15_A SCONN288_DDR506112002KQ-SCONN288_DDR506112002KQ,SMA    I22 @T6G_MB_LIB.T6G(SCH_1):PAGE104

M_H_CPU1_SA_DQ<16> @T6G_MB_LIB.T6G(SCH_1):M_H_CPU1_SA_DQ(16)
   U26  U12 MHA_DATA16 GENOA_SP5-SOCKET6096_13568-001,SMLF,IO,DGA^6000030   I159 @T6G_MB_LIB.T6G(SCH_1):PAGE44
   J27   29 DQ16_A SCONN288_DDR506112002KQ-SCONN288_DDR506112002KQ,SMA    I22 @T6G_MB_LIB.T6G(SCH_1):PAGE104

M_H_CPU1_SA_DQ<17> @T6G_MB_LIB.T6G(SCH_1):M_H_CPU1_SA_DQ(17)
   U26  V14 MHA_DATA17 GENOA_SP5-SOCKET6096_13568-001,SMLF,IO,DGA^6000030   I159 @T6G_MB_LIB.T6G(SCH_1):PAGE44
   J27   31 DQ17_A SCONN288_DDR506112002KQ-SCONN288_DDR506112002KQ,SMA    I22 @T6G_MB_LIB.T6G(SCH_1):PAGE104

M_H_CPU1_SA_DQ<18> @T6G_MB_LIB.T6G(SCH_1):M_H_CPU1_SA_DQ(18)
   U26  V13 MHA_DATA18 GENOA_SP5-SOCKET6096_13568-001,SMLF,IO,DGA^6000030   I159 @T6G_MB_LIB.T6G(SCH_1):PAGE44
   J27  174 DQ18_A SCONN288_DDR506112002KQ-SCONN288_DDR506112002KQ,SMA    I22 @T6G_MB_LIB.T6G(SCH_1):PAGE104

M_H_CPU1_SA_DQ<19> @T6G_MB_LIB.T6G(SCH_1):M_H_CPU1_SA_DQ(19)
   U26  W14 MHA_DATA19 GENOA_SP5-SOCKET6096_13568-001,SMLF,IO,DGA^6000030   I159 @T6G_MB_LIB.T6G(SCH_1):PAGE44
   J27  176 DQ19_A SCONN288_DDR506112002KQ-SCONN288_DDR506112002KQ,SMA    I22 @T6G_MB_LIB.T6G(SCH_1):PAGE104

M_H_CPU1_SA_DQ<1> @T6G_MB_LIB.T6G(SCH_1):M_H_CPU1_SA_DQ(1)
   U26  F14 MHA_DATA1 GENOA_SP5-SOCKET6096_13568-001,SMLF,IO,DGA^6000030   I159 @T6G_MB_LIB.T6G(SCH_1):PAGE44
   J27    9  DQ1_A SCONN288_DDR506112002KQ-SCONN288_DDR506112002KQ,SMA    I22 @T6G_MB_LIB.T6G(SCH_1):PAGE104

M_H_CPU1_SA_DQ<20> @T6G_MB_LIB.T6G(SCH_1):M_H_CPU1_SA_DQ(20)
   U26 AA12 MHA_DATA20 GENOA_SP5-SOCKET6096_13568-001,SMLF,IO,DGA^6000030   I159 @T6G_MB_LIB.T6G(SCH_1):PAGE44
   J27   36 DQ20_A SCONN288_DDR506112002KQ-SCONN288_DDR506112002KQ,SMA    I22 @T6G_MB_LIB.T6G(SCH_1):PAGE104

M_H_CPU1_SA_DQ<21> @T6G_MB_LIB.T6G(SCH_1):M_H_CPU1_SA_DQ(21)
   U26 AB14 MHA_DATA21 GENOA_SP5-SOCKET6096_13568-001,SMLF,IO,DGA^6000030   I159 @T6G_MB_LIB.T6G(SCH_1):PAGE44
   J27   38 DQ21_A SCONN288_DDR506112002KQ-SCONN288_DDR506112002KQ,SMA    I22 @T6G_MB_LIB.T6G(SCH_1):PAGE104

M_H_CPU1_SA_DQ<22> @T6G_MB_LIB.T6G(SCH_1):M_H_CPU1_SA_DQ(22)
   U26 AB13 MHA_DATA22 GENOA_SP5-SOCKET6096_13568-001,SMLF,IO,DGA^6000030   I159 @T6G_MB_LIB.T6G(SCH_1):PAGE44
   J27  181 DQ22_A SCONN288_DDR506112002KQ-SCONN288_DDR506112002KQ,SMA    I22 @T6G_MB_LIB.T6G(SCH_1):PAGE104

M_H_CPU1_SA_DQ<23> @T6G_MB_LIB.T6G(SCH_1):M_H_CPU1_SA_DQ(23)
   U26 AC14 MHA_DATA23 GENOA_SP5-SOCKET6096_13568-001,SMLF,IO,DGA^6000030   I159 @T6G_MB_LIB.T6G(SCH_1):PAGE44
   J27  183 DQ23_A SCONN288_DDR506112002KQ-SCONN288_DDR506112002KQ,SMA    I22 @T6G_MB_LIB.T6G(SCH_1):PAGE104

M_H_CPU1_SA_DQ<24> @T6G_MB_LIB.T6G(SCH_1):M_H_CPU1_SA_DQ(24)
   U26 AC12 MHA_DATA24 GENOA_SP5-SOCKET6096_13568-001,SMLF,IO,DGA^6000030   I159 @T6G_MB_LIB.T6G(SCH_1):PAGE44
   J27   40 DQ24_A SCONN288_DDR506112002KQ-SCONN288_DDR506112002KQ,SMA    I22 @T6G_MB_LIB.T6G(SCH_1):PAGE104

M_H_CPU1_SA_DQ<25> @T6G_MB_LIB.T6G(SCH_1):M_H_CPU1_SA_DQ(25)
   U26 AD14 MHA_DATA25 GENOA_SP5-SOCKET6096_13568-001,SMLF,IO,DGA^6000030   I159 @T6G_MB_LIB.T6G(SCH_1):PAGE44
   J27   42 DQ25_A SCONN288_DDR506112002KQ-SCONN288_DDR506112002KQ,SMA    I22 @T6G_MB_LIB.T6G(SCH_1):PAGE104

M_H_CPU1_SA_DQ<26> @T6G_MB_LIB.T6G(SCH_1):M_H_CPU1_SA_DQ(26)
   U26 AD13 MHA_DATA26 GENOA_SP5-SOCKET6096_13568-001,SMLF,IO,DGA^6000030   I159 @T6G_MB_LIB.T6G(SCH_1):PAGE44
   J27  185 DQ26_A SCONN288_DDR506112002KQ-SCONN288_DDR506112002KQ,SMA    I22 @T6G_MB_LIB.T6G(SCH_1):PAGE104

M_H_CPU1_SA_DQ<27> @T6G_MB_LIB.T6G(SCH_1):M_H_CPU1_SA_DQ(27)
   U26 AE14 MHA_DATA27 GENOA_SP5-SOCKET6096_13568-001,SMLF,IO,DGA^6000030   I159 @T6G_MB_LIB.T6G(SCH_1):PAGE44
   J27  187 DQ27_A SCONN288_DDR506112002KQ-SCONN288_DDR506112002KQ,SMA    I22 @T6G_MB_LIB.T6G(SCH_1):PAGE104

M_H_CPU1_SA_DQ<28> @T6G_MB_LIB.T6G(SCH_1):M_H_CPU1_SA_DQ(28)
   U26 AG12 MHA_DATA28 GENOA_SP5-SOCKET6096_13568-001,SMLF,IO,DGA^6000030   I159 @T6G_MB_LIB.T6G(SCH_1):PAGE44
   J27   47 DQ28_A SCONN288_DDR506112002KQ-SCONN288_DDR506112002KQ,SMA    I22 @T6G_MB_LIB.T6G(SCH_1):PAGE104

M_H_CPU1_SA_DQ<29> @T6G_MB_LIB.T6G(SCH_1):M_H_CPU1_SA_DQ(29)
   U26 AH14 MHA_DATA29 GENOA_SP5-SOCKET6096_13568-001,SMLF,IO,DGA^6000030   I159 @T6G_MB_LIB.T6G(SCH_1):PAGE44
   J27   49 DQ29_A SCONN288_DDR506112002KQ-SCONN288_DDR506112002KQ,SMA    I22 @T6G_MB_LIB.T6G(SCH_1):PAGE104

M_H_CPU1_SA_DQ<2> @T6G_MB_LIB.T6G(SCH_1):M_H_CPU1_SA_DQ(2)
   U26  F13 MHA_DATA2 GENOA_SP5-SOCKET6096_13568-001,SMLF,IO,DGA^6000030   I159 @T6G_MB_LIB.T6G(SCH_1):PAGE44
   J27  152  DQ2_A SCONN288_DDR506112002KQ-SCONN288_DDR506112002KQ,SMA    I22 @T6G_MB_LIB.T6G(SCH_1):PAGE104

M_H_CPU1_SA_DQ<30> @T6G_MB_LIB.T6G(SCH_1):M_H_CPU1_SA_DQ(30)
   U26 AH13 MHA_DATA30 GENOA_SP5-SOCKET6096_13568-001,SMLF,IO,DGA^6000030   I159 @T6G_MB_LIB.T6G(SCH_1):PAGE44
   J27  192 DQ30_A SCONN288_DDR506112002KQ-SCONN288_DDR506112002KQ,SMA    I22 @T6G_MB_LIB.T6G(SCH_1):PAGE104

M_H_CPU1_SA_DQ<31> @T6G_MB_LIB.T6G(SCH_1):M_H_CPU1_SA_DQ(31)
   U26 AJ14 MHA_DATA31 GENOA_SP5-SOCKET6096_13568-001,SMLF,IO,DGA^6000030   I159 @T6G_MB_LIB.T6G(SCH_1):PAGE44
   J27  194 DQ31_A SCONN288_DDR506112002KQ-SCONN288_DDR506112002KQ,SMA    I22 @T6G_MB_LIB.T6G(SCH_1):PAGE104

M_H_CPU1_SA_DQ<3> @T6G_MB_LIB.T6G(SCH_1):M_H_CPU1_SA_DQ(3)
   U26  G14 MHA_DATA3 GENOA_SP5-SOCKET6096_13568-001,SMLF,IO,DGA^6000030   I159 @T6G_MB_LIB.T6G(SCH_1):PAGE44
   J27  154  DQ3_A SCONN288_DDR506112002KQ-SCONN288_DDR506112002KQ,SMA    I22 @T6G_MB_LIB.T6G(SCH_1):PAGE104

M_H_CPU1_SA_DQ<4> @T6G_MB_LIB.T6G(SCH_1):M_H_CPU1_SA_DQ(4)
   U26  J12 MHA_DATA4 GENOA_SP5-SOCKET6096_13568-001,SMLF,IO,DGA^6000030   I159 @T6G_MB_LIB.T6G(SCH_1):PAGE44
   J27   14  DQ4_A SCONN288_DDR506112002KQ-SCONN288_DDR506112002KQ,SMA    I22 @T6G_MB_LIB.T6G(SCH_1):PAGE104

M_H_CPU1_SA_DQ<5> @T6G_MB_LIB.T6G(SCH_1):M_H_CPU1_SA_DQ(5)
   U26  K14 MHA_DATA5 GENOA_SP5-SOCKET6096_13568-001,SMLF,IO,DGA^6000030   I159 @T6G_MB_LIB.T6G(SCH_1):PAGE44
   J27   16  DQ5_A SCONN288_DDR506112002KQ-SCONN288_DDR506112002KQ,SMA    I22 @T6G_MB_LIB.T6G(SCH_1):PAGE104

M_H_CPU1_SA_DQ<6> @T6G_MB_LIB.T6G(SCH_1):M_H_CPU1_SA_DQ(6)
   U26  K13 MHA_DATA6 GENOA_SP5-SOCKET6096_13568-001,SMLF,IO,DGA^6000030   I159 @T6G_MB_LIB.T6G(SCH_1):PAGE44
   J27  159  DQ6_A SCONN288_DDR506112002KQ-SCONN288_DDR506112002KQ,SMA    I22 @T6G_MB_LIB.T6G(SCH_1):PAGE104

M_H_CPU1_SA_DQ<7> @T6G_MB_LIB.T6G(SCH_1):M_H_CPU1_SA_DQ(7)
   U26  L14 MHA_DATA7 GENOA_SP5-SOCKET6096_13568-001,SMLF,IO,DGA^6000030   I159 @T6G_MB_LIB.T6G(SCH_1):PAGE44
   J27  161  DQ7_A SCONN288_DDR506112002KQ-SCONN288_DDR506112002KQ,SMA    I22 @T6G_MB_LIB.T6G(SCH_1):PAGE104

M_H_CPU1_SA_DQ<8> @T6G_MB_LIB.T6G(SCH_1):M_H_CPU1_SA_DQ(8)
   U26  L12 MHA_DATA8 GENOA_SP5-SOCKET6096_13568-001,SMLF,IO,DGA^6000030   I159 @T6G_MB_LIB.T6G(SCH_1):PAGE44
   J27   18  DQ8_A SCONN288_DDR506112002KQ-SCONN288_DDR506112002KQ,SMA    I22 @T6G_MB_LIB.T6G(SCH_1):PAGE104

M_H_CPU1_SA_DQ<9> @T6G_MB_LIB.T6G(SCH_1):M_H_CPU1_SA_DQ(9)
   U26  M14 MHA_DATA9 GENOA_SP5-SOCKET6096_13568-001,SMLF,IO,DGA^6000030   I159 @T6G_MB_LIB.T6G(SCH_1):PAGE44
   J27   20  DQ9_A SCONN288_DDR506112002KQ-SCONN288_DDR506112002KQ,SMA    I22 @T6G_MB_LIB.T6G(SCH_1):PAGE104

M_H_CPU1_SA_DQS_DN<0> @T6G_MB_LIB.T6G(SCH_1):M_H_CPU1_SA_DQS_DN(0)
   U26  H13 MHA_DQS_L0 GENOA_SP5-SOCKET6096_13568-001,SMLF,IO,DGA^6000030   I159 @T6G_MB_LIB.T6G(SCH_1):PAGE44
   J27   12 DQS0_A_C SCONN288_DDR506112002KQ-SCONN288_DDR506112002KQ,SMA   I238 @T6G_MB_LIB.T6G(SCH_1):PAGE104

M_H_CPU1_SA_DQS_DN<1> @T6G_MB_LIB.T6G(SCH_1):M_H_CPU1_SA_DQS_DN(1)
   U26  P13 MHA_DQS_L1 GENOA_SP5-SOCKET6096_13568-001,SMLF,IO,DGA^6000030   I159 @T6G_MB_LIB.T6G(SCH_1):PAGE44
   J27   23 DQS1_A_C SCONN288_DDR506112002KQ-SCONN288_DDR506112002KQ,SMA   I238 @T6G_MB_LIB.T6G(SCH_1):PAGE104

M_H_CPU1_SA_DQS_DN<2> @T6G_MB_LIB.T6G(SCH_1):M_H_CPU1_SA_DQS_DN(2)
   U26  Y13 MHA_DQS_L2 GENOA_SP5-SOCKET6096_13568-001,SMLF,IO,DGA^6000030   I159 @T6G_MB_LIB.T6G(SCH_1):PAGE44
   J27   34 DQS2_A_C SCONN288_DDR506112002KQ-SCONN288_DDR506112002KQ,SMA   I238 @T6G_MB_LIB.T6G(SCH_1):PAGE104

M_H_CPU1_SA_DQS_DN<3> @T6G_MB_LIB.T6G(SCH_1):M_H_CPU1_SA_DQS_DN(3)
   U26 AF13 MHA_DQS_L3 GENOA_SP5-SOCKET6096_13568-001,SMLF,IO,DGA^6000030   I159 @T6G_MB_LIB.T6G(SCH_1):PAGE44
   J27   45 DQS3_A_C SCONN288_DDR506112002KQ-SCONN288_DDR506112002KQ,SMA   I238 @T6G_MB_LIB.T6G(SCH_1):PAGE104

M_H_CPU1_SA_DQS_DN<4> @T6G_MB_LIB.T6G(SCH_1):M_H_CPU1_SA_DQS_DN(4)
   U26 AM13 MHA_DQS_L4 GENOA_SP5-SOCKET6096_13568-001,SMLF,IO,DGA^6000030   I159 @T6G_MB_LIB.T6G(SCH_1):PAGE44
   J27   56 DQS4_A_C SCONN288_DDR506112002KQ-SCONN288_DDR506112002KQ,SMA   I238 @T6G_MB_LIB.T6G(SCH_1):PAGE104

M_H_CPU1_SA_DQS_DN<5> @T6G_MB_LIB.T6G(SCH_1):M_H_CPU1_SA_DQS_DN(5)
   U26  H14 MHA_DQS_L5 GENOA_SP5-SOCKET6096_13568-001,SMLF,IO,DGA^6000030   I159 @T6G_MB_LIB.T6G(SCH_1):PAGE44
   J27  156 DQS5_A_C||TDQS5_A_C||DQS5_A_T||TDQS5_A_T SCONN288_DDR506112002KQ-SCONN288_DDR506112002KQ,SMA   I238 @T6G_MB_LIB.T6G(SCH_1):PAGE104

M_H_CPU1_SA_DQS_DN<6> @T6G_MB_LIB.T6G(SCH_1):M_H_CPU1_SA_DQS_DN(6)
   U26  P14 MHA_DQS_L6 GENOA_SP5-SOCKET6096_13568-001,SMLF,IO,DGA^6000030   I159 @T6G_MB_LIB.T6G(SCH_1):PAGE44
   J27  167 DQS6_A_C||TDQS6_A_C||DQS6_A_T||TDQS6_A_T SCONN288_DDR506112002KQ-SCONN288_DDR506112002KQ,SMA   I238 @T6G_MB_LIB.T6G(SCH_1):PAGE104

M_H_CPU1_SA_DQS_DN<7> @T6G_MB_LIB.T6G(SCH_1):M_H_CPU1_SA_DQS_DN(7)
   U26  Y14 MHA_DQS_L7 GENOA_SP5-SOCKET6096_13568-001,SMLF,IO,DGA^6000030   I159 @T6G_MB_LIB.T6G(SCH_1):PAGE44
   J27  178 DQS7_A_C||TDQS7_A_C SCONN288_DDR506112002KQ-SCONN288_DDR506112002KQ,SMA   I238 @T6G_MB_LIB.T6G(SCH_1):PAGE104

M_H_CPU1_SA_DQS_DN<8> @T6G_MB_LIB.T6G(SCH_1):M_H_CPU1_SA_DQS_DN(8)
   U26 AF14 MHA_DQS_L8 GENOA_SP5-SOCKET6096_13568-001,SMLF,IO,DGA^6000030   I159 @T6G_MB_LIB.T6G(SCH_1):PAGE44
   J27  189 DQS8_A_C||TDQS8_A_C SCONN288_DDR506112002KQ-SCONN288_DDR506112002KQ,SMA   I238 @T6G_MB_LIB.T6G(SCH_1):PAGE104

M_H_CPU1_SA_DQS_DN<9> @T6G_MB_LIB.T6G(SCH_1):M_H_CPU1_SA_DQS_DN(9)
   U26 AM14 MHA_DQS_L9 GENOA_SP5-SOCKET6096_13568-001,SMLF,IO,DGA^6000030   I159 @T6G_MB_LIB.T6G(SCH_1):PAGE44
   J27  200 DQS9_A_C||TDQS9_A_C SCONN288_DDR506112002KQ-SCONN288_DDR506112002KQ,SMA   I238 @T6G_MB_LIB.T6G(SCH_1):PAGE104

M_H_CPU1_SA_DQS_DP<0> @T6G_MB_LIB.T6G(SCH_1):M_H_CPU1_SA_DQS_DP(0)
   U26  G12 MHA_DQS_H0 GENOA_SP5-SOCKET6096_13568-001,SMLF,IO,DGA^6000030   I159 @T6G_MB_LIB.T6G(SCH_1):PAGE44
   J27   11 DQS0_A_T SCONN288_DDR506112002KQ-SCONN288_DDR506112002KQ,SMA   I238 @T6G_MB_LIB.T6G(SCH_1):PAGE104

M_H_CPU1_SA_DQS_DP<1> @T6G_MB_LIB.T6G(SCH_1):M_H_CPU1_SA_DQS_DP(1)
   U26  N12 MHA_DQS_H1 GENOA_SP5-SOCKET6096_13568-001,SMLF,IO,DGA^6000030   I159 @T6G_MB_LIB.T6G(SCH_1):PAGE44
   J27   22 DQS1_A_T SCONN288_DDR506112002KQ-SCONN288_DDR506112002KQ,SMA   I238 @T6G_MB_LIB.T6G(SCH_1):PAGE104

M_H_CPU1_SA_DQS_DP<2> @T6G_MB_LIB.T6G(SCH_1):M_H_CPU1_SA_DQS_DP(2)
   U26  W12 MHA_DQS_H2 GENOA_SP5-SOCKET6096_13568-001,SMLF,IO,DGA^6000030   I159 @T6G_MB_LIB.T6G(SCH_1):PAGE44
   J27   33 DQS2_A_T SCONN288_DDR506112002KQ-SCONN288_DDR506112002KQ,SMA   I238 @T6G_MB_LIB.T6G(SCH_1):PAGE104

M_H_CPU1_SA_DQS_DP<3> @T6G_MB_LIB.T6G(SCH_1):M_H_CPU1_SA_DQS_DP(3)
   U26 AE12 MHA_DQS_H3 GENOA_SP5-SOCKET6096_13568-001,SMLF,IO,DGA^6000030   I159 @T6G_MB_LIB.T6G(SCH_1):PAGE44
   J27   44 DQS3_A_T SCONN288_DDR506112002KQ-SCONN288_DDR506112002KQ,SMA   I238 @T6G_MB_LIB.T6G(SCH_1):PAGE104

M_H_CPU1_SA_DQS_DP<4> @T6G_MB_LIB.T6G(SCH_1):M_H_CPU1_SA_DQS_DP(4)
   U26 AL12 MHA_DQS_H4 GENOA_SP5-SOCKET6096_13568-001,SMLF,IO,DGA^6000030   I159 @T6G_MB_LIB.T6G(SCH_1):PAGE44
   J27   55 DQS4_A_T SCONN288_DDR506112002KQ-SCONN288_DDR506112002KQ,SMA   I238 @T6G_MB_LIB.T6G(SCH_1):PAGE104

M_H_CPU1_SA_DQS_DP<5> @T6G_MB_LIB.T6G(SCH_1):M_H_CPU1_SA_DQS_DP(5)
   U26  J14 MHA_DQS_H5 GENOA_SP5-SOCKET6096_13568-001,SMLF,IO,DGA^6000030   I159 @T6G_MB_LIB.T6G(SCH_1):PAGE44
   J27  157 DQS5_A_T||TDQS5_A_T SCONN288_DDR506112002KQ-SCONN288_DDR506112002KQ,SMA   I238 @T6G_MB_LIB.T6G(SCH_1):PAGE104

M_H_CPU1_SA_DQS_DP<6> @T6G_MB_LIB.T6G(SCH_1):M_H_CPU1_SA_DQS_DP(6)
   U26  R14 MHA_DQS_H6 GENOA_SP5-SOCKET6096_13568-001,SMLF,IO,DGA^6000030   I159 @T6G_MB_LIB.T6G(SCH_1):PAGE44
   J27  168 DQS6_A_T||TDQS6_A_T SCONN288_DDR506112002KQ-SCONN288_DDR506112002KQ,SMA   I238 @T6G_MB_LIB.T6G(SCH_1):PAGE104

M_H_CPU1_SA_DQS_DP<7> @T6G_MB_LIB.T6G(SCH_1):M_H_CPU1_SA_DQS_DP(7)
   U26 AA14 MHA_DQS_H7 GENOA_SP5-SOCKET6096_13568-001,SMLF,IO,DGA^6000030   I159 @T6G_MB_LIB.T6G(SCH_1):PAGE44
   J27  179 DQS7_A_T||TDQS7_A_T SCONN288_DDR506112002KQ-SCONN288_DDR506112002KQ,SMA   I238 @T6G_MB_LIB.T6G(SCH_1):PAGE104

M_H_CPU1_SA_DQS_DP<8> @T6G_MB_LIB.T6G(SCH_1):M_H_CPU1_SA_DQS_DP(8)
   U26 AG14 MHA_DQS_H8 GENOA_SP5-SOCKET6096_13568-001,SMLF,IO,DGA^6000030   I159 @T6G_MB_LIB.T6G(SCH_1):PAGE44
   J27  190 DQS8_A_T||TDQS8_A_T SCONN288_DDR506112002KQ-SCONN288_DDR506112002KQ,SMA   I238 @T6G_MB_LIB.T6G(SCH_1):PAGE104

M_H_CPU1_SA_DQS_DP<9> @T6G_MB_LIB.T6G(SCH_1):M_H_CPU1_SA_DQS_DP(9)
   U26 AN14 MHA_DQS_H9 GENOA_SP5-SOCKET6096_13568-001,SMLF,IO,DGA^6000030   I159 @T6G_MB_LIB.T6G(SCH_1):PAGE44
   J27  201 DQS9_A_T||TDQS9_A_T SCONN288_DDR506112002KQ-SCONN288_DDR506112002KQ,SMA   I238 @T6G_MB_LIB.T6G(SCH_1):PAGE104

M_H_CPU1_SA_PAR @T6G_MB_LIB.T6G(SCH_1):M_H_CPU1_SA_PAR
   U26 BC14 MHA_PAR GENOA_SP5-SOCKET6096_13568-001,SMLF,IO,DGA^6000030   I159 @T6G_MB_LIB.T6G(SCH_1):PAGE44
   J27   74  PAR_A SCONN288_DDR506112002KQ-SCONN288_DDR506112002KQ,SMA    I22 @T6G_MB_LIB.T6G(SCH_1):PAGE104

M_H_CPU1_SA_RSP<0> @T6G_MB_LIB.T6G(SCH_1):M_H_CPU1_SA_RSP(0)
   U26 BN14 MHA0_RSP_L GENOA_SP5-SOCKET6096_13568-001,SMLF,IO,DGA^6000030   I159 @T6G_MB_LIB.T6G(SCH_1):PAGE44
   J27   86 LBD||RSP_A_N SCONN288_DDR506112002KQ-SCONN288_DDR506112002KQ,SMA    I22 @T6G_MB_LIB.T6G(SCH_1):PAGE104

M_H_CPU1_SB_CA<0> @T6G_MB_LIB.T6G(SCH_1):M_H_CPU1_SB_CA(0)
   U26 BG14 MHB_CA0 GENOA_SP5-SOCKET6096_13568-001,SMLF,IO,DGA^6000030   I159 @T6G_MB_LIB.T6G(SCH_1):PAGE44
   J27   76  CA0_B SCONN288_DDR506112002KQ-SCONN288_DDR506112002KQ,SMA    I22 @T6G_MB_LIB.T6G(SCH_1):PAGE104

M_H_CPU1_SB_CA<1> @T6G_MB_LIB.T6G(SCH_1):M_H_CPU1_SB_CA(1)
   U26 BH14 MHB_CA1 GENOA_SP5-SOCKET6096_13568-001,SMLF,IO,DGA^6000030   I159 @T6G_MB_LIB.T6G(SCH_1):PAGE44
   J27  221  CA1_B SCONN288_DDR506112002KQ-SCONN288_DDR506112002KQ,SMA    I22 @T6G_MB_LIB.T6G(SCH_1):PAGE104

M_H_CPU1_SB_CA<2> @T6G_MB_LIB.T6G(SCH_1):M_H_CPU1_SB_CA(2)
   U26 BH13 MHB_CA2 GENOA_SP5-SOCKET6096_13568-001,SMLF,IO,DGA^6000030   I159 @T6G_MB_LIB.T6G(SCH_1):PAGE44
   J27   78  CA2_B SCONN288_DDR506112002KQ-SCONN288_DDR506112002KQ,SMA    I22 @T6G_MB_LIB.T6G(SCH_1):PAGE104

M_H_CPU1_SB_CA<3> @T6G_MB_LIB.T6G(SCH_1):M_H_CPU1_SB_CA(3)
   U26 BJ12 MHB_CA3 GENOA_SP5-SOCKET6096_13568-001,SMLF,IO,DGA^6000030   I159 @T6G_MB_LIB.T6G(SCH_1):PAGE44
   J27  223  CA3_B SCONN288_DDR506112002KQ-SCONN288_DDR506112002KQ,SMA    I22 @T6G_MB_LIB.T6G(SCH_1):PAGE104

M_H_CPU1_SB_CA<4> @T6G_MB_LIB.T6G(SCH_1):M_H_CPU1_SB_CA(4)
   U26 BJ14 MHB_CA4 GENOA_SP5-SOCKET6096_13568-001,SMLF,IO,DGA^6000030   I159 @T6G_MB_LIB.T6G(SCH_1):PAGE44
   J27   80  CA4_B SCONN288_DDR506112002KQ-SCONN288_DDR506112002KQ,SMA    I22 @T6G_MB_LIB.T6G(SCH_1):PAGE104

M_H_CPU1_SB_CA<5> @T6G_MB_LIB.T6G(SCH_1):M_H_CPU1_SB_CA(5)
   U26 BK14 MHB_CA5 GENOA_SP5-SOCKET6096_13568-001,SMLF,IO,DGA^6000030   I159 @T6G_MB_LIB.T6G(SCH_1):PAGE44
   J27  225  CA5_B SCONN288_DDR506112002KQ-SCONN288_DDR506112002KQ,SMA    I22 @T6G_MB_LIB.T6G(SCH_1):PAGE104

M_H_CPU1_SB_CA<6> @T6G_MB_LIB.T6G(SCH_1):M_H_CPU1_SB_CA(6)
   U26 BK13 MHB_CA6 GENOA_SP5-SOCKET6096_13568-001,SMLF,IO,DGA^6000030   I159 @T6G_MB_LIB.T6G(SCH_1):PAGE44
   J27   82  CA6_B SCONN288_DDR506112002KQ-SCONN288_DDR506112002KQ,SMA    I22 @T6G_MB_LIB.T6G(SCH_1):PAGE104

M_H_CPU1_SB_CB<0> @T6G_MB_LIB.T6G(SCH_1):M_H_CPU1_SB_CB(0)
   U26 BY13 MHB_CHECK0 GENOA_SP5-SOCKET6096_13568-001,SMLF,IO,DGA^6000030   I159 @T6G_MB_LIB.T6G(SCH_1):PAGE44
   J27   96  CB0_B SCONN288_DDR506112002KQ-SCONN288_DDR506112002KQ,SMA    I22 @T6G_MB_LIB.T6G(SCH_1):PAGE104

M_H_CPU1_SB_CB<1> @T6G_MB_LIB.T6G(SCH_1):M_H_CPU1_SB_CB(1)
   U26 CA14 MHB_CHECK1 GENOA_SP5-SOCKET6096_13568-001,SMLF,IO,DGA^6000030   I159 @T6G_MB_LIB.T6G(SCH_1):PAGE44
   J27   98  CB1_B SCONN288_DDR506112002KQ-SCONN288_DDR506112002KQ,SMA    I22 @T6G_MB_LIB.T6G(SCH_1):PAGE104

M_H_CPU1_SB_CB<2> @T6G_MB_LIB.T6G(SCH_1):M_H_CPU1_SB_CB(2)
   U26 CA12 MHB_CHECK2 GENOA_SP5-SOCKET6096_13568-001,SMLF,IO,DGA^6000030   I159 @T6G_MB_LIB.T6G(SCH_1):PAGE44
   J27  241  CB2_B SCONN288_DDR506112002KQ-SCONN288_DDR506112002KQ,SMA    I22 @T6G_MB_LIB.T6G(SCH_1):PAGE104

M_H_CPU1_SB_CB<3> @T6G_MB_LIB.T6G(SCH_1):M_H_CPU1_SB_CB(3)
   U26 CB14 MHB_CHECK3 GENOA_SP5-SOCKET6096_13568-001,SMLF,IO,DGA^6000030   I159 @T6G_MB_LIB.T6G(SCH_1):PAGE44
   J27  243  CB3_B SCONN288_DDR506112002KQ-SCONN288_DDR506112002KQ,SMA    I22 @T6G_MB_LIB.T6G(SCH_1):PAGE104

M_H_CPU1_SB_CB<4> @T6G_MB_LIB.T6G(SCH_1):M_H_CPU1_SB_CB(4)
   U26 BT13 MHB_CHECK4 GENOA_SP5-SOCKET6096_13568-001,SMLF,IO,DGA^6000030   I159 @T6G_MB_LIB.T6G(SCH_1):PAGE44
   J27   89  CB4_B SCONN288_DDR506112002KQ-SCONN288_DDR506112002KQ,SMA    I22 @T6G_MB_LIB.T6G(SCH_1):PAGE104

M_H_CPU1_SB_CB<5> @T6G_MB_LIB.T6G(SCH_1):M_H_CPU1_SB_CB(5)
   U26 BU14 MHB_CHECK5 GENOA_SP5-SOCKET6096_13568-001,SMLF,IO,DGA^6000030   I159 @T6G_MB_LIB.T6G(SCH_1):PAGE44
   J27   91  CB5_B SCONN288_DDR506112002KQ-SCONN288_DDR506112002KQ,SMA    I22 @T6G_MB_LIB.T6G(SCH_1):PAGE104

M_H_CPU1_SB_CB<6> @T6G_MB_LIB.T6G(SCH_1):M_H_CPU1_SB_CB(6)
   U26 BU12 MHB_CHECK6 GENOA_SP5-SOCKET6096_13568-001,SMLF,IO,DGA^6000030   I159 @T6G_MB_LIB.T6G(SCH_1):PAGE44
   J27  234  CB6_B SCONN288_DDR506112002KQ-SCONN288_DDR506112002KQ,SMA    I22 @T6G_MB_LIB.T6G(SCH_1):PAGE104

M_H_CPU1_SB_CB<7> @T6G_MB_LIB.T6G(SCH_1):M_H_CPU1_SB_CB(7)
   U26 BV14 MHB_CHECK7 GENOA_SP5-SOCKET6096_13568-001,SMLF,IO,DGA^6000030   I159 @T6G_MB_LIB.T6G(SCH_1):PAGE44
   J27  236  CB7_B SCONN288_DDR506112002KQ-SCONN288_DDR506112002KQ,SMA    I22 @T6G_MB_LIB.T6G(SCH_1):PAGE104

M_H_CPU1_SB_CS_N<0> @T6G_MB_LIB.T6G(SCH_1):M_H_CPU1_SB_CS_N(0)
   U26 BM14 MHB0_CS_L0 GENOA_SP5-SOCKET6096_13568-001,SMLF,IO,DGA^6000030   I159 @T6G_MB_LIB.T6G(SCH_1):PAGE44
   J27   84 CS0_B_N SCONN288_DDR506112002KQ-SCONN288_DDR506112002KQ,SMA    I22 @T6G_MB_LIB.T6G(SCH_1):PAGE104

M_H_CPU1_SB_CS_N<1> @T6G_MB_LIB.T6G(SCH_1):M_H_CPU1_SB_CS_N(1)
   U26 BN12 MHB0_CS_L1 GENOA_SP5-SOCKET6096_13568-001,SMLF,IO,DGA^6000030   I159 @T6G_MB_LIB.T6G(SCH_1):PAGE44
   J27  229 CS1_B_N SCONN288_DDR506112002KQ-SCONN288_DDR506112002KQ,SMA    I22 @T6G_MB_LIB.T6G(SCH_1):PAGE104

M_H_CPU1_SB_DQ<0> @T6G_MB_LIB.T6G(SCH_1):M_H_CPU1_SB_DQ(0)
   U26 CB13 MHB_DATA0 GENOA_SP5-SOCKET6096_13568-001,SMLF,IO,DGA^6000030   I159 @T6G_MB_LIB.T6G(SCH_1):PAGE44
   J27  100  DQ0_B SCONN288_DDR506112002KQ-SCONN288_DDR506112002KQ,SMA    I22 @T6G_MB_LIB.T6G(SCH_1):PAGE104

M_H_CPU1_SB_DQ<10> @T6G_MB_LIB.T6G(SCH_1):M_H_CPU1_SB_DQ(10)
   U26 CJ12 MHB_DATA10 GENOA_SP5-SOCKET6096_13568-001,SMLF,IO,DGA^6000030   I159 @T6G_MB_LIB.T6G(SCH_1):PAGE44
   J27  256 DQ10_B SCONN288_DDR506112002KQ-SCONN288_DDR506112002KQ,SMA    I22 @T6G_MB_LIB.T6G(SCH_1):PAGE104

M_H_CPU1_SB_DQ<11> @T6G_MB_LIB.T6G(SCH_1):M_H_CPU1_SB_DQ(11)
   U26 CK14 MHB_DATA11 GENOA_SP5-SOCKET6096_13568-001,SMLF,IO,DGA^6000030   I159 @T6G_MB_LIB.T6G(SCH_1):PAGE44
   J27  258 DQ11_B SCONN288_DDR506112002KQ-SCONN288_DDR506112002KQ,SMA    I22 @T6G_MB_LIB.T6G(SCH_1):PAGE104

M_H_CPU1_SB_DQ<12> @T6G_MB_LIB.T6G(SCH_1):M_H_CPU1_SB_DQ(12)
   U26 CM13 MHB_DATA12 GENOA_SP5-SOCKET6096_13568-001,SMLF,IO,DGA^6000030   I159 @T6G_MB_LIB.T6G(SCH_1):PAGE44
   J27  118 DQ12_B SCONN288_DDR506112002KQ-SCONN288_DDR506112002KQ,SMA    I22 @T6G_MB_LIB.T6G(SCH_1):PAGE104

M_H_CPU1_SB_DQ<13> @T6G_MB_LIB.T6G(SCH_1):M_H_CPU1_SB_DQ(13)
   U26 CN14 MHB_DATA13 GENOA_SP5-SOCKET6096_13568-001,SMLF,IO,DGA^6000030   I159 @T6G_MB_LIB.T6G(SCH_1):PAGE44
   J27  120 DQ13_B SCONN288_DDR506112002KQ-SCONN288_DDR506112002KQ,SMA    I22 @T6G_MB_LIB.T6G(SCH_1):PAGE104

M_H_CPU1_SB_DQ<14> @T6G_MB_LIB.T6G(SCH_1):M_H_CPU1_SB_DQ(14)
   U26 CN12 MHB_DATA14 GENOA_SP5-SOCKET6096_13568-001,SMLF,IO,DGA^6000030   I159 @T6G_MB_LIB.T6G(SCH_1):PAGE44
   J27  263 DQ14_B SCONN288_DDR506112002KQ-SCONN288_DDR506112002KQ,SMA    I22 @T6G_MB_LIB.T6G(SCH_1):PAGE104

M_H_CPU1_SB_DQ<15> @T6G_MB_LIB.T6G(SCH_1):M_H_CPU1_SB_DQ(15)
   U26 CP14 MHB_DATA15 GENOA_SP5-SOCKET6096_13568-001,SMLF,IO,DGA^6000030   I159 @T6G_MB_LIB.T6G(SCH_1):PAGE44
   J27  265 DQ15_B SCONN288_DDR506112002KQ-SCONN288_DDR506112002KQ,SMA    I22 @T6G_MB_LIB.T6G(SCH_1):PAGE104

M_H_CPU1_SB_DQ<16> @T6G_MB_LIB.T6G(SCH_1):M_H_CPU1_SB_DQ(16)
   U26 CP13 MHB_DATA16 GENOA_SP5-SOCKET6096_13568-001,SMLF,IO,DGA^6000030   I159 @T6G_MB_LIB.T6G(SCH_1):PAGE44
   J27  122 DQ16_B SCONN288_DDR506112002KQ-SCONN288_DDR506112002KQ,SMA    I22 @T6G_MB_LIB.T6G(SCH_1):PAGE104

M_H_CPU1_SB_DQ<17> @T6G_MB_LIB.T6G(SCH_1):M_H_CPU1_SB_DQ(17)
   U26 CR14 MHB_DATA17 GENOA_SP5-SOCKET6096_13568-001,SMLF,IO,DGA^6000030   I159 @T6G_MB_LIB.T6G(SCH_1):PAGE44
   J27  124 DQ17_B SCONN288_DDR506112002KQ-SCONN288_DDR506112002KQ,SMA    I22 @T6G_MB_LIB.T6G(SCH_1):PAGE104

M_H_CPU1_SB_DQ<18> @T6G_MB_LIB.T6G(SCH_1):M_H_CPU1_SB_DQ(18)
   U26 CR12 MHB_DATA18 GENOA_SP5-SOCKET6096_13568-001,SMLF,IO,DGA^6000030   I159 @T6G_MB_LIB.T6G(SCH_1):PAGE44
   J27  267 DQ18_B SCONN288_DDR506112002KQ-SCONN288_DDR506112002KQ,SMA    I22 @T6G_MB_LIB.T6G(SCH_1):PAGE104

M_H_CPU1_SB_DQ<19> @T6G_MB_LIB.T6G(SCH_1):M_H_CPU1_SB_DQ(19)
   U26 CT14 MHB_DATA19 GENOA_SP5-SOCKET6096_13568-001,SMLF,IO,DGA^6000030   I159 @T6G_MB_LIB.T6G(SCH_1):PAGE44
   J27  269 DQ19_B SCONN288_DDR506112002KQ-SCONN288_DDR506112002KQ,SMA    I22 @T6G_MB_LIB.T6G(SCH_1):PAGE104

M_H_CPU1_SB_DQ<1> @T6G_MB_LIB.T6G(SCH_1):M_H_CPU1_SB_DQ(1)
   U26 CC14 MHB_DATA1 GENOA_SP5-SOCKET6096_13568-001,SMLF,IO,DGA^6000030   I159 @T6G_MB_LIB.T6G(SCH_1):PAGE44
   J27  102  DQ1_B SCONN288_DDR506112002KQ-SCONN288_DDR506112002KQ,SMA    I22 @T6G_MB_LIB.T6G(SCH_1):PAGE104

M_H_CPU1_SB_DQ<20> @T6G_MB_LIB.T6G(SCH_1):M_H_CPU1_SB_DQ(20)
   U26 CV13 MHB_DATA20 GENOA_SP5-SOCKET6096_13568-001,SMLF,IO,DGA^6000030   I159 @T6G_MB_LIB.T6G(SCH_1):PAGE44
   J27  129 DQ20_B SCONN288_DDR506112002KQ-SCONN288_DDR506112002KQ,SMA    I22 @T6G_MB_LIB.T6G(SCH_1):PAGE104

M_H_CPU1_SB_DQ<21> @T6G_MB_LIB.T6G(SCH_1):M_H_CPU1_SB_DQ(21)
   U26 CW14 MHB_DATA21 GENOA_SP5-SOCKET6096_13568-001,SMLF,IO,DGA^6000030   I159 @T6G_MB_LIB.T6G(SCH_1):PAGE44
   J27  131 DQ21_B SCONN288_DDR506112002KQ-SCONN288_DDR506112002KQ,SMA    I22 @T6G_MB_LIB.T6G(SCH_1):PAGE104

M_H_CPU1_SB_DQ<22> @T6G_MB_LIB.T6G(SCH_1):M_H_CPU1_SB_DQ(22)
   U26 CW12 MHB_DATA22 GENOA_SP5-SOCKET6096_13568-001,SMLF,IO,DGA^6000030   I159 @T6G_MB_LIB.T6G(SCH_1):PAGE44
   J27  274 DQ22_B SCONN288_DDR506112002KQ-SCONN288_DDR506112002KQ,SMA    I22 @T6G_MB_LIB.T6G(SCH_1):PAGE104

M_H_CPU1_SB_DQ<23> @T6G_MB_LIB.T6G(SCH_1):M_H_CPU1_SB_DQ(23)
   U26 CY14 MHB_DATA23 GENOA_SP5-SOCKET6096_13568-001,SMLF,IO,DGA^6000030   I159 @T6G_MB_LIB.T6G(SCH_1):PAGE44
   J27  276 DQ23_B SCONN288_DDR506112002KQ-SCONN288_DDR506112002KQ,SMA    I22 @T6G_MB_LIB.T6G(SCH_1):PAGE104

M_H_CPU1_SB_DQ<24> @T6G_MB_LIB.T6G(SCH_1):M_H_CPU1_SB_DQ(24)
   U26 CY13 MHB_DATA24 GENOA_SP5-SOCKET6096_13568-001,SMLF,IO,DGA^6000030   I159 @T6G_MB_LIB.T6G(SCH_1):PAGE44
   J27  133 DQ24_B SCONN288_DDR506112002KQ-SCONN288_DDR506112002KQ,SMA    I22 @T6G_MB_LIB.T6G(SCH_1):PAGE104

M_H_CPU1_SB_DQ<25> @T6G_MB_LIB.T6G(SCH_1):M_H_CPU1_SB_DQ(25)
   U26 DA14 MHB_DATA25 GENOA_SP5-SOCKET6096_13568-001,SMLF,IO,DGA^6000030   I159 @T6G_MB_LIB.T6G(SCH_1):PAGE44
   J27  135 DQ25_B SCONN288_DDR506112002KQ-SCONN288_DDR506112002KQ,SMA    I22 @T6G_MB_LIB.T6G(SCH_1):PAGE104

M_H_CPU1_SB_DQ<26> @T6G_MB_LIB.T6G(SCH_1):M_H_CPU1_SB_DQ(26)
   U26 DA12 MHB_DATA26 GENOA_SP5-SOCKET6096_13568-001,SMLF,IO,DGA^6000030   I159 @T6G_MB_LIB.T6G(SCH_1):PAGE44
   J27  278 DQ26_B SCONN288_DDR506112002KQ-SCONN288_DDR506112002KQ,SMA    I22 @T6G_MB_LIB.T6G(SCH_1):PAGE104

M_H_CPU1_SB_DQ<27> @T6G_MB_LIB.T6G(SCH_1):M_H_CPU1_SB_DQ(27)
   U26 DB14 MHB_DATA27 GENOA_SP5-SOCKET6096_13568-001,SMLF,IO,DGA^6000030   I159 @T6G_MB_LIB.T6G(SCH_1):PAGE44
   J27  280 DQ27_B SCONN288_DDR506112002KQ-SCONN288_DDR506112002KQ,SMA    I22 @T6G_MB_LIB.T6G(SCH_1):PAGE104

M_H_CPU1_SB_DQ<28> @T6G_MB_LIB.T6G(SCH_1):M_H_CPU1_SB_DQ(28)
   U26 DD13 MHB_DATA28 GENOA_SP5-SOCKET6096_13568-001,SMLF,IO,DGA^6000030   I159 @T6G_MB_LIB.T6G(SCH_1):PAGE44
   J27  140 DQ28_B SCONN288_DDR506112002KQ-SCONN288_DDR506112002KQ,SMA    I22 @T6G_MB_LIB.T6G(SCH_1):PAGE104

M_H_CPU1_SB_DQ<29> @T6G_MB_LIB.T6G(SCH_1):M_H_CPU1_SB_DQ(29)
   U26 DE14 MHB_DATA29 GENOA_SP5-SOCKET6096_13568-001,SMLF,IO,DGA^6000030   I159 @T6G_MB_LIB.T6G(SCH_1):PAGE44
   J27  142 DQ29_B SCONN288_DDR506112002KQ-SCONN288_DDR506112002KQ,SMA    I22 @T6G_MB_LIB.T6G(SCH_1):PAGE104

M_H_CPU1_SB_DQ<2> @T6G_MB_LIB.T6G(SCH_1):M_H_CPU1_SB_DQ(2)
   U26 CC12 MHB_DATA2 GENOA_SP5-SOCKET6096_13568-001,SMLF,IO,DGA^6000030   I159 @T6G_MB_LIB.T6G(SCH_1):PAGE44
   J27  245  DQ2_B SCONN288_DDR506112002KQ-SCONN288_DDR506112002KQ,SMA    I22 @T6G_MB_LIB.T6G(SCH_1):PAGE104

M_H_CPU1_SB_DQ<30> @T6G_MB_LIB.T6G(SCH_1):M_H_CPU1_SB_DQ(30)
   U26 DE12 MHB_DATA30 GENOA_SP5-SOCKET6096_13568-001,SMLF,IO,DGA^6000030   I159 @T6G_MB_LIB.T6G(SCH_1):PAGE44
   J27  285 DQ30_B SCONN288_DDR506112002KQ-SCONN288_DDR506112002KQ,SMA    I22 @T6G_MB_LIB.T6G(SCH_1):PAGE104

M_H_CPU1_SB_DQ<31> @T6G_MB_LIB.T6G(SCH_1):M_H_CPU1_SB_DQ(31)
   U26 DF14 MHB_DATA31 GENOA_SP5-SOCKET6096_13568-001,SMLF,IO,DGA^6000030   I159 @T6G_MB_LIB.T6G(SCH_1):PAGE44
   J27  287 DQ31_B SCONN288_DDR506112002KQ-SCONN288_DDR506112002KQ,SMA    I22 @T6G_MB_LIB.T6G(SCH_1):PAGE104

M_H_CPU1_SB_DQ<3> @T6G_MB_LIB.T6G(SCH_1):M_H_CPU1_SB_DQ(3)
   U26 CD14 MHB_DATA3 GENOA_SP5-SOCKET6096_13568-001,SMLF,IO,DGA^6000030   I159 @T6G_MB_LIB.T6G(SCH_1):PAGE44
   J27  247  DQ3_B SCONN288_DDR506112002KQ-SCONN288_DDR506112002KQ,SMA    I22 @T6G_MB_LIB.T6G(SCH_1):PAGE104

M_H_CPU1_SB_DQ<4> @T6G_MB_LIB.T6G(SCH_1):M_H_CPU1_SB_DQ(4)
   U26 CF13 MHB_DATA4 GENOA_SP5-SOCKET6096_13568-001,SMLF,IO,DGA^6000030   I159 @T6G_MB_LIB.T6G(SCH_1):PAGE44
   J27  107  DQ4_B SCONN288_DDR506112002KQ-SCONN288_DDR506112002KQ,SMA    I22 @T6G_MB_LIB.T6G(SCH_1):PAGE104

M_H_CPU1_SB_DQ<5> @T6G_MB_LIB.T6G(SCH_1):M_H_CPU1_SB_DQ(5)
   U26 CG14 MHB_DATA5 GENOA_SP5-SOCKET6096_13568-001,SMLF,IO,DGA^6000030   I159 @T6G_MB_LIB.T6G(SCH_1):PAGE44
   J27  109  DQ5_B SCONN288_DDR506112002KQ-SCONN288_DDR506112002KQ,SMA    I22 @T6G_MB_LIB.T6G(SCH_1):PAGE104

M_H_CPU1_SB_DQ<6> @T6G_MB_LIB.T6G(SCH_1):M_H_CPU1_SB_DQ(6)
   U26 CG12 MHB_DATA6 GENOA_SP5-SOCKET6096_13568-001,SMLF,IO,DGA^6000030   I159 @T6G_MB_LIB.T6G(SCH_1):PAGE44
   J27  252  DQ6_B SCONN288_DDR506112002KQ-SCONN288_DDR506112002KQ,SMA    I22 @T6G_MB_LIB.T6G(SCH_1):PAGE104

M_H_CPU1_SB_DQ<7> @T6G_MB_LIB.T6G(SCH_1):M_H_CPU1_SB_DQ(7)
   U26 CH14 MHB_DATA7 GENOA_SP5-SOCKET6096_13568-001,SMLF,IO,DGA^6000030   I159 @T6G_MB_LIB.T6G(SCH_1):PAGE44
   J27  254  DQ7_B SCONN288_DDR506112002KQ-SCONN288_DDR506112002KQ,SMA    I22 @T6G_MB_LIB.T6G(SCH_1):PAGE104

M_H_CPU1_SB_DQ<8> @T6G_MB_LIB.T6G(SCH_1):M_H_CPU1_SB_DQ(8)
   U26 CH13 MHB_DATA8 GENOA_SP5-SOCKET6096_13568-001,SMLF,IO,DGA^6000030   I159 @T6G_MB_LIB.T6G(SCH_1):PAGE44
   J27  111  DQ8_B SCONN288_DDR506112002KQ-SCONN288_DDR506112002KQ,SMA    I22 @T6G_MB_LIB.T6G(SCH_1):PAGE104

M_H_CPU1_SB_DQ<9> @T6G_MB_LIB.T6G(SCH_1):M_H_CPU1_SB_DQ(9)
   U26 CJ14 MHB_DATA9 GENOA_SP5-SOCKET6096_13568-001,SMLF,IO,DGA^6000030   I159 @T6G_MB_LIB.T6G(SCH_1):PAGE44
   J27  113  DQ9_B SCONN288_DDR506112002KQ-SCONN288_DDR506112002KQ,SMA    I22 @T6G_MB_LIB.T6G(SCH_1):PAGE104

M_H_CPU1_SB_DQS_DN<0> @T6G_MB_LIB.T6G(SCH_1):M_H_CPU1_SB_DQS_DN(0)
   U26 CE12 MHB_DQS_L0 GENOA_SP5-SOCKET6096_13568-001,SMLF,IO,DGA^6000030   I159 @T6G_MB_LIB.T6G(SCH_1):PAGE44
   J27  105 DQS0_B_C SCONN288_DDR506112002KQ-SCONN288_DDR506112002KQ,SMA   I238 @T6G_MB_LIB.T6G(SCH_1):PAGE104

M_H_CPU1_SB_DQS_DN<1> @T6G_MB_LIB.T6G(SCH_1):M_H_CPU1_SB_DQS_DN(1)
   U26 CL12 MHB_DQS_L1 GENOA_SP5-SOCKET6096_13568-001,SMLF,IO,DGA^6000030   I159 @T6G_MB_LIB.T6G(SCH_1):PAGE44
   J27  116 DQS1_B_C SCONN288_DDR506112002KQ-SCONN288_DDR506112002KQ,SMA   I238 @T6G_MB_LIB.T6G(SCH_1):PAGE104

M_H_CPU1_SB_DQS_DN<2> @T6G_MB_LIB.T6G(SCH_1):M_H_CPU1_SB_DQS_DN(2)
   U26 CU12 MHB_DQS_L2 GENOA_SP5-SOCKET6096_13568-001,SMLF,IO,DGA^6000030   I159 @T6G_MB_LIB.T6G(SCH_1):PAGE44
   J27  127 DQS2_B_C SCONN288_DDR506112002KQ-SCONN288_DDR506112002KQ,SMA   I238 @T6G_MB_LIB.T6G(SCH_1):PAGE104

M_H_CPU1_SB_DQS_DN<3> @T6G_MB_LIB.T6G(SCH_1):M_H_CPU1_SB_DQS_DN(3)
   U26 DC12 MHB_DQS_L3 GENOA_SP5-SOCKET6096_13568-001,SMLF,IO,DGA^6000030   I159 @T6G_MB_LIB.T6G(SCH_1):PAGE44
   J27  138 DQS3_B_C SCONN288_DDR506112002KQ-SCONN288_DDR506112002KQ,SMA   I238 @T6G_MB_LIB.T6G(SCH_1):PAGE104

M_H_CPU1_SB_DQS_DN<4> @T6G_MB_LIB.T6G(SCH_1):M_H_CPU1_SB_DQS_DN(4)
   U26 BW14 MHB_DQS_L4 GENOA_SP5-SOCKET6096_13568-001,SMLF,IO,DGA^6000030   I159 @T6G_MB_LIB.T6G(SCH_1):PAGE44
   J27  238 DQS4_B_C SCONN288_DDR506112002KQ-SCONN288_DDR506112002KQ,SMA   I238 @T6G_MB_LIB.T6G(SCH_1):PAGE104

M_H_CPU1_SB_DQS_DN<5> @T6G_MB_LIB.T6G(SCH_1):M_H_CPU1_SB_DQS_DN(5)
   U26 CE14 MHB_DQS_L5 GENOA_SP5-SOCKET6096_13568-001,SMLF,IO,DGA^6000030   I159 @T6G_MB_LIB.T6G(SCH_1):PAGE44
   J27  249 DQS5_B_C||TDQS5_B_C SCONN288_DDR506112002KQ-SCONN288_DDR506112002KQ,SMA   I238 @T6G_MB_LIB.T6G(SCH_1):PAGE104

M_H_CPU1_SB_DQS_DN<6> @T6G_MB_LIB.T6G(SCH_1):M_H_CPU1_SB_DQS_DN(6)
   U26 CL14 MHB_DQS_L6 GENOA_SP5-SOCKET6096_13568-001,SMLF,IO,DGA^6000030   I159 @T6G_MB_LIB.T6G(SCH_1):PAGE44
   J27  260 DQS6_B_C||TDQS6_B_C SCONN288_DDR506112002KQ-SCONN288_DDR506112002KQ,SMA   I238 @T6G_MB_LIB.T6G(SCH_1):PAGE104

M_H_CPU1_SB_DQS_DN<7> @T6G_MB_LIB.T6G(SCH_1):M_H_CPU1_SB_DQS_DN(7)
   U26 CU14 MHB_DQS_L7 GENOA_SP5-SOCKET6096_13568-001,SMLF,IO,DGA^6000030   I159 @T6G_MB_LIB.T6G(SCH_1):PAGE44
   J27  271 DQS7_B_C||TDQS7_B_C SCONN288_DDR506112002KQ-SCONN288_DDR506112002KQ,SMA   I238 @T6G_MB_LIB.T6G(SCH_1):PAGE104

M_H_CPU1_SB_DQS_DN<8> @T6G_MB_LIB.T6G(SCH_1):M_H_CPU1_SB_DQS_DN(8)
   U26 DC14 MHB_DQS_L8 GENOA_SP5-SOCKET6096_13568-001,SMLF,IO,DGA^6000030   I159 @T6G_MB_LIB.T6G(SCH_1):PAGE44
   J27  282 DQS8_B_C||TDQS8_B_C SCONN288_DDR506112002KQ-SCONN288_DDR506112002KQ,SMA   I238 @T6G_MB_LIB.T6G(SCH_1):PAGE104

M_H_CPU1_SB_DQS_DN<9> @T6G_MB_LIB.T6G(SCH_1):M_H_CPU1_SB_DQS_DN(9)
   U26 BW12 MHB_DQS_L9 GENOA_SP5-SOCKET6096_13568-001,SMLF,IO,DGA^6000030   I159 @T6G_MB_LIB.T6G(SCH_1):PAGE44
   J27   94 DQS9_B_C||TDQS9_B_C SCONN288_DDR506112002KQ-SCONN288_DDR506112002KQ,SMA   I238 @T6G_MB_LIB.T6G(SCH_1):PAGE104

M_H_CPU1_SB_DQS_DP<0> @T6G_MB_LIB.T6G(SCH_1):M_H_CPU1_SB_DQS_DP(0)
   U26 CD13 MHB_DQS_H0 GENOA_SP5-SOCKET6096_13568-001,SMLF,IO,DGA^6000030   I159 @T6G_MB_LIB.T6G(SCH_1):PAGE44
   J27  104 DQS0_B_T SCONN288_DDR506112002KQ-SCONN288_DDR506112002KQ,SMA   I238 @T6G_MB_LIB.T6G(SCH_1):PAGE104

M_H_CPU1_SB_DQS_DP<1> @T6G_MB_LIB.T6G(SCH_1):M_H_CPU1_SB_DQS_DP(1)
   U26 CK13 MHB_DQS_H1 GENOA_SP5-SOCKET6096_13568-001,SMLF,IO,DGA^6000030   I159 @T6G_MB_LIB.T6G(SCH_1):PAGE44
   J27  115 DQS1_B_T SCONN288_DDR506112002KQ-SCONN288_DDR506112002KQ,SMA   I238 @T6G_MB_LIB.T6G(SCH_1):PAGE104

M_H_CPU1_SB_DQS_DP<2> @T6G_MB_LIB.T6G(SCH_1):M_H_CPU1_SB_DQS_DP(2)
   U26 CT13 MHB_DQS_H2 GENOA_SP5-SOCKET6096_13568-001,SMLF,IO,DGA^6000030   I159 @T6G_MB_LIB.T6G(SCH_1):PAGE44
   J27  126 DQS2_B_T SCONN288_DDR506112002KQ-SCONN288_DDR506112002KQ,SMA   I238 @T6G_MB_LIB.T6G(SCH_1):PAGE104

M_H_CPU1_SB_DQS_DP<3> @T6G_MB_LIB.T6G(SCH_1):M_H_CPU1_SB_DQS_DP(3)
   U26 DB13 MHB_DQS_H3 GENOA_SP5-SOCKET6096_13568-001,SMLF,IO,DGA^6000030   I159 @T6G_MB_LIB.T6G(SCH_1):PAGE44
   J27  137 DQS3_B_T SCONN288_DDR506112002KQ-SCONN288_DDR506112002KQ,SMA   I238 @T6G_MB_LIB.T6G(SCH_1):PAGE104

M_H_CPU1_SB_DQS_DP<4> @T6G_MB_LIB.T6G(SCH_1):M_H_CPU1_SB_DQS_DP(4)
   U26 BY14 MHB_DQS_H4 GENOA_SP5-SOCKET6096_13568-001,SMLF,IO,DGA^6000030   I159 @T6G_MB_LIB.T6G(SCH_1):PAGE44
   J27  239 DQS4_B_T SCONN288_DDR506112002KQ-SCONN288_DDR506112002KQ,SMA   I238 @T6G_MB_LIB.T6G(SCH_1):PAGE104

M_H_CPU1_SB_DQS_DP<5> @T6G_MB_LIB.T6G(SCH_1):M_H_CPU1_SB_DQS_DP(5)
   U26 CF14 MHB_DQS_H5 GENOA_SP5-SOCKET6096_13568-001,SMLF,IO,DGA^6000030   I159 @T6G_MB_LIB.T6G(SCH_1):PAGE44
   J27  250 DQS5_B_T||TDQS5_B_T SCONN288_DDR506112002KQ-SCONN288_DDR506112002KQ,SMA   I238 @T6G_MB_LIB.T6G(SCH_1):PAGE104

M_H_CPU1_SB_DQS_DP<6> @T6G_MB_LIB.T6G(SCH_1):M_H_CPU1_SB_DQS_DP(6)
   U26 CM14 MHB_DQS_H6 GENOA_SP5-SOCKET6096_13568-001,SMLF,IO,DGA^6000030   I159 @T6G_MB_LIB.T6G(SCH_1):PAGE44
   J27  261 DQS6_B_T||TDQS6_B_T SCONN288_DDR506112002KQ-SCONN288_DDR506112002KQ,SMA   I238 @T6G_MB_LIB.T6G(SCH_1):PAGE104

M_H_CPU1_SB_DQS_DP<7> @T6G_MB_LIB.T6G(SCH_1):M_H_CPU1_SB_DQS_DP(7)
   U26 CV14 MHB_DQS_H7 GENOA_SP5-SOCKET6096_13568-001,SMLF,IO,DGA^6000030   I159 @T6G_MB_LIB.T6G(SCH_1):PAGE44
   J27  272 DQS7_B_T||TDQS7_B_T SCONN288_DDR506112002KQ-SCONN288_DDR506112002KQ,SMA   I238 @T6G_MB_LIB.T6G(SCH_1):PAGE104

M_H_CPU1_SB_DQS_DP<8> @T6G_MB_LIB.T6G(SCH_1):M_H_CPU1_SB_DQS_DP(8)
   U26 DD14 MHB_DQS_H8 GENOA_SP5-SOCKET6096_13568-001,SMLF,IO,DGA^6000030   I159 @T6G_MB_LIB.T6G(SCH_1):PAGE44
   J27  283 DQS8_B_T||TDQS8_B_T SCONN288_DDR506112002KQ-SCONN288_DDR506112002KQ,SMA   I238 @T6G_MB_LIB.T6G(SCH_1):PAGE104

M_H_CPU1_SB_DQS_DP<9> @T6G_MB_LIB.T6G(SCH_1):M_H_CPU1_SB_DQS_DP(9)
   U26 BV13 MHB_DQS_H9 GENOA_SP5-SOCKET6096_13568-001,SMLF,IO,DGA^6000030   I159 @T6G_MB_LIB.T6G(SCH_1):PAGE44
   J27   93 DQS9_B_T||TDQS9_B_T||DBI4_B_N SCONN288_DDR506112002KQ-SCONN288_DDR506112002KQ,SMA   I238 @T6G_MB_LIB.T6G(SCH_1):PAGE104

M_H_CPU1_SB_PAR @T6G_MB_LIB.T6G(SCH_1):M_H_CPU1_SB_PAR
   U26 BL14 MHB_PAR GENOA_SP5-SOCKET6096_13568-001,SMLF,IO,DGA^6000030   I159 @T6G_MB_LIB.T6G(SCH_1):PAGE44
   J27  227  PAR_B SCONN288_DDR506112002KQ-SCONN288_DDR506112002KQ,SMA    I22 @T6G_MB_LIB.T6G(SCH_1):PAGE104

M_H_CPU1_SB_RSP<0> @T6G_MB_LIB.T6G(SCH_1):M_H_CPU1_SB_RSP(0)
   U26 BP13 MHB0_RSP_L GENOA_SP5-SOCKET6096_13568-001,SMLF,IO,DGA^6000030   I159 @T6G_MB_LIB.T6G(SCH_1):PAGE44
   J27   87 LBS||RSP_B_N SCONN288_DDR506112002KQ-SCONN288_DDR506112002KQ,SMA    I22 @T6G_MB_LIB.T6G(SCH_1):PAGE104

M_I_CPU0_ALERT_N @T6G_MB_LIB.T6G(SCH_1):M_I_CPU0_ALERT_N
  R383    1      A Q_RES_0402LF-15,1%,1/16W,CHIP,CS01502FB03   I314 @T6G_MB_LIB.T6G(SCH_1):PAGE18
   J18   62 ALERT_N SCONN288_DDR506112002KQ-SCONN288_DDR506112002KQ,SMA    I22 @T6G_MB_LIB.T6G(SCH_1):PAGE93

M_I_CPU0_ALERT_R_N @T6G_MB_LIB.T6G(SCH_1):M_I_CPU0_ALERT_R_N
   U25 AT21 MI_ALERT_L GENOA_SP5-SOCKET6096_13568-001,SMLF,IO,DGA^6000030   I159 @T6G_MB_LIB.T6G(SCH_1):PAGE18
  R383    2      B Q_RES_0402LF-15,1%,1/16W,CHIP,CS01502FB03   I314 @T6G_MB_LIB.T6G(SCH_1):PAGE18

M_I_CPU0_CLK_DN<0> @T6G_MB_LIB.T6G(SCH_1):M_I_CPU0_CLK_DN(0)
   U25 BD20 MI0_CLK_L GENOA_SP5-SOCKET6096_13568-001,SMLF,IO,DGA^6000030   I159 @T6G_MB_LIB.T6G(SCH_1):PAGE18
   J18  218   CK_C SCONN288_DDR506112002KQ-SCONN288_DDR506112002KQ,SMA    I22 @T6G_MB_LIB.T6G(SCH_1):PAGE93

M_I_CPU0_CLK_DP<0> @T6G_MB_LIB.T6G(SCH_1):M_I_CPU0_CLK_DP(0)
   U25 BC19 MI0_CLK_H GENOA_SP5-SOCKET6096_13568-001,SMLF,IO,DGA^6000030   I159 @T6G_MB_LIB.T6G(SCH_1):PAGE18
   J18  217   CK_T SCONN288_DDR506112002KQ-SCONN288_DDR506112002KQ,SMA    I22 @T6G_MB_LIB.T6G(SCH_1):PAGE93

M_I_CPU0_RESET_N @T6G_MB_LIB.T6G(SCH_1):M_I_CPU0_RESET_N
   U25 AU21 MI_RESET_L GENOA_SP5-SOCKET6096_13568-001,SMLF,IO,DGA^6000030   I159 @T6G_MB_LIB.T6G(SCH_1):PAGE18
   J18  207 RESET_N SCONN288_DDR506112002KQ-SCONN288_DDR506112002KQ,SMA    I22 @T6G_MB_LIB.T6G(SCH_1):PAGE93

M_I_CPU0_SA_CA<0> @T6G_MB_LIB.T6G(SCH_1):M_I_CPU0_SA_CA(0)
   U25 AW19 MIA_CA0 GENOA_SP5-SOCKET6096_13568-001,SMLF,IO,DGA^6000030   I159 @T6G_MB_LIB.T6G(SCH_1):PAGE18
   J18   66  CA0_A SCONN288_DDR506112002KQ-SCONN288_DDR506112002KQ,SMA    I22 @T6G_MB_LIB.T6G(SCH_1):PAGE93

M_I_CPU0_SA_CA<1> @T6G_MB_LIB.T6G(SCH_1):M_I_CPU0_SA_CA(1)
   U25 AY20 MIA_CA1 GENOA_SP5-SOCKET6096_13568-001,SMLF,IO,DGA^6000030   I159 @T6G_MB_LIB.T6G(SCH_1):PAGE18
   J18  211  CA1_A SCONN288_DDR506112002KQ-SCONN288_DDR506112002KQ,SMA    I22 @T6G_MB_LIB.T6G(SCH_1):PAGE93

M_I_CPU0_SA_CA<2> @T6G_MB_LIB.T6G(SCH_1):M_I_CPU0_SA_CA(2)
   U25 AY21 MIA_CA2 GENOA_SP5-SOCKET6096_13568-001,SMLF,IO,DGA^6000030   I159 @T6G_MB_LIB.T6G(SCH_1):PAGE18
   J18   68  CA2_A SCONN288_DDR506112002KQ-SCONN288_DDR506112002KQ,SMA    I22 @T6G_MB_LIB.T6G(SCH_1):PAGE93

M_I_CPU0_SA_CA<3> @T6G_MB_LIB.T6G(SCH_1):M_I_CPU0_SA_CA(3)
   U25 BA21 MIA_CA3 GENOA_SP5-SOCKET6096_13568-001,SMLF,IO,DGA^6000030   I159 @T6G_MB_LIB.T6G(SCH_1):PAGE18
   J18  213  CA3_A SCONN288_DDR506112002KQ-SCONN288_DDR506112002KQ,SMA    I22 @T6G_MB_LIB.T6G(SCH_1):PAGE93

M_I_CPU0_SA_CA<4> @T6G_MB_LIB.T6G(SCH_1):M_I_CPU0_SA_CA(4)
   U25 BA19 MIA_CA4 GENOA_SP5-SOCKET6096_13568-001,SMLF,IO,DGA^6000030   I159 @T6G_MB_LIB.T6G(SCH_1):PAGE18
   J18   70  CA4_A SCONN288_DDR506112002KQ-SCONN288_DDR506112002KQ,SMA    I22 @T6G_MB_LIB.T6G(SCH_1):PAGE93

M_I_CPU0_SA_CA<5> @T6G_MB_LIB.T6G(SCH_1):M_I_CPU0_SA_CA(5)
   U25 BB20 MIA_CA5 GENOA_SP5-SOCKET6096_13568-001,SMLF,IO,DGA^6000030   I159 @T6G_MB_LIB.T6G(SCH_1):PAGE18
   J18  215  CA5_A SCONN288_DDR506112002KQ-SCONN288_DDR506112002KQ,SMA    I22 @T6G_MB_LIB.T6G(SCH_1):PAGE93

M_I_CPU0_SA_CA<6> @T6G_MB_LIB.T6G(SCH_1):M_I_CPU0_SA_CA(6)
   U25 BB21 MIA_CA6 GENOA_SP5-SOCKET6096_13568-001,SMLF,IO,DGA^6000030   I159 @T6G_MB_LIB.T6G(SCH_1):PAGE18
   J18   72  CA6_A SCONN288_DDR506112002KQ-SCONN288_DDR506112002KQ,SMA    I22 @T6G_MB_LIB.T6G(SCH_1):PAGE93

M_I_CPU0_SA_CB<0> @T6G_MB_LIB.T6G(SCH_1):M_I_CPU0_SA_CB(0)
   U25 AJ19 MIA_CHECK0 GENOA_SP5-SOCKET6096_13568-001,SMLF,IO,DGA^6000030   I159 @T6G_MB_LIB.T6G(SCH_1):PAGE18
   J18   51  CB0_A SCONN288_DDR506112002KQ-SCONN288_DDR506112002KQ,SMA    I22 @T6G_MB_LIB.T6G(SCH_1):PAGE93

M_I_CPU0_SA_CB<1> @T6G_MB_LIB.T6G(SCH_1):M_I_CPU0_SA_CB(1)
   U25 AK21 MIA_CHECK1 GENOA_SP5-SOCKET6096_13568-001,SMLF,IO,DGA^6000030   I159 @T6G_MB_LIB.T6G(SCH_1):PAGE18
   J18   53  CB1_A SCONN288_DDR506112002KQ-SCONN288_DDR506112002KQ,SMA    I22 @T6G_MB_LIB.T6G(SCH_1):PAGE93

M_I_CPU0_SA_CB<2> @T6G_MB_LIB.T6G(SCH_1):M_I_CPU0_SA_CB(2)
   U25 AK20 MIA_CHECK2 GENOA_SP5-SOCKET6096_13568-001,SMLF,IO,DGA^6000030   I159 @T6G_MB_LIB.T6G(SCH_1):PAGE18
   J18  196  CB2_A SCONN288_DDR506112002KQ-SCONN288_DDR506112002KQ,SMA    I22 @T6G_MB_LIB.T6G(SCH_1):PAGE93

M_I_CPU0_SA_CB<3> @T6G_MB_LIB.T6G(SCH_1):M_I_CPU0_SA_CB(3)
   U25 AL21 MIA_CHECK3 GENOA_SP5-SOCKET6096_13568-001,SMLF,IO,DGA^6000030   I159 @T6G_MB_LIB.T6G(SCH_1):PAGE18
   J18  198  CB3_A SCONN288_DDR506112002KQ-SCONN288_DDR506112002KQ,SMA    I22 @T6G_MB_LIB.T6G(SCH_1):PAGE93

M_I_CPU0_SA_CB<4> @T6G_MB_LIB.T6G(SCH_1):M_I_CPU0_SA_CB(4)
   U25 AN19 MIA_CHECK4 GENOA_SP5-SOCKET6096_13568-001,SMLF,IO,DGA^6000030   I159 @T6G_MB_LIB.T6G(SCH_1):PAGE18
   J18   58  CB4_A SCONN288_DDR506112002KQ-SCONN288_DDR506112002KQ,SMA    I22 @T6G_MB_LIB.T6G(SCH_1):PAGE93

M_I_CPU0_SA_CB<5> @T6G_MB_LIB.T6G(SCH_1):M_I_CPU0_SA_CB(5)
   U25 AP21 MIA_CHECK5 GENOA_SP5-SOCKET6096_13568-001,SMLF,IO,DGA^6000030   I159 @T6G_MB_LIB.T6G(SCH_1):PAGE18
   J18   60  CB5_A SCONN288_DDR506112002KQ-SCONN288_DDR506112002KQ,SMA    I22 @T6G_MB_LIB.T6G(SCH_1):PAGE93

M_I_CPU0_SA_CB<6> @T6G_MB_LIB.T6G(SCH_1):M_I_CPU0_SA_CB(6)
   U25 AP20 MIA_CHECK6 GENOA_SP5-SOCKET6096_13568-001,SMLF,IO,DGA^6000030   I159 @T6G_MB_LIB.T6G(SCH_1):PAGE18
   J18  203  CB6_A SCONN288_DDR506112002KQ-SCONN288_DDR506112002KQ,SMA    I22 @T6G_MB_LIB.T6G(SCH_1):PAGE93

M_I_CPU0_SA_CB<7> @T6G_MB_LIB.T6G(SCH_1):M_I_CPU0_SA_CB(7)
   U25 AR21 MIA_CHECK7 GENOA_SP5-SOCKET6096_13568-001,SMLF,IO,DGA^6000030   I159 @T6G_MB_LIB.T6G(SCH_1):PAGE18
   J18  205  CB7_A SCONN288_DDR506112002KQ-SCONN288_DDR506112002KQ,SMA    I22 @T6G_MB_LIB.T6G(SCH_1):PAGE93

M_I_CPU0_SA_CS_N<0> @T6G_MB_LIB.T6G(SCH_1):M_I_CPU0_SA_CS_N(0)
   U25 AU19 MIA0_CS_L0 GENOA_SP5-SOCKET6096_13568-001,SMLF,IO,DGA^6000030   I159 @T6G_MB_LIB.T6G(SCH_1):PAGE18
   J18   64 CS0_A_N SCONN288_DDR506112002KQ-SCONN288_DDR506112002KQ,SMA    I22 @T6G_MB_LIB.T6G(SCH_1):PAGE93

M_I_CPU0_SA_CS_N<1> @T6G_MB_LIB.T6G(SCH_1):M_I_CPU0_SA_CS_N(1)
   U25 AV21 MIA0_CS_L1 GENOA_SP5-SOCKET6096_13568-001,SMLF,IO,DGA^6000030   I159 @T6G_MB_LIB.T6G(SCH_1):PAGE18
   J18  209 CS1_A_N SCONN288_DDR506112002KQ-SCONN288_DDR506112002KQ,SMA    I22 @T6G_MB_LIB.T6G(SCH_1):PAGE93

M_I_CPU0_SA_DQ<0> @T6G_MB_LIB.T6G(SCH_1):M_I_CPU0_SA_DQ(0)
   U25  E19 MIA_DATA0 GENOA_SP5-SOCKET6096_13568-001,SMLF,IO,DGA^6000030   I159 @T6G_MB_LIB.T6G(SCH_1):PAGE18
   J18    7  DQ0_A SCONN288_DDR506112002KQ-SCONN288_DDR506112002KQ,SMA    I22 @T6G_MB_LIB.T6G(SCH_1):PAGE93

M_I_CPU0_SA_DQ<10> @T6G_MB_LIB.T6G(SCH_1):M_I_CPU0_SA_DQ(10)
   U25  M20 MIA_DATA10 GENOA_SP5-SOCKET6096_13568-001,SMLF,IO,DGA^6000030   I159 @T6G_MB_LIB.T6G(SCH_1):PAGE18
   J18  163 DQ10_A SCONN288_DDR506112002KQ-SCONN288_DDR506112002KQ,SMA    I22 @T6G_MB_LIB.T6G(SCH_1):PAGE93

M_I_CPU0_SA_DQ<11> @T6G_MB_LIB.T6G(SCH_1):M_I_CPU0_SA_DQ(11)
   U25  N21 MIA_DATA11 GENOA_SP5-SOCKET6096_13568-001,SMLF,IO,DGA^6000030   I159 @T6G_MB_LIB.T6G(SCH_1):PAGE18
   J18  165 DQ11_A SCONN288_DDR506112002KQ-SCONN288_DDR506112002KQ,SMA    I22 @T6G_MB_LIB.T6G(SCH_1):PAGE93

M_I_CPU0_SA_DQ<12> @T6G_MB_LIB.T6G(SCH_1):M_I_CPU0_SA_DQ(12)
   U25  R19 MIA_DATA12 GENOA_SP5-SOCKET6096_13568-001,SMLF,IO,DGA^6000030   I159 @T6G_MB_LIB.T6G(SCH_1):PAGE18
   J18   25 DQ12_A SCONN288_DDR506112002KQ-SCONN288_DDR506112002KQ,SMA    I22 @T6G_MB_LIB.T6G(SCH_1):PAGE93

M_I_CPU0_SA_DQ<13> @T6G_MB_LIB.T6G(SCH_1):M_I_CPU0_SA_DQ(13)
   U25  T21 MIA_DATA13 GENOA_SP5-SOCKET6096_13568-001,SMLF,IO,DGA^6000030   I159 @T6G_MB_LIB.T6G(SCH_1):PAGE18
   J18   27 DQ13_A SCONN288_DDR506112002KQ-SCONN288_DDR506112002KQ,SMA    I22 @T6G_MB_LIB.T6G(SCH_1):PAGE93

M_I_CPU0_SA_DQ<14> @T6G_MB_LIB.T6G(SCH_1):M_I_CPU0_SA_DQ(14)
   U25  T20 MIA_DATA14 GENOA_SP5-SOCKET6096_13568-001,SMLF,IO,DGA^6000030   I159 @T6G_MB_LIB.T6G(SCH_1):PAGE18
   J18  170 DQ14_A SCONN288_DDR506112002KQ-SCONN288_DDR506112002KQ,SMA    I22 @T6G_MB_LIB.T6G(SCH_1):PAGE93

M_I_CPU0_SA_DQ<15> @T6G_MB_LIB.T6G(SCH_1):M_I_CPU0_SA_DQ(15)
   U25  U21 MIA_DATA15 GENOA_SP5-SOCKET6096_13568-001,SMLF,IO,DGA^6000030   I159 @T6G_MB_LIB.T6G(SCH_1):PAGE18
   J18  172 DQ15_A SCONN288_DDR506112002KQ-SCONN288_DDR506112002KQ,SMA    I22 @T6G_MB_LIB.T6G(SCH_1):PAGE93

M_I_CPU0_SA_DQ<16> @T6G_MB_LIB.T6G(SCH_1):M_I_CPU0_SA_DQ(16)
   U25  U19 MIA_DATA16 GENOA_SP5-SOCKET6096_13568-001,SMLF,IO,DGA^6000030   I159 @T6G_MB_LIB.T6G(SCH_1):PAGE18
   J18   29 DQ16_A SCONN288_DDR506112002KQ-SCONN288_DDR506112002KQ,SMA    I22 @T6G_MB_LIB.T6G(SCH_1):PAGE93

M_I_CPU0_SA_DQ<17> @T6G_MB_LIB.T6G(SCH_1):M_I_CPU0_SA_DQ(17)
   U25  V21 MIA_DATA17 GENOA_SP5-SOCKET6096_13568-001,SMLF,IO,DGA^6000030   I159 @T6G_MB_LIB.T6G(SCH_1):PAGE18
   J18   31 DQ17_A SCONN288_DDR506112002KQ-SCONN288_DDR506112002KQ,SMA    I22 @T6G_MB_LIB.T6G(SCH_1):PAGE93

M_I_CPU0_SA_DQ<18> @T6G_MB_LIB.T6G(SCH_1):M_I_CPU0_SA_DQ(18)
   U25  V20 MIA_DATA18 GENOA_SP5-SOCKET6096_13568-001,SMLF,IO,DGA^6000030   I159 @T6G_MB_LIB.T6G(SCH_1):PAGE18
   J18  174 DQ18_A SCONN288_DDR506112002KQ-SCONN288_DDR506112002KQ,SMA    I22 @T6G_MB_LIB.T6G(SCH_1):PAGE93

M_I_CPU0_SA_DQ<19> @T6G_MB_LIB.T6G(SCH_1):M_I_CPU0_SA_DQ(19)
   U25  W21 MIA_DATA19 GENOA_SP5-SOCKET6096_13568-001,SMLF,IO,DGA^6000030   I159 @T6G_MB_LIB.T6G(SCH_1):PAGE18
   J18  176 DQ19_A SCONN288_DDR506112002KQ-SCONN288_DDR506112002KQ,SMA    I22 @T6G_MB_LIB.T6G(SCH_1):PAGE93

M_I_CPU0_SA_DQ<1> @T6G_MB_LIB.T6G(SCH_1):M_I_CPU0_SA_DQ(1)
   U25  F21 MIA_DATA1 GENOA_SP5-SOCKET6096_13568-001,SMLF,IO,DGA^6000030   I159 @T6G_MB_LIB.T6G(SCH_1):PAGE18
   J18    9  DQ1_A SCONN288_DDR506112002KQ-SCONN288_DDR506112002KQ,SMA    I22 @T6G_MB_LIB.T6G(SCH_1):PAGE93

M_I_CPU0_SA_DQ<20> @T6G_MB_LIB.T6G(SCH_1):M_I_CPU0_SA_DQ(20)
   U25 AA19 MIA_DATA20 GENOA_SP5-SOCKET6096_13568-001,SMLF,IO,DGA^6000030   I159 @T6G_MB_LIB.T6G(SCH_1):PAGE18
   J18   36 DQ20_A SCONN288_DDR506112002KQ-SCONN288_DDR506112002KQ,SMA    I22 @T6G_MB_LIB.T6G(SCH_1):PAGE93

M_I_CPU0_SA_DQ<21> @T6G_MB_LIB.T6G(SCH_1):M_I_CPU0_SA_DQ(21)
   U25 AB21 MIA_DATA21 GENOA_SP5-SOCKET6096_13568-001,SMLF,IO,DGA^6000030   I159 @T6G_MB_LIB.T6G(SCH_1):PAGE18
   J18   38 DQ21_A SCONN288_DDR506112002KQ-SCONN288_DDR506112002KQ,SMA    I22 @T6G_MB_LIB.T6G(SCH_1):PAGE93

M_I_CPU0_SA_DQ<22> @T6G_MB_LIB.T6G(SCH_1):M_I_CPU0_SA_DQ(22)
   U25 AB20 MIA_DATA22 GENOA_SP5-SOCKET6096_13568-001,SMLF,IO,DGA^6000030   I159 @T6G_MB_LIB.T6G(SCH_1):PAGE18
   J18  181 DQ22_A SCONN288_DDR506112002KQ-SCONN288_DDR506112002KQ,SMA    I22 @T6G_MB_LIB.T6G(SCH_1):PAGE93

M_I_CPU0_SA_DQ<23> @T6G_MB_LIB.T6G(SCH_1):M_I_CPU0_SA_DQ(23)
   U25 AC21 MIA_DATA23 GENOA_SP5-SOCKET6096_13568-001,SMLF,IO,DGA^6000030   I159 @T6G_MB_LIB.T6G(SCH_1):PAGE18
   J18  183 DQ23_A SCONN288_DDR506112002KQ-SCONN288_DDR506112002KQ,SMA    I22 @T6G_MB_LIB.T6G(SCH_1):PAGE93

M_I_CPU0_SA_DQ<24> @T6G_MB_LIB.T6G(SCH_1):M_I_CPU0_SA_DQ(24)
   U25 AC19 MIA_DATA24 GENOA_SP5-SOCKET6096_13568-001,SMLF,IO,DGA^6000030   I159 @T6G_MB_LIB.T6G(SCH_1):PAGE18
   J18   40 DQ24_A SCONN288_DDR506112002KQ-SCONN288_DDR506112002KQ,SMA    I22 @T6G_MB_LIB.T6G(SCH_1):PAGE93

M_I_CPU0_SA_DQ<25> @T6G_MB_LIB.T6G(SCH_1):M_I_CPU0_SA_DQ(25)
   U25 AD21 MIA_DATA25 GENOA_SP5-SOCKET6096_13568-001,SMLF,IO,DGA^6000030   I159 @T6G_MB_LIB.T6G(SCH_1):PAGE18
   J18   42 DQ25_A SCONN288_DDR506112002KQ-SCONN288_DDR506112002KQ,SMA    I22 @T6G_MB_LIB.T6G(SCH_1):PAGE93

M_I_CPU0_SA_DQ<26> @T6G_MB_LIB.T6G(SCH_1):M_I_CPU0_SA_DQ(26)
   U25 AD20 MIA_DATA26 GENOA_SP5-SOCKET6096_13568-001,SMLF,IO,DGA^6000030   I159 @T6G_MB_LIB.T6G(SCH_1):PAGE18
   J18  185 DQ26_A SCONN288_DDR506112002KQ-SCONN288_DDR506112002KQ,SMA    I22 @T6G_MB_LIB.T6G(SCH_1):PAGE93

M_I_CPU0_SA_DQ<27> @T6G_MB_LIB.T6G(SCH_1):M_I_CPU0_SA_DQ(27)
   U25 AE21 MIA_DATA27 GENOA_SP5-SOCKET6096_13568-001,SMLF,IO,DGA^6000030   I159 @T6G_MB_LIB.T6G(SCH_1):PAGE18
   J18  187 DQ27_A SCONN288_DDR506112002KQ-SCONN288_DDR506112002KQ,SMA    I22 @T6G_MB_LIB.T6G(SCH_1):PAGE93

M_I_CPU0_SA_DQ<28> @T6G_MB_LIB.T6G(SCH_1):M_I_CPU0_SA_DQ(28)
   U25 AG19 MIA_DATA28 GENOA_SP5-SOCKET6096_13568-001,SMLF,IO,DGA^6000030   I159 @T6G_MB_LIB.T6G(SCH_1):PAGE18
   J18   47 DQ28_A SCONN288_DDR506112002KQ-SCONN288_DDR506112002KQ,SMA    I22 @T6G_MB_LIB.T6G(SCH_1):PAGE93

M_I_CPU0_SA_DQ<29> @T6G_MB_LIB.T6G(SCH_1):M_I_CPU0_SA_DQ(29)
   U25 AH21 MIA_DATA29 GENOA_SP5-SOCKET6096_13568-001,SMLF,IO,DGA^6000030   I159 @T6G_MB_LIB.T6G(SCH_1):PAGE18
   J18   49 DQ29_A SCONN288_DDR506112002KQ-SCONN288_DDR506112002KQ,SMA    I22 @T6G_MB_LIB.T6G(SCH_1):PAGE93

M_I_CPU0_SA_DQ<2> @T6G_MB_LIB.T6G(SCH_1):M_I_CPU0_SA_DQ(2)
   U25  F20 MIA_DATA2 GENOA_SP5-SOCKET6096_13568-001,SMLF,IO,DGA^6000030   I159 @T6G_MB_LIB.T6G(SCH_1):PAGE18
   J18  152  DQ2_A SCONN288_DDR506112002KQ-SCONN288_DDR506112002KQ,SMA    I22 @T6G_MB_LIB.T6G(SCH_1):PAGE93

M_I_CPU0_SA_DQ<30> @T6G_MB_LIB.T6G(SCH_1):M_I_CPU0_SA_DQ(30)
   U25 AH20 MIA_DATA30 GENOA_SP5-SOCKET6096_13568-001,SMLF,IO,DGA^6000030   I159 @T6G_MB_LIB.T6G(SCH_1):PAGE18
   J18  192 DQ30_A SCONN288_DDR506112002KQ-SCONN288_DDR506112002KQ,SMA    I22 @T6G_MB_LIB.T6G(SCH_1):PAGE93

M_I_CPU0_SA_DQ<31> @T6G_MB_LIB.T6G(SCH_1):M_I_CPU0_SA_DQ(31)
   U25 AJ21 MIA_DATA31 GENOA_SP5-SOCKET6096_13568-001,SMLF,IO,DGA^6000030   I159 @T6G_MB_LIB.T6G(SCH_1):PAGE18
   J18  194 DQ31_A SCONN288_DDR506112002KQ-SCONN288_DDR506112002KQ,SMA    I22 @T6G_MB_LIB.T6G(SCH_1):PAGE93

M_I_CPU0_SA_DQ<3> @T6G_MB_LIB.T6G(SCH_1):M_I_CPU0_SA_DQ(3)
   U25  G21 MIA_DATA3 GENOA_SP5-SOCKET6096_13568-001,SMLF,IO,DGA^6000030   I159 @T6G_MB_LIB.T6G(SCH_1):PAGE18
   J18  154  DQ3_A SCONN288_DDR506112002KQ-SCONN288_DDR506112002KQ,SMA    I22 @T6G_MB_LIB.T6G(SCH_1):PAGE93

M_I_CPU0_SA_DQ<4> @T6G_MB_LIB.T6G(SCH_1):M_I_CPU0_SA_DQ(4)
   U25  J19 MIA_DATA4 GENOA_SP5-SOCKET6096_13568-001,SMLF,IO,DGA^6000030   I159 @T6G_MB_LIB.T6G(SCH_1):PAGE18
   J18   14  DQ4_A SCONN288_DDR506112002KQ-SCONN288_DDR506112002KQ,SMA    I22 @T6G_MB_LIB.T6G(SCH_1):PAGE93

M_I_CPU0_SA_DQ<5> @T6G_MB_LIB.T6G(SCH_1):M_I_CPU0_SA_DQ(5)
   U25  K21 MIA_DATA5 GENOA_SP5-SOCKET6096_13568-001,SMLF,IO,DGA^6000030   I159 @T6G_MB_LIB.T6G(SCH_1):PAGE18
   J18   16  DQ5_A SCONN288_DDR506112002KQ-SCONN288_DDR506112002KQ,SMA    I22 @T6G_MB_LIB.T6G(SCH_1):PAGE93

M_I_CPU0_SA_DQ<6> @T6G_MB_LIB.T6G(SCH_1):M_I_CPU0_SA_DQ(6)
   U25  K20 MIA_DATA6 GENOA_SP5-SOCKET6096_13568-001,SMLF,IO,DGA^6000030   I159 @T6G_MB_LIB.T6G(SCH_1):PAGE18
   J18  159  DQ6_A SCONN288_DDR506112002KQ-SCONN288_DDR506112002KQ,SMA    I22 @T6G_MB_LIB.T6G(SCH_1):PAGE93

M_I_CPU0_SA_DQ<7> @T6G_MB_LIB.T6G(SCH_1):M_I_CPU0_SA_DQ(7)
   U25  L21 MIA_DATA7 GENOA_SP5-SOCKET6096_13568-001,SMLF,IO,DGA^6000030   I159 @T6G_MB_LIB.T6G(SCH_1):PAGE18
   J18  161  DQ7_A SCONN288_DDR506112002KQ-SCONN288_DDR506112002KQ,SMA    I22 @T6G_MB_LIB.T6G(SCH_1):PAGE93

M_I_CPU0_SA_DQ<8> @T6G_MB_LIB.T6G(SCH_1):M_I_CPU0_SA_DQ(8)
   U25  L19 MIA_DATA8 GENOA_SP5-SOCKET6096_13568-001,SMLF,IO,DGA^6000030   I159 @T6G_MB_LIB.T6G(SCH_1):PAGE18
   J18   18  DQ8_A SCONN288_DDR506112002KQ-SCONN288_DDR506112002KQ,SMA    I22 @T6G_MB_LIB.T6G(SCH_1):PAGE93

M_I_CPU0_SA_DQ<9> @T6G_MB_LIB.T6G(SCH_1):M_I_CPU0_SA_DQ(9)
   U25  M21 MIA_DATA9 GENOA_SP5-SOCKET6096_13568-001,SMLF,IO,DGA^6000030   I159 @T6G_MB_LIB.T6G(SCH_1):PAGE18
   J18   20  DQ9_A SCONN288_DDR506112002KQ-SCONN288_DDR506112002KQ,SMA    I22 @T6G_MB_LIB.T6G(SCH_1):PAGE93

M_I_CPU0_SA_DQS_DN<0> @T6G_MB_LIB.T6G(SCH_1):M_I_CPU0_SA_DQS_DN(0)
   U25  H20 MIA_DQS_L0 GENOA_SP5-SOCKET6096_13568-001,SMLF,IO,DGA^6000030   I159 @T6G_MB_LIB.T6G(SCH_1):PAGE18
   J18   12 DQS0_A_C SCONN288_DDR506112002KQ-SCONN288_DDR506112002KQ,SMA   I236 @T6G_MB_LIB.T6G(SCH_1):PAGE93

M_I_CPU0_SA_DQS_DN<1> @T6G_MB_LIB.T6G(SCH_1):M_I_CPU0_SA_DQS_DN(1)
   U25  P20 MIA_DQS_L1 GENOA_SP5-SOCKET6096_13568-001,SMLF,IO,DGA^6000030   I159 @T6G_MB_LIB.T6G(SCH_1):PAGE18
   J18   23 DQS1_A_C SCONN288_DDR506112002KQ-SCONN288_DDR506112002KQ,SMA   I236 @T6G_MB_LIB.T6G(SCH_1):PAGE93

M_I_CPU0_SA_DQS_DN<2> @T6G_MB_LIB.T6G(SCH_1):M_I_CPU0_SA_DQS_DN(2)
   U25  Y20 MIA_DQS_L2 GENOA_SP5-SOCKET6096_13568-001,SMLF,IO,DGA^6000030   I159 @T6G_MB_LIB.T6G(SCH_1):PAGE18
   J18   34 DQS2_A_C SCONN288_DDR506112002KQ-SCONN288_DDR506112002KQ,SMA   I236 @T6G_MB_LIB.T6G(SCH_1):PAGE93

M_I_CPU0_SA_DQS_DN<3> @T6G_MB_LIB.T6G(SCH_1):M_I_CPU0_SA_DQS_DN(3)
   U25 AF20 MIA_DQS_L3 GENOA_SP5-SOCKET6096_13568-001,SMLF,IO,DGA^6000030   I159 @T6G_MB_LIB.T6G(SCH_1):PAGE18
   J18   45 DQS3_A_C SCONN288_DDR506112002KQ-SCONN288_DDR506112002KQ,SMA   I236 @T6G_MB_LIB.T6G(SCH_1):PAGE93

M_I_CPU0_SA_DQS_DN<4> @T6G_MB_LIB.T6G(SCH_1):M_I_CPU0_SA_DQS_DN(4)
   U25 AM20 MIA_DQS_L4 GENOA_SP5-SOCKET6096_13568-001,SMLF,IO,DGA^6000030   I159 @T6G_MB_LIB.T6G(SCH_1):PAGE18
   J18   56 DQS4_A_C SCONN288_DDR506112002KQ-SCONN288_DDR506112002KQ,SMA   I236 @T6G_MB_LIB.T6G(SCH_1):PAGE93

M_I_CPU0_SA_DQS_DN<5> @T6G_MB_LIB.T6G(SCH_1):M_I_CPU0_SA_DQS_DN(5)
   U25  H21 MIA_DQS_L5 GENOA_SP5-SOCKET6096_13568-001,SMLF,IO,DGA^6000030   I159 @T6G_MB_LIB.T6G(SCH_1):PAGE18
   J18  156 DQS5_A_C||TDQS5_A_C||DQS5_A_T||TDQS5_A_T SCONN288_DDR506112002KQ-SCONN288_DDR506112002KQ,SMA   I236 @T6G_MB_LIB.T6G(SCH_1):PAGE93

M_I_CPU0_SA_DQS_DN<6> @T6G_MB_LIB.T6G(SCH_1):M_I_CPU0_SA_DQS_DN(6)
   U25  P21 MIA_DQS_L6 GENOA_SP5-SOCKET6096_13568-001,SMLF,IO,DGA^6000030   I159 @T6G_MB_LIB.T6G(SCH_1):PAGE18
   J18  167 DQS6_A_C||TDQS6_A_C||DQS6_A_T||TDQS6_A_T SCONN288_DDR506112002KQ-SCONN288_DDR506112002KQ,SMA   I236 @T6G_MB_LIB.T6G(SCH_1):PAGE93

M_I_CPU0_SA_DQS_DN<7> @T6G_MB_LIB.T6G(SCH_1):M_I_CPU0_SA_DQS_DN(7)
   U25  Y21 MIA_DQS_L7 GENOA_SP5-SOCKET6096_13568-001,SMLF,IO,DGA^6000030   I159 @T6G_MB_LIB.T6G(SCH_1):PAGE18
   J18  178 DQS7_A_C||TDQS7_A_C SCONN288_DDR506112002KQ-SCONN288_DDR506112002KQ,SMA   I236 @T6G_MB_LIB.T6G(SCH_1):PAGE93

M_I_CPU0_SA_DQS_DN<8> @T6G_MB_LIB.T6G(SCH_1):M_I_CPU0_SA_DQS_DN(8)
   U25 AF21 MIA_DQS_L8 GENOA_SP5-SOCKET6096_13568-001,SMLF,IO,DGA^6000030   I159 @T6G_MB_LIB.T6G(SCH_1):PAGE18
   J18  189 DQS8_A_C||TDQS8_A_C SCONN288_DDR506112002KQ-SCONN288_DDR506112002KQ,SMA   I236 @T6G_MB_LIB.T6G(SCH_1):PAGE93

M_I_CPU0_SA_DQS_DN<9> @T6G_MB_LIB.T6G(SCH_1):M_I_CPU0_SA_DQS_DN(9)
   U25 AM21 MIA_DQS_L9 GENOA_SP5-SOCKET6096_13568-001,SMLF,IO,DGA^6000030   I159 @T6G_MB_LIB.T6G(SCH_1):PAGE18
   J18  200 DQS9_A_C||TDQS9_A_C SCONN288_DDR506112002KQ-SCONN288_DDR506112002KQ,SMA   I236 @T6G_MB_LIB.T6G(SCH_1):PAGE93

M_I_CPU0_SA_DQS_DP<0> @T6G_MB_LIB.T6G(SCH_1):M_I_CPU0_SA_DQS_DP(0)
   U25  G19 MIA_DQS_H0 GENOA_SP5-SOCKET6096_13568-001,SMLF,IO,DGA^6000030   I159 @T6G_MB_LIB.T6G(SCH_1):PAGE18
   J18   11 DQS0_A_T SCONN288_DDR506112002KQ-SCONN288_DDR506112002KQ,SMA   I236 @T6G_MB_LIB.T6G(SCH_1):PAGE93

M_I_CPU0_SA_DQS_DP<1> @T6G_MB_LIB.T6G(SCH_1):M_I_CPU0_SA_DQS_DP(1)
   U25  N19 MIA_DQS_H1 GENOA_SP5-SOCKET6096_13568-001,SMLF,IO,DGA^6000030   I159 @T6G_MB_LIB.T6G(SCH_1):PAGE18
   J18   22 DQS1_A_T SCONN288_DDR506112002KQ-SCONN288_DDR506112002KQ,SMA   I236 @T6G_MB_LIB.T6G(SCH_1):PAGE93

M_I_CPU0_SA_DQS_DP<2> @T6G_MB_LIB.T6G(SCH_1):M_I_CPU0_SA_DQS_DP(2)
   U25  W19 MIA_DQS_H2 GENOA_SP5-SOCKET6096_13568-001,SMLF,IO,DGA^6000030   I159 @T6G_MB_LIB.T6G(SCH_1):PAGE18
   J18   33 DQS2_A_T SCONN288_DDR506112002KQ-SCONN288_DDR506112002KQ,SMA   I236 @T6G_MB_LIB.T6G(SCH_1):PAGE93

M_I_CPU0_SA_DQS_DP<3> @T6G_MB_LIB.T6G(SCH_1):M_I_CPU0_SA_DQS_DP(3)
   U25 AE19 MIA_DQS_H3 GENOA_SP5-SOCKET6096_13568-001,SMLF,IO,DGA^6000030   I159 @T6G_MB_LIB.T6G(SCH_1):PAGE18
   J18   44 DQS3_A_T SCONN288_DDR506112002KQ-SCONN288_DDR506112002KQ,SMA   I236 @T6G_MB_LIB.T6G(SCH_1):PAGE93

M_I_CPU0_SA_DQS_DP<4> @T6G_MB_LIB.T6G(SCH_1):M_I_CPU0_SA_DQS_DP(4)
   U25 AL19 MIA_DQS_H4 GENOA_SP5-SOCKET6096_13568-001,SMLF,IO,DGA^6000030   I159 @T6G_MB_LIB.T6G(SCH_1):PAGE18
   J18   55 DQS4_A_T SCONN288_DDR506112002KQ-SCONN288_DDR506112002KQ,SMA   I236 @T6G_MB_LIB.T6G(SCH_1):PAGE93

M_I_CPU0_SA_DQS_DP<5> @T6G_MB_LIB.T6G(SCH_1):M_I_CPU0_SA_DQS_DP(5)
   U25  J21 MIA_DQS_H5 GENOA_SP5-SOCKET6096_13568-001,SMLF,IO,DGA^6000030   I159 @T6G_MB_LIB.T6G(SCH_1):PAGE18
   J18  157 DQS5_A_T||TDQS5_A_T SCONN288_DDR506112002KQ-SCONN288_DDR506112002KQ,SMA   I236 @T6G_MB_LIB.T6G(SCH_1):PAGE93

M_I_CPU0_SA_DQS_DP<6> @T6G_MB_LIB.T6G(SCH_1):M_I_CPU0_SA_DQS_DP(6)
   U25  R21 MIA_DQS_H6 GENOA_SP5-SOCKET6096_13568-001,SMLF,IO,DGA^6000030   I159 @T6G_MB_LIB.T6G(SCH_1):PAGE18
   J18  168 DQS6_A_T||TDQS6_A_T SCONN288_DDR506112002KQ-SCONN288_DDR506112002KQ,SMA   I236 @T6G_MB_LIB.T6G(SCH_1):PAGE93

M_I_CPU0_SA_DQS_DP<7> @T6G_MB_LIB.T6G(SCH_1):M_I_CPU0_SA_DQS_DP(7)
   U25 AA21 MIA_DQS_H7 GENOA_SP5-SOCKET6096_13568-001,SMLF,IO,DGA^6000030   I159 @T6G_MB_LIB.T6G(SCH_1):PAGE18
   J18  179 DQS7_A_T||TDQS7_A_T SCONN288_DDR506112002KQ-SCONN288_DDR506112002KQ,SMA   I236 @T6G_MB_LIB.T6G(SCH_1):PAGE93

M_I_CPU0_SA_DQS_DP<8> @T6G_MB_LIB.T6G(SCH_1):M_I_CPU0_SA_DQS_DP(8)
   U25 AG21 MIA_DQS_H8 GENOA_SP5-SOCKET6096_13568-001,SMLF,IO,DGA^6000030   I159 @T6G_MB_LIB.T6G(SCH_1):PAGE18
   J18  190 DQS8_A_T||TDQS8_A_T SCONN288_DDR506112002KQ-SCONN288_DDR506112002KQ,SMA   I236 @T6G_MB_LIB.T6G(SCH_1):PAGE93

M_I_CPU0_SA_DQS_DP<9> @T6G_MB_LIB.T6G(SCH_1):M_I_CPU0_SA_DQS_DP(9)
   U25 AN21 MIA_DQS_H9 GENOA_SP5-SOCKET6096_13568-001,SMLF,IO,DGA^6000030   I159 @T6G_MB_LIB.T6G(SCH_1):PAGE18
   J18  201 DQS9_A_T||TDQS9_A_T SCONN288_DDR506112002KQ-SCONN288_DDR506112002KQ,SMA   I236 @T6G_MB_LIB.T6G(SCH_1):PAGE93

M_I_CPU0_SA_PAR @T6G_MB_LIB.T6G(SCH_1):M_I_CPU0_SA_PAR
   U25 BC21 MIA_PAR GENOA_SP5-SOCKET6096_13568-001,SMLF,IO,DGA^6000030   I159 @T6G_MB_LIB.T6G(SCH_1):PAGE18
   J18   74  PAR_A SCONN288_DDR506112002KQ-SCONN288_DDR506112002KQ,SMA    I22 @T6G_MB_LIB.T6G(SCH_1):PAGE93

M_I_CPU0_SA_RSP<0> @T6G_MB_LIB.T6G(SCH_1):M_I_CPU0_SA_RSP(0)
   U25 BN21 MIA0_RSP_L GENOA_SP5-SOCKET6096_13568-001,SMLF,IO,DGA^6000030   I159 @T6G_MB_LIB.T6G(SCH_1):PAGE18
   J18   86 LBD||RSP_A_N SCONN288_DDR506112002KQ-SCONN288_DDR506112002KQ,SMA    I22 @T6G_MB_LIB.T6G(SCH_1):PAGE93

M_I_CPU0_SB_CA<0> @T6G_MB_LIB.T6G(SCH_1):M_I_CPU0_SB_CA(0)
   U25 BG21 MIB_CA0 GENOA_SP5-SOCKET6096_13568-001,SMLF,IO,DGA^6000030   I159 @T6G_MB_LIB.T6G(SCH_1):PAGE18
   J18   76  CA0_B SCONN288_DDR506112002KQ-SCONN288_DDR506112002KQ,SMA    I22 @T6G_MB_LIB.T6G(SCH_1):PAGE93

M_I_CPU0_SB_CA<1> @T6G_MB_LIB.T6G(SCH_1):M_I_CPU0_SB_CA(1)
   U25 BH21 MIB_CA1 GENOA_SP5-SOCKET6096_13568-001,SMLF,IO,DGA^6000030   I159 @T6G_MB_LIB.T6G(SCH_1):PAGE18
   J18  221  CA1_B SCONN288_DDR506112002KQ-SCONN288_DDR506112002KQ,SMA    I22 @T6G_MB_LIB.T6G(SCH_1):PAGE93

M_I_CPU0_SB_CA<2> @T6G_MB_LIB.T6G(SCH_1):M_I_CPU0_SB_CA(2)
   U25 BH20 MIB_CA2 GENOA_SP5-SOCKET6096_13568-001,SMLF,IO,DGA^6000030   I159 @T6G_MB_LIB.T6G(SCH_1):PAGE18
   J18   78  CA2_B SCONN288_DDR506112002KQ-SCONN288_DDR506112002KQ,SMA    I22 @T6G_MB_LIB.T6G(SCH_1):PAGE93

M_I_CPU0_SB_CA<3> @T6G_MB_LIB.T6G(SCH_1):M_I_CPU0_SB_CA(3)
   U25 BJ19 MIB_CA3 GENOA_SP5-SOCKET6096_13568-001,SMLF,IO,DGA^6000030   I159 @T6G_MB_LIB.T6G(SCH_1):PAGE18
   J18  223  CA3_B SCONN288_DDR506112002KQ-SCONN288_DDR506112002KQ,SMA    I22 @T6G_MB_LIB.T6G(SCH_1):PAGE93

M_I_CPU0_SB_CA<4> @T6G_MB_LIB.T6G(SCH_1):M_I_CPU0_SB_CA(4)
   U25 BJ21 MIB_CA4 GENOA_SP5-SOCKET6096_13568-001,SMLF,IO,DGA^6000030   I159 @T6G_MB_LIB.T6G(SCH_1):PAGE18
   J18   80  CA4_B SCONN288_DDR506112002KQ-SCONN288_DDR506112002KQ,SMA    I22 @T6G_MB_LIB.T6G(SCH_1):PAGE93

M_I_CPU0_SB_CA<5> @T6G_MB_LIB.T6G(SCH_1):M_I_CPU0_SB_CA(5)
   U25 BK21 MIB_CA5 GENOA_SP5-SOCKET6096_13568-001,SMLF,IO,DGA^6000030   I159 @T6G_MB_LIB.T6G(SCH_1):PAGE18
   J18  225  CA5_B SCONN288_DDR506112002KQ-SCONN288_DDR506112002KQ,SMA    I22 @T6G_MB_LIB.T6G(SCH_1):PAGE93

M_I_CPU0_SB_CA<6> @T6G_MB_LIB.T6G(SCH_1):M_I_CPU0_SB_CA(6)
   U25 BK20 MIB_CA6 GENOA_SP5-SOCKET6096_13568-001,SMLF,IO,DGA^6000030   I159 @T6G_MB_LIB.T6G(SCH_1):PAGE18
   J18   82  CA6_B SCONN288_DDR506112002KQ-SCONN288_DDR506112002KQ,SMA    I22 @T6G_MB_LIB.T6G(SCH_1):PAGE93

M_I_CPU0_SB_CB<0> @T6G_MB_LIB.T6G(SCH_1):M_I_CPU0_SB_CB(0)
   U25 BY20 MIB_CHECK0 GENOA_SP5-SOCKET6096_13568-001,SMLF,IO,DGA^6000030   I159 @T6G_MB_LIB.T6G(SCH_1):PAGE18
   J18   96  CB0_B SCONN288_DDR506112002KQ-SCONN288_DDR506112002KQ,SMA    I22 @T6G_MB_LIB.T6G(SCH_1):PAGE93

M_I_CPU0_SB_CB<1> @T6G_MB_LIB.T6G(SCH_1):M_I_CPU0_SB_CB(1)
   U25 CA21 MIB_CHECK1 GENOA_SP5-SOCKET6096_13568-001,SMLF,IO,DGA^6000030   I159 @T6G_MB_LIB.T6G(SCH_1):PAGE18
   J18   98  CB1_B SCONN288_DDR506112002KQ-SCONN288_DDR506112002KQ,SMA    I22 @T6G_MB_LIB.T6G(SCH_1):PAGE93

M_I_CPU0_SB_CB<2> @T6G_MB_LIB.T6G(SCH_1):M_I_CPU0_SB_CB(2)
   U25 CA19 MIB_CHECK2 GENOA_SP5-SOCKET6096_13568-001,SMLF,IO,DGA^6000030   I159 @T6G_MB_LIB.T6G(SCH_1):PAGE18
   J18  241  CB2_B SCONN288_DDR506112002KQ-SCONN288_DDR506112002KQ,SMA    I22 @T6G_MB_LIB.T6G(SCH_1):PAGE93

M_I_CPU0_SB_CB<3> @T6G_MB_LIB.T6G(SCH_1):M_I_CPU0_SB_CB(3)
   U25 CB21 MIB_CHECK3 GENOA_SP5-SOCKET6096_13568-001,SMLF,IO,DGA^6000030   I159 @T6G_MB_LIB.T6G(SCH_1):PAGE18
   J18  243  CB3_B SCONN288_DDR506112002KQ-SCONN288_DDR506112002KQ,SMA    I22 @T6G_MB_LIB.T6G(SCH_1):PAGE93

M_I_CPU0_SB_CB<4> @T6G_MB_LIB.T6G(SCH_1):M_I_CPU0_SB_CB(4)
   U25 BT20 MIB_CHECK4 GENOA_SP5-SOCKET6096_13568-001,SMLF,IO,DGA^6000030   I159 @T6G_MB_LIB.T6G(SCH_1):PAGE18
   J18   89  CB4_B SCONN288_DDR506112002KQ-SCONN288_DDR506112002KQ,SMA    I22 @T6G_MB_LIB.T6G(SCH_1):PAGE93

M_I_CPU0_SB_CB<5> @T6G_MB_LIB.T6G(SCH_1):M_I_CPU0_SB_CB(5)
   U25 BU21 MIB_CHECK5 GENOA_SP5-SOCKET6096_13568-001,SMLF,IO,DGA^6000030   I159 @T6G_MB_LIB.T6G(SCH_1):PAGE18
   J18   91  CB5_B SCONN288_DDR506112002KQ-SCONN288_DDR506112002KQ,SMA    I22 @T6G_MB_LIB.T6G(SCH_1):PAGE93

M_I_CPU0_SB_CB<6> @T6G_MB_LIB.T6G(SCH_1):M_I_CPU0_SB_CB(6)
   U25 BU19 MIB_CHECK6 GENOA_SP5-SOCKET6096_13568-001,SMLF,IO,DGA^6000030   I159 @T6G_MB_LIB.T6G(SCH_1):PAGE18
   J18  234  CB6_B SCONN288_DDR506112002KQ-SCONN288_DDR506112002KQ,SMA    I22 @T6G_MB_LIB.T6G(SCH_1):PAGE93

M_I_CPU0_SB_CB<7> @T6G_MB_LIB.T6G(SCH_1):M_I_CPU0_SB_CB(7)
   U25 BV21 MIB_CHECK7 GENOA_SP5-SOCKET6096_13568-001,SMLF,IO,DGA^6000030   I159 @T6G_MB_LIB.T6G(SCH_1):PAGE18
   J18  236  CB7_B SCONN288_DDR506112002KQ-SCONN288_DDR506112002KQ,SMA    I22 @T6G_MB_LIB.T6G(SCH_1):PAGE93

M_I_CPU0_SB_CS_N<0> @T6G_MB_LIB.T6G(SCH_1):M_I_CPU0_SB_CS_N(0)
   U25 BM21 MIB0_CS_L0 GENOA_SP5-SOCKET6096_13568-001,SMLF,IO,DGA^6000030   I159 @T6G_MB_LIB.T6G(SCH_1):PAGE18
   J18   84 CS0_B_N SCONN288_DDR506112002KQ-SCONN288_DDR506112002KQ,SMA    I22 @T6G_MB_LIB.T6G(SCH_1):PAGE93

M_I_CPU0_SB_CS_N<1> @T6G_MB_LIB.T6G(SCH_1):M_I_CPU0_SB_CS_N(1)
   U25 BN19 MIB0_CS_L1 GENOA_SP5-SOCKET6096_13568-001,SMLF,IO,DGA^6000030   I159 @T6G_MB_LIB.T6G(SCH_1):PAGE18
   J18  229 CS1_B_N SCONN288_DDR506112002KQ-SCONN288_DDR506112002KQ,SMA    I22 @T6G_MB_LIB.T6G(SCH_1):PAGE93

M_I_CPU0_SB_DQ<0> @T6G_MB_LIB.T6G(SCH_1):M_I_CPU0_SB_DQ(0)
   U25 CB20 MIB_DATA0 GENOA_SP5-SOCKET6096_13568-001,SMLF,IO,DGA^6000030   I159 @T6G_MB_LIB.T6G(SCH_1):PAGE18
   J18  100  DQ0_B SCONN288_DDR506112002KQ-SCONN288_DDR506112002KQ,SMA    I22 @T6G_MB_LIB.T6G(SCH_1):PAGE93

M_I_CPU0_SB_DQ<10> @T6G_MB_LIB.T6G(SCH_1):M_I_CPU0_SB_DQ(10)
   U25 CJ19 MIB_DATA10 GENOA_SP5-SOCKET6096_13568-001,SMLF,IO,DGA^6000030   I159 @T6G_MB_LIB.T6G(SCH_1):PAGE18
   J18  256 DQ10_B SCONN288_DDR506112002KQ-SCONN288_DDR506112002KQ,SMA    I22 @T6G_MB_LIB.T6G(SCH_1):PAGE93

M_I_CPU0_SB_DQ<11> @T6G_MB_LIB.T6G(SCH_1):M_I_CPU0_SB_DQ(11)
   U25 CK21 MIB_DATA11 GENOA_SP5-SOCKET6096_13568-001,SMLF,IO,DGA^6000030   I159 @T6G_MB_LIB.T6G(SCH_1):PAGE18
   J18  258 DQ11_B SCONN288_DDR506112002KQ-SCONN288_DDR506112002KQ,SMA    I22 @T6G_MB_LIB.T6G(SCH_1):PAGE93

M_I_CPU0_SB_DQ<12> @T6G_MB_LIB.T6G(SCH_1):M_I_CPU0_SB_DQ(12)
   U25 CM20 MIB_DATA12 GENOA_SP5-SOCKET6096_13568-001,SMLF,IO,DGA^6000030   I159 @T6G_MB_LIB.T6G(SCH_1):PAGE18
   J18  118 DQ12_B SCONN288_DDR506112002KQ-SCONN288_DDR506112002KQ,SMA    I22 @T6G_MB_LIB.T6G(SCH_1):PAGE93

M_I_CPU0_SB_DQ<13> @T6G_MB_LIB.T6G(SCH_1):M_I_CPU0_SB_DQ(13)
   U25 CN21 MIB_DATA13 GENOA_SP5-SOCKET6096_13568-001,SMLF,IO,DGA^6000030   I159 @T6G_MB_LIB.T6G(SCH_1):PAGE18
   J18  120 DQ13_B SCONN288_DDR506112002KQ-SCONN288_DDR506112002KQ,SMA    I22 @T6G_MB_LIB.T6G(SCH_1):PAGE93

M_I_CPU0_SB_DQ<14> @T6G_MB_LIB.T6G(SCH_1):M_I_CPU0_SB_DQ(14)
   U25 CN19 MIB_DATA14 GENOA_SP5-SOCKET6096_13568-001,SMLF,IO,DGA^6000030   I159 @T6G_MB_LIB.T6G(SCH_1):PAGE18
   J18  263 DQ14_B SCONN288_DDR506112002KQ-SCONN288_DDR506112002KQ,SMA    I22 @T6G_MB_LIB.T6G(SCH_1):PAGE93

M_I_CPU0_SB_DQ<15> @T6G_MB_LIB.T6G(SCH_1):M_I_CPU0_SB_DQ(15)
   U25 CP21 MIB_DATA15 GENOA_SP5-SOCKET6096_13568-001,SMLF,IO,DGA^6000030   I159 @T6G_MB_LIB.T6G(SCH_1):PAGE18
   J18  265 DQ15_B SCONN288_DDR506112002KQ-SCONN288_DDR506112002KQ,SMA    I22 @T6G_MB_LIB.T6G(SCH_1):PAGE93

M_I_CPU0_SB_DQ<16> @T6G_MB_LIB.T6G(SCH_1):M_I_CPU0_SB_DQ(16)
   U25 CP20 MIB_DATA16 GENOA_SP5-SOCKET6096_13568-001,SMLF,IO,DGA^6000030   I159 @T6G_MB_LIB.T6G(SCH_1):PAGE18
   J18  122 DQ16_B SCONN288_DDR506112002KQ-SCONN288_DDR506112002KQ,SMA    I22 @T6G_MB_LIB.T6G(SCH_1):PAGE93

M_I_CPU0_SB_DQ<17> @T6G_MB_LIB.T6G(SCH_1):M_I_CPU0_SB_DQ(17)
   U25 CR21 MIB_DATA17 GENOA_SP5-SOCKET6096_13568-001,SMLF,IO,DGA^6000030   I159 @T6G_MB_LIB.T6G(SCH_1):PAGE18
   J18  124 DQ17_B SCONN288_DDR506112002KQ-SCONN288_DDR506112002KQ,SMA    I22 @T6G_MB_LIB.T6G(SCH_1):PAGE93

M_I_CPU0_SB_DQ<18> @T6G_MB_LIB.T6G(SCH_1):M_I_CPU0_SB_DQ(18)
   U25 CR19 MIB_DATA18 GENOA_SP5-SOCKET6096_13568-001,SMLF,IO,DGA^6000030   I159 @T6G_MB_LIB.T6G(SCH_1):PAGE18
   J18  267 DQ18_B SCONN288_DDR506112002KQ-SCONN288_DDR506112002KQ,SMA    I22 @T6G_MB_LIB.T6G(SCH_1):PAGE93

M_I_CPU0_SB_DQ<19> @T6G_MB_LIB.T6G(SCH_1):M_I_CPU0_SB_DQ(19)
   U25 CT21 MIB_DATA19 GENOA_SP5-SOCKET6096_13568-001,SMLF,IO,DGA^6000030   I159 @T6G_MB_LIB.T6G(SCH_1):PAGE18
   J18  269 DQ19_B SCONN288_DDR506112002KQ-SCONN288_DDR506112002KQ,SMA    I22 @T6G_MB_LIB.T6G(SCH_1):PAGE93

M_I_CPU0_SB_DQ<1> @T6G_MB_LIB.T6G(SCH_1):M_I_CPU0_SB_DQ(1)
   U25 CC21 MIB_DATA1 GENOA_SP5-SOCKET6096_13568-001,SMLF,IO,DGA^6000030   I159 @T6G_MB_LIB.T6G(SCH_1):PAGE18
   J18  102  DQ1_B SCONN288_DDR506112002KQ-SCONN288_DDR506112002KQ,SMA    I22 @T6G_MB_LIB.T6G(SCH_1):PAGE93

M_I_CPU0_SB_DQ<20> @T6G_MB_LIB.T6G(SCH_1):M_I_CPU0_SB_DQ(20)
   U25 CV20 MIB_DATA20 GENOA_SP5-SOCKET6096_13568-001,SMLF,IO,DGA^6000030   I159 @T6G_MB_LIB.T6G(SCH_1):PAGE18
   J18  129 DQ20_B SCONN288_DDR506112002KQ-SCONN288_DDR506112002KQ,SMA    I22 @T6G_MB_LIB.T6G(SCH_1):PAGE93

M_I_CPU0_SB_DQ<21> @T6G_MB_LIB.T6G(SCH_1):M_I_CPU0_SB_DQ(21)
   U25 CW21 MIB_DATA21 GENOA_SP5-SOCKET6096_13568-001,SMLF,IO,DGA^6000030   I159 @T6G_MB_LIB.T6G(SCH_1):PAGE18
   J18  131 DQ21_B SCONN288_DDR506112002KQ-SCONN288_DDR506112002KQ,SMA    I22 @T6G_MB_LIB.T6G(SCH_1):PAGE93

M_I_CPU0_SB_DQ<22> @T6G_MB_LIB.T6G(SCH_1):M_I_CPU0_SB_DQ(22)
   U25 CW19 MIB_DATA22 GENOA_SP5-SOCKET6096_13568-001,SMLF,IO,DGA^6000030   I159 @T6G_MB_LIB.T6G(SCH_1):PAGE18
   J18  274 DQ22_B SCONN288_DDR506112002KQ-SCONN288_DDR506112002KQ,SMA    I22 @T6G_MB_LIB.T6G(SCH_1):PAGE93

M_I_CPU0_SB_DQ<23> @T6G_MB_LIB.T6G(SCH_1):M_I_CPU0_SB_DQ(23)
   U25 CY21 MIB_DATA23 GENOA_SP5-SOCKET6096_13568-001,SMLF,IO,DGA^6000030   I159 @T6G_MB_LIB.T6G(SCH_1):PAGE18
   J18  276 DQ23_B SCONN288_DDR506112002KQ-SCONN288_DDR506112002KQ,SMA    I22 @T6G_MB_LIB.T6G(SCH_1):PAGE93

M_I_CPU0_SB_DQ<24> @T6G_MB_LIB.T6G(SCH_1):M_I_CPU0_SB_DQ(24)
   U25 CY20 MIB_DATA24 GENOA_SP5-SOCKET6096_13568-001,SMLF,IO,DGA^6000030   I159 @T6G_MB_LIB.T6G(SCH_1):PAGE18
   J18  133 DQ24_B SCONN288_DDR506112002KQ-SCONN288_DDR506112002KQ,SMA    I22 @T6G_MB_LIB.T6G(SCH_1):PAGE93

M_I_CPU0_SB_DQ<25> @T6G_MB_LIB.T6G(SCH_1):M_I_CPU0_SB_DQ(25)
   U25 DA21 MIB_DATA25 GENOA_SP5-SOCKET6096_13568-001,SMLF,IO,DGA^6000030   I159 @T6G_MB_LIB.T6G(SCH_1):PAGE18
   J18  135 DQ25_B SCONN288_DDR506112002KQ-SCONN288_DDR506112002KQ,SMA    I22 @T6G_MB_LIB.T6G(SCH_1):PAGE93

M_I_CPU0_SB_DQ<26> @T6G_MB_LIB.T6G(SCH_1):M_I_CPU0_SB_DQ(26)
   U25 DA19 MIB_DATA26 GENOA_SP5-SOCKET6096_13568-001,SMLF,IO,DGA^6000030   I159 @T6G_MB_LIB.T6G(SCH_1):PAGE18
   J18  278 DQ26_B SCONN288_DDR506112002KQ-SCONN288_DDR506112002KQ,SMA    I22 @T6G_MB_LIB.T6G(SCH_1):PAGE93

M_I_CPU0_SB_DQ<27> @T6G_MB_LIB.T6G(SCH_1):M_I_CPU0_SB_DQ(27)
   U25 DB21 MIB_DATA27 GENOA_SP5-SOCKET6096_13568-001,SMLF,IO,DGA^6000030   I159 @T6G_MB_LIB.T6G(SCH_1):PAGE18
   J18  280 DQ27_B SCONN288_DDR506112002KQ-SCONN288_DDR506112002KQ,SMA    I22 @T6G_MB_LIB.T6G(SCH_1):PAGE93

M_I_CPU0_SB_DQ<28> @T6G_MB_LIB.T6G(SCH_1):M_I_CPU0_SB_DQ(28)
   U25 DD20 MIB_DATA28 GENOA_SP5-SOCKET6096_13568-001,SMLF,IO,DGA^6000030   I159 @T6G_MB_LIB.T6G(SCH_1):PAGE18
   J18  140 DQ28_B SCONN288_DDR506112002KQ-SCONN288_DDR506112002KQ,SMA    I22 @T6G_MB_LIB.T6G(SCH_1):PAGE93

M_I_CPU0_SB_DQ<29> @T6G_MB_LIB.T6G(SCH_1):M_I_CPU0_SB_DQ(29)
   U25 DE21 MIB_DATA29 GENOA_SP5-SOCKET6096_13568-001,SMLF,IO,DGA^6000030   I159 @T6G_MB_LIB.T6G(SCH_1):PAGE18
   J18  142 DQ29_B SCONN288_DDR506112002KQ-SCONN288_DDR506112002KQ,SMA    I22 @T6G_MB_LIB.T6G(SCH_1):PAGE93

M_I_CPU0_SB_DQ<2> @T6G_MB_LIB.T6G(SCH_1):M_I_CPU0_SB_DQ(2)
   U25 CC19 MIB_DATA2 GENOA_SP5-SOCKET6096_13568-001,SMLF,IO,DGA^6000030   I159 @T6G_MB_LIB.T6G(SCH_1):PAGE18
   J18  245  DQ2_B SCONN288_DDR506112002KQ-SCONN288_DDR506112002KQ,SMA    I22 @T6G_MB_LIB.T6G(SCH_1):PAGE93

M_I_CPU0_SB_DQ<30> @T6G_MB_LIB.T6G(SCH_1):M_I_CPU0_SB_DQ(30)
   U25 DE19 MIB_DATA30 GENOA_SP5-SOCKET6096_13568-001,SMLF,IO,DGA^6000030   I159 @T6G_MB_LIB.T6G(SCH_1):PAGE18
   J18  285 DQ30_B SCONN288_DDR506112002KQ-SCONN288_DDR506112002KQ,SMA    I22 @T6G_MB_LIB.T6G(SCH_1):PAGE93

M_I_CPU0_SB_DQ<31> @T6G_MB_LIB.T6G(SCH_1):M_I_CPU0_SB_DQ(31)
   U25 DF21 MIB_DATA31 GENOA_SP5-SOCKET6096_13568-001,SMLF,IO,DGA^6000030   I159 @T6G_MB_LIB.T6G(SCH_1):PAGE18
   J18  287 DQ31_B SCONN288_DDR506112002KQ-SCONN288_DDR506112002KQ,SMA    I22 @T6G_MB_LIB.T6G(SCH_1):PAGE93

M_I_CPU0_SB_DQ<3> @T6G_MB_LIB.T6G(SCH_1):M_I_CPU0_SB_DQ(3)
   U25 CD21 MIB_DATA3 GENOA_SP5-SOCKET6096_13568-001,SMLF,IO,DGA^6000030   I159 @T6G_MB_LIB.T6G(SCH_1):PAGE18
   J18  247  DQ3_B SCONN288_DDR506112002KQ-SCONN288_DDR506112002KQ,SMA    I22 @T6G_MB_LIB.T6G(SCH_1):PAGE93

M_I_CPU0_SB_DQ<4> @T6G_MB_LIB.T6G(SCH_1):M_I_CPU0_SB_DQ(4)
   U25 CF20 MIB_DATA4 GENOA_SP5-SOCKET6096_13568-001,SMLF,IO,DGA^6000030   I159 @T6G_MB_LIB.T6G(SCH_1):PAGE18
   J18  107  DQ4_B SCONN288_DDR506112002KQ-SCONN288_DDR506112002KQ,SMA    I22 @T6G_MB_LIB.T6G(SCH_1):PAGE93

M_I_CPU0_SB_DQ<5> @T6G_MB_LIB.T6G(SCH_1):M_I_CPU0_SB_DQ(5)
   U25 CG21 MIB_DATA5 GENOA_SP5-SOCKET6096_13568-001,SMLF,IO,DGA^6000030   I159 @T6G_MB_LIB.T6G(SCH_1):PAGE18
   J18  109  DQ5_B SCONN288_DDR506112002KQ-SCONN288_DDR506112002KQ,SMA    I22 @T6G_MB_LIB.T6G(SCH_1):PAGE93

M_I_CPU0_SB_DQ<6> @T6G_MB_LIB.T6G(SCH_1):M_I_CPU0_SB_DQ(6)
   U25 CG19 MIB_DATA6 GENOA_SP5-SOCKET6096_13568-001,SMLF,IO,DGA^6000030   I159 @T6G_MB_LIB.T6G(SCH_1):PAGE18
   J18  252  DQ6_B SCONN288_DDR506112002KQ-SCONN288_DDR506112002KQ,SMA    I22 @T6G_MB_LIB.T6G(SCH_1):PAGE93

M_I_CPU0_SB_DQ<7> @T6G_MB_LIB.T6G(SCH_1):M_I_CPU0_SB_DQ(7)
   U25 CH21 MIB_DATA7 GENOA_SP5-SOCKET6096_13568-001,SMLF,IO,DGA^6000030   I159 @T6G_MB_LIB.T6G(SCH_1):PAGE18
   J18  254  DQ7_B SCONN288_DDR506112002KQ-SCONN288_DDR506112002KQ,SMA    I22 @T6G_MB_LIB.T6G(SCH_1):PAGE93

M_I_CPU0_SB_DQ<8> @T6G_MB_LIB.T6G(SCH_1):M_I_CPU0_SB_DQ(8)
   U25 CH20 MIB_DATA8 GENOA_SP5-SOCKET6096_13568-001,SMLF,IO,DGA^6000030   I159 @T6G_MB_LIB.T6G(SCH_1):PAGE18
   J18  111  DQ8_B SCONN288_DDR506112002KQ-SCONN288_DDR506112002KQ,SMA    I22 @T6G_MB_LIB.T6G(SCH_1):PAGE93

M_I_CPU0_SB_DQ<9> @T6G_MB_LIB.T6G(SCH_1):M_I_CPU0_SB_DQ(9)
   U25 CJ21 MIB_DATA9 GENOA_SP5-SOCKET6096_13568-001,SMLF,IO,DGA^6000030   I159 @T6G_MB_LIB.T6G(SCH_1):PAGE18
   J18  113  DQ9_B SCONN288_DDR506112002KQ-SCONN288_DDR506112002KQ,SMA    I22 @T6G_MB_LIB.T6G(SCH_1):PAGE93

M_I_CPU0_SB_DQS_DN<0> @T6G_MB_LIB.T6G(SCH_1):M_I_CPU0_SB_DQS_DN(0)
   U25 CE19 MIB_DQS_L0 GENOA_SP5-SOCKET6096_13568-001,SMLF,IO,DGA^6000030   I159 @T6G_MB_LIB.T6G(SCH_1):PAGE18
   J18  105 DQS0_B_C SCONN288_DDR506112002KQ-SCONN288_DDR506112002KQ,SMA   I236 @T6G_MB_LIB.T6G(SCH_1):PAGE93

M_I_CPU0_SB_DQS_DN<1> @T6G_MB_LIB.T6G(SCH_1):M_I_CPU0_SB_DQS_DN(1)
   U25 CL19 MIB_DQS_L1 GENOA_SP5-SOCKET6096_13568-001,SMLF,IO,DGA^6000030   I159 @T6G_MB_LIB.T6G(SCH_1):PAGE18
   J18  116 DQS1_B_C SCONN288_DDR506112002KQ-SCONN288_DDR506112002KQ,SMA   I236 @T6G_MB_LIB.T6G(SCH_1):PAGE93

M_I_CPU0_SB_DQS_DN<2> @T6G_MB_LIB.T6G(SCH_1):M_I_CPU0_SB_DQS_DN(2)
   U25 CU19 MIB_DQS_L2 GENOA_SP5-SOCKET6096_13568-001,SMLF,IO,DGA^6000030   I159 @T6G_MB_LIB.T6G(SCH_1):PAGE18
   J18  127 DQS2_B_C SCONN288_DDR506112002KQ-SCONN288_DDR506112002KQ,SMA   I236 @T6G_MB_LIB.T6G(SCH_1):PAGE93

M_I_CPU0_SB_DQS_DN<3> @T6G_MB_LIB.T6G(SCH_1):M_I_CPU0_SB_DQS_DN(3)
   U25 DC19 MIB_DQS_L3 GENOA_SP5-SOCKET6096_13568-001,SMLF,IO,DGA^6000030   I159 @T6G_MB_LIB.T6G(SCH_1):PAGE18
   J18  138 DQS3_B_C SCONN288_DDR506112002KQ-SCONN288_DDR506112002KQ,SMA   I236 @T6G_MB_LIB.T6G(SCH_1):PAGE93

M_I_CPU0_SB_DQS_DN<4> @T6G_MB_LIB.T6G(SCH_1):M_I_CPU0_SB_DQS_DN(4)
   U25 BW21 MIB_DQS_L4 GENOA_SP5-SOCKET6096_13568-001,SMLF,IO,DGA^6000030   I159 @T6G_MB_LIB.T6G(SCH_1):PAGE18
   J18  238 DQS4_B_C SCONN288_DDR506112002KQ-SCONN288_DDR506112002KQ,SMA   I236 @T6G_MB_LIB.T6G(SCH_1):PAGE93

M_I_CPU0_SB_DQS_DN<5> @T6G_MB_LIB.T6G(SCH_1):M_I_CPU0_SB_DQS_DN(5)
   U25 CE21 MIB_DQS_L5 GENOA_SP5-SOCKET6096_13568-001,SMLF,IO,DGA^6000030   I159 @T6G_MB_LIB.T6G(SCH_1):PAGE18
   J18  249 DQS5_B_C||TDQS5_B_C SCONN288_DDR506112002KQ-SCONN288_DDR506112002KQ,SMA   I236 @T6G_MB_LIB.T6G(SCH_1):PAGE93

M_I_CPU0_SB_DQS_DN<6> @T6G_MB_LIB.T6G(SCH_1):M_I_CPU0_SB_DQS_DN(6)
   U25 CL21 MIB_DQS_L6 GENOA_SP5-SOCKET6096_13568-001,SMLF,IO,DGA^6000030   I159 @T6G_MB_LIB.T6G(SCH_1):PAGE18
   J18  260 DQS6_B_C||TDQS6_B_C SCONN288_DDR506112002KQ-SCONN288_DDR506112002KQ,SMA   I236 @T6G_MB_LIB.T6G(SCH_1):PAGE93

M_I_CPU0_SB_DQS_DN<7> @T6G_MB_LIB.T6G(SCH_1):M_I_CPU0_SB_DQS_DN(7)
   U25 CU21 MIB_DQS_L7 GENOA_SP5-SOCKET6096_13568-001,SMLF,IO,DGA^6000030   I159 @T6G_MB_LIB.T6G(SCH_1):PAGE18
   J18  271 DQS7_B_C||TDQS7_B_C SCONN288_DDR506112002KQ-SCONN288_DDR506112002KQ,SMA   I236 @T6G_MB_LIB.T6G(SCH_1):PAGE93

M_I_CPU0_SB_DQS_DN<8> @T6G_MB_LIB.T6G(SCH_1):M_I_CPU0_SB_DQS_DN(8)
   U25 DC21 MIB_DQS_L8 GENOA_SP5-SOCKET6096_13568-001,SMLF,IO,DGA^6000030   I159 @T6G_MB_LIB.T6G(SCH_1):PAGE18
   J18  282 DQS8_B_C||TDQS8_B_C SCONN288_DDR506112002KQ-SCONN288_DDR506112002KQ,SMA   I236 @T6G_MB_LIB.T6G(SCH_1):PAGE93

M_I_CPU0_SB_DQS_DN<9> @T6G_MB_LIB.T6G(SCH_1):M_I_CPU0_SB_DQS_DN(9)
   U25 BW19 MIB_DQS_L9 GENOA_SP5-SOCKET6096_13568-001,SMLF,IO,DGA^6000030   I159 @T6G_MB_LIB.T6G(SCH_1):PAGE18
   J18   94 DQS9_B_C||TDQS9_B_C SCONN288_DDR506112002KQ-SCONN288_DDR506112002KQ,SMA   I236 @T6G_MB_LIB.T6G(SCH_1):PAGE93

M_I_CPU0_SB_DQS_DP<0> @T6G_MB_LIB.T6G(SCH_1):M_I_CPU0_SB_DQS_DP(0)
   U25 CD20 MIB_DQS_H0 GENOA_SP5-SOCKET6096_13568-001,SMLF,IO,DGA^6000030   I159 @T6G_MB_LIB.T6G(SCH_1):PAGE18
   J18  104 DQS0_B_T SCONN288_DDR506112002KQ-SCONN288_DDR506112002KQ,SMA   I236 @T6G_MB_LIB.T6G(SCH_1):PAGE93

M_I_CPU0_SB_DQS_DP<1> @T6G_MB_LIB.T6G(SCH_1):M_I_CPU0_SB_DQS_DP(1)
   U25 CK20 MIB_DQS_H1 GENOA_SP5-SOCKET6096_13568-001,SMLF,IO,DGA^6000030   I159 @T6G_MB_LIB.T6G(SCH_1):PAGE18
   J18  115 DQS1_B_T SCONN288_DDR506112002KQ-SCONN288_DDR506112002KQ,SMA   I236 @T6G_MB_LIB.T6G(SCH_1):PAGE93

M_I_CPU0_SB_DQS_DP<2> @T6G_MB_LIB.T6G(SCH_1):M_I_CPU0_SB_DQS_DP(2)
   U25 CT20 MIB_DQS_H2 GENOA_SP5-SOCKET6096_13568-001,SMLF,IO,DGA^6000030   I159 @T6G_MB_LIB.T6G(SCH_1):PAGE18
   J18  126 DQS2_B_T SCONN288_DDR506112002KQ-SCONN288_DDR506112002KQ,SMA   I236 @T6G_MB_LIB.T6G(SCH_1):PAGE93

M_I_CPU0_SB_DQS_DP<3> @T6G_MB_LIB.T6G(SCH_1):M_I_CPU0_SB_DQS_DP(3)
   U25 DB20 MIB_DQS_H3 GENOA_SP5-SOCKET6096_13568-001,SMLF,IO,DGA^6000030   I159 @T6G_MB_LIB.T6G(SCH_1):PAGE18
   J18  137 DQS3_B_T SCONN288_DDR506112002KQ-SCONN288_DDR506112002KQ,SMA   I236 @T6G_MB_LIB.T6G(SCH_1):PAGE93

M_I_CPU0_SB_DQS_DP<4> @T6G_MB_LIB.T6G(SCH_1):M_I_CPU0_SB_DQS_DP(4)
   U25 BY21 MIB_DQS_H4 GENOA_SP5-SOCKET6096_13568-001,SMLF,IO,DGA^6000030   I159 @T6G_MB_LIB.T6G(SCH_1):PAGE18
   J18  239 DQS4_B_T SCONN288_DDR506112002KQ-SCONN288_DDR506112002KQ,SMA   I236 @T6G_MB_LIB.T6G(SCH_1):PAGE93

M_I_CPU0_SB_DQS_DP<5> @T6G_MB_LIB.T6G(SCH_1):M_I_CPU0_SB_DQS_DP(5)
   U25 CF21 MIB_DQS_H5 GENOA_SP5-SOCKET6096_13568-001,SMLF,IO,DGA^6000030   I159 @T6G_MB_LIB.T6G(SCH_1):PAGE18
   J18  250 DQS5_B_T||TDQS5_B_T SCONN288_DDR506112002KQ-SCONN288_DDR506112002KQ,SMA   I236 @T6G_MB_LIB.T6G(SCH_1):PAGE93

M_I_CPU0_SB_DQS_DP<6> @T6G_MB_LIB.T6G(SCH_1):M_I_CPU0_SB_DQS_DP(6)
   U25 CM21 MIB_DQS_H6 GENOA_SP5-SOCKET6096_13568-001,SMLF,IO,DGA^6000030   I159 @T6G_MB_LIB.T6G(SCH_1):PAGE18
   J18  261 DQS6_B_T||TDQS6_B_T SCONN288_DDR506112002KQ-SCONN288_DDR506112002KQ,SMA   I236 @T6G_MB_LIB.T6G(SCH_1):PAGE93

M_I_CPU0_SB_DQS_DP<7> @T6G_MB_LIB.T6G(SCH_1):M_I_CPU0_SB_DQS_DP(7)
   U25 CV21 MIB_DQS_H7 GENOA_SP5-SOCKET6096_13568-001,SMLF,IO,DGA^6000030   I159 @T6G_MB_LIB.T6G(SCH_1):PAGE18
   J18  272 DQS7_B_T||TDQS7_B_T SCONN288_DDR506112002KQ-SCONN288_DDR506112002KQ,SMA   I236 @T6G_MB_LIB.T6G(SCH_1):PAGE93

M_I_CPU0_SB_DQS_DP<8> @T6G_MB_LIB.T6G(SCH_1):M_I_CPU0_SB_DQS_DP(8)
   U25 DD21 MIB_DQS_H8 GENOA_SP5-SOCKET6096_13568-001,SMLF,IO,DGA^6000030   I159 @T6G_MB_LIB.T6G(SCH_1):PAGE18
   J18  283 DQS8_B_T||TDQS8_B_T SCONN288_DDR506112002KQ-SCONN288_DDR506112002KQ,SMA   I236 @T6G_MB_LIB.T6G(SCH_1):PAGE93

M_I_CPU0_SB_DQS_DP<9> @T6G_MB_LIB.T6G(SCH_1):M_I_CPU0_SB_DQS_DP(9)
   U25 BV20 MIB_DQS_H9 GENOA_SP5-SOCKET6096_13568-001,SMLF,IO,DGA^6000030   I159 @T6G_MB_LIB.T6G(SCH_1):PAGE18
   J18   93 DQS9_B_T||TDQS9_B_T||DBI4_B_N SCONN288_DDR506112002KQ-SCONN288_DDR506112002KQ,SMA   I236 @T6G_MB_LIB.T6G(SCH_1):PAGE93

M_I_CPU0_SB_PAR @T6G_MB_LIB.T6G(SCH_1):M_I_CPU0_SB_PAR
   U25 BL21 MIB_PAR GENOA_SP5-SOCKET6096_13568-001,SMLF,IO,DGA^6000030   I159 @T6G_MB_LIB.T6G(SCH_1):PAGE18
   J18  227  PAR_B SCONN288_DDR506112002KQ-SCONN288_DDR506112002KQ,SMA    I22 @T6G_MB_LIB.T6G(SCH_1):PAGE93

M_I_CPU0_SB_RSP<0> @T6G_MB_LIB.T6G(SCH_1):M_I_CPU0_SB_RSP(0)
   U25 BP20 MIB0_RSP_L GENOA_SP5-SOCKET6096_13568-001,SMLF,IO,DGA^6000030   I159 @T6G_MB_LIB.T6G(SCH_1):PAGE18
   J18   87 LBS||RSP_B_N SCONN288_DDR506112002KQ-SCONN288_DDR506112002KQ,SMA    I22 @T6G_MB_LIB.T6G(SCH_1):PAGE93

M_I_CPU1_ALERT_N @T6G_MB_LIB.T6G(SCH_1):M_I_CPU1_ALERT_N
  R508    1      A Q_RES_0402LF-15,1%,1/16W,CHIP,CS01502FB03   I314 @T6G_MB_LIB.T6G(SCH_1):PAGE45
  J100   62 ALERT_N SCONN288_DDR506112002KQ-SCONN288_DDR506112002KQ,SMA    I22 @T6G_MB_LIB.T6G(SCH_1):PAGE105

M_I_CPU1_ALERT_R_N @T6G_MB_LIB.T6G(SCH_1):M_I_CPU1_ALERT_R_N
   U26 AT21 MI_ALERT_L GENOA_SP5-SOCKET6096_13568-001,SMLF,IO,DGA^6000030   I159 @T6G_MB_LIB.T6G(SCH_1):PAGE45
  R508    2      B Q_RES_0402LF-15,1%,1/16W,CHIP,CS01502FB03   I314 @T6G_MB_LIB.T6G(SCH_1):PAGE45

M_I_CPU1_CLK_DN<0> @T6G_MB_LIB.T6G(SCH_1):M_I_CPU1_CLK_DN(0)
   U26 BD20 MI0_CLK_L GENOA_SP5-SOCKET6096_13568-001,SMLF,IO,DGA^6000030   I159 @T6G_MB_LIB.T6G(SCH_1):PAGE45
  J100  218   CK_C SCONN288_DDR506112002KQ-SCONN288_DDR506112002KQ,SMA    I22 @T6G_MB_LIB.T6G(SCH_1):PAGE105

M_I_CPU1_CLK_DP<0> @T6G_MB_LIB.T6G(SCH_1):M_I_CPU1_CLK_DP(0)
   U26 BC19 MI0_CLK_H GENOA_SP5-SOCKET6096_13568-001,SMLF,IO,DGA^6000030   I159 @T6G_MB_LIB.T6G(SCH_1):PAGE45
  J100  217   CK_T SCONN288_DDR506112002KQ-SCONN288_DDR506112002KQ,SMA    I22 @T6G_MB_LIB.T6G(SCH_1):PAGE105

M_I_CPU1_RESET_N @T6G_MB_LIB.T6G(SCH_1):M_I_CPU1_RESET_N
   U26 AU21 MI_RESET_L GENOA_SP5-SOCKET6096_13568-001,SMLF,IO,DGA^6000030   I159 @T6G_MB_LIB.T6G(SCH_1):PAGE45
  J100  207 RESET_N SCONN288_DDR506112002KQ-SCONN288_DDR506112002KQ,SMA    I22 @T6G_MB_LIB.T6G(SCH_1):PAGE105

M_I_CPU1_SA_CA<0> @T6G_MB_LIB.T6G(SCH_1):M_I_CPU1_SA_CA(0)
   U26 AW19 MIA_CA0 GENOA_SP5-SOCKET6096_13568-001,SMLF,IO,DGA^6000030   I159 @T6G_MB_LIB.T6G(SCH_1):PAGE45
  J100   66  CA0_A SCONN288_DDR506112002KQ-SCONN288_DDR506112002KQ,SMA    I22 @T6G_MB_LIB.T6G(SCH_1):PAGE105

M_I_CPU1_SA_CA<1> @T6G_MB_LIB.T6G(SCH_1):M_I_CPU1_SA_CA(1)
   U26 AY20 MIA_CA1 GENOA_SP5-SOCKET6096_13568-001,SMLF,IO,DGA^6000030   I159 @T6G_MB_LIB.T6G(SCH_1):PAGE45
  J100  211  CA1_A SCONN288_DDR506112002KQ-SCONN288_DDR506112002KQ,SMA    I22 @T6G_MB_LIB.T6G(SCH_1):PAGE105

M_I_CPU1_SA_CA<2> @T6G_MB_LIB.T6G(SCH_1):M_I_CPU1_SA_CA(2)
   U26 AY21 MIA_CA2 GENOA_SP5-SOCKET6096_13568-001,SMLF,IO,DGA^6000030   I159 @T6G_MB_LIB.T6G(SCH_1):PAGE45
  J100   68  CA2_A SCONN288_DDR506112002KQ-SCONN288_DDR506112002KQ,SMA    I22 @T6G_MB_LIB.T6G(SCH_1):PAGE105

M_I_CPU1_SA_CA<3> @T6G_MB_LIB.T6G(SCH_1):M_I_CPU1_SA_CA(3)
   U26 BA21 MIA_CA3 GENOA_SP5-SOCKET6096_13568-001,SMLF,IO,DGA^6000030   I159 @T6G_MB_LIB.T6G(SCH_1):PAGE45
  J100  213  CA3_A SCONN288_DDR506112002KQ-SCONN288_DDR506112002KQ,SMA    I22 @T6G_MB_LIB.T6G(SCH_1):PAGE105

M_I_CPU1_SA_CA<4> @T6G_MB_LIB.T6G(SCH_1):M_I_CPU1_SA_CA(4)
   U26 BA19 MIA_CA4 GENOA_SP5-SOCKET6096_13568-001,SMLF,IO,DGA^6000030   I159 @T6G_MB_LIB.T6G(SCH_1):PAGE45
  J100   70  CA4_A SCONN288_DDR506112002KQ-SCONN288_DDR506112002KQ,SMA    I22 @T6G_MB_LIB.T6G(SCH_1):PAGE105

M_I_CPU1_SA_CA<5> @T6G_MB_LIB.T6G(SCH_1):M_I_CPU1_SA_CA(5)
   U26 BB20 MIA_CA5 GENOA_SP5-SOCKET6096_13568-001,SMLF,IO,DGA^6000030   I159 @T6G_MB_LIB.T6G(SCH_1):PAGE45
  J100  215  CA5_A SCONN288_DDR506112002KQ-SCONN288_DDR506112002KQ,SMA    I22 @T6G_MB_LIB.T6G(SCH_1):PAGE105

M_I_CPU1_SA_CA<6> @T6G_MB_LIB.T6G(SCH_1):M_I_CPU1_SA_CA(6)
   U26 BB21 MIA_CA6 GENOA_SP5-SOCKET6096_13568-001,SMLF,IO,DGA^6000030   I159 @T6G_MB_LIB.T6G(SCH_1):PAGE45
  J100   72  CA6_A SCONN288_DDR506112002KQ-SCONN288_DDR506112002KQ,SMA    I22 @T6G_MB_LIB.T6G(SCH_1):PAGE105

M_I_CPU1_SA_CB<0> @T6G_MB_LIB.T6G(SCH_1):M_I_CPU1_SA_CB(0)
   U26 AJ19 MIA_CHECK0 GENOA_SP5-SOCKET6096_13568-001,SMLF,IO,DGA^6000030   I159 @T6G_MB_LIB.T6G(SCH_1):PAGE45
  J100   51  CB0_A SCONN288_DDR506112002KQ-SCONN288_DDR506112002KQ,SMA    I22 @T6G_MB_LIB.T6G(SCH_1):PAGE105

M_I_CPU1_SA_CB<1> @T6G_MB_LIB.T6G(SCH_1):M_I_CPU1_SA_CB(1)
   U26 AK21 MIA_CHECK1 GENOA_SP5-SOCKET6096_13568-001,SMLF,IO,DGA^6000030   I159 @T6G_MB_LIB.T6G(SCH_1):PAGE45
  J100   53  CB1_A SCONN288_DDR506112002KQ-SCONN288_DDR506112002KQ,SMA    I22 @T6G_MB_LIB.T6G(SCH_1):PAGE105

M_I_CPU1_SA_CB<2> @T6G_MB_LIB.T6G(SCH_1):M_I_CPU1_SA_CB(2)
   U26 AK20 MIA_CHECK2 GENOA_SP5-SOCKET6096_13568-001,SMLF,IO,DGA^6000030   I159 @T6G_MB_LIB.T6G(SCH_1):PAGE45
  J100  196  CB2_A SCONN288_DDR506112002KQ-SCONN288_DDR506112002KQ,SMA    I22 @T6G_MB_LIB.T6G(SCH_1):PAGE105

M_I_CPU1_SA_CB<3> @T6G_MB_LIB.T6G(SCH_1):M_I_CPU1_SA_CB(3)
   U26 AL21 MIA_CHECK3 GENOA_SP5-SOCKET6096_13568-001,SMLF,IO,DGA^6000030   I159 @T6G_MB_LIB.T6G(SCH_1):PAGE45
  J100  198  CB3_A SCONN288_DDR506112002KQ-SCONN288_DDR506112002KQ,SMA    I22 @T6G_MB_LIB.T6G(SCH_1):PAGE105

M_I_CPU1_SA_CB<4> @T6G_MB_LIB.T6G(SCH_1):M_I_CPU1_SA_CB(4)
   U26 AN19 MIA_CHECK4 GENOA_SP5-SOCKET6096_13568-001,SMLF,IO,DGA^6000030   I159 @T6G_MB_LIB.T6G(SCH_1):PAGE45
  J100   58  CB4_A SCONN288_DDR506112002KQ-SCONN288_DDR506112002KQ,SMA    I22 @T6G_MB_LIB.T6G(SCH_1):PAGE105

M_I_CPU1_SA_CB<5> @T6G_MB_LIB.T6G(SCH_1):M_I_CPU1_SA_CB(5)
   U26 AP21 MIA_CHECK5 GENOA_SP5-SOCKET6096_13568-001,SMLF,IO,DGA^6000030   I159 @T6G_MB_LIB.T6G(SCH_1):PAGE45
  J100   60  CB5_A SCONN288_DDR506112002KQ-SCONN288_DDR506112002KQ,SMA    I22 @T6G_MB_LIB.T6G(SCH_1):PAGE105

M_I_CPU1_SA_CB<6> @T6G_MB_LIB.T6G(SCH_1):M_I_CPU1_SA_CB(6)
   U26 AP20 MIA_CHECK6 GENOA_SP5-SOCKET6096_13568-001,SMLF,IO,DGA^6000030   I159 @T6G_MB_LIB.T6G(SCH_1):PAGE45
  J100  203  CB6_A SCONN288_DDR506112002KQ-SCONN288_DDR506112002KQ,SMA    I22 @T6G_MB_LIB.T6G(SCH_1):PAGE105

M_I_CPU1_SA_CB<7> @T6G_MB_LIB.T6G(SCH_1):M_I_CPU1_SA_CB(7)
   U26 AR21 MIA_CHECK7 GENOA_SP5-SOCKET6096_13568-001,SMLF,IO,DGA^6000030   I159 @T6G_MB_LIB.T6G(SCH_1):PAGE45
  J100  205  CB7_A SCONN288_DDR506112002KQ-SCONN288_DDR506112002KQ,SMA    I22 @T6G_MB_LIB.T6G(SCH_1):PAGE105

M_I_CPU1_SA_CS_N<0> @T6G_MB_LIB.T6G(SCH_1):M_I_CPU1_SA_CS_N(0)
   U26 AU19 MIA0_CS_L0 GENOA_SP5-SOCKET6096_13568-001,SMLF,IO,DGA^6000030   I159 @T6G_MB_LIB.T6G(SCH_1):PAGE45
  J100   64 CS0_A_N SCONN288_DDR506112002KQ-SCONN288_DDR506112002KQ,SMA    I22 @T6G_MB_LIB.T6G(SCH_1):PAGE105

M_I_CPU1_SA_CS_N<1> @T6G_MB_LIB.T6G(SCH_1):M_I_CPU1_SA_CS_N(1)
   U26 AV21 MIA0_CS_L1 GENOA_SP5-SOCKET6096_13568-001,SMLF,IO,DGA^6000030   I159 @T6G_MB_LIB.T6G(SCH_1):PAGE45
  J100  209 CS1_A_N SCONN288_DDR506112002KQ-SCONN288_DDR506112002KQ,SMA    I22 @T6G_MB_LIB.T6G(SCH_1):PAGE105

M_I_CPU1_SA_DQ<0> @T6G_MB_LIB.T6G(SCH_1):M_I_CPU1_SA_DQ(0)
   U26  E19 MIA_DATA0 GENOA_SP5-SOCKET6096_13568-001,SMLF,IO,DGA^6000030   I159 @T6G_MB_LIB.T6G(SCH_1):PAGE45
  J100    7  DQ0_A SCONN288_DDR506112002KQ-SCONN288_DDR506112002KQ,SMA    I22 @T6G_MB_LIB.T6G(SCH_1):PAGE105

M_I_CPU1_SA_DQ<10> @T6G_MB_LIB.T6G(SCH_1):M_I_CPU1_SA_DQ(10)
   U26  M20 MIA_DATA10 GENOA_SP5-SOCKET6096_13568-001,SMLF,IO,DGA^6000030   I159 @T6G_MB_LIB.T6G(SCH_1):PAGE45
  J100  163 DQ10_A SCONN288_DDR506112002KQ-SCONN288_DDR506112002KQ,SMA    I22 @T6G_MB_LIB.T6G(SCH_1):PAGE105

M_I_CPU1_SA_DQ<11> @T6G_MB_LIB.T6G(SCH_1):M_I_CPU1_SA_DQ(11)
   U26  N21 MIA_DATA11 GENOA_SP5-SOCKET6096_13568-001,SMLF,IO,DGA^6000030   I159 @T6G_MB_LIB.T6G(SCH_1):PAGE45
  J100  165 DQ11_A SCONN288_DDR506112002KQ-SCONN288_DDR506112002KQ,SMA    I22 @T6G_MB_LIB.T6G(SCH_1):PAGE105

M_I_CPU1_SA_DQ<12> @T6G_MB_LIB.T6G(SCH_1):M_I_CPU1_SA_DQ(12)
   U26  R19 MIA_DATA12 GENOA_SP5-SOCKET6096_13568-001,SMLF,IO,DGA^6000030   I159 @T6G_MB_LIB.T6G(SCH_1):PAGE45
  J100   25 DQ12_A SCONN288_DDR506112002KQ-SCONN288_DDR506112002KQ,SMA    I22 @T6G_MB_LIB.T6G(SCH_1):PAGE105

M_I_CPU1_SA_DQ<13> @T6G_MB_LIB.T6G(SCH_1):M_I_CPU1_SA_DQ(13)
   U26  T21 MIA_DATA13 GENOA_SP5-SOCKET6096_13568-001,SMLF,IO,DGA^6000030   I159 @T6G_MB_LIB.T6G(SCH_1):PAGE45
  J100   27 DQ13_A SCONN288_DDR506112002KQ-SCONN288_DDR506112002KQ,SMA    I22 @T6G_MB_LIB.T6G(SCH_1):PAGE105

M_I_CPU1_SA_DQ<14> @T6G_MB_LIB.T6G(SCH_1):M_I_CPU1_SA_DQ(14)
   U26  T20 MIA_DATA14 GENOA_SP5-SOCKET6096_13568-001,SMLF,IO,DGA^6000030   I159 @T6G_MB_LIB.T6G(SCH_1):PAGE45
  J100  170 DQ14_A SCONN288_DDR506112002KQ-SCONN288_DDR506112002KQ,SMA    I22 @T6G_MB_LIB.T6G(SCH_1):PAGE105

M_I_CPU1_SA_DQ<15> @T6G_MB_LIB.T6G(SCH_1):M_I_CPU1_SA_DQ(15)
   U26  U21 MIA_DATA15 GENOA_SP5-SOCKET6096_13568-001,SMLF,IO,DGA^6000030   I159 @T6G_MB_LIB.T6G(SCH_1):PAGE45
  J100  172 DQ15_A SCONN288_DDR506112002KQ-SCONN288_DDR506112002KQ,SMA    I22 @T6G_MB_LIB.T6G(SCH_1):PAGE105

M_I_CPU1_SA_DQ<16> @T6G_MB_LIB.T6G(SCH_1):M_I_CPU1_SA_DQ(16)
   U26  U19 MIA_DATA16 GENOA_SP5-SOCKET6096_13568-001,SMLF,IO,DGA^6000030   I159 @T6G_MB_LIB.T6G(SCH_1):PAGE45
  J100   29 DQ16_A SCONN288_DDR506112002KQ-SCONN288_DDR506112002KQ,SMA    I22 @T6G_MB_LIB.T6G(SCH_1):PAGE105

M_I_CPU1_SA_DQ<17> @T6G_MB_LIB.T6G(SCH_1):M_I_CPU1_SA_DQ(17)
   U26  V21 MIA_DATA17 GENOA_SP5-SOCKET6096_13568-001,SMLF,IO,DGA^6000030   I159 @T6G_MB_LIB.T6G(SCH_1):PAGE45
  J100   31 DQ17_A SCONN288_DDR506112002KQ-SCONN288_DDR506112002KQ,SMA    I22 @T6G_MB_LIB.T6G(SCH_1):PAGE105

M_I_CPU1_SA_DQ<18> @T6G_MB_LIB.T6G(SCH_1):M_I_CPU1_SA_DQ(18)
   U26  V20 MIA_DATA18 GENOA_SP5-SOCKET6096_13568-001,SMLF,IO,DGA^6000030   I159 @T6G_MB_LIB.T6G(SCH_1):PAGE45
  J100  174 DQ18_A SCONN288_DDR506112002KQ-SCONN288_DDR506112002KQ,SMA    I22 @T6G_MB_LIB.T6G(SCH_1):PAGE105

M_I_CPU1_SA_DQ<19> @T6G_MB_LIB.T6G(SCH_1):M_I_CPU1_SA_DQ(19)
   U26  W21 MIA_DATA19 GENOA_SP5-SOCKET6096_13568-001,SMLF,IO,DGA^6000030   I159 @T6G_MB_LIB.T6G(SCH_1):PAGE45
  J100  176 DQ19_A SCONN288_DDR506112002KQ-SCONN288_DDR506112002KQ,SMA    I22 @T6G_MB_LIB.T6G(SCH_1):PAGE105

M_I_CPU1_SA_DQ<1> @T6G_MB_LIB.T6G(SCH_1):M_I_CPU1_SA_DQ(1)
   U26  F21 MIA_DATA1 GENOA_SP5-SOCKET6096_13568-001,SMLF,IO,DGA^6000030   I159 @T6G_MB_LIB.T6G(SCH_1):PAGE45
  J100    9  DQ1_A SCONN288_DDR506112002KQ-SCONN288_DDR506112002KQ,SMA    I22 @T6G_MB_LIB.T6G(SCH_1):PAGE105

M_I_CPU1_SA_DQ<20> @T6G_MB_LIB.T6G(SCH_1):M_I_CPU1_SA_DQ(20)
   U26 AA19 MIA_DATA20 GENOA_SP5-SOCKET6096_13568-001,SMLF,IO,DGA^6000030   I159 @T6G_MB_LIB.T6G(SCH_1):PAGE45
  J100   36 DQ20_A SCONN288_DDR506112002KQ-SCONN288_DDR506112002KQ,SMA    I22 @T6G_MB_LIB.T6G(SCH_1):PAGE105

M_I_CPU1_SA_DQ<21> @T6G_MB_LIB.T6G(SCH_1):M_I_CPU1_SA_DQ(21)
   U26 AB21 MIA_DATA21 GENOA_SP5-SOCKET6096_13568-001,SMLF,IO,DGA^6000030   I159 @T6G_MB_LIB.T6G(SCH_1):PAGE45
  J100   38 DQ21_A SCONN288_DDR506112002KQ-SCONN288_DDR506112002KQ,SMA    I22 @T6G_MB_LIB.T6G(SCH_1):PAGE105

M_I_CPU1_SA_DQ<22> @T6G_MB_LIB.T6G(SCH_1):M_I_CPU1_SA_DQ(22)
   U26 AB20 MIA_DATA22 GENOA_SP5-SOCKET6096_13568-001,SMLF,IO,DGA^6000030   I159 @T6G_MB_LIB.T6G(SCH_1):PAGE45
  J100  181 DQ22_A SCONN288_DDR506112002KQ-SCONN288_DDR506112002KQ,SMA    I22 @T6G_MB_LIB.T6G(SCH_1):PAGE105

M_I_CPU1_SA_DQ<23> @T6G_MB_LIB.T6G(SCH_1):M_I_CPU1_SA_DQ(23)
   U26 AC21 MIA_DATA23 GENOA_SP5-SOCKET6096_13568-001,SMLF,IO,DGA^6000030   I159 @T6G_MB_LIB.T6G(SCH_1):PAGE45
  J100  183 DQ23_A SCONN288_DDR506112002KQ-SCONN288_DDR506112002KQ,SMA    I22 @T6G_MB_LIB.T6G(SCH_1):PAGE105

M_I_CPU1_SA_DQ<24> @T6G_MB_LIB.T6G(SCH_1):M_I_CPU1_SA_DQ(24)
   U26 AC19 MIA_DATA24 GENOA_SP5-SOCKET6096_13568-001,SMLF,IO,DGA^6000030   I159 @T6G_MB_LIB.T6G(SCH_1):PAGE45
  J100   40 DQ24_A SCONN288_DDR506112002KQ-SCONN288_DDR506112002KQ,SMA    I22 @T6G_MB_LIB.T6G(SCH_1):PAGE105

M_I_CPU1_SA_DQ<25> @T6G_MB_LIB.T6G(SCH_1):M_I_CPU1_SA_DQ(25)
   U26 AD21 MIA_DATA25 GENOA_SP5-SOCKET6096_13568-001,SMLF,IO,DGA^6000030   I159 @T6G_MB_LIB.T6G(SCH_1):PAGE45
  J100   42 DQ25_A SCONN288_DDR506112002KQ-SCONN288_DDR506112002KQ,SMA    I22 @T6G_MB_LIB.T6G(SCH_1):PAGE105

M_I_CPU1_SA_DQ<26> @T6G_MB_LIB.T6G(SCH_1):M_I_CPU1_SA_DQ(26)
   U26 AD20 MIA_DATA26 GENOA_SP5-SOCKET6096_13568-001,SMLF,IO,DGA^6000030   I159 @T6G_MB_LIB.T6G(SCH_1):PAGE45
  J100  185 DQ26_A SCONN288_DDR506112002KQ-SCONN288_DDR506112002KQ,SMA    I22 @T6G_MB_LIB.T6G(SCH_1):PAGE105

M_I_CPU1_SA_DQ<27> @T6G_MB_LIB.T6G(SCH_1):M_I_CPU1_SA_DQ(27)
   U26 AE21 MIA_DATA27 GENOA_SP5-SOCKET6096_13568-001,SMLF,IO,DGA^6000030   I159 @T6G_MB_LIB.T6G(SCH_1):PAGE45
  J100  187 DQ27_A SCONN288_DDR506112002KQ-SCONN288_DDR506112002KQ,SMA    I22 @T6G_MB_LIB.T6G(SCH_1):PAGE105

M_I_CPU1_SA_DQ<28> @T6G_MB_LIB.T6G(SCH_1):M_I_CPU1_SA_DQ(28)
   U26 AG19 MIA_DATA28 GENOA_SP5-SOCKET6096_13568-001,SMLF,IO,DGA^6000030   I159 @T6G_MB_LIB.T6G(SCH_1):PAGE45
  J100   47 DQ28_A SCONN288_DDR506112002KQ-SCONN288_DDR506112002KQ,SMA    I22 @T6G_MB_LIB.T6G(SCH_1):PAGE105

M_I_CPU1_SA_DQ<29> @T6G_MB_LIB.T6G(SCH_1):M_I_CPU1_SA_DQ(29)
   U26 AH21 MIA_DATA29 GENOA_SP5-SOCKET6096_13568-001,SMLF,IO,DGA^6000030   I159 @T6G_MB_LIB.T6G(SCH_1):PAGE45
  J100   49 DQ29_A SCONN288_DDR506112002KQ-SCONN288_DDR506112002KQ,SMA    I22 @T6G_MB_LIB.T6G(SCH_1):PAGE105

M_I_CPU1_SA_DQ<2> @T6G_MB_LIB.T6G(SCH_1):M_I_CPU1_SA_DQ(2)
   U26  F20 MIA_DATA2 GENOA_SP5-SOCKET6096_13568-001,SMLF,IO,DGA^6000030   I159 @T6G_MB_LIB.T6G(SCH_1):PAGE45
  J100  152  DQ2_A SCONN288_DDR506112002KQ-SCONN288_DDR506112002KQ,SMA    I22 @T6G_MB_LIB.T6G(SCH_1):PAGE105

M_I_CPU1_SA_DQ<30> @T6G_MB_LIB.T6G(SCH_1):M_I_CPU1_SA_DQ(30)
   U26 AH20 MIA_DATA30 GENOA_SP5-SOCKET6096_13568-001,SMLF,IO,DGA^6000030   I159 @T6G_MB_LIB.T6G(SCH_1):PAGE45
  J100  192 DQ30_A SCONN288_DDR506112002KQ-SCONN288_DDR506112002KQ,SMA    I22 @T6G_MB_LIB.T6G(SCH_1):PAGE105

M_I_CPU1_SA_DQ<31> @T6G_MB_LIB.T6G(SCH_1):M_I_CPU1_SA_DQ(31)
   U26 AJ21 MIA_DATA31 GENOA_SP5-SOCKET6096_13568-001,SMLF,IO,DGA^6000030   I159 @T6G_MB_LIB.T6G(SCH_1):PAGE45
  J100  194 DQ31_A SCONN288_DDR506112002KQ-SCONN288_DDR506112002KQ,SMA    I22 @T6G_MB_LIB.T6G(SCH_1):PAGE105

M_I_CPU1_SA_DQ<3> @T6G_MB_LIB.T6G(SCH_1):M_I_CPU1_SA_DQ(3)
   U26  G21 MIA_DATA3 GENOA_SP5-SOCKET6096_13568-001,SMLF,IO,DGA^6000030   I159 @T6G_MB_LIB.T6G(SCH_1):PAGE45
  J100  154  DQ3_A SCONN288_DDR506112002KQ-SCONN288_DDR506112002KQ,SMA    I22 @T6G_MB_LIB.T6G(SCH_1):PAGE105

M_I_CPU1_SA_DQ<4> @T6G_MB_LIB.T6G(SCH_1):M_I_CPU1_SA_DQ(4)
   U26  J19 MIA_DATA4 GENOA_SP5-SOCKET6096_13568-001,SMLF,IO,DGA^6000030   I159 @T6G_MB_LIB.T6G(SCH_1):PAGE45
  J100   14  DQ4_A SCONN288_DDR506112002KQ-SCONN288_DDR506112002KQ,SMA    I22 @T6G_MB_LIB.T6G(SCH_1):PAGE105

M_I_CPU1_SA_DQ<5> @T6G_MB_LIB.T6G(SCH_1):M_I_CPU1_SA_DQ(5)
   U26  K21 MIA_DATA5 GENOA_SP5-SOCKET6096_13568-001,SMLF,IO,DGA^6000030   I159 @T6G_MB_LIB.T6G(SCH_1):PAGE45
  J100   16  DQ5_A SCONN288_DDR506112002KQ-SCONN288_DDR506112002KQ,SMA    I22 @T6G_MB_LIB.T6G(SCH_1):PAGE105

M_I_CPU1_SA_DQ<6> @T6G_MB_LIB.T6G(SCH_1):M_I_CPU1_SA_DQ(6)
   U26  K20 MIA_DATA6 GENOA_SP5-SOCKET6096_13568-001,SMLF,IO,DGA^6000030   I159 @T6G_MB_LIB.T6G(SCH_1):PAGE45
  J100  159  DQ6_A SCONN288_DDR506112002KQ-SCONN288_DDR506112002KQ,SMA    I22 @T6G_MB_LIB.T6G(SCH_1):PAGE105

M_I_CPU1_SA_DQ<7> @T6G_MB_LIB.T6G(SCH_1):M_I_CPU1_SA_DQ(7)
   U26  L21 MIA_DATA7 GENOA_SP5-SOCKET6096_13568-001,SMLF,IO,DGA^6000030   I159 @T6G_MB_LIB.T6G(SCH_1):PAGE45
  J100  161  DQ7_A SCONN288_DDR506112002KQ-SCONN288_DDR506112002KQ,SMA    I22 @T6G_MB_LIB.T6G(SCH_1):PAGE105

M_I_CPU1_SA_DQ<8> @T6G_MB_LIB.T6G(SCH_1):M_I_CPU1_SA_DQ(8)
   U26  L19 MIA_DATA8 GENOA_SP5-SOCKET6096_13568-001,SMLF,IO,DGA^6000030   I159 @T6G_MB_LIB.T6G(SCH_1):PAGE45
  J100   18  DQ8_A SCONN288_DDR506112002KQ-SCONN288_DDR506112002KQ,SMA    I22 @T6G_MB_LIB.T6G(SCH_1):PAGE105

M_I_CPU1_SA_DQ<9> @T6G_MB_LIB.T6G(SCH_1):M_I_CPU1_SA_DQ(9)
   U26  M21 MIA_DATA9 GENOA_SP5-SOCKET6096_13568-001,SMLF,IO,DGA^6000030   I159 @T6G_MB_LIB.T6G(SCH_1):PAGE45
  J100   20  DQ9_A SCONN288_DDR506112002KQ-SCONN288_DDR506112002KQ,SMA    I22 @T6G_MB_LIB.T6G(SCH_1):PAGE105

M_I_CPU1_SA_DQS_DN<0> @T6G_MB_LIB.T6G(SCH_1):M_I_CPU1_SA_DQS_DN(0)
   U26  H20 MIA_DQS_L0 GENOA_SP5-SOCKET6096_13568-001,SMLF,IO,DGA^6000030   I159 @T6G_MB_LIB.T6G(SCH_1):PAGE45
  J100   12 DQS0_A_C SCONN288_DDR506112002KQ-SCONN288_DDR506112002KQ,SMA   I236 @T6G_MB_LIB.T6G(SCH_1):PAGE105

M_I_CPU1_SA_DQS_DN<1> @T6G_MB_LIB.T6G(SCH_1):M_I_CPU1_SA_DQS_DN(1)
   U26  P20 MIA_DQS_L1 GENOA_SP5-SOCKET6096_13568-001,SMLF,IO,DGA^6000030   I159 @T6G_MB_LIB.T6G(SCH_1):PAGE45
  J100   23 DQS1_A_C SCONN288_DDR506112002KQ-SCONN288_DDR506112002KQ,SMA   I236 @T6G_MB_LIB.T6G(SCH_1):PAGE105

M_I_CPU1_SA_DQS_DN<2> @T6G_MB_LIB.T6G(SCH_1):M_I_CPU1_SA_DQS_DN(2)
   U26  Y20 MIA_DQS_L2 GENOA_SP5-SOCKET6096_13568-001,SMLF,IO,DGA^6000030   I159 @T6G_MB_LIB.T6G(SCH_1):PAGE45
  J100   34 DQS2_A_C SCONN288_DDR506112002KQ-SCONN288_DDR506112002KQ,SMA   I236 @T6G_MB_LIB.T6G(SCH_1):PAGE105

M_I_CPU1_SA_DQS_DN<3> @T6G_MB_LIB.T6G(SCH_1):M_I_CPU1_SA_DQS_DN(3)
   U26 AF20 MIA_DQS_L3 GENOA_SP5-SOCKET6096_13568-001,SMLF,IO,DGA^6000030   I159 @T6G_MB_LIB.T6G(SCH_1):PAGE45
  J100   45 DQS3_A_C SCONN288_DDR506112002KQ-SCONN288_DDR506112002KQ,SMA   I236 @T6G_MB_LIB.T6G(SCH_1):PAGE105

M_I_CPU1_SA_DQS_DN<4> @T6G_MB_LIB.T6G(SCH_1):M_I_CPU1_SA_DQS_DN(4)
   U26 AM20 MIA_DQS_L4 GENOA_SP5-SOCKET6096_13568-001,SMLF,IO,DGA^6000030   I159 @T6G_MB_LIB.T6G(SCH_1):PAGE45
  J100   56 DQS4_A_C SCONN288_DDR506112002KQ-SCONN288_DDR506112002KQ,SMA   I236 @T6G_MB_LIB.T6G(SCH_1):PAGE105

M_I_CPU1_SA_DQS_DN<5> @T6G_MB_LIB.T6G(SCH_1):M_I_CPU1_SA_DQS_DN(5)
   U26  H21 MIA_DQS_L5 GENOA_SP5-SOCKET6096_13568-001,SMLF,IO,DGA^6000030   I159 @T6G_MB_LIB.T6G(SCH_1):PAGE45
  J100  156 DQS5_A_C||TDQS5_A_C||DQS5_A_T||TDQS5_A_T SCONN288_DDR506112002KQ-SCONN288_DDR506112002KQ,SMA   I236 @T6G_MB_LIB.T6G(SCH_1):PAGE105

M_I_CPU1_SA_DQS_DN<6> @T6G_MB_LIB.T6G(SCH_1):M_I_CPU1_SA_DQS_DN(6)
   U26  P21 MIA_DQS_L6 GENOA_SP5-SOCKET6096_13568-001,SMLF,IO,DGA^6000030   I159 @T6G_MB_LIB.T6G(SCH_1):PAGE45
  J100  167 DQS6_A_C||TDQS6_A_C||DQS6_A_T||TDQS6_A_T SCONN288_DDR506112002KQ-SCONN288_DDR506112002KQ,SMA   I236 @T6G_MB_LIB.T6G(SCH_1):PAGE105

M_I_CPU1_SA_DQS_DN<7> @T6G_MB_LIB.T6G(SCH_1):M_I_CPU1_SA_DQS_DN(7)
   U26  Y21 MIA_DQS_L7 GENOA_SP5-SOCKET6096_13568-001,SMLF,IO,DGA^6000030   I159 @T6G_MB_LIB.T6G(SCH_1):PAGE45
  J100  178 DQS7_A_C||TDQS7_A_C SCONN288_DDR506112002KQ-SCONN288_DDR506112002KQ,SMA   I236 @T6G_MB_LIB.T6G(SCH_1):PAGE105

M_I_CPU1_SA_DQS_DN<8> @T6G_MB_LIB.T6G(SCH_1):M_I_CPU1_SA_DQS_DN(8)
   U26 AF21 MIA_DQS_L8 GENOA_SP5-SOCKET6096_13568-001,SMLF,IO,DGA^6000030   I159 @T6G_MB_LIB.T6G(SCH_1):PAGE45
  J100  189 DQS8_A_C||TDQS8_A_C SCONN288_DDR506112002KQ-SCONN288_DDR506112002KQ,SMA   I236 @T6G_MB_LIB.T6G(SCH_1):PAGE105

M_I_CPU1_SA_DQS_DN<9> @T6G_MB_LIB.T6G(SCH_1):M_I_CPU1_SA_DQS_DN(9)
   U26 AM21 MIA_DQS_L9 GENOA_SP5-SOCKET6096_13568-001,SMLF,IO,DGA^6000030   I159 @T6G_MB_LIB.T6G(SCH_1):PAGE45
  J100  200 DQS9_A_C||TDQS9_A_C SCONN288_DDR506112002KQ-SCONN288_DDR506112002KQ,SMA   I236 @T6G_MB_LIB.T6G(SCH_1):PAGE105

M_I_CPU1_SA_DQS_DP<0> @T6G_MB_LIB.T6G(SCH_1):M_I_CPU1_SA_DQS_DP(0)
   U26  G19 MIA_DQS_H0 GENOA_SP5-SOCKET6096_13568-001,SMLF,IO,DGA^6000030   I159 @T6G_MB_LIB.T6G(SCH_1):PAGE45
  J100   11 DQS0_A_T SCONN288_DDR506112002KQ-SCONN288_DDR506112002KQ,SMA   I236 @T6G_MB_LIB.T6G(SCH_1):PAGE105

M_I_CPU1_SA_DQS_DP<1> @T6G_MB_LIB.T6G(SCH_1):M_I_CPU1_SA_DQS_DP(1)
   U26  N19 MIA_DQS_H1 GENOA_SP5-SOCKET6096_13568-001,SMLF,IO,DGA^6000030   I159 @T6G_MB_LIB.T6G(SCH_1):PAGE45
  J100   22 DQS1_A_T SCONN288_DDR506112002KQ-SCONN288_DDR506112002KQ,SMA   I236 @T6G_MB_LIB.T6G(SCH_1):PAGE105

M_I_CPU1_SA_DQS_DP<2> @T6G_MB_LIB.T6G(SCH_1):M_I_CPU1_SA_DQS_DP(2)
   U26  W19 MIA_DQS_H2 GENOA_SP5-SOCKET6096_13568-001,SMLF,IO,DGA^6000030   I159 @T6G_MB_LIB.T6G(SCH_1):PAGE45
  J100   33 DQS2_A_T SCONN288_DDR506112002KQ-SCONN288_DDR506112002KQ,SMA   I236 @T6G_MB_LIB.T6G(SCH_1):PAGE105

M_I_CPU1_SA_DQS_DP<3> @T6G_MB_LIB.T6G(SCH_1):M_I_CPU1_SA_DQS_DP(3)
   U26 AE19 MIA_DQS_H3 GENOA_SP5-SOCKET6096_13568-001,SMLF,IO,DGA^6000030   I159 @T6G_MB_LIB.T6G(SCH_1):PAGE45
  J100   44 DQS3_A_T SCONN288_DDR506112002KQ-SCONN288_DDR506112002KQ,SMA   I236 @T6G_MB_LIB.T6G(SCH_1):PAGE105

M_I_CPU1_SA_DQS_DP<4> @T6G_MB_LIB.T6G(SCH_1):M_I_CPU1_SA_DQS_DP(4)
   U26 AL19 MIA_DQS_H4 GENOA_SP5-SOCKET6096_13568-001,SMLF,IO,DGA^6000030   I159 @T6G_MB_LIB.T6G(SCH_1):PAGE45
  J100   55 DQS4_A_T SCONN288_DDR506112002KQ-SCONN288_DDR506112002KQ,SMA   I236 @T6G_MB_LIB.T6G(SCH_1):PAGE105

M_I_CPU1_SA_DQS_DP<5> @T6G_MB_LIB.T6G(SCH_1):M_I_CPU1_SA_DQS_DP(5)
   U26  J21 MIA_DQS_H5 GENOA_SP5-SOCKET6096_13568-001,SMLF,IO,DGA^6000030   I159 @T6G_MB_LIB.T6G(SCH_1):PAGE45
  J100  157 DQS5_A_T||TDQS5_A_T SCONN288_DDR506112002KQ-SCONN288_DDR506112002KQ,SMA   I236 @T6G_MB_LIB.T6G(SCH_1):PAGE105

M_I_CPU1_SA_DQS_DP<6> @T6G_MB_LIB.T6G(SCH_1):M_I_CPU1_SA_DQS_DP(6)
   U26  R21 MIA_DQS_H6 GENOA_SP5-SOCKET6096_13568-001,SMLF,IO,DGA^6000030   I159 @T6G_MB_LIB.T6G(SCH_1):PAGE45
  J100  168 DQS6_A_T||TDQS6_A_T SCONN288_DDR506112002KQ-SCONN288_DDR506112002KQ,SMA   I236 @T6G_MB_LIB.T6G(SCH_1):PAGE105

M_I_CPU1_SA_DQS_DP<7> @T6G_MB_LIB.T6G(SCH_1):M_I_CPU1_SA_DQS_DP(7)
   U26 AA21 MIA_DQS_H7 GENOA_SP5-SOCKET6096_13568-001,SMLF,IO,DGA^6000030   I159 @T6G_MB_LIB.T6G(SCH_1):PAGE45
  J100  179 DQS7_A_T||TDQS7_A_T SCONN288_DDR506112002KQ-SCONN288_DDR506112002KQ,SMA   I236 @T6G_MB_LIB.T6G(SCH_1):PAGE105

M_I_CPU1_SA_DQS_DP<8> @T6G_MB_LIB.T6G(SCH_1):M_I_CPU1_SA_DQS_DP(8)
   U26 AG21 MIA_DQS_H8 GENOA_SP5-SOCKET6096_13568-001,SMLF,IO,DGA^6000030   I159 @T6G_MB_LIB.T6G(SCH_1):PAGE45
  J100  190 DQS8_A_T||TDQS8_A_T SCONN288_DDR506112002KQ-SCONN288_DDR506112002KQ,SMA   I236 @T6G_MB_LIB.T6G(SCH_1):PAGE105

M_I_CPU1_SA_DQS_DP<9> @T6G_MB_LIB.T6G(SCH_1):M_I_CPU1_SA_DQS_DP(9)
   U26 AN21 MIA_DQS_H9 GENOA_SP5-SOCKET6096_13568-001,SMLF,IO,DGA^6000030   I159 @T6G_MB_LIB.T6G(SCH_1):PAGE45
  J100  201 DQS9_A_T||TDQS9_A_T SCONN288_DDR506112002KQ-SCONN288_DDR506112002KQ,SMA   I236 @T6G_MB_LIB.T6G(SCH_1):PAGE105

M_I_CPU1_SA_PAR @T6G_MB_LIB.T6G(SCH_1):M_I_CPU1_SA_PAR
   U26 BC21 MIA_PAR GENOA_SP5-SOCKET6096_13568-001,SMLF,IO,DGA^6000030   I159 @T6G_MB_LIB.T6G(SCH_1):PAGE45
  J100   74  PAR_A SCONN288_DDR506112002KQ-SCONN288_DDR506112002KQ,SMA    I22 @T6G_MB_LIB.T6G(SCH_1):PAGE105

M_I_CPU1_SA_RSP<0> @T6G_MB_LIB.T6G(SCH_1):M_I_CPU1_SA_RSP(0)
   U26 BN21 MIA0_RSP_L GENOA_SP5-SOCKET6096_13568-001,SMLF,IO,DGA^6000030   I159 @T6G_MB_LIB.T6G(SCH_1):PAGE45
  J100   86 LBD||RSP_A_N SCONN288_DDR506112002KQ-SCONN288_DDR506112002KQ,SMA    I22 @T6G_MB_LIB.T6G(SCH_1):PAGE105

M_I_CPU1_SB_CA<0> @T6G_MB_LIB.T6G(SCH_1):M_I_CPU1_SB_CA(0)
   U26 BG21 MIB_CA0 GENOA_SP5-SOCKET6096_13568-001,SMLF,IO,DGA^6000030   I159 @T6G_MB_LIB.T6G(SCH_1):PAGE45
  J100   76  CA0_B SCONN288_DDR506112002KQ-SCONN288_DDR506112002KQ,SMA    I22 @T6G_MB_LIB.T6G(SCH_1):PAGE105

M_I_CPU1_SB_CA<1> @T6G_MB_LIB.T6G(SCH_1):M_I_CPU1_SB_CA(1)
   U26 BH21 MIB_CA1 GENOA_SP5-SOCKET6096_13568-001,SMLF,IO,DGA^6000030   I159 @T6G_MB_LIB.T6G(SCH_1):PAGE45
  J100  221  CA1_B SCONN288_DDR506112002KQ-SCONN288_DDR506112002KQ,SMA    I22 @T6G_MB_LIB.T6G(SCH_1):PAGE105

M_I_CPU1_SB_CA<2> @T6G_MB_LIB.T6G(SCH_1):M_I_CPU1_SB_CA(2)
   U26 BH20 MIB_CA2 GENOA_SP5-SOCKET6096_13568-001,SMLF,IO,DGA^6000030   I159 @T6G_MB_LIB.T6G(SCH_1):PAGE45
  J100   78  CA2_B SCONN288_DDR506112002KQ-SCONN288_DDR506112002KQ,SMA    I22 @T6G_MB_LIB.T6G(SCH_1):PAGE105

M_I_CPU1_SB_CA<3> @T6G_MB_LIB.T6G(SCH_1):M_I_CPU1_SB_CA(3)
   U26 BJ19 MIB_CA3 GENOA_SP5-SOCKET6096_13568-001,SMLF,IO,DGA^6000030   I159 @T6G_MB_LIB.T6G(SCH_1):PAGE45
  J100  223  CA3_B SCONN288_DDR506112002KQ-SCONN288_DDR506112002KQ,SMA    I22 @T6G_MB_LIB.T6G(SCH_1):PAGE105

M_I_CPU1_SB_CA<4> @T6G_MB_LIB.T6G(SCH_1):M_I_CPU1_SB_CA(4)
   U26 BJ21 MIB_CA4 GENOA_SP5-SOCKET6096_13568-001,SMLF,IO,DGA^6000030   I159 @T6G_MB_LIB.T6G(SCH_1):PAGE45
  J100   80  CA4_B SCONN288_DDR506112002KQ-SCONN288_DDR506112002KQ,SMA    I22 @T6G_MB_LIB.T6G(SCH_1):PAGE105

M_I_CPU1_SB_CA<5> @T6G_MB_LIB.T6G(SCH_1):M_I_CPU1_SB_CA(5)
   U26 BK21 MIB_CA5 GENOA_SP5-SOCKET6096_13568-001,SMLF,IO,DGA^6000030   I159 @T6G_MB_LIB.T6G(SCH_1):PAGE45
  J100  225  CA5_B SCONN288_DDR506112002KQ-SCONN288_DDR506112002KQ,SMA    I22 @T6G_MB_LIB.T6G(SCH_1):PAGE105

M_I_CPU1_SB_CA<6> @T6G_MB_LIB.T6G(SCH_1):M_I_CPU1_SB_CA(6)
   U26 BK20 MIB_CA6 GENOA_SP5-SOCKET6096_13568-001,SMLF,IO,DGA^6000030   I159 @T6G_MB_LIB.T6G(SCH_1):PAGE45
  J100   82  CA6_B SCONN288_DDR506112002KQ-SCONN288_DDR506112002KQ,SMA    I22 @T6G_MB_LIB.T6G(SCH_1):PAGE105

M_I_CPU1_SB_CB<0> @T6G_MB_LIB.T6G(SCH_1):M_I_CPU1_SB_CB(0)
   U26 BY20 MIB_CHECK0 GENOA_SP5-SOCKET6096_13568-001,SMLF,IO,DGA^6000030   I159 @T6G_MB_LIB.T6G(SCH_1):PAGE45
  J100   96  CB0_B SCONN288_DDR506112002KQ-SCONN288_DDR506112002KQ,SMA    I22 @T6G_MB_LIB.T6G(SCH_1):PAGE105

M_I_CPU1_SB_CB<1> @T6G_MB_LIB.T6G(SCH_1):M_I_CPU1_SB_CB(1)
   U26 CA21 MIB_CHECK1 GENOA_SP5-SOCKET6096_13568-001,SMLF,IO,DGA^6000030   I159 @T6G_MB_LIB.T6G(SCH_1):PAGE45
  J100   98  CB1_B SCONN288_DDR506112002KQ-SCONN288_DDR506112002KQ,SMA    I22 @T6G_MB_LIB.T6G(SCH_1):PAGE105

M_I_CPU1_SB_CB<2> @T6G_MB_LIB.T6G(SCH_1):M_I_CPU1_SB_CB(2)
   U26 CA19 MIB_CHECK2 GENOA_SP5-SOCKET6096_13568-001,SMLF,IO,DGA^6000030   I159 @T6G_MB_LIB.T6G(SCH_1):PAGE45
  J100  241  CB2_B SCONN288_DDR506112002KQ-SCONN288_DDR506112002KQ,SMA    I22 @T6G_MB_LIB.T6G(SCH_1):PAGE105

M_I_CPU1_SB_CB<3> @T6G_MB_LIB.T6G(SCH_1):M_I_CPU1_SB_CB(3)
   U26 CB21 MIB_CHECK3 GENOA_SP5-SOCKET6096_13568-001,SMLF,IO,DGA^6000030   I159 @T6G_MB_LIB.T6G(SCH_1):PAGE45
  J100  243  CB3_B SCONN288_DDR506112002KQ-SCONN288_DDR506112002KQ,SMA    I22 @T6G_MB_LIB.T6G(SCH_1):PAGE105

M_I_CPU1_SB_CB<4> @T6G_MB_LIB.T6G(SCH_1):M_I_CPU1_SB_CB(4)
   U26 BT20 MIB_CHECK4 GENOA_SP5-SOCKET6096_13568-001,SMLF,IO,DGA^6000030   I159 @T6G_MB_LIB.T6G(SCH_1):PAGE45
  J100   89  CB4_B SCONN288_DDR506112002KQ-SCONN288_DDR506112002KQ,SMA    I22 @T6G_MB_LIB.T6G(SCH_1):PAGE105

M_I_CPU1_SB_CB<5> @T6G_MB_LIB.T6G(SCH_1):M_I_CPU1_SB_CB(5)
   U26 BU21 MIB_CHECK5 GENOA_SP5-SOCKET6096_13568-001,SMLF,IO,DGA^6000030   I159 @T6G_MB_LIB.T6G(SCH_1):PAGE45
  J100   91  CB5_B SCONN288_DDR506112002KQ-SCONN288_DDR506112002KQ,SMA    I22 @T6G_MB_LIB.T6G(SCH_1):PAGE105

M_I_CPU1_SB_CB<6> @T6G_MB_LIB.T6G(SCH_1):M_I_CPU1_SB_CB(6)
   U26 BU19 MIB_CHECK6 GENOA_SP5-SOCKET6096_13568-001,SMLF,IO,DGA^6000030   I159 @T6G_MB_LIB.T6G(SCH_1):PAGE45
  J100  234  CB6_B SCONN288_DDR506112002KQ-SCONN288_DDR506112002KQ,SMA    I22 @T6G_MB_LIB.T6G(SCH_1):PAGE105

M_I_CPU1_SB_CB<7> @T6G_MB_LIB.T6G(SCH_1):M_I_CPU1_SB_CB(7)
   U26 BV21 MIB_CHECK7 GENOA_SP5-SOCKET6096_13568-001,SMLF,IO,DGA^6000030   I159 @T6G_MB_LIB.T6G(SCH_1):PAGE45
  J100  236  CB7_B SCONN288_DDR506112002KQ-SCONN288_DDR506112002KQ,SMA    I22 @T6G_MB_LIB.T6G(SCH_1):PAGE105

M_I_CPU1_SB_CS_N<0> @T6G_MB_LIB.T6G(SCH_1):M_I_CPU1_SB_CS_N(0)
   U26 BM21 MIB0_CS_L0 GENOA_SP5-SOCKET6096_13568-001,SMLF,IO,DGA^6000030   I159 @T6G_MB_LIB.T6G(SCH_1):PAGE45
  J100   84 CS0_B_N SCONN288_DDR506112002KQ-SCONN288_DDR506112002KQ,SMA    I22 @T6G_MB_LIB.T6G(SCH_1):PAGE105

M_I_CPU1_SB_CS_N<1> @T6G_MB_LIB.T6G(SCH_1):M_I_CPU1_SB_CS_N(1)
   U26 BN19 MIB0_CS_L1 GENOA_SP5-SOCKET6096_13568-001,SMLF,IO,DGA^6000030   I159 @T6G_MB_LIB.T6G(SCH_1):PAGE45
  J100  229 CS1_B_N SCONN288_DDR506112002KQ-SCONN288_DDR506112002KQ,SMA    I22 @T6G_MB_LIB.T6G(SCH_1):PAGE105

M_I_CPU1_SB_DQ<0> @T6G_MB_LIB.T6G(SCH_1):M_I_CPU1_SB_DQ(0)
   U26 CB20 MIB_DATA0 GENOA_SP5-SOCKET6096_13568-001,SMLF,IO,DGA^6000030   I159 @T6G_MB_LIB.T6G(SCH_1):PAGE45
  J100  100  DQ0_B SCONN288_DDR506112002KQ-SCONN288_DDR506112002KQ,SMA    I22 @T6G_MB_LIB.T6G(SCH_1):PAGE105

M_I_CPU1_SB_DQ<10> @T6G_MB_LIB.T6G(SCH_1):M_I_CPU1_SB_DQ(10)
   U26 CJ19 MIB_DATA10 GENOA_SP5-SOCKET6096_13568-001,SMLF,IO,DGA^6000030   I159 @T6G_MB_LIB.T6G(SCH_1):PAGE45
  J100  256 DQ10_B SCONN288_DDR506112002KQ-SCONN288_DDR506112002KQ,SMA    I22 @T6G_MB_LIB.T6G(SCH_1):PAGE105

M_I_CPU1_SB_DQ<11> @T6G_MB_LIB.T6G(SCH_1):M_I_CPU1_SB_DQ(11)
   U26 CK21 MIB_DATA11 GENOA_SP5-SOCKET6096_13568-001,SMLF,IO,DGA^6000030   I159 @T6G_MB_LIB.T6G(SCH_1):PAGE45
  J100  258 DQ11_B SCONN288_DDR506112002KQ-SCONN288_DDR506112002KQ,SMA    I22 @T6G_MB_LIB.T6G(SCH_1):PAGE105

M_I_CPU1_SB_DQ<12> @T6G_MB_LIB.T6G(SCH_1):M_I_CPU1_SB_DQ(12)
   U26 CM20 MIB_DATA12 GENOA_SP5-SOCKET6096_13568-001,SMLF,IO,DGA^6000030   I159 @T6G_MB_LIB.T6G(SCH_1):PAGE45
  J100  118 DQ12_B SCONN288_DDR506112002KQ-SCONN288_DDR506112002KQ,SMA    I22 @T6G_MB_LIB.T6G(SCH_1):PAGE105

M_I_CPU1_SB_DQ<13> @T6G_MB_LIB.T6G(SCH_1):M_I_CPU1_SB_DQ(13)
   U26 CN21 MIB_DATA13 GENOA_SP5-SOCKET6096_13568-001,SMLF,IO,DGA^6000030   I159 @T6G_MB_LIB.T6G(SCH_1):PAGE45
  J100  120 DQ13_B SCONN288_DDR506112002KQ-SCONN288_DDR506112002KQ,SMA    I22 @T6G_MB_LIB.T6G(SCH_1):PAGE105

M_I_CPU1_SB_DQ<14> @T6G_MB_LIB.T6G(SCH_1):M_I_CPU1_SB_DQ(14)
   U26 CN19 MIB_DATA14 GENOA_SP5-SOCKET6096_13568-001,SMLF,IO,DGA^6000030   I159 @T6G_MB_LIB.T6G(SCH_1):PAGE45
  J100  263 DQ14_B SCONN288_DDR506112002KQ-SCONN288_DDR506112002KQ,SMA    I22 @T6G_MB_LIB.T6G(SCH_1):PAGE105

M_I_CPU1_SB_DQ<15> @T6G_MB_LIB.T6G(SCH_1):M_I_CPU1_SB_DQ(15)
   U26 CP21 MIB_DATA15 GENOA_SP5-SOCKET6096_13568-001,SMLF,IO,DGA^6000030   I159 @T6G_MB_LIB.T6G(SCH_1):PAGE45
  J100  265 DQ15_B SCONN288_DDR506112002KQ-SCONN288_DDR506112002KQ,SMA    I22 @T6G_MB_LIB.T6G(SCH_1):PAGE105

M_I_CPU1_SB_DQ<16> @T6G_MB_LIB.T6G(SCH_1):M_I_CPU1_SB_DQ(16)
   U26 CP20 MIB_DATA16 GENOA_SP5-SOCKET6096_13568-001,SMLF,IO,DGA^6000030   I159 @T6G_MB_LIB.T6G(SCH_1):PAGE45
  J100  122 DQ16_B SCONN288_DDR506112002KQ-SCONN288_DDR506112002KQ,SMA    I22 @T6G_MB_LIB.T6G(SCH_1):PAGE105

M_I_CPU1_SB_DQ<17> @T6G_MB_LIB.T6G(SCH_1):M_I_CPU1_SB_DQ(17)
   U26 CR21 MIB_DATA17 GENOA_SP5-SOCKET6096_13568-001,SMLF,IO,DGA^6000030   I159 @T6G_MB_LIB.T6G(SCH_1):PAGE45
  J100  124 DQ17_B SCONN288_DDR506112002KQ-SCONN288_DDR506112002KQ,SMA    I22 @T6G_MB_LIB.T6G(SCH_1):PAGE105

M_I_CPU1_SB_DQ<18> @T6G_MB_LIB.T6G(SCH_1):M_I_CPU1_SB_DQ(18)
   U26 CR19 MIB_DATA18 GENOA_SP5-SOCKET6096_13568-001,SMLF,IO,DGA^6000030   I159 @T6G_MB_LIB.T6G(SCH_1):PAGE45
  J100  267 DQ18_B SCONN288_DDR506112002KQ-SCONN288_DDR506112002KQ,SMA    I22 @T6G_MB_LIB.T6G(SCH_1):PAGE105

M_I_CPU1_SB_DQ<19> @T6G_MB_LIB.T6G(SCH_1):M_I_CPU1_SB_DQ(19)
   U26 CT21 MIB_DATA19 GENOA_SP5-SOCKET6096_13568-001,SMLF,IO,DGA^6000030   I159 @T6G_MB_LIB.T6G(SCH_1):PAGE45
  J100  269 DQ19_B SCONN288_DDR506112002KQ-SCONN288_DDR506112002KQ,SMA    I22 @T6G_MB_LIB.T6G(SCH_1):PAGE105

M_I_CPU1_SB_DQ<1> @T6G_MB_LIB.T6G(SCH_1):M_I_CPU1_SB_DQ(1)
   U26 CC21 MIB_DATA1 GENOA_SP5-SOCKET6096_13568-001,SMLF,IO,DGA^6000030   I159 @T6G_MB_LIB.T6G(SCH_1):PAGE45
  J100  102  DQ1_B SCONN288_DDR506112002KQ-SCONN288_DDR506112002KQ,SMA    I22 @T6G_MB_LIB.T6G(SCH_1):PAGE105

M_I_CPU1_SB_DQ<20> @T6G_MB_LIB.T6G(SCH_1):M_I_CPU1_SB_DQ(20)
   U26 CV20 MIB_DATA20 GENOA_SP5-SOCKET6096_13568-001,SMLF,IO,DGA^6000030   I159 @T6G_MB_LIB.T6G(SCH_1):PAGE45
  J100  129 DQ20_B SCONN288_DDR506112002KQ-SCONN288_DDR506112002KQ,SMA    I22 @T6G_MB_LIB.T6G(SCH_1):PAGE105

M_I_CPU1_SB_DQ<21> @T6G_MB_LIB.T6G(SCH_1):M_I_CPU1_SB_DQ(21)
   U26 CW21 MIB_DATA21 GENOA_SP5-SOCKET6096_13568-001,SMLF,IO,DGA^6000030   I159 @T6G_MB_LIB.T6G(SCH_1):PAGE45
  J100  131 DQ21_B SCONN288_DDR506112002KQ-SCONN288_DDR506112002KQ,SMA    I22 @T6G_MB_LIB.T6G(SCH_1):PAGE105

M_I_CPU1_SB_DQ<22> @T6G_MB_LIB.T6G(SCH_1):M_I_CPU1_SB_DQ(22)
   U26 CW19 MIB_DATA22 GENOA_SP5-SOCKET6096_13568-001,SMLF,IO,DGA^6000030   I159 @T6G_MB_LIB.T6G(SCH_1):PAGE45
  J100  274 DQ22_B SCONN288_DDR506112002KQ-SCONN288_DDR506112002KQ,SMA    I22 @T6G_MB_LIB.T6G(SCH_1):PAGE105

M_I_CPU1_SB_DQ<23> @T6G_MB_LIB.T6G(SCH_1):M_I_CPU1_SB_DQ(23)
   U26 CY21 MIB_DATA23 GENOA_SP5-SOCKET6096_13568-001,SMLF,IO,DGA^6000030   I159 @T6G_MB_LIB.T6G(SCH_1):PAGE45
  J100  276 DQ23_B SCONN288_DDR506112002KQ-SCONN288_DDR506112002KQ,SMA    I22 @T6G_MB_LIB.T6G(SCH_1):PAGE105

M_I_CPU1_SB_DQ<24> @T6G_MB_LIB.T6G(SCH_1):M_I_CPU1_SB_DQ(24)
   U26 CY20 MIB_DATA24 GENOA_SP5-SOCKET6096_13568-001,SMLF,IO,DGA^6000030   I159 @T6G_MB_LIB.T6G(SCH_1):PAGE45
  J100  133 DQ24_B SCONN288_DDR506112002KQ-SCONN288_DDR506112002KQ,SMA    I22 @T6G_MB_LIB.T6G(SCH_1):PAGE105

M_I_CPU1_SB_DQ<25> @T6G_MB_LIB.T6G(SCH_1):M_I_CPU1_SB_DQ(25)
   U26 DA21 MIB_DATA25 GENOA_SP5-SOCKET6096_13568-001,SMLF,IO,DGA^6000030   I159 @T6G_MB_LIB.T6G(SCH_1):PAGE45
  J100  135 DQ25_B SCONN288_DDR506112002KQ-SCONN288_DDR506112002KQ,SMA    I22 @T6G_MB_LIB.T6G(SCH_1):PAGE105

M_I_CPU1_SB_DQ<26> @T6G_MB_LIB.T6G(SCH_1):M_I_CPU1_SB_DQ(26)
   U26 DA19 MIB_DATA26 GENOA_SP5-SOCKET6096_13568-001,SMLF,IO,DGA^6000030   I159 @T6G_MB_LIB.T6G(SCH_1):PAGE45
  J100  278 DQ26_B SCONN288_DDR506112002KQ-SCONN288_DDR506112002KQ,SMA    I22 @T6G_MB_LIB.T6G(SCH_1):PAGE105

M_I_CPU1_SB_DQ<27> @T6G_MB_LIB.T6G(SCH_1):M_I_CPU1_SB_DQ(27)
   U26 DB21 MIB_DATA27 GENOA_SP5-SOCKET6096_13568-001,SMLF,IO,DGA^6000030   I159 @T6G_MB_LIB.T6G(SCH_1):PAGE45
  J100  280 DQ27_B SCONN288_DDR506112002KQ-SCONN288_DDR506112002KQ,SMA    I22 @T6G_MB_LIB.T6G(SCH_1):PAGE105

M_I_CPU1_SB_DQ<28> @T6G_MB_LIB.T6G(SCH_1):M_I_CPU1_SB_DQ(28)
   U26 DD20 MIB_DATA28 GENOA_SP5-SOCKET6096_13568-001,SMLF,IO,DGA^6000030   I159 @T6G_MB_LIB.T6G(SCH_1):PAGE45
  J100  140 DQ28_B SCONN288_DDR506112002KQ-SCONN288_DDR506112002KQ,SMA    I22 @T6G_MB_LIB.T6G(SCH_1):PAGE105

M_I_CPU1_SB_DQ<29> @T6G_MB_LIB.T6G(SCH_1):M_I_CPU1_SB_DQ(29)
   U26 DE21 MIB_DATA29 GENOA_SP5-SOCKET6096_13568-001,SMLF,IO,DGA^6000030   I159 @T6G_MB_LIB.T6G(SCH_1):PAGE45
  J100  142 DQ29_B SCONN288_DDR506112002KQ-SCONN288_DDR506112002KQ,SMA    I22 @T6G_MB_LIB.T6G(SCH_1):PAGE105

M_I_CPU1_SB_DQ<2> @T6G_MB_LIB.T6G(SCH_1):M_I_CPU1_SB_DQ(2)
   U26 CC19 MIB_DATA2 GENOA_SP5-SOCKET6096_13568-001,SMLF,IO,DGA^6000030   I159 @T6G_MB_LIB.T6G(SCH_1):PAGE45
  J100  245  DQ2_B SCONN288_DDR506112002KQ-SCONN288_DDR506112002KQ,SMA    I22 @T6G_MB_LIB.T6G(SCH_1):PAGE105

M_I_CPU1_SB_DQ<30> @T6G_MB_LIB.T6G(SCH_1):M_I_CPU1_SB_DQ(30)
   U26 DE19 MIB_DATA30 GENOA_SP5-SOCKET6096_13568-001,SMLF,IO,DGA^6000030   I159 @T6G_MB_LIB.T6G(SCH_1):PAGE45
  J100  285 DQ30_B SCONN288_DDR506112002KQ-SCONN288_DDR506112002KQ,SMA    I22 @T6G_MB_LIB.T6G(SCH_1):PAGE105

M_I_CPU1_SB_DQ<31> @T6G_MB_LIB.T6G(SCH_1):M_I_CPU1_SB_DQ(31)
   U26 DF21 MIB_DATA31 GENOA_SP5-SOCKET6096_13568-001,SMLF,IO,DGA^6000030   I159 @T6G_MB_LIB.T6G(SCH_1):PAGE45
  J100  287 DQ31_B SCONN288_DDR506112002KQ-SCONN288_DDR506112002KQ,SMA    I22 @T6G_MB_LIB.T6G(SCH_1):PAGE105

M_I_CPU1_SB_DQ<3> @T6G_MB_LIB.T6G(SCH_1):M_I_CPU1_SB_DQ(3)
   U26 CD21 MIB_DATA3 GENOA_SP5-SOCKET6096_13568-001,SMLF,IO,DGA^6000030   I159 @T6G_MB_LIB.T6G(SCH_1):PAGE45
  J100  247  DQ3_B SCONN288_DDR506112002KQ-SCONN288_DDR506112002KQ,SMA    I22 @T6G_MB_LIB.T6G(SCH_1):PAGE105

M_I_CPU1_SB_DQ<4> @T6G_MB_LIB.T6G(SCH_1):M_I_CPU1_SB_DQ(4)
   U26 CF20 MIB_DATA4 GENOA_SP5-SOCKET6096_13568-001,SMLF,IO,DGA^6000030   I159 @T6G_MB_LIB.T6G(SCH_1):PAGE45
  J100  107  DQ4_B SCONN288_DDR506112002KQ-SCONN288_DDR506112002KQ,SMA    I22 @T6G_MB_LIB.T6G(SCH_1):PAGE105

M_I_CPU1_SB_DQ<5> @T6G_MB_LIB.T6G(SCH_1):M_I_CPU1_SB_DQ(5)
   U26 CG21 MIB_DATA5 GENOA_SP5-SOCKET6096_13568-001,SMLF,IO,DGA^6000030   I159 @T6G_MB_LIB.T6G(SCH_1):PAGE45
  J100  109  DQ5_B SCONN288_DDR506112002KQ-SCONN288_DDR506112002KQ,SMA    I22 @T6G_MB_LIB.T6G(SCH_1):PAGE105

M_I_CPU1_SB_DQ<6> @T6G_MB_LIB.T6G(SCH_1):M_I_CPU1_SB_DQ(6)
   U26 CG19 MIB_DATA6 GENOA_SP5-SOCKET6096_13568-001,SMLF,IO,DGA^6000030   I159 @T6G_MB_LIB.T6G(SCH_1):PAGE45
  J100  252  DQ6_B SCONN288_DDR506112002KQ-SCONN288_DDR506112002KQ,SMA    I22 @T6G_MB_LIB.T6G(SCH_1):PAGE105

M_I_CPU1_SB_DQ<7> @T6G_MB_LIB.T6G(SCH_1):M_I_CPU1_SB_DQ(7)
   U26 CH21 MIB_DATA7 GENOA_SP5-SOCKET6096_13568-001,SMLF,IO,DGA^6000030   I159 @T6G_MB_LIB.T6G(SCH_1):PAGE45
  J100  254  DQ7_B SCONN288_DDR506112002KQ-SCONN288_DDR506112002KQ,SMA    I22 @T6G_MB_LIB.T6G(SCH_1):PAGE105

M_I_CPU1_SB_DQ<8> @T6G_MB_LIB.T6G(SCH_1):M_I_CPU1_SB_DQ(8)
   U26 CH20 MIB_DATA8 GENOA_SP5-SOCKET6096_13568-001,SMLF,IO,DGA^6000030   I159 @T6G_MB_LIB.T6G(SCH_1):PAGE45
  J100  111  DQ8_B SCONN288_DDR506112002KQ-SCONN288_DDR506112002KQ,SMA    I22 @T6G_MB_LIB.T6G(SCH_1):PAGE105

M_I_CPU1_SB_DQ<9> @T6G_MB_LIB.T6G(SCH_1):M_I_CPU1_SB_DQ(9)
   U26 CJ21 MIB_DATA9 GENOA_SP5-SOCKET6096_13568-001,SMLF,IO,DGA^6000030   I159 @T6G_MB_LIB.T6G(SCH_1):PAGE45
  J100  113  DQ9_B SCONN288_DDR506112002KQ-SCONN288_DDR506112002KQ,SMA    I22 @T6G_MB_LIB.T6G(SCH_1):PAGE105

M_I_CPU1_SB_DQS_DN<0> @T6G_MB_LIB.T6G(SCH_1):M_I_CPU1_SB_DQS_DN(0)
   U26 CE19 MIB_DQS_L0 GENOA_SP5-SOCKET6096_13568-001,SMLF,IO,DGA^6000030   I159 @T6G_MB_LIB.T6G(SCH_1):PAGE45
  J100  105 DQS0_B_C SCONN288_DDR506112002KQ-SCONN288_DDR506112002KQ,SMA   I236 @T6G_MB_LIB.T6G(SCH_1):PAGE105

M_I_CPU1_SB_DQS_DN<1> @T6G_MB_LIB.T6G(SCH_1):M_I_CPU1_SB_DQS_DN(1)
   U26 CL19 MIB_DQS_L1 GENOA_SP5-SOCKET6096_13568-001,SMLF,IO,DGA^6000030   I159 @T6G_MB_LIB.T6G(SCH_1):PAGE45
  J100  116 DQS1_B_C SCONN288_DDR506112002KQ-SCONN288_DDR506112002KQ,SMA   I236 @T6G_MB_LIB.T6G(SCH_1):PAGE105

M_I_CPU1_SB_DQS_DN<2> @T6G_MB_LIB.T6G(SCH_1):M_I_CPU1_SB_DQS_DN(2)
   U26 CU19 MIB_DQS_L2 GENOA_SP5-SOCKET6096_13568-001,SMLF,IO,DGA^6000030   I159 @T6G_MB_LIB.T6G(SCH_1):PAGE45
  J100  127 DQS2_B_C SCONN288_DDR506112002KQ-SCONN288_DDR506112002KQ,SMA   I236 @T6G_MB_LIB.T6G(SCH_1):PAGE105

M_I_CPU1_SB_DQS_DN<3> @T6G_MB_LIB.T6G(SCH_1):M_I_CPU1_SB_DQS_DN(3)
   U26 DC19 MIB_DQS_L3 GENOA_SP5-SOCKET6096_13568-001,SMLF,IO,DGA^6000030   I159 @T6G_MB_LIB.T6G(SCH_1):PAGE45
  J100  138 DQS3_B_C SCONN288_DDR506112002KQ-SCONN288_DDR506112002KQ,SMA   I236 @T6G_MB_LIB.T6G(SCH_1):PAGE105

M_I_CPU1_SB_DQS_DN<4> @T6G_MB_LIB.T6G(SCH_1):M_I_CPU1_SB_DQS_DN(4)
   U26 BW21 MIB_DQS_L4 GENOA_SP5-SOCKET6096_13568-001,SMLF,IO,DGA^6000030   I159 @T6G_MB_LIB.T6G(SCH_1):PAGE45
  J100  238 DQS4_B_C SCONN288_DDR506112002KQ-SCONN288_DDR506112002KQ,SMA   I236 @T6G_MB_LIB.T6G(SCH_1):PAGE105

M_I_CPU1_SB_DQS_DN<5> @T6G_MB_LIB.T6G(SCH_1):M_I_CPU1_SB_DQS_DN(5)
   U26 CE21 MIB_DQS_L5 GENOA_SP5-SOCKET6096_13568-001,SMLF,IO,DGA^6000030   I159 @T6G_MB_LIB.T6G(SCH_1):PAGE45
  J100  249 DQS5_B_C||TDQS5_B_C SCONN288_DDR506112002KQ-SCONN288_DDR506112002KQ,SMA   I236 @T6G_MB_LIB.T6G(SCH_1):PAGE105

M_I_CPU1_SB_DQS_DN<6> @T6G_MB_LIB.T6G(SCH_1):M_I_CPU1_SB_DQS_DN(6)
   U26 CL21 MIB_DQS_L6 GENOA_SP5-SOCKET6096_13568-001,SMLF,IO,DGA^6000030   I159 @T6G_MB_LIB.T6G(SCH_1):PAGE45
  J100  260 DQS6_B_C||TDQS6_B_C SCONN288_DDR506112002KQ-SCONN288_DDR506112002KQ,SMA   I236 @T6G_MB_LIB.T6G(SCH_1):PAGE105

M_I_CPU1_SB_DQS_DN<7> @T6G_MB_LIB.T6G(SCH_1):M_I_CPU1_SB_DQS_DN(7)
   U26 CU21 MIB_DQS_L7 GENOA_SP5-SOCKET6096_13568-001,SMLF,IO,DGA^6000030   I159 @T6G_MB_LIB.T6G(SCH_1):PAGE45
  J100  271 DQS7_B_C||TDQS7_B_C SCONN288_DDR506112002KQ-SCONN288_DDR506112002KQ,SMA   I236 @T6G_MB_LIB.T6G(SCH_1):PAGE105

M_I_CPU1_SB_DQS_DN<8> @T6G_MB_LIB.T6G(SCH_1):M_I_CPU1_SB_DQS_DN(8)
   U26 DC21 MIB_DQS_L8 GENOA_SP5-SOCKET6096_13568-001,SMLF,IO,DGA^6000030   I159 @T6G_MB_LIB.T6G(SCH_1):PAGE45
  J100  282 DQS8_B_C||TDQS8_B_C SCONN288_DDR506112002KQ-SCONN288_DDR506112002KQ,SMA   I236 @T6G_MB_LIB.T6G(SCH_1):PAGE105

M_I_CPU1_SB_DQS_DN<9> @T6G_MB_LIB.T6G(SCH_1):M_I_CPU1_SB_DQS_DN(9)
   U26 BW19 MIB_DQS_L9 GENOA_SP5-SOCKET6096_13568-001,SMLF,IO,DGA^6000030   I159 @T6G_MB_LIB.T6G(SCH_1):PAGE45
  J100   94 DQS9_B_C||TDQS9_B_C SCONN288_DDR506112002KQ-SCONN288_DDR506112002KQ,SMA   I236 @T6G_MB_LIB.T6G(SCH_1):PAGE105

M_I_CPU1_SB_DQS_DP<0> @T6G_MB_LIB.T6G(SCH_1):M_I_CPU1_SB_DQS_DP(0)
   U26 CD20 MIB_DQS_H0 GENOA_SP5-SOCKET6096_13568-001,SMLF,IO,DGA^6000030   I159 @T6G_MB_LIB.T6G(SCH_1):PAGE45
  J100  104 DQS0_B_T SCONN288_DDR506112002KQ-SCONN288_DDR506112002KQ,SMA   I236 @T6G_MB_LIB.T6G(SCH_1):PAGE105

M_I_CPU1_SB_DQS_DP<1> @T6G_MB_LIB.T6G(SCH_1):M_I_CPU1_SB_DQS_DP(1)
   U26 CK20 MIB_DQS_H1 GENOA_SP5-SOCKET6096_13568-001,SMLF,IO,DGA^6000030   I159 @T6G_MB_LIB.T6G(SCH_1):PAGE45
  J100  115 DQS1_B_T SCONN288_DDR506112002KQ-SCONN288_DDR506112002KQ,SMA   I236 @T6G_MB_LIB.T6G(SCH_1):PAGE105

M_I_CPU1_SB_DQS_DP<2> @T6G_MB_LIB.T6G(SCH_1):M_I_CPU1_SB_DQS_DP(2)
   U26 CT20 MIB_DQS_H2 GENOA_SP5-SOCKET6096_13568-001,SMLF,IO,DGA^6000030   I159 @T6G_MB_LIB.T6G(SCH_1):PAGE45
  J100  126 DQS2_B_T SCONN288_DDR506112002KQ-SCONN288_DDR506112002KQ,SMA   I236 @T6G_MB_LIB.T6G(SCH_1):PAGE105

M_I_CPU1_SB_DQS_DP<3> @T6G_MB_LIB.T6G(SCH_1):M_I_CPU1_SB_DQS_DP(3)
   U26 DB20 MIB_DQS_H3 GENOA_SP5-SOCKET6096_13568-001,SMLF,IO,DGA^6000030   I159 @T6G_MB_LIB.T6G(SCH_1):PAGE45
  J100  137 DQS3_B_T SCONN288_DDR506112002KQ-SCONN288_DDR506112002KQ,SMA   I236 @T6G_MB_LIB.T6G(SCH_1):PAGE105

M_I_CPU1_SB_DQS_DP<4> @T6G_MB_LIB.T6G(SCH_1):M_I_CPU1_SB_DQS_DP(4)
   U26 BY21 MIB_DQS_H4 GENOA_SP5-SOCKET6096_13568-001,SMLF,IO,DGA^6000030   I159 @T6G_MB_LIB.T6G(SCH_1):PAGE45
  J100  239 DQS4_B_T SCONN288_DDR506112002KQ-SCONN288_DDR506112002KQ,SMA   I236 @T6G_MB_LIB.T6G(SCH_1):PAGE105

M_I_CPU1_SB_DQS_DP<5> @T6G_MB_LIB.T6G(SCH_1):M_I_CPU1_SB_DQS_DP(5)
   U26 CF21 MIB_DQS_H5 GENOA_SP5-SOCKET6096_13568-001,SMLF,IO,DGA^6000030   I159 @T6G_MB_LIB.T6G(SCH_1):PAGE45
  J100  250 DQS5_B_T||TDQS5_B_T SCONN288_DDR506112002KQ-SCONN288_DDR506112002KQ,SMA   I236 @T6G_MB_LIB.T6G(SCH_1):PAGE105

M_I_CPU1_SB_DQS_DP<6> @T6G_MB_LIB.T6G(SCH_1):M_I_CPU1_SB_DQS_DP(6)
   U26 CM21 MIB_DQS_H6 GENOA_SP5-SOCKET6096_13568-001,SMLF,IO,DGA^6000030   I159 @T6G_MB_LIB.T6G(SCH_1):PAGE45
  J100  261 DQS6_B_T||TDQS6_B_T SCONN288_DDR506112002KQ-SCONN288_DDR506112002KQ,SMA   I236 @T6G_MB_LIB.T6G(SCH_1):PAGE105

M_I_CPU1_SB_DQS_DP<7> @T6G_MB_LIB.T6G(SCH_1):M_I_CPU1_SB_DQS_DP(7)
   U26 CV21 MIB_DQS_H7 GENOA_SP5-SOCKET6096_13568-001,SMLF,IO,DGA^6000030   I159 @T6G_MB_LIB.T6G(SCH_1):PAGE45
  J100  272 DQS7_B_T||TDQS7_B_T SCONN288_DDR506112002KQ-SCONN288_DDR506112002KQ,SMA   I236 @T6G_MB_LIB.T6G(SCH_1):PAGE105

M_I_CPU1_SB_DQS_DP<8> @T6G_MB_LIB.T6G(SCH_1):M_I_CPU1_SB_DQS_DP(8)
   U26 DD21 MIB_DQS_H8 GENOA_SP5-SOCKET6096_13568-001,SMLF,IO,DGA^6000030   I159 @T6G_MB_LIB.T6G(SCH_1):PAGE45
  J100  283 DQS8_B_T||TDQS8_B_T SCONN288_DDR506112002KQ-SCONN288_DDR506112002KQ,SMA   I236 @T6G_MB_LIB.T6G(SCH_1):PAGE105

M_I_CPU1_SB_DQS_DP<9> @T6G_MB_LIB.T6G(SCH_1):M_I_CPU1_SB_DQS_DP(9)
   U26 BV20 MIB_DQS_H9 GENOA_SP5-SOCKET6096_13568-001,SMLF,IO,DGA^6000030   I159 @T6G_MB_LIB.T6G(SCH_1):PAGE45
  J100   93 DQS9_B_T||TDQS9_B_T||DBI4_B_N SCONN288_DDR506112002KQ-SCONN288_DDR506112002KQ,SMA   I236 @T6G_MB_LIB.T6G(SCH_1):PAGE105

M_I_CPU1_SB_PAR @T6G_MB_LIB.T6G(SCH_1):M_I_CPU1_SB_PAR
   U26 BL21 MIB_PAR GENOA_SP5-SOCKET6096_13568-001,SMLF,IO,DGA^6000030   I159 @T6G_MB_LIB.T6G(SCH_1):PAGE45
  J100  227  PAR_B SCONN288_DDR506112002KQ-SCONN288_DDR506112002KQ,SMA    I22 @T6G_MB_LIB.T6G(SCH_1):PAGE105

M_I_CPU1_SB_RSP<0> @T6G_MB_LIB.T6G(SCH_1):M_I_CPU1_SB_RSP(0)
   U26 BP20 MIB0_RSP_L GENOA_SP5-SOCKET6096_13568-001,SMLF,IO,DGA^6000030   I159 @T6G_MB_LIB.T6G(SCH_1):PAGE45
  J100   87 LBS||RSP_B_N SCONN288_DDR506112002KQ-SCONN288_DDR506112002KQ,SMA    I22 @T6G_MB_LIB.T6G(SCH_1):PAGE105

M_J_CPU0_ALERT_N @T6G_MB_LIB.T6G(SCH_1):M_J_CPU0_ALERT_N
  R384    1      A Q_RES_0402LF-15,1%,1/16W,CHIP,CS01502FB03   I314 @T6G_MB_LIB.T6G(SCH_1):PAGE19
   J68   62 ALERT_N SCONN288_DDR506112002KQ-SCONN288_DDR506112002KQ,SMA    I22 @T6G_MB_LIB.T6G(SCH_1):PAGE94

M_J_CPU0_ALERT_R_N @T6G_MB_LIB.T6G(SCH_1):M_J_CPU0_ALERT_R_N
   U25 AT18 MJ_ALERT_L GENOA_SP5-SOCKET6096_13568-001,SMLF,IO,DGA^6000030   I159 @T6G_MB_LIB.T6G(SCH_1):PAGE19
  R384    2      B Q_RES_0402LF-15,1%,1/16W,CHIP,CS01502FB03   I314 @T6G_MB_LIB.T6G(SCH_1):PAGE19

M_J_CPU0_CLK_DN<0> @T6G_MB_LIB.T6G(SCH_1):M_J_CPU0_CLK_DN(0)
   U25 BD16 MJ0_CLK_L GENOA_SP5-SOCKET6096_13568-001,SMLF,IO,DGA^6000030   I159 @T6G_MB_LIB.T6G(SCH_1):PAGE19
   J68  218   CK_C SCONN288_DDR506112002KQ-SCONN288_DDR506112002KQ,SMA    I22 @T6G_MB_LIB.T6G(SCH_1):PAGE94

M_J_CPU0_CLK_DP<0> @T6G_MB_LIB.T6G(SCH_1):M_J_CPU0_CLK_DP(0)
   U25 BC16 MJ0_CLK_H GENOA_SP5-SOCKET6096_13568-001,SMLF,IO,DGA^6000030   I159 @T6G_MB_LIB.T6G(SCH_1):PAGE19
   J68  217   CK_T SCONN288_DDR506112002KQ-SCONN288_DDR506112002KQ,SMA    I22 @T6G_MB_LIB.T6G(SCH_1):PAGE94

M_J_CPU0_RESET_N @T6G_MB_LIB.T6G(SCH_1):M_J_CPU0_RESET_N
   U25 AU17 MJ_RESET_L GENOA_SP5-SOCKET6096_13568-001,SMLF,IO,DGA^6000030   I159 @T6G_MB_LIB.T6G(SCH_1):PAGE19
   J68  207 RESET_N SCONN288_DDR506112002KQ-SCONN288_DDR506112002KQ,SMA    I22 @T6G_MB_LIB.T6G(SCH_1):PAGE94

M_J_CPU0_SA_CA<0> @T6G_MB_LIB.T6G(SCH_1):M_J_CPU0_SA_CA(0)
   U25 AW16 MJA_CA0 GENOA_SP5-SOCKET6096_13568-001,SMLF,IO,DGA^6000030   I159 @T6G_MB_LIB.T6G(SCH_1):PAGE19
   J68   66  CA0_A SCONN288_DDR506112002KQ-SCONN288_DDR506112002KQ,SMA    I22 @T6G_MB_LIB.T6G(SCH_1):PAGE94

M_J_CPU0_SA_CA<1> @T6G_MB_LIB.T6G(SCH_1):M_J_CPU0_SA_CA(1)
   U25 AY16 MJA_CA1 GENOA_SP5-SOCKET6096_13568-001,SMLF,IO,DGA^6000030   I159 @T6G_MB_LIB.T6G(SCH_1):PAGE19
   J68  211  CA1_A SCONN288_DDR506112002KQ-SCONN288_DDR506112002KQ,SMA    I22 @T6G_MB_LIB.T6G(SCH_1):PAGE94

M_J_CPU0_SA_CA<2> @T6G_MB_LIB.T6G(SCH_1):M_J_CPU0_SA_CA(2)
   U25 AY18 MJA_CA2 GENOA_SP5-SOCKET6096_13568-001,SMLF,IO,DGA^6000030   I159 @T6G_MB_LIB.T6G(SCH_1):PAGE19
   J68   68  CA2_A SCONN288_DDR506112002KQ-SCONN288_DDR506112002KQ,SMA    I22 @T6G_MB_LIB.T6G(SCH_1):PAGE94

M_J_CPU0_SA_CA<3> @T6G_MB_LIB.T6G(SCH_1):M_J_CPU0_SA_CA(3)
   U25 BA17 MJA_CA3 GENOA_SP5-SOCKET6096_13568-001,SMLF,IO,DGA^6000030   I159 @T6G_MB_LIB.T6G(SCH_1):PAGE19
   J68  213  CA3_A SCONN288_DDR506112002KQ-SCONN288_DDR506112002KQ,SMA    I22 @T6G_MB_LIB.T6G(SCH_1):PAGE94

M_J_CPU0_SA_CA<4> @T6G_MB_LIB.T6G(SCH_1):M_J_CPU0_SA_CA(4)
   U25 BA16 MJA_CA4 GENOA_SP5-SOCKET6096_13568-001,SMLF,IO,DGA^6000030   I159 @T6G_MB_LIB.T6G(SCH_1):PAGE19
   J68   70  CA4_A SCONN288_DDR506112002KQ-SCONN288_DDR506112002KQ,SMA    I22 @T6G_MB_LIB.T6G(SCH_1):PAGE94

M_J_CPU0_SA_CA<5> @T6G_MB_LIB.T6G(SCH_1):M_J_CPU0_SA_CA(5)
   U25 BB16 MJA_CA5 GENOA_SP5-SOCKET6096_13568-001,SMLF,IO,DGA^6000030   I159 @T6G_MB_LIB.T6G(SCH_1):PAGE19
   J68  215  CA5_A SCONN288_DDR506112002KQ-SCONN288_DDR506112002KQ,SMA    I22 @T6G_MB_LIB.T6G(SCH_1):PAGE94

M_J_CPU0_SA_CA<6> @T6G_MB_LIB.T6G(SCH_1):M_J_CPU0_SA_CA(6)
   U25 BB18 MJA_CA6 GENOA_SP5-SOCKET6096_13568-001,SMLF,IO,DGA^6000030   I159 @T6G_MB_LIB.T6G(SCH_1):PAGE19
   J68   72  CA6_A SCONN288_DDR506112002KQ-SCONN288_DDR506112002KQ,SMA    I22 @T6G_MB_LIB.T6G(SCH_1):PAGE94

M_J_CPU0_SA_CB<0> @T6G_MB_LIB.T6G(SCH_1):M_J_CPU0_SA_CB(0)
   U25 AJ16 MJA_CHECK0 GENOA_SP5-SOCKET6096_13568-001,SMLF,IO,DGA^6000030   I159 @T6G_MB_LIB.T6G(SCH_1):PAGE19
   J68   51  CB0_A SCONN288_DDR506112002KQ-SCONN288_DDR506112002KQ,SMA    I22 @T6G_MB_LIB.T6G(SCH_1):PAGE94

M_J_CPU0_SA_CB<1> @T6G_MB_LIB.T6G(SCH_1):M_J_CPU0_SA_CB(1)
   U25 AK18 MJA_CHECK1 GENOA_SP5-SOCKET6096_13568-001,SMLF,IO,DGA^6000030   I159 @T6G_MB_LIB.T6G(SCH_1):PAGE19
   J68   53  CB1_A SCONN288_DDR506112002KQ-SCONN288_DDR506112002KQ,SMA    I22 @T6G_MB_LIB.T6G(SCH_1):PAGE94

M_J_CPU0_SA_CB<2> @T6G_MB_LIB.T6G(SCH_1):M_J_CPU0_SA_CB(2)
   U25 AK16 MJA_CHECK2 GENOA_SP5-SOCKET6096_13568-001,SMLF,IO,DGA^6000030   I159 @T6G_MB_LIB.T6G(SCH_1):PAGE19
   J68  196  CB2_A SCONN288_DDR506112002KQ-SCONN288_DDR506112002KQ,SMA    I22 @T6G_MB_LIB.T6G(SCH_1):PAGE94

M_J_CPU0_SA_CB<3> @T6G_MB_LIB.T6G(SCH_1):M_J_CPU0_SA_CB(3)
   U25 AL17 MJA_CHECK3 GENOA_SP5-SOCKET6096_13568-001,SMLF,IO,DGA^6000030   I159 @T6G_MB_LIB.T6G(SCH_1):PAGE19
   J68  198  CB3_A SCONN288_DDR506112002KQ-SCONN288_DDR506112002KQ,SMA    I22 @T6G_MB_LIB.T6G(SCH_1):PAGE94

M_J_CPU0_SA_CB<4> @T6G_MB_LIB.T6G(SCH_1):M_J_CPU0_SA_CB(4)
   U25 AN16 MJA_CHECK4 GENOA_SP5-SOCKET6096_13568-001,SMLF,IO,DGA^6000030   I159 @T6G_MB_LIB.T6G(SCH_1):PAGE19
   J68   58  CB4_A SCONN288_DDR506112002KQ-SCONN288_DDR506112002KQ,SMA    I22 @T6G_MB_LIB.T6G(SCH_1):PAGE94

M_J_CPU0_SA_CB<5> @T6G_MB_LIB.T6G(SCH_1):M_J_CPU0_SA_CB(5)
   U25 AP18 MJA_CHECK5 GENOA_SP5-SOCKET6096_13568-001,SMLF,IO,DGA^6000030   I159 @T6G_MB_LIB.T6G(SCH_1):PAGE19
   J68   60  CB5_A SCONN288_DDR506112002KQ-SCONN288_DDR506112002KQ,SMA    I22 @T6G_MB_LIB.T6G(SCH_1):PAGE94

M_J_CPU0_SA_CB<6> @T6G_MB_LIB.T6G(SCH_1):M_J_CPU0_SA_CB(6)
   U25 AP16 MJA_CHECK6 GENOA_SP5-SOCKET6096_13568-001,SMLF,IO,DGA^6000030   I159 @T6G_MB_LIB.T6G(SCH_1):PAGE19
   J68  203  CB6_A SCONN288_DDR506112002KQ-SCONN288_DDR506112002KQ,SMA    I22 @T6G_MB_LIB.T6G(SCH_1):PAGE94

M_J_CPU0_SA_CB<7> @T6G_MB_LIB.T6G(SCH_1):M_J_CPU0_SA_CB(7)
   U25 AR17 MJA_CHECK7 GENOA_SP5-SOCKET6096_13568-001,SMLF,IO,DGA^6000030   I159 @T6G_MB_LIB.T6G(SCH_1):PAGE19
   J68  205  CB7_A SCONN288_DDR506112002KQ-SCONN288_DDR506112002KQ,SMA    I22 @T6G_MB_LIB.T6G(SCH_1):PAGE94

M_J_CPU0_SA_CS_N<0> @T6G_MB_LIB.T6G(SCH_1):M_J_CPU0_SA_CS_N(0)
   U25 AU16 MJA0_CS_L0 GENOA_SP5-SOCKET6096_13568-001,SMLF,IO,DGA^6000030   I159 @T6G_MB_LIB.T6G(SCH_1):PAGE19
   J68   64 CS0_A_N SCONN288_DDR506112002KQ-SCONN288_DDR506112002KQ,SMA    I22 @T6G_MB_LIB.T6G(SCH_1):PAGE94

M_J_CPU0_SA_CS_N<1> @T6G_MB_LIB.T6G(SCH_1):M_J_CPU0_SA_CS_N(1)
   U25 AV18 MJA0_CS_L1 GENOA_SP5-SOCKET6096_13568-001,SMLF,IO,DGA^6000030   I159 @T6G_MB_LIB.T6G(SCH_1):PAGE19
   J68  209 CS1_A_N SCONN288_DDR506112002KQ-SCONN288_DDR506112002KQ,SMA    I22 @T6G_MB_LIB.T6G(SCH_1):PAGE94

M_J_CPU0_SA_DQ<0> @T6G_MB_LIB.T6G(SCH_1):M_J_CPU0_SA_DQ(0)
   U25  E16 MJA_DATA0 GENOA_SP5-SOCKET6096_13568-001,SMLF,IO,DGA^6000030   I159 @T6G_MB_LIB.T6G(SCH_1):PAGE19
   J68    7  DQ0_A SCONN288_DDR506112002KQ-SCONN288_DDR506112002KQ,SMA    I22 @T6G_MB_LIB.T6G(SCH_1):PAGE94

M_J_CPU0_SA_DQ<10> @T6G_MB_LIB.T6G(SCH_1):M_J_CPU0_SA_DQ(10)
   U25  M16 MJA_DATA10 GENOA_SP5-SOCKET6096_13568-001,SMLF,IO,DGA^6000030   I159 @T6G_MB_LIB.T6G(SCH_1):PAGE19
   J68  163 DQ10_A SCONN288_DDR506112002KQ-SCONN288_DDR506112002KQ,SMA    I22 @T6G_MB_LIB.T6G(SCH_1):PAGE94

M_J_CPU0_SA_DQ<11> @T6G_MB_LIB.T6G(SCH_1):M_J_CPU0_SA_DQ(11)
   U25  N17 MJA_DATA11 GENOA_SP5-SOCKET6096_13568-001,SMLF,IO,DGA^6000030   I159 @T6G_MB_LIB.T6G(SCH_1):PAGE19
   J68  165 DQ11_A SCONN288_DDR506112002KQ-SCONN288_DDR506112002KQ,SMA    I22 @T6G_MB_LIB.T6G(SCH_1):PAGE94

M_J_CPU0_SA_DQ<12> @T6G_MB_LIB.T6G(SCH_1):M_J_CPU0_SA_DQ(12)
   U25  R16 MJA_DATA12 GENOA_SP5-SOCKET6096_13568-001,SMLF,IO,DGA^6000030   I159 @T6G_MB_LIB.T6G(SCH_1):PAGE19
   J68   25 DQ12_A SCONN288_DDR506112002KQ-SCONN288_DDR506112002KQ,SMA    I22 @T6G_MB_LIB.T6G(SCH_1):PAGE94

M_J_CPU0_SA_DQ<13> @T6G_MB_LIB.T6G(SCH_1):M_J_CPU0_SA_DQ(13)
   U25  T18 MJA_DATA13 GENOA_SP5-SOCKET6096_13568-001,SMLF,IO,DGA^6000030   I159 @T6G_MB_LIB.T6G(SCH_1):PAGE19
   J68   27 DQ13_A SCONN288_DDR506112002KQ-SCONN288_DDR506112002KQ,SMA    I22 @T6G_MB_LIB.T6G(SCH_1):PAGE94

M_J_CPU0_SA_DQ<14> @T6G_MB_LIB.T6G(SCH_1):M_J_CPU0_SA_DQ(14)
   U25  T16 MJA_DATA14 GENOA_SP5-SOCKET6096_13568-001,SMLF,IO,DGA^6000030   I159 @T6G_MB_LIB.T6G(SCH_1):PAGE19
   J68  170 DQ14_A SCONN288_DDR506112002KQ-SCONN288_DDR506112002KQ,SMA    I22 @T6G_MB_LIB.T6G(SCH_1):PAGE94

M_J_CPU0_SA_DQ<15> @T6G_MB_LIB.T6G(SCH_1):M_J_CPU0_SA_DQ(15)
   U25  U17 MJA_DATA15 GENOA_SP5-SOCKET6096_13568-001,SMLF,IO,DGA^6000030   I159 @T6G_MB_LIB.T6G(SCH_1):PAGE19
   J68  172 DQ15_A SCONN288_DDR506112002KQ-SCONN288_DDR506112002KQ,SMA    I22 @T6G_MB_LIB.T6G(SCH_1):PAGE94

M_J_CPU0_SA_DQ<16> @T6G_MB_LIB.T6G(SCH_1):M_J_CPU0_SA_DQ(16)
   U25  U16 MJA_DATA16 GENOA_SP5-SOCKET6096_13568-001,SMLF,IO,DGA^6000030   I159 @T6G_MB_LIB.T6G(SCH_1):PAGE19
   J68   29 DQ16_A SCONN288_DDR506112002KQ-SCONN288_DDR506112002KQ,SMA    I22 @T6G_MB_LIB.T6G(SCH_1):PAGE94

M_J_CPU0_SA_DQ<17> @T6G_MB_LIB.T6G(SCH_1):M_J_CPU0_SA_DQ(17)
   U25  V18 MJA_DATA17 GENOA_SP5-SOCKET6096_13568-001,SMLF,IO,DGA^6000030   I159 @T6G_MB_LIB.T6G(SCH_1):PAGE19
   J68   31 DQ17_A SCONN288_DDR506112002KQ-SCONN288_DDR506112002KQ,SMA    I22 @T6G_MB_LIB.T6G(SCH_1):PAGE94

M_J_CPU0_SA_DQ<18> @T6G_MB_LIB.T6G(SCH_1):M_J_CPU0_SA_DQ(18)
   U25  V16 MJA_DATA18 GENOA_SP5-SOCKET6096_13568-001,SMLF,IO,DGA^6000030   I159 @T6G_MB_LIB.T6G(SCH_1):PAGE19
   J68  174 DQ18_A SCONN288_DDR506112002KQ-SCONN288_DDR506112002KQ,SMA    I22 @T6G_MB_LIB.T6G(SCH_1):PAGE94

M_J_CPU0_SA_DQ<19> @T6G_MB_LIB.T6G(SCH_1):M_J_CPU0_SA_DQ(19)
   U25  W17 MJA_DATA19 GENOA_SP5-SOCKET6096_13568-001,SMLF,IO,DGA^6000030   I159 @T6G_MB_LIB.T6G(SCH_1):PAGE19
   J68  176 DQ19_A SCONN288_DDR506112002KQ-SCONN288_DDR506112002KQ,SMA    I22 @T6G_MB_LIB.T6G(SCH_1):PAGE94

M_J_CPU0_SA_DQ<1> @T6G_MB_LIB.T6G(SCH_1):M_J_CPU0_SA_DQ(1)
   U25  F18 MJA_DATA1 GENOA_SP5-SOCKET6096_13568-001,SMLF,IO,DGA^6000030   I159 @T6G_MB_LIB.T6G(SCH_1):PAGE19
   J68    9  DQ1_A SCONN288_DDR506112002KQ-SCONN288_DDR506112002KQ,SMA    I22 @T6G_MB_LIB.T6G(SCH_1):PAGE94

M_J_CPU0_SA_DQ<20> @T6G_MB_LIB.T6G(SCH_1):M_J_CPU0_SA_DQ(20)
   U25 AA16 MJA_DATA20 GENOA_SP5-SOCKET6096_13568-001,SMLF,IO,DGA^6000030   I159 @T6G_MB_LIB.T6G(SCH_1):PAGE19
   J68   36 DQ20_A SCONN288_DDR506112002KQ-SCONN288_DDR506112002KQ,SMA    I22 @T6G_MB_LIB.T6G(SCH_1):PAGE94

M_J_CPU0_SA_DQ<21> @T6G_MB_LIB.T6G(SCH_1):M_J_CPU0_SA_DQ(21)
   U25 AB18 MJA_DATA21 GENOA_SP5-SOCKET6096_13568-001,SMLF,IO,DGA^6000030   I159 @T6G_MB_LIB.T6G(SCH_1):PAGE19
   J68   38 DQ21_A SCONN288_DDR506112002KQ-SCONN288_DDR506112002KQ,SMA    I22 @T6G_MB_LIB.T6G(SCH_1):PAGE94

M_J_CPU0_SA_DQ<22> @T6G_MB_LIB.T6G(SCH_1):M_J_CPU0_SA_DQ(22)
   U25 AB16 MJA_DATA22 GENOA_SP5-SOCKET6096_13568-001,SMLF,IO,DGA^6000030   I159 @T6G_MB_LIB.T6G(SCH_1):PAGE19
   J68  181 DQ22_A SCONN288_DDR506112002KQ-SCONN288_DDR506112002KQ,SMA    I22 @T6G_MB_LIB.T6G(SCH_1):PAGE94

M_J_CPU0_SA_DQ<23> @T6G_MB_LIB.T6G(SCH_1):M_J_CPU0_SA_DQ(23)
   U25 AC17 MJA_DATA23 GENOA_SP5-SOCKET6096_13568-001,SMLF,IO,DGA^6000030   I159 @T6G_MB_LIB.T6G(SCH_1):PAGE19
   J68  183 DQ23_A SCONN288_DDR506112002KQ-SCONN288_DDR506112002KQ,SMA    I22 @T6G_MB_LIB.T6G(SCH_1):PAGE94

M_J_CPU0_SA_DQ<24> @T6G_MB_LIB.T6G(SCH_1):M_J_CPU0_SA_DQ(24)
   U25 AC16 MJA_DATA24 GENOA_SP5-SOCKET6096_13568-001,SMLF,IO,DGA^6000030   I159 @T6G_MB_LIB.T6G(SCH_1):PAGE19
   J68   40 DQ24_A SCONN288_DDR506112002KQ-SCONN288_DDR506112002KQ,SMA    I22 @T6G_MB_LIB.T6G(SCH_1):PAGE94

M_J_CPU0_SA_DQ<25> @T6G_MB_LIB.T6G(SCH_1):M_J_CPU0_SA_DQ(25)
   U25 AD18 MJA_DATA25 GENOA_SP5-SOCKET6096_13568-001,SMLF,IO,DGA^6000030   I159 @T6G_MB_LIB.T6G(SCH_1):PAGE19
   J68   42 DQ25_A SCONN288_DDR506112002KQ-SCONN288_DDR506112002KQ,SMA    I22 @T6G_MB_LIB.T6G(SCH_1):PAGE94

M_J_CPU0_SA_DQ<26> @T6G_MB_LIB.T6G(SCH_1):M_J_CPU0_SA_DQ(26)
   U25 AD16 MJA_DATA26 GENOA_SP5-SOCKET6096_13568-001,SMLF,IO,DGA^6000030   I159 @T6G_MB_LIB.T6G(SCH_1):PAGE19
   J68  185 DQ26_A SCONN288_DDR506112002KQ-SCONN288_DDR506112002KQ,SMA    I22 @T6G_MB_LIB.T6G(SCH_1):PAGE94

M_J_CPU0_SA_DQ<27> @T6G_MB_LIB.T6G(SCH_1):M_J_CPU0_SA_DQ(27)
   U25 AE17 MJA_DATA27 GENOA_SP5-SOCKET6096_13568-001,SMLF,IO,DGA^6000030   I159 @T6G_MB_LIB.T6G(SCH_1):PAGE19
   J68  187 DQ27_A SCONN288_DDR506112002KQ-SCONN288_DDR506112002KQ,SMA    I22 @T6G_MB_LIB.T6G(SCH_1):PAGE94

M_J_CPU0_SA_DQ<28> @T6G_MB_LIB.T6G(SCH_1):M_J_CPU0_SA_DQ(28)
   U25 AG16 MJA_DATA28 GENOA_SP5-SOCKET6096_13568-001,SMLF,IO,DGA^6000030   I159 @T6G_MB_LIB.T6G(SCH_1):PAGE19
   J68   47 DQ28_A SCONN288_DDR506112002KQ-SCONN288_DDR506112002KQ,SMA    I22 @T6G_MB_LIB.T6G(SCH_1):PAGE94

M_J_CPU0_SA_DQ<29> @T6G_MB_LIB.T6G(SCH_1):M_J_CPU0_SA_DQ(29)
   U25 AH18 MJA_DATA29 GENOA_SP5-SOCKET6096_13568-001,SMLF,IO,DGA^6000030   I159 @T6G_MB_LIB.T6G(SCH_1):PAGE19
   J68   49 DQ29_A SCONN288_DDR506112002KQ-SCONN288_DDR506112002KQ,SMA    I22 @T6G_MB_LIB.T6G(SCH_1):PAGE94

M_J_CPU0_SA_DQ<2> @T6G_MB_LIB.T6G(SCH_1):M_J_CPU0_SA_DQ(2)
   U25  F16 MJA_DATA2 GENOA_SP5-SOCKET6096_13568-001,SMLF,IO,DGA^6000030   I159 @T6G_MB_LIB.T6G(SCH_1):PAGE19
   J68  152  DQ2_A SCONN288_DDR506112002KQ-SCONN288_DDR506112002KQ,SMA    I22 @T6G_MB_LIB.T6G(SCH_1):PAGE94

M_J_CPU0_SA_DQ<30> @T6G_MB_LIB.T6G(SCH_1):M_J_CPU0_SA_DQ(30)
   U25 AH16 MJA_DATA30 GENOA_SP5-SOCKET6096_13568-001,SMLF,IO,DGA^6000030   I159 @T6G_MB_LIB.T6G(SCH_1):PAGE19
   J68  192 DQ30_A SCONN288_DDR506112002KQ-SCONN288_DDR506112002KQ,SMA    I22 @T6G_MB_LIB.T6G(SCH_1):PAGE94

M_J_CPU0_SA_DQ<31> @T6G_MB_LIB.T6G(SCH_1):M_J_CPU0_SA_DQ(31)
   U25 AJ17 MJA_DATA31 GENOA_SP5-SOCKET6096_13568-001,SMLF,IO,DGA^6000030   I159 @T6G_MB_LIB.T6G(SCH_1):PAGE19
   J68  194 DQ31_A SCONN288_DDR506112002KQ-SCONN288_DDR506112002KQ,SMA    I22 @T6G_MB_LIB.T6G(SCH_1):PAGE94

M_J_CPU0_SA_DQ<3> @T6G_MB_LIB.T6G(SCH_1):M_J_CPU0_SA_DQ(3)
   U25  G17 MJA_DATA3 GENOA_SP5-SOCKET6096_13568-001,SMLF,IO,DGA^6000030   I159 @T6G_MB_LIB.T6G(SCH_1):PAGE19
   J68  154  DQ3_A SCONN288_DDR506112002KQ-SCONN288_DDR506112002KQ,SMA    I22 @T6G_MB_LIB.T6G(SCH_1):PAGE94

M_J_CPU0_SA_DQ<4> @T6G_MB_LIB.T6G(SCH_1):M_J_CPU0_SA_DQ(4)
   U25  J16 MJA_DATA4 GENOA_SP5-SOCKET6096_13568-001,SMLF,IO,DGA^6000030   I159 @T6G_MB_LIB.T6G(SCH_1):PAGE19
   J68   14  DQ4_A SCONN288_DDR506112002KQ-SCONN288_DDR506112002KQ,SMA    I22 @T6G_MB_LIB.T6G(SCH_1):PAGE94

M_J_CPU0_SA_DQ<5> @T6G_MB_LIB.T6G(SCH_1):M_J_CPU0_SA_DQ(5)
   U25  K18 MJA_DATA5 GENOA_SP5-SOCKET6096_13568-001,SMLF,IO,DGA^6000030   I159 @T6G_MB_LIB.T6G(SCH_1):PAGE19
   J68   16  DQ5_A SCONN288_DDR506112002KQ-SCONN288_DDR506112002KQ,SMA    I22 @T6G_MB_LIB.T6G(SCH_1):PAGE94

M_J_CPU0_SA_DQ<6> @T6G_MB_LIB.T6G(SCH_1):M_J_CPU0_SA_DQ(6)
   U25  K16 MJA_DATA6 GENOA_SP5-SOCKET6096_13568-001,SMLF,IO,DGA^6000030   I159 @T6G_MB_LIB.T6G(SCH_1):PAGE19
   J68  159  DQ6_A SCONN288_DDR506112002KQ-SCONN288_DDR506112002KQ,SMA    I22 @T6G_MB_LIB.T6G(SCH_1):PAGE94

M_J_CPU0_SA_DQ<7> @T6G_MB_LIB.T6G(SCH_1):M_J_CPU0_SA_DQ(7)
   U25  L17 MJA_DATA7 GENOA_SP5-SOCKET6096_13568-001,SMLF,IO,DGA^6000030   I159 @T6G_MB_LIB.T6G(SCH_1):PAGE19
   J68  161  DQ7_A SCONN288_DDR506112002KQ-SCONN288_DDR506112002KQ,SMA    I22 @T6G_MB_LIB.T6G(SCH_1):PAGE94

M_J_CPU0_SA_DQ<8> @T6G_MB_LIB.T6G(SCH_1):M_J_CPU0_SA_DQ(8)
   U25  L16 MJA_DATA8 GENOA_SP5-SOCKET6096_13568-001,SMLF,IO,DGA^6000030   I159 @T6G_MB_LIB.T6G(SCH_1):PAGE19
   J68   18  DQ8_A SCONN288_DDR506112002KQ-SCONN288_DDR506112002KQ,SMA    I22 @T6G_MB_LIB.T6G(SCH_1):PAGE94

M_J_CPU0_SA_DQ<9> @T6G_MB_LIB.T6G(SCH_1):M_J_CPU0_SA_DQ(9)
   U25  M18 MJA_DATA9 GENOA_SP5-SOCKET6096_13568-001,SMLF,IO,DGA^6000030   I159 @T6G_MB_LIB.T6G(SCH_1):PAGE19
   J68   20  DQ9_A SCONN288_DDR506112002KQ-SCONN288_DDR506112002KQ,SMA    I22 @T6G_MB_LIB.T6G(SCH_1):PAGE94

M_J_CPU0_SA_DQS_DN<0> @T6G_MB_LIB.T6G(SCH_1):M_J_CPU0_SA_DQS_DN(0)
   U25  H16 MJA_DQS_L0 GENOA_SP5-SOCKET6096_13568-001,SMLF,IO,DGA^6000030   I159 @T6G_MB_LIB.T6G(SCH_1):PAGE19
   J68   12 DQS0_A_C SCONN288_DDR506112002KQ-SCONN288_DDR506112002KQ,SMA   I236 @T6G_MB_LIB.T6G(SCH_1):PAGE94

M_J_CPU0_SA_DQS_DN<1> @T6G_MB_LIB.T6G(SCH_1):M_J_CPU0_SA_DQS_DN(1)
   U25  P16 MJA_DQS_L1 GENOA_SP5-SOCKET6096_13568-001,SMLF,IO,DGA^6000030   I159 @T6G_MB_LIB.T6G(SCH_1):PAGE19
   J68   23 DQS1_A_C SCONN288_DDR506112002KQ-SCONN288_DDR506112002KQ,SMA   I236 @T6G_MB_LIB.T6G(SCH_1):PAGE94

M_J_CPU0_SA_DQS_DN<2> @T6G_MB_LIB.T6G(SCH_1):M_J_CPU0_SA_DQS_DN(2)
   U25  Y16 MJA_DQS_L2 GENOA_SP5-SOCKET6096_13568-001,SMLF,IO,DGA^6000030   I159 @T6G_MB_LIB.T6G(SCH_1):PAGE19
   J68   34 DQS2_A_C SCONN288_DDR506112002KQ-SCONN288_DDR506112002KQ,SMA   I236 @T6G_MB_LIB.T6G(SCH_1):PAGE94

M_J_CPU0_SA_DQS_DN<3> @T6G_MB_LIB.T6G(SCH_1):M_J_CPU0_SA_DQS_DN(3)
   U25 AF16 MJA_DQS_L3 GENOA_SP5-SOCKET6096_13568-001,SMLF,IO,DGA^6000030   I159 @T6G_MB_LIB.T6G(SCH_1):PAGE19
   J68   45 DQS3_A_C SCONN288_DDR506112002KQ-SCONN288_DDR506112002KQ,SMA   I236 @T6G_MB_LIB.T6G(SCH_1):PAGE94

M_J_CPU0_SA_DQS_DN<4> @T6G_MB_LIB.T6G(SCH_1):M_J_CPU0_SA_DQS_DN(4)
   U25 AM16 MJA_DQS_L4 GENOA_SP5-SOCKET6096_13568-001,SMLF,IO,DGA^6000030   I159 @T6G_MB_LIB.T6G(SCH_1):PAGE19
   J68   56 DQS4_A_C SCONN288_DDR506112002KQ-SCONN288_DDR506112002KQ,SMA   I236 @T6G_MB_LIB.T6G(SCH_1):PAGE94

M_J_CPU0_SA_DQS_DN<5> @T6G_MB_LIB.T6G(SCH_1):M_J_CPU0_SA_DQS_DN(5)
   U25  H18 MJA_DQS_L5 GENOA_SP5-SOCKET6096_13568-001,SMLF,IO,DGA^6000030   I159 @T6G_MB_LIB.T6G(SCH_1):PAGE19
   J68  156 DQS5_A_C||TDQS5_A_C||DQS5_A_T||TDQS5_A_T SCONN288_DDR506112002KQ-SCONN288_DDR506112002KQ,SMA   I236 @T6G_MB_LIB.T6G(SCH_1):PAGE94

M_J_CPU0_SA_DQS_DN<6> @T6G_MB_LIB.T6G(SCH_1):M_J_CPU0_SA_DQS_DN(6)
   U25  P18 MJA_DQS_L6 GENOA_SP5-SOCKET6096_13568-001,SMLF,IO,DGA^6000030   I159 @T6G_MB_LIB.T6G(SCH_1):PAGE19
   J68  167 DQS6_A_C||TDQS6_A_C||DQS6_A_T||TDQS6_A_T SCONN288_DDR506112002KQ-SCONN288_DDR506112002KQ,SMA   I236 @T6G_MB_LIB.T6G(SCH_1):PAGE94

M_J_CPU0_SA_DQS_DN<7> @T6G_MB_LIB.T6G(SCH_1):M_J_CPU0_SA_DQS_DN(7)
   U25  Y18 MJA_DQS_L7 GENOA_SP5-SOCKET6096_13568-001,SMLF,IO,DGA^6000030   I159 @T6G_MB_LIB.T6G(SCH_1):PAGE19
   J68  178 DQS7_A_C||TDQS7_A_C SCONN288_DDR506112002KQ-SCONN288_DDR506112002KQ,SMA   I236 @T6G_MB_LIB.T6G(SCH_1):PAGE94

M_J_CPU0_SA_DQS_DN<8> @T6G_MB_LIB.T6G(SCH_1):M_J_CPU0_SA_DQS_DN(8)
   U25 AF18 MJA_DQS_L8 GENOA_SP5-SOCKET6096_13568-001,SMLF,IO,DGA^6000030   I159 @T6G_MB_LIB.T6G(SCH_1):PAGE19
   J68  189 DQS8_A_C||TDQS8_A_C SCONN288_DDR506112002KQ-SCONN288_DDR506112002KQ,SMA   I236 @T6G_MB_LIB.T6G(SCH_1):PAGE94

M_J_CPU0_SA_DQS_DN<9> @T6G_MB_LIB.T6G(SCH_1):M_J_CPU0_SA_DQS_DN(9)
   U25 AM18 MJA_DQS_L9 GENOA_SP5-SOCKET6096_13568-001,SMLF,IO,DGA^6000030   I159 @T6G_MB_LIB.T6G(SCH_1):PAGE19
   J68  200 DQS9_A_C||TDQS9_A_C SCONN288_DDR506112002KQ-SCONN288_DDR506112002KQ,SMA   I236 @T6G_MB_LIB.T6G(SCH_1):PAGE94

M_J_CPU0_SA_DQS_DP<0> @T6G_MB_LIB.T6G(SCH_1):M_J_CPU0_SA_DQS_DP(0)
   U25  G16 MJA_DQS_H0 GENOA_SP5-SOCKET6096_13568-001,SMLF,IO,DGA^6000030   I159 @T6G_MB_LIB.T6G(SCH_1):PAGE19
   J68   11 DQS0_A_T SCONN288_DDR506112002KQ-SCONN288_DDR506112002KQ,SMA   I236 @T6G_MB_LIB.T6G(SCH_1):PAGE94

M_J_CPU0_SA_DQS_DP<1> @T6G_MB_LIB.T6G(SCH_1):M_J_CPU0_SA_DQS_DP(1)
   U25  N16 MJA_DQS_H1 GENOA_SP5-SOCKET6096_13568-001,SMLF,IO,DGA^6000030   I159 @T6G_MB_LIB.T6G(SCH_1):PAGE19
   J68   22 DQS1_A_T SCONN288_DDR506112002KQ-SCONN288_DDR506112002KQ,SMA   I236 @T6G_MB_LIB.T6G(SCH_1):PAGE94

M_J_CPU0_SA_DQS_DP<2> @T6G_MB_LIB.T6G(SCH_1):M_J_CPU0_SA_DQS_DP(2)
   U25  W16 MJA_DQS_H2 GENOA_SP5-SOCKET6096_13568-001,SMLF,IO,DGA^6000030   I159 @T6G_MB_LIB.T6G(SCH_1):PAGE19
   J68   33 DQS2_A_T SCONN288_DDR506112002KQ-SCONN288_DDR506112002KQ,SMA   I236 @T6G_MB_LIB.T6G(SCH_1):PAGE94

M_J_CPU0_SA_DQS_DP<3> @T6G_MB_LIB.T6G(SCH_1):M_J_CPU0_SA_DQS_DP(3)
   U25 AE16 MJA_DQS_H3 GENOA_SP5-SOCKET6096_13568-001,SMLF,IO,DGA^6000030   I159 @T6G_MB_LIB.T6G(SCH_1):PAGE19
   J68   44 DQS3_A_T SCONN288_DDR506112002KQ-SCONN288_DDR506112002KQ,SMA   I236 @T6G_MB_LIB.T6G(SCH_1):PAGE94

M_J_CPU0_SA_DQS_DP<4> @T6G_MB_LIB.T6G(SCH_1):M_J_CPU0_SA_DQS_DP(4)
   U25 AL16 MJA_DQS_H4 GENOA_SP5-SOCKET6096_13568-001,SMLF,IO,DGA^6000030   I159 @T6G_MB_LIB.T6G(SCH_1):PAGE19
   J68   55 DQS4_A_T SCONN288_DDR506112002KQ-SCONN288_DDR506112002KQ,SMA   I236 @T6G_MB_LIB.T6G(SCH_1):PAGE94

M_J_CPU0_SA_DQS_DP<5> @T6G_MB_LIB.T6G(SCH_1):M_J_CPU0_SA_DQS_DP(5)
   U25  J17 MJA_DQS_H5 GENOA_SP5-SOCKET6096_13568-001,SMLF,IO,DGA^6000030   I159 @T6G_MB_LIB.T6G(SCH_1):PAGE19
   J68  157 DQS5_A_T||TDQS5_A_T SCONN288_DDR506112002KQ-SCONN288_DDR506112002KQ,SMA   I236 @T6G_MB_LIB.T6G(SCH_1):PAGE94

M_J_CPU0_SA_DQS_DP<6> @T6G_MB_LIB.T6G(SCH_1):M_J_CPU0_SA_DQS_DP(6)
   U25  R17 MJA_DQS_H6 GENOA_SP5-SOCKET6096_13568-001,SMLF,IO,DGA^6000030   I159 @T6G_MB_LIB.T6G(SCH_1):PAGE19
   J68  168 DQS6_A_T||TDQS6_A_T SCONN288_DDR506112002KQ-SCONN288_DDR506112002KQ,SMA   I236 @T6G_MB_LIB.T6G(SCH_1):PAGE94

M_J_CPU0_SA_DQS_DP<7> @T6G_MB_LIB.T6G(SCH_1):M_J_CPU0_SA_DQS_DP(7)
   U25 AA17 MJA_DQS_H7 GENOA_SP5-SOCKET6096_13568-001,SMLF,IO,DGA^6000030   I159 @T6G_MB_LIB.T6G(SCH_1):PAGE19
   J68  179 DQS7_A_T||TDQS7_A_T SCONN288_DDR506112002KQ-SCONN288_DDR506112002KQ,SMA   I236 @T6G_MB_LIB.T6G(SCH_1):PAGE94

M_J_CPU0_SA_DQS_DP<8> @T6G_MB_LIB.T6G(SCH_1):M_J_CPU0_SA_DQS_DP(8)
   U25 AG17 MJA_DQS_H8 GENOA_SP5-SOCKET6096_13568-001,SMLF,IO,DGA^6000030   I159 @T6G_MB_LIB.T6G(SCH_1):PAGE19
   J68  190 DQS8_A_T||TDQS8_A_T SCONN288_DDR506112002KQ-SCONN288_DDR506112002KQ,SMA   I236 @T6G_MB_LIB.T6G(SCH_1):PAGE94

M_J_CPU0_SA_DQS_DP<9> @T6G_MB_LIB.T6G(SCH_1):M_J_CPU0_SA_DQS_DP(9)
   U25 AN17 MJA_DQS_H9 GENOA_SP5-SOCKET6096_13568-001,SMLF,IO,DGA^6000030   I159 @T6G_MB_LIB.T6G(SCH_1):PAGE19
   J68  201 DQS9_A_T||TDQS9_A_T SCONN288_DDR506112002KQ-SCONN288_DDR506112002KQ,SMA   I236 @T6G_MB_LIB.T6G(SCH_1):PAGE94

M_J_CPU0_SA_PAR @T6G_MB_LIB.T6G(SCH_1):M_J_CPU0_SA_PAR
   U25 BC17 MJA_PAR GENOA_SP5-SOCKET6096_13568-001,SMLF,IO,DGA^6000030   I159 @T6G_MB_LIB.T6G(SCH_1):PAGE19
   J68   74  PAR_A SCONN288_DDR506112002KQ-SCONN288_DDR506112002KQ,SMA    I22 @T6G_MB_LIB.T6G(SCH_1):PAGE94

M_J_CPU0_SA_RSP<0> @T6G_MB_LIB.T6G(SCH_1):M_J_CPU0_SA_RSP(0)
   U25 BN17 MJA0_RSP_L GENOA_SP5-SOCKET6096_13568-001,SMLF,IO,DGA^6000030   I159 @T6G_MB_LIB.T6G(SCH_1):PAGE19
   J68   86 LBD||RSP_A_N SCONN288_DDR506112002KQ-SCONN288_DDR506112002KQ,SMA    I22 @T6G_MB_LIB.T6G(SCH_1):PAGE94

M_J_CPU0_SB_CA<0> @T6G_MB_LIB.T6G(SCH_1):M_J_CPU0_SB_CA(0)
   U25 BG17 MJB_CA0 GENOA_SP5-SOCKET6096_13568-001,SMLF,IO,DGA^6000030   I159 @T6G_MB_LIB.T6G(SCH_1):PAGE19
   J68   76  CA0_B SCONN288_DDR506112002KQ-SCONN288_DDR506112002KQ,SMA    I22 @T6G_MB_LIB.T6G(SCH_1):PAGE94

M_J_CPU0_SB_CA<1> @T6G_MB_LIB.T6G(SCH_1):M_J_CPU0_SB_CA(1)
   U25 BH18 MJB_CA1 GENOA_SP5-SOCKET6096_13568-001,SMLF,IO,DGA^6000030   I159 @T6G_MB_LIB.T6G(SCH_1):PAGE19
   J68  221  CA1_B SCONN288_DDR506112002KQ-SCONN288_DDR506112002KQ,SMA    I22 @T6G_MB_LIB.T6G(SCH_1):PAGE94

M_J_CPU0_SB_CA<2> @T6G_MB_LIB.T6G(SCH_1):M_J_CPU0_SB_CA(2)
   U25 BH16 MJB_CA2 GENOA_SP5-SOCKET6096_13568-001,SMLF,IO,DGA^6000030   I159 @T6G_MB_LIB.T6G(SCH_1):PAGE19
   J68   78  CA2_B SCONN288_DDR506112002KQ-SCONN288_DDR506112002KQ,SMA    I22 @T6G_MB_LIB.T6G(SCH_1):PAGE94

M_J_CPU0_SB_CA<3> @T6G_MB_LIB.T6G(SCH_1):M_J_CPU0_SB_CA(3)
   U25 BJ16 MJB_CA3 GENOA_SP5-SOCKET6096_13568-001,SMLF,IO,DGA^6000030   I159 @T6G_MB_LIB.T6G(SCH_1):PAGE19
   J68  223  CA3_B SCONN288_DDR506112002KQ-SCONN288_DDR506112002KQ,SMA    I22 @T6G_MB_LIB.T6G(SCH_1):PAGE94

M_J_CPU0_SB_CA<4> @T6G_MB_LIB.T6G(SCH_1):M_J_CPU0_SB_CA(4)
   U25 BJ17 MJB_CA4 GENOA_SP5-SOCKET6096_13568-001,SMLF,IO,DGA^6000030   I159 @T6G_MB_LIB.T6G(SCH_1):PAGE19
   J68   80  CA4_B SCONN288_DDR506112002KQ-SCONN288_DDR506112002KQ,SMA    I22 @T6G_MB_LIB.T6G(SCH_1):PAGE94

M_J_CPU0_SB_CA<5> @T6G_MB_LIB.T6G(SCH_1):M_J_CPU0_SB_CA(5)
   U25 BK18 MJB_CA5 GENOA_SP5-SOCKET6096_13568-001,SMLF,IO,DGA^6000030   I159 @T6G_MB_LIB.T6G(SCH_1):PAGE19
   J68  225  CA5_B SCONN288_DDR506112002KQ-SCONN288_DDR506112002KQ,SMA    I22 @T6G_MB_LIB.T6G(SCH_1):PAGE94

M_J_CPU0_SB_CA<6> @T6G_MB_LIB.T6G(SCH_1):M_J_CPU0_SB_CA(6)
   U25 BK16 MJB_CA6 GENOA_SP5-SOCKET6096_13568-001,SMLF,IO,DGA^6000030   I159 @T6G_MB_LIB.T6G(SCH_1):PAGE19
   J68   82  CA6_B SCONN288_DDR506112002KQ-SCONN288_DDR506112002KQ,SMA    I22 @T6G_MB_LIB.T6G(SCH_1):PAGE94

M_J_CPU0_SB_CB<0> @T6G_MB_LIB.T6G(SCH_1):M_J_CPU0_SB_CB(0)
   U25 BY16 MJB_CHECK0 GENOA_SP5-SOCKET6096_13568-001,SMLF,IO,DGA^6000030   I159 @T6G_MB_LIB.T6G(SCH_1):PAGE19
   J68   96  CB0_B SCONN288_DDR506112002KQ-SCONN288_DDR506112002KQ,SMA    I22 @T6G_MB_LIB.T6G(SCH_1):PAGE94

M_J_CPU0_SB_CB<1> @T6G_MB_LIB.T6G(SCH_1):M_J_CPU0_SB_CB(1)
   U25 CA17 MJB_CHECK1 GENOA_SP5-SOCKET6096_13568-001,SMLF,IO,DGA^6000030   I159 @T6G_MB_LIB.T6G(SCH_1):PAGE19
   J68   98  CB1_B SCONN288_DDR506112002KQ-SCONN288_DDR506112002KQ,SMA    I22 @T6G_MB_LIB.T6G(SCH_1):PAGE94

M_J_CPU0_SB_CB<2> @T6G_MB_LIB.T6G(SCH_1):M_J_CPU0_SB_CB(2)
   U25 CA16 MJB_CHECK2 GENOA_SP5-SOCKET6096_13568-001,SMLF,IO,DGA^6000030   I159 @T6G_MB_LIB.T6G(SCH_1):PAGE19
   J68  241  CB2_B SCONN288_DDR506112002KQ-SCONN288_DDR506112002KQ,SMA    I22 @T6G_MB_LIB.T6G(SCH_1):PAGE94

M_J_CPU0_SB_CB<3> @T6G_MB_LIB.T6G(SCH_1):M_J_CPU0_SB_CB(3)
   U25 CB18 MJB_CHECK3 GENOA_SP5-SOCKET6096_13568-001,SMLF,IO,DGA^6000030   I159 @T6G_MB_LIB.T6G(SCH_1):PAGE19
   J68  243  CB3_B SCONN288_DDR506112002KQ-SCONN288_DDR506112002KQ,SMA    I22 @T6G_MB_LIB.T6G(SCH_1):PAGE94

M_J_CPU0_SB_CB<4> @T6G_MB_LIB.T6G(SCH_1):M_J_CPU0_SB_CB(4)
   U25 BT16 MJB_CHECK4 GENOA_SP5-SOCKET6096_13568-001,SMLF,IO,DGA^6000030   I159 @T6G_MB_LIB.T6G(SCH_1):PAGE19
   J68   89  CB4_B SCONN288_DDR506112002KQ-SCONN288_DDR506112002KQ,SMA    I22 @T6G_MB_LIB.T6G(SCH_1):PAGE94

M_J_CPU0_SB_CB<5> @T6G_MB_LIB.T6G(SCH_1):M_J_CPU0_SB_CB(5)
   U25 BU17 MJB_CHECK5 GENOA_SP5-SOCKET6096_13568-001,SMLF,IO,DGA^6000030   I159 @T6G_MB_LIB.T6G(SCH_1):PAGE19
   J68   91  CB5_B SCONN288_DDR506112002KQ-SCONN288_DDR506112002KQ,SMA    I22 @T6G_MB_LIB.T6G(SCH_1):PAGE94

M_J_CPU0_SB_CB<6> @T6G_MB_LIB.T6G(SCH_1):M_J_CPU0_SB_CB(6)
   U25 BU16 MJB_CHECK6 GENOA_SP5-SOCKET6096_13568-001,SMLF,IO,DGA^6000030   I159 @T6G_MB_LIB.T6G(SCH_1):PAGE19
   J68  234  CB6_B SCONN288_DDR506112002KQ-SCONN288_DDR506112002KQ,SMA    I22 @T6G_MB_LIB.T6G(SCH_1):PAGE94

M_J_CPU0_SB_CB<7> @T6G_MB_LIB.T6G(SCH_1):M_J_CPU0_SB_CB(7)
   U25 BV18 MJB_CHECK7 GENOA_SP5-SOCKET6096_13568-001,SMLF,IO,DGA^6000030   I159 @T6G_MB_LIB.T6G(SCH_1):PAGE19
   J68  236  CB7_B SCONN288_DDR506112002KQ-SCONN288_DDR506112002KQ,SMA    I22 @T6G_MB_LIB.T6G(SCH_1):PAGE94

M_J_CPU0_SB_CS_N<0> @T6G_MB_LIB.T6G(SCH_1):M_J_CPU0_SB_CS_N(0)
   U25 BM18 MJB0_CS_L0 GENOA_SP5-SOCKET6096_13568-001,SMLF,IO,DGA^6000030   I159 @T6G_MB_LIB.T6G(SCH_1):PAGE19
   J68   84 CS0_B_N SCONN288_DDR506112002KQ-SCONN288_DDR506112002KQ,SMA    I22 @T6G_MB_LIB.T6G(SCH_1):PAGE94

M_J_CPU0_SB_CS_N<1> @T6G_MB_LIB.T6G(SCH_1):M_J_CPU0_SB_CS_N(1)
   U25 BN16 MJB0_CS_L1 GENOA_SP5-SOCKET6096_13568-001,SMLF,IO,DGA^6000030   I159 @T6G_MB_LIB.T6G(SCH_1):PAGE19
   J68  229 CS1_B_N SCONN288_DDR506112002KQ-SCONN288_DDR506112002KQ,SMA    I22 @T6G_MB_LIB.T6G(SCH_1):PAGE94

M_J_CPU0_SB_DQ<0> @T6G_MB_LIB.T6G(SCH_1):M_J_CPU0_SB_DQ(0)
   U25 CB16 MJB_DATA0 GENOA_SP5-SOCKET6096_13568-001,SMLF,IO,DGA^6000030   I159 @T6G_MB_LIB.T6G(SCH_1):PAGE19
   J68  100  DQ0_B SCONN288_DDR506112002KQ-SCONN288_DDR506112002KQ,SMA    I22 @T6G_MB_LIB.T6G(SCH_1):PAGE94

M_J_CPU0_SB_DQ<10> @T6G_MB_LIB.T6G(SCH_1):M_J_CPU0_SB_DQ(10)
   U25 CJ16 MJB_DATA10 GENOA_SP5-SOCKET6096_13568-001,SMLF,IO,DGA^6000030   I159 @T6G_MB_LIB.T6G(SCH_1):PAGE19
   J68  256 DQ10_B SCONN288_DDR506112002KQ-SCONN288_DDR506112002KQ,SMA    I22 @T6G_MB_LIB.T6G(SCH_1):PAGE94

M_J_CPU0_SB_DQ<11> @T6G_MB_LIB.T6G(SCH_1):M_J_CPU0_SB_DQ(11)
   U25 CK18 MJB_DATA11 GENOA_SP5-SOCKET6096_13568-001,SMLF,IO,DGA^6000030   I159 @T6G_MB_LIB.T6G(SCH_1):PAGE19
   J68  258 DQ11_B SCONN288_DDR506112002KQ-SCONN288_DDR506112002KQ,SMA    I22 @T6G_MB_LIB.T6G(SCH_1):PAGE94

M_J_CPU0_SB_DQ<12> @T6G_MB_LIB.T6G(SCH_1):M_J_CPU0_SB_DQ(12)
   U25 CM16 MJB_DATA12 GENOA_SP5-SOCKET6096_13568-001,SMLF,IO,DGA^6000030   I159 @T6G_MB_LIB.T6G(SCH_1):PAGE19
   J68  118 DQ12_B SCONN288_DDR506112002KQ-SCONN288_DDR506112002KQ,SMA    I22 @T6G_MB_LIB.T6G(SCH_1):PAGE94

M_J_CPU0_SB_DQ<13> @T6G_MB_LIB.T6G(SCH_1):M_J_CPU0_SB_DQ(13)
   U25 CN17 MJB_DATA13 GENOA_SP5-SOCKET6096_13568-001,SMLF,IO,DGA^6000030   I159 @T6G_MB_LIB.T6G(SCH_1):PAGE19
   J68  120 DQ13_B SCONN288_DDR506112002KQ-SCONN288_DDR506112002KQ,SMA    I22 @T6G_MB_LIB.T6G(SCH_1):PAGE94

M_J_CPU0_SB_DQ<14> @T6G_MB_LIB.T6G(SCH_1):M_J_CPU0_SB_DQ(14)
   U25 CN16 MJB_DATA14 GENOA_SP5-SOCKET6096_13568-001,SMLF,IO,DGA^6000030   I159 @T6G_MB_LIB.T6G(SCH_1):PAGE19
   J68  263 DQ14_B SCONN288_DDR506112002KQ-SCONN288_DDR506112002KQ,SMA    I22 @T6G_MB_LIB.T6G(SCH_1):PAGE94

M_J_CPU0_SB_DQ<15> @T6G_MB_LIB.T6G(SCH_1):M_J_CPU0_SB_DQ(15)
   U25 CP18 MJB_DATA15 GENOA_SP5-SOCKET6096_13568-001,SMLF,IO,DGA^6000030   I159 @T6G_MB_LIB.T6G(SCH_1):PAGE19
   J68  265 DQ15_B SCONN288_DDR506112002KQ-SCONN288_DDR506112002KQ,SMA    I22 @T6G_MB_LIB.T6G(SCH_1):PAGE94

M_J_CPU0_SB_DQ<16> @T6G_MB_LIB.T6G(SCH_1):M_J_CPU0_SB_DQ(16)
   U25 CP16 MJB_DATA16 GENOA_SP5-SOCKET6096_13568-001,SMLF,IO,DGA^6000030   I159 @T6G_MB_LIB.T6G(SCH_1):PAGE19
   J68  122 DQ16_B SCONN288_DDR506112002KQ-SCONN288_DDR506112002KQ,SMA    I22 @T6G_MB_LIB.T6G(SCH_1):PAGE94

M_J_CPU0_SB_DQ<17> @T6G_MB_LIB.T6G(SCH_1):M_J_CPU0_SB_DQ(17)
   U25 CR17 MJB_DATA17 GENOA_SP5-SOCKET6096_13568-001,SMLF,IO,DGA^6000030   I159 @T6G_MB_LIB.T6G(SCH_1):PAGE19
   J68  124 DQ17_B SCONN288_DDR506112002KQ-SCONN288_DDR506112002KQ,SMA    I22 @T6G_MB_LIB.T6G(SCH_1):PAGE94

M_J_CPU0_SB_DQ<18> @T6G_MB_LIB.T6G(SCH_1):M_J_CPU0_SB_DQ(18)
   U25 CR16 MJB_DATA18 GENOA_SP5-SOCKET6096_13568-001,SMLF,IO,DGA^6000030   I159 @T6G_MB_LIB.T6G(SCH_1):PAGE19
   J68  267 DQ18_B SCONN288_DDR506112002KQ-SCONN288_DDR506112002KQ,SMA    I22 @T6G_MB_LIB.T6G(SCH_1):PAGE94

M_J_CPU0_SB_DQ<19> @T6G_MB_LIB.T6G(SCH_1):M_J_CPU0_SB_DQ(19)
   U25 CT18 MJB_DATA19 GENOA_SP5-SOCKET6096_13568-001,SMLF,IO,DGA^6000030   I159 @T6G_MB_LIB.T6G(SCH_1):PAGE19
   J68  269 DQ19_B SCONN288_DDR506112002KQ-SCONN288_DDR506112002KQ,SMA    I22 @T6G_MB_LIB.T6G(SCH_1):PAGE94

M_J_CPU0_SB_DQ<1> @T6G_MB_LIB.T6G(SCH_1):M_J_CPU0_SB_DQ(1)
   U25 CC17 MJB_DATA1 GENOA_SP5-SOCKET6096_13568-001,SMLF,IO,DGA^6000030   I159 @T6G_MB_LIB.T6G(SCH_1):PAGE19
   J68  102  DQ1_B SCONN288_DDR506112002KQ-SCONN288_DDR506112002KQ,SMA    I22 @T6G_MB_LIB.T6G(SCH_1):PAGE94

M_J_CPU0_SB_DQ<20> @T6G_MB_LIB.T6G(SCH_1):M_J_CPU0_SB_DQ(20)
   U25 CV16 MJB_DATA20 GENOA_SP5-SOCKET6096_13568-001,SMLF,IO,DGA^6000030   I159 @T6G_MB_LIB.T6G(SCH_1):PAGE19
   J68  129 DQ20_B SCONN288_DDR506112002KQ-SCONN288_DDR506112002KQ,SMA    I22 @T6G_MB_LIB.T6G(SCH_1):PAGE94

M_J_CPU0_SB_DQ<21> @T6G_MB_LIB.T6G(SCH_1):M_J_CPU0_SB_DQ(21)
   U25 CW17 MJB_DATA21 GENOA_SP5-SOCKET6096_13568-001,SMLF,IO,DGA^6000030   I159 @T6G_MB_LIB.T6G(SCH_1):PAGE19
   J68  131 DQ21_B SCONN288_DDR506112002KQ-SCONN288_DDR506112002KQ,SMA    I22 @T6G_MB_LIB.T6G(SCH_1):PAGE94

M_J_CPU0_SB_DQ<22> @T6G_MB_LIB.T6G(SCH_1):M_J_CPU0_SB_DQ(22)
   U25 CW16 MJB_DATA22 GENOA_SP5-SOCKET6096_13568-001,SMLF,IO,DGA^6000030   I159 @T6G_MB_LIB.T6G(SCH_1):PAGE19
   J68  274 DQ22_B SCONN288_DDR506112002KQ-SCONN288_DDR506112002KQ,SMA    I22 @T6G_MB_LIB.T6G(SCH_1):PAGE94

M_J_CPU0_SB_DQ<23> @T6G_MB_LIB.T6G(SCH_1):M_J_CPU0_SB_DQ(23)
   U25 CY18 MJB_DATA23 GENOA_SP5-SOCKET6096_13568-001,SMLF,IO,DGA^6000030   I159 @T6G_MB_LIB.T6G(SCH_1):PAGE19
   J68  276 DQ23_B SCONN288_DDR506112002KQ-SCONN288_DDR506112002KQ,SMA    I22 @T6G_MB_LIB.T6G(SCH_1):PAGE94

M_J_CPU0_SB_DQ<24> @T6G_MB_LIB.T6G(SCH_1):M_J_CPU0_SB_DQ(24)
   U25 CY16 MJB_DATA24 GENOA_SP5-SOCKET6096_13568-001,SMLF,IO,DGA^6000030   I159 @T6G_MB_LIB.T6G(SCH_1):PAGE19
   J68  133 DQ24_B SCONN288_DDR506112002KQ-SCONN288_DDR506112002KQ,SMA    I22 @T6G_MB_LIB.T6G(SCH_1):PAGE94

M_J_CPU0_SB_DQ<25> @T6G_MB_LIB.T6G(SCH_1):M_J_CPU0_SB_DQ(25)
   U25 DA17 MJB_DATA25 GENOA_SP5-SOCKET6096_13568-001,SMLF,IO,DGA^6000030   I159 @T6G_MB_LIB.T6G(SCH_1):PAGE19
   J68  135 DQ25_B SCONN288_DDR506112002KQ-SCONN288_DDR506112002KQ,SMA    I22 @T6G_MB_LIB.T6G(SCH_1):PAGE94

M_J_CPU0_SB_DQ<26> @T6G_MB_LIB.T6G(SCH_1):M_J_CPU0_SB_DQ(26)
   U25 DA16 MJB_DATA26 GENOA_SP5-SOCKET6096_13568-001,SMLF,IO,DGA^6000030   I159 @T6G_MB_LIB.T6G(SCH_1):PAGE19
   J68  278 DQ26_B SCONN288_DDR506112002KQ-SCONN288_DDR506112002KQ,SMA    I22 @T6G_MB_LIB.T6G(SCH_1):PAGE94

M_J_CPU0_SB_DQ<27> @T6G_MB_LIB.T6G(SCH_1):M_J_CPU0_SB_DQ(27)
   U25 DB18 MJB_DATA27 GENOA_SP5-SOCKET6096_13568-001,SMLF,IO,DGA^6000030   I159 @T6G_MB_LIB.T6G(SCH_1):PAGE19
   J68  280 DQ27_B SCONN288_DDR506112002KQ-SCONN288_DDR506112002KQ,SMA    I22 @T6G_MB_LIB.T6G(SCH_1):PAGE94

M_J_CPU0_SB_DQ<28> @T6G_MB_LIB.T6G(SCH_1):M_J_CPU0_SB_DQ(28)
   U25 DD16 MJB_DATA28 GENOA_SP5-SOCKET6096_13568-001,SMLF,IO,DGA^6000030   I159 @T6G_MB_LIB.T6G(SCH_1):PAGE19
   J68  140 DQ28_B SCONN288_DDR506112002KQ-SCONN288_DDR506112002KQ,SMA    I22 @T6G_MB_LIB.T6G(SCH_1):PAGE94

M_J_CPU0_SB_DQ<29> @T6G_MB_LIB.T6G(SCH_1):M_J_CPU0_SB_DQ(29)
   U25 DE17 MJB_DATA29 GENOA_SP5-SOCKET6096_13568-001,SMLF,IO,DGA^6000030   I159 @T6G_MB_LIB.T6G(SCH_1):PAGE19
   J68  142 DQ29_B SCONN288_DDR506112002KQ-SCONN288_DDR506112002KQ,SMA    I22 @T6G_MB_LIB.T6G(SCH_1):PAGE94

M_J_CPU0_SB_DQ<2> @T6G_MB_LIB.T6G(SCH_1):M_J_CPU0_SB_DQ(2)
   U25 CC16 MJB_DATA2 GENOA_SP5-SOCKET6096_13568-001,SMLF,IO,DGA^6000030   I159 @T6G_MB_LIB.T6G(SCH_1):PAGE19
   J68  245  DQ2_B SCONN288_DDR506112002KQ-SCONN288_DDR506112002KQ,SMA    I22 @T6G_MB_LIB.T6G(SCH_1):PAGE94

M_J_CPU0_SB_DQ<30> @T6G_MB_LIB.T6G(SCH_1):M_J_CPU0_SB_DQ(30)
   U25 DE16 MJB_DATA30 GENOA_SP5-SOCKET6096_13568-001,SMLF,IO,DGA^6000030   I159 @T6G_MB_LIB.T6G(SCH_1):PAGE19
   J68  285 DQ30_B SCONN288_DDR506112002KQ-SCONN288_DDR506112002KQ,SMA    I22 @T6G_MB_LIB.T6G(SCH_1):PAGE94

M_J_CPU0_SB_DQ<31> @T6G_MB_LIB.T6G(SCH_1):M_J_CPU0_SB_DQ(31)
   U25 DF16 MJB_DATA31 GENOA_SP5-SOCKET6096_13568-001,SMLF,IO,DGA^6000030   I159 @T6G_MB_LIB.T6G(SCH_1):PAGE19
   J68  287 DQ31_B SCONN288_DDR506112002KQ-SCONN288_DDR506112002KQ,SMA    I22 @T6G_MB_LIB.T6G(SCH_1):PAGE94

M_J_CPU0_SB_DQ<3> @T6G_MB_LIB.T6G(SCH_1):M_J_CPU0_SB_DQ(3)
   U25 CD18 MJB_DATA3 GENOA_SP5-SOCKET6096_13568-001,SMLF,IO,DGA^6000030   I159 @T6G_MB_LIB.T6G(SCH_1):PAGE19
   J68  247  DQ3_B SCONN288_DDR506112002KQ-SCONN288_DDR506112002KQ,SMA    I22 @T6G_MB_LIB.T6G(SCH_1):PAGE94

M_J_CPU0_SB_DQ<4> @T6G_MB_LIB.T6G(SCH_1):M_J_CPU0_SB_DQ(4)
   U25 CF16 MJB_DATA4 GENOA_SP5-SOCKET6096_13568-001,SMLF,IO,DGA^6000030   I159 @T6G_MB_LIB.T6G(SCH_1):PAGE19
   J68  107  DQ4_B SCONN288_DDR506112002KQ-SCONN288_DDR506112002KQ,SMA    I22 @T6G_MB_LIB.T6G(SCH_1):PAGE94

M_J_CPU0_SB_DQ<5> @T6G_MB_LIB.T6G(SCH_1):M_J_CPU0_SB_DQ(5)
   U25 CG17 MJB_DATA5 GENOA_SP5-SOCKET6096_13568-001,SMLF,IO,DGA^6000030   I159 @T6G_MB_LIB.T6G(SCH_1):PAGE19
   J68  109  DQ5_B SCONN288_DDR506112002KQ-SCONN288_DDR506112002KQ,SMA    I22 @T6G_MB_LIB.T6G(SCH_1):PAGE94

M_J_CPU0_SB_DQ<6> @T6G_MB_LIB.T6G(SCH_1):M_J_CPU0_SB_DQ(6)
   U25 CG16 MJB_DATA6 GENOA_SP5-SOCKET6096_13568-001,SMLF,IO,DGA^6000030   I159 @T6G_MB_LIB.T6G(SCH_1):PAGE19
   J68  252  DQ6_B SCONN288_DDR506112002KQ-SCONN288_DDR506112002KQ,SMA    I22 @T6G_MB_LIB.T6G(SCH_1):PAGE94

M_J_CPU0_SB_DQ<7> @T6G_MB_LIB.T6G(SCH_1):M_J_CPU0_SB_DQ(7)
   U25 CH18 MJB_DATA7 GENOA_SP5-SOCKET6096_13568-001,SMLF,IO,DGA^6000030   I159 @T6G_MB_LIB.T6G(SCH_1):PAGE19
   J68  254  DQ7_B SCONN288_DDR506112002KQ-SCONN288_DDR506112002KQ,SMA    I22 @T6G_MB_LIB.T6G(SCH_1):PAGE94

M_J_CPU0_SB_DQ<8> @T6G_MB_LIB.T6G(SCH_1):M_J_CPU0_SB_DQ(8)
   U25 CH16 MJB_DATA8 GENOA_SP5-SOCKET6096_13568-001,SMLF,IO,DGA^6000030   I159 @T6G_MB_LIB.T6G(SCH_1):PAGE19
   J68  111  DQ8_B SCONN288_DDR506112002KQ-SCONN288_DDR506112002KQ,SMA    I22 @T6G_MB_LIB.T6G(SCH_1):PAGE94

M_J_CPU0_SB_DQ<9> @T6G_MB_LIB.T6G(SCH_1):M_J_CPU0_SB_DQ(9)
   U25 CJ17 MJB_DATA9 GENOA_SP5-SOCKET6096_13568-001,SMLF,IO,DGA^6000030   I159 @T6G_MB_LIB.T6G(SCH_1):PAGE19
   J68  113  DQ9_B SCONN288_DDR506112002KQ-SCONN288_DDR506112002KQ,SMA    I22 @T6G_MB_LIB.T6G(SCH_1):PAGE94

M_J_CPU0_SB_DQS_DN<0> @T6G_MB_LIB.T6G(SCH_1):M_J_CPU0_SB_DQS_DN(0)
   U25 CE16 MJB_DQS_L0 GENOA_SP5-SOCKET6096_13568-001,SMLF,IO,DGA^6000030   I159 @T6G_MB_LIB.T6G(SCH_1):PAGE19
   J68  105 DQS0_B_C SCONN288_DDR506112002KQ-SCONN288_DDR506112002KQ,SMA   I236 @T6G_MB_LIB.T6G(SCH_1):PAGE94

M_J_CPU0_SB_DQS_DN<1> @T6G_MB_LIB.T6G(SCH_1):M_J_CPU0_SB_DQS_DN(1)
   U25 CL16 MJB_DQS_L1 GENOA_SP5-SOCKET6096_13568-001,SMLF,IO,DGA^6000030   I159 @T6G_MB_LIB.T6G(SCH_1):PAGE19
   J68  116 DQS1_B_C SCONN288_DDR506112002KQ-SCONN288_DDR506112002KQ,SMA   I236 @T6G_MB_LIB.T6G(SCH_1):PAGE94

M_J_CPU0_SB_DQS_DN<2> @T6G_MB_LIB.T6G(SCH_1):M_J_CPU0_SB_DQS_DN(2)
   U25 CU16 MJB_DQS_L2 GENOA_SP5-SOCKET6096_13568-001,SMLF,IO,DGA^6000030   I159 @T6G_MB_LIB.T6G(SCH_1):PAGE19
   J68  127 DQS2_B_C SCONN288_DDR506112002KQ-SCONN288_DDR506112002KQ,SMA   I236 @T6G_MB_LIB.T6G(SCH_1):PAGE94

M_J_CPU0_SB_DQS_DN<3> @T6G_MB_LIB.T6G(SCH_1):M_J_CPU0_SB_DQS_DN(3)
   U25 DC16 MJB_DQS_L3 GENOA_SP5-SOCKET6096_13568-001,SMLF,IO,DGA^6000030   I159 @T6G_MB_LIB.T6G(SCH_1):PAGE19
   J68  138 DQS3_B_C SCONN288_DDR506112002KQ-SCONN288_DDR506112002KQ,SMA   I236 @T6G_MB_LIB.T6G(SCH_1):PAGE94

M_J_CPU0_SB_DQS_DN<4> @T6G_MB_LIB.T6G(SCH_1):M_J_CPU0_SB_DQS_DN(4)
   U25 BW17 MJB_DQS_L4 GENOA_SP5-SOCKET6096_13568-001,SMLF,IO,DGA^6000030   I159 @T6G_MB_LIB.T6G(SCH_1):PAGE19
   J68  238 DQS4_B_C SCONN288_DDR506112002KQ-SCONN288_DDR506112002KQ,SMA   I236 @T6G_MB_LIB.T6G(SCH_1):PAGE94

M_J_CPU0_SB_DQS_DN<5> @T6G_MB_LIB.T6G(SCH_1):M_J_CPU0_SB_DQS_DN(5)
   U25 CE17 MJB_DQS_L5 GENOA_SP5-SOCKET6096_13568-001,SMLF,IO,DGA^6000030   I159 @T6G_MB_LIB.T6G(SCH_1):PAGE19
   J68  249 DQS5_B_C||TDQS5_B_C SCONN288_DDR506112002KQ-SCONN288_DDR506112002KQ,SMA   I236 @T6G_MB_LIB.T6G(SCH_1):PAGE94

M_J_CPU0_SB_DQS_DN<6> @T6G_MB_LIB.T6G(SCH_1):M_J_CPU0_SB_DQS_DN(6)
   U25 CL17 MJB_DQS_L6 GENOA_SP5-SOCKET6096_13568-001,SMLF,IO,DGA^6000030   I159 @T6G_MB_LIB.T6G(SCH_1):PAGE19
   J68  260 DQS6_B_C||TDQS6_B_C SCONN288_DDR506112002KQ-SCONN288_DDR506112002KQ,SMA   I236 @T6G_MB_LIB.T6G(SCH_1):PAGE94

M_J_CPU0_SB_DQS_DN<7> @T6G_MB_LIB.T6G(SCH_1):M_J_CPU0_SB_DQS_DN(7)
   U25 CU17 MJB_DQS_L7 GENOA_SP5-SOCKET6096_13568-001,SMLF,IO,DGA^6000030   I159 @T6G_MB_LIB.T6G(SCH_1):PAGE19
   J68  271 DQS7_B_C||TDQS7_B_C SCONN288_DDR506112002KQ-SCONN288_DDR506112002KQ,SMA   I236 @T6G_MB_LIB.T6G(SCH_1):PAGE94

M_J_CPU0_SB_DQS_DN<8> @T6G_MB_LIB.T6G(SCH_1):M_J_CPU0_SB_DQS_DN(8)
   U25 DC17 MJB_DQS_L8 GENOA_SP5-SOCKET6096_13568-001,SMLF,IO,DGA^6000030   I159 @T6G_MB_LIB.T6G(SCH_1):PAGE19
   J68  282 DQS8_B_C||TDQS8_B_C SCONN288_DDR506112002KQ-SCONN288_DDR506112002KQ,SMA   I236 @T6G_MB_LIB.T6G(SCH_1):PAGE94

M_J_CPU0_SB_DQS_DN<9> @T6G_MB_LIB.T6G(SCH_1):M_J_CPU0_SB_DQS_DN(9)
   U25 BW16 MJB_DQS_L9 GENOA_SP5-SOCKET6096_13568-001,SMLF,IO,DGA^6000030   I159 @T6G_MB_LIB.T6G(SCH_1):PAGE19
   J68   94 DQS9_B_C||TDQS9_B_C SCONN288_DDR506112002KQ-SCONN288_DDR506112002KQ,SMA   I236 @T6G_MB_LIB.T6G(SCH_1):PAGE94

M_J_CPU0_SB_DQS_DP<0> @T6G_MB_LIB.T6G(SCH_1):M_J_CPU0_SB_DQS_DP(0)
   U25 CD16 MJB_DQS_H0 GENOA_SP5-SOCKET6096_13568-001,SMLF,IO,DGA^6000030   I159 @T6G_MB_LIB.T6G(SCH_1):PAGE19
   J68  104 DQS0_B_T SCONN288_DDR506112002KQ-SCONN288_DDR506112002KQ,SMA   I236 @T6G_MB_LIB.T6G(SCH_1):PAGE94

M_J_CPU0_SB_DQS_DP<1> @T6G_MB_LIB.T6G(SCH_1):M_J_CPU0_SB_DQS_DP(1)
   U25 CK16 MJB_DQS_H1 GENOA_SP5-SOCKET6096_13568-001,SMLF,IO,DGA^6000030   I159 @T6G_MB_LIB.T6G(SCH_1):PAGE19
   J68  115 DQS1_B_T SCONN288_DDR506112002KQ-SCONN288_DDR506112002KQ,SMA   I236 @T6G_MB_LIB.T6G(SCH_1):PAGE94

M_J_CPU0_SB_DQS_DP<2> @T6G_MB_LIB.T6G(SCH_1):M_J_CPU0_SB_DQS_DP(2)
   U25 CT16 MJB_DQS_H2 GENOA_SP5-SOCKET6096_13568-001,SMLF,IO,DGA^6000030   I159 @T6G_MB_LIB.T6G(SCH_1):PAGE19
   J68  126 DQS2_B_T SCONN288_DDR506112002KQ-SCONN288_DDR506112002KQ,SMA   I236 @T6G_MB_LIB.T6G(SCH_1):PAGE94

M_J_CPU0_SB_DQS_DP<3> @T6G_MB_LIB.T6G(SCH_1):M_J_CPU0_SB_DQS_DP(3)
   U25 DB16 MJB_DQS_H3 GENOA_SP5-SOCKET6096_13568-001,SMLF,IO,DGA^6000030   I159 @T6G_MB_LIB.T6G(SCH_1):PAGE19
   J68  137 DQS3_B_T SCONN288_DDR506112002KQ-SCONN288_DDR506112002KQ,SMA   I236 @T6G_MB_LIB.T6G(SCH_1):PAGE94

M_J_CPU0_SB_DQS_DP<4> @T6G_MB_LIB.T6G(SCH_1):M_J_CPU0_SB_DQS_DP(4)
   U25 BY18 MJB_DQS_H4 GENOA_SP5-SOCKET6096_13568-001,SMLF,IO,DGA^6000030   I159 @T6G_MB_LIB.T6G(SCH_1):PAGE19
   J68  239 DQS4_B_T SCONN288_DDR506112002KQ-SCONN288_DDR506112002KQ,SMA   I236 @T6G_MB_LIB.T6G(SCH_1):PAGE94

M_J_CPU0_SB_DQS_DP<5> @T6G_MB_LIB.T6G(SCH_1):M_J_CPU0_SB_DQS_DP(5)
   U25 CF18 MJB_DQS_H5 GENOA_SP5-SOCKET6096_13568-001,SMLF,IO,DGA^6000030   I159 @T6G_MB_LIB.T6G(SCH_1):PAGE19
   J68  250 DQS5_B_T||TDQS5_B_T SCONN288_DDR506112002KQ-SCONN288_DDR506112002KQ,SMA   I236 @T6G_MB_LIB.T6G(SCH_1):PAGE94

M_J_CPU0_SB_DQS_DP<6> @T6G_MB_LIB.T6G(SCH_1):M_J_CPU0_SB_DQS_DP(6)
   U25 CM18 MJB_DQS_H6 GENOA_SP5-SOCKET6096_13568-001,SMLF,IO,DGA^6000030   I159 @T6G_MB_LIB.T6G(SCH_1):PAGE19
   J68  261 DQS6_B_T||TDQS6_B_T SCONN288_DDR506112002KQ-SCONN288_DDR506112002KQ,SMA   I236 @T6G_MB_LIB.T6G(SCH_1):PAGE94

M_J_CPU0_SB_DQS_DP<7> @T6G_MB_LIB.T6G(SCH_1):M_J_CPU0_SB_DQS_DP(7)
   U25 CV18 MJB_DQS_H7 GENOA_SP5-SOCKET6096_13568-001,SMLF,IO,DGA^6000030   I159 @T6G_MB_LIB.T6G(SCH_1):PAGE19
   J68  272 DQS7_B_T||TDQS7_B_T SCONN288_DDR506112002KQ-SCONN288_DDR506112002KQ,SMA   I236 @T6G_MB_LIB.T6G(SCH_1):PAGE94

M_J_CPU0_SB_DQS_DP<8> @T6G_MB_LIB.T6G(SCH_1):M_J_CPU0_SB_DQS_DP(8)
   U25 DD18 MJB_DQS_H8 GENOA_SP5-SOCKET6096_13568-001,SMLF,IO,DGA^6000030   I159 @T6G_MB_LIB.T6G(SCH_1):PAGE19
   J68  283 DQS8_B_T||TDQS8_B_T SCONN288_DDR506112002KQ-SCONN288_DDR506112002KQ,SMA   I236 @T6G_MB_LIB.T6G(SCH_1):PAGE94

M_J_CPU0_SB_DQS_DP<9> @T6G_MB_LIB.T6G(SCH_1):M_J_CPU0_SB_DQS_DP(9)
   U25 BV16 MJB_DQS_H9 GENOA_SP5-SOCKET6096_13568-001,SMLF,IO,DGA^6000030   I159 @T6G_MB_LIB.T6G(SCH_1):PAGE19
   J68   93 DQS9_B_T||TDQS9_B_T||DBI4_B_N SCONN288_DDR506112002KQ-SCONN288_DDR506112002KQ,SMA   I236 @T6G_MB_LIB.T6G(SCH_1):PAGE94

M_J_CPU0_SB_PAR @T6G_MB_LIB.T6G(SCH_1):M_J_CPU0_SB_PAR
   U25 BL17 MJB_PAR GENOA_SP5-SOCKET6096_13568-001,SMLF,IO,DGA^6000030   I159 @T6G_MB_LIB.T6G(SCH_1):PAGE19
   J68  227  PAR_B SCONN288_DDR506112002KQ-SCONN288_DDR506112002KQ,SMA    I22 @T6G_MB_LIB.T6G(SCH_1):PAGE94

M_J_CPU0_SB_RSP<0> @T6G_MB_LIB.T6G(SCH_1):M_J_CPU0_SB_RSP(0)
   U25 BP16 MJB0_RSP_L GENOA_SP5-SOCKET6096_13568-001,SMLF,IO,DGA^6000030   I159 @T6G_MB_LIB.T6G(SCH_1):PAGE19
   J68   87 LBS||RSP_B_N SCONN288_DDR506112002KQ-SCONN288_DDR506112002KQ,SMA    I22 @T6G_MB_LIB.T6G(SCH_1):PAGE94

M_J_CPU1_ALERT_N @T6G_MB_LIB.T6G(SCH_1):M_J_CPU1_ALERT_N
  R509    1      A Q_RES_0402LF-15,1%,1/16W,CHIP,CS01502FB03   I314 @T6G_MB_LIB.T6G(SCH_1):PAGE46
   J29   62 ALERT_N SCONN288_DDR506112002KQ-SCONN288_DDR506112002KQ,SMA    I22 @T6G_MB_LIB.T6G(SCH_1):PAGE106

M_J_CPU1_ALERT_R_N @T6G_MB_LIB.T6G(SCH_1):M_J_CPU1_ALERT_R_N
   U26 AT18 MJ_ALERT_L GENOA_SP5-SOCKET6096_13568-001,SMLF,IO,DGA^6000030   I159 @T6G_MB_LIB.T6G(SCH_1):PAGE46
  R509    2      B Q_RES_0402LF-15,1%,1/16W,CHIP,CS01502FB03   I314 @T6G_MB_LIB.T6G(SCH_1):PAGE46

M_J_CPU1_CLK_DN<0> @T6G_MB_LIB.T6G(SCH_1):M_J_CPU1_CLK_DN(0)
   U26 BD16 MJ0_CLK_L GENOA_SP5-SOCKET6096_13568-001,SMLF,IO,DGA^6000030   I159 @T6G_MB_LIB.T6G(SCH_1):PAGE46
   J29  218   CK_C SCONN288_DDR506112002KQ-SCONN288_DDR506112002KQ,SMA    I22 @T6G_MB_LIB.T6G(SCH_1):PAGE106

M_J_CPU1_CLK_DP<0> @T6G_MB_LIB.T6G(SCH_1):M_J_CPU1_CLK_DP(0)
   U26 BC16 MJ0_CLK_H GENOA_SP5-SOCKET6096_13568-001,SMLF,IO,DGA^6000030   I159 @T6G_MB_LIB.T6G(SCH_1):PAGE46
   J29  217   CK_T SCONN288_DDR506112002KQ-SCONN288_DDR506112002KQ,SMA    I22 @T6G_MB_LIB.T6G(SCH_1):PAGE106

M_J_CPU1_RESET_N @T6G_MB_LIB.T6G(SCH_1):M_J_CPU1_RESET_N
   U26 AU17 MJ_RESET_L GENOA_SP5-SOCKET6096_13568-001,SMLF,IO,DGA^6000030   I159 @T6G_MB_LIB.T6G(SCH_1):PAGE46
   J29  207 RESET_N SCONN288_DDR506112002KQ-SCONN288_DDR506112002KQ,SMA    I22 @T6G_MB_LIB.T6G(SCH_1):PAGE106

M_J_CPU1_SA_CA<0> @T6G_MB_LIB.T6G(SCH_1):M_J_CPU1_SA_CA(0)
   U26 AW16 MJA_CA0 GENOA_SP5-SOCKET6096_13568-001,SMLF,IO,DGA^6000030   I159 @T6G_MB_LIB.T6G(SCH_1):PAGE46
   J29   66  CA0_A SCONN288_DDR506112002KQ-SCONN288_DDR506112002KQ,SMA    I22 @T6G_MB_LIB.T6G(SCH_1):PAGE106

M_J_CPU1_SA_CA<1> @T6G_MB_LIB.T6G(SCH_1):M_J_CPU1_SA_CA(1)
   U26 AY16 MJA_CA1 GENOA_SP5-SOCKET6096_13568-001,SMLF,IO,DGA^6000030   I159 @T6G_MB_LIB.T6G(SCH_1):PAGE46
   J29  211  CA1_A SCONN288_DDR506112002KQ-SCONN288_DDR506112002KQ,SMA    I22 @T6G_MB_LIB.T6G(SCH_1):PAGE106

M_J_CPU1_SA_CA<2> @T6G_MB_LIB.T6G(SCH_1):M_J_CPU1_SA_CA(2)
   U26 AY18 MJA_CA2 GENOA_SP5-SOCKET6096_13568-001,SMLF,IO,DGA^6000030   I159 @T6G_MB_LIB.T6G(SCH_1):PAGE46
   J29   68  CA2_A SCONN288_DDR506112002KQ-SCONN288_DDR506112002KQ,SMA    I22 @T6G_MB_LIB.T6G(SCH_1):PAGE106

M_J_CPU1_SA_CA<3> @T6G_MB_LIB.T6G(SCH_1):M_J_CPU1_SA_CA(3)
   U26 BA17 MJA_CA3 GENOA_SP5-SOCKET6096_13568-001,SMLF,IO,DGA^6000030   I159 @T6G_MB_LIB.T6G(SCH_1):PAGE46
   J29  213  CA3_A SCONN288_DDR506112002KQ-SCONN288_DDR506112002KQ,SMA    I22 @T6G_MB_LIB.T6G(SCH_1):PAGE106

M_J_CPU1_SA_CA<4> @T6G_MB_LIB.T6G(SCH_1):M_J_CPU1_SA_CA(4)
   U26 BA16 MJA_CA4 GENOA_SP5-SOCKET6096_13568-001,SMLF,IO,DGA^6000030   I159 @T6G_MB_LIB.T6G(SCH_1):PAGE46
   J29   70  CA4_A SCONN288_DDR506112002KQ-SCONN288_DDR506112002KQ,SMA    I22 @T6G_MB_LIB.T6G(SCH_1):PAGE106

M_J_CPU1_SA_CA<5> @T6G_MB_LIB.T6G(SCH_1):M_J_CPU1_SA_CA(5)
   U26 BB16 MJA_CA5 GENOA_SP5-SOCKET6096_13568-001,SMLF,IO,DGA^6000030   I159 @T6G_MB_LIB.T6G(SCH_1):PAGE46
   J29  215  CA5_A SCONN288_DDR506112002KQ-SCONN288_DDR506112002KQ,SMA    I22 @T6G_MB_LIB.T6G(SCH_1):PAGE106

M_J_CPU1_SA_CA<6> @T6G_MB_LIB.T6G(SCH_1):M_J_CPU1_SA_CA(6)
   U26 BB18 MJA_CA6 GENOA_SP5-SOCKET6096_13568-001,SMLF,IO,DGA^6000030   I159 @T6G_MB_LIB.T6G(SCH_1):PAGE46
   J29   72  CA6_A SCONN288_DDR506112002KQ-SCONN288_DDR506112002KQ,SMA    I22 @T6G_MB_LIB.T6G(SCH_1):PAGE106

M_J_CPU1_SA_CB<0> @T6G_MB_LIB.T6G(SCH_1):M_J_CPU1_SA_CB(0)
   U26 AJ16 MJA_CHECK0 GENOA_SP5-SOCKET6096_13568-001,SMLF,IO,DGA^6000030   I159 @T6G_MB_LIB.T6G(SCH_1):PAGE46
   J29   51  CB0_A SCONN288_DDR506112002KQ-SCONN288_DDR506112002KQ,SMA    I22 @T6G_MB_LIB.T6G(SCH_1):PAGE106

M_J_CPU1_SA_CB<1> @T6G_MB_LIB.T6G(SCH_1):M_J_CPU1_SA_CB(1)
   U26 AK18 MJA_CHECK1 GENOA_SP5-SOCKET6096_13568-001,SMLF,IO,DGA^6000030   I159 @T6G_MB_LIB.T6G(SCH_1):PAGE46
   J29   53  CB1_A SCONN288_DDR506112002KQ-SCONN288_DDR506112002KQ,SMA    I22 @T6G_MB_LIB.T6G(SCH_1):PAGE106

M_J_CPU1_SA_CB<2> @T6G_MB_LIB.T6G(SCH_1):M_J_CPU1_SA_CB(2)
   U26 AK16 MJA_CHECK2 GENOA_SP5-SOCKET6096_13568-001,SMLF,IO,DGA^6000030   I159 @T6G_MB_LIB.T6G(SCH_1):PAGE46
   J29  196  CB2_A SCONN288_DDR506112002KQ-SCONN288_DDR506112002KQ,SMA    I22 @T6G_MB_LIB.T6G(SCH_1):PAGE106

M_J_CPU1_SA_CB<3> @T6G_MB_LIB.T6G(SCH_1):M_J_CPU1_SA_CB(3)
   U26 AL17 MJA_CHECK3 GENOA_SP5-SOCKET6096_13568-001,SMLF,IO,DGA^6000030   I159 @T6G_MB_LIB.T6G(SCH_1):PAGE46
   J29  198  CB3_A SCONN288_DDR506112002KQ-SCONN288_DDR506112002KQ,SMA    I22 @T6G_MB_LIB.T6G(SCH_1):PAGE106

M_J_CPU1_SA_CB<4> @T6G_MB_LIB.T6G(SCH_1):M_J_CPU1_SA_CB(4)
   U26 AN16 MJA_CHECK4 GENOA_SP5-SOCKET6096_13568-001,SMLF,IO,DGA^6000030   I159 @T6G_MB_LIB.T6G(SCH_1):PAGE46
   J29   58  CB4_A SCONN288_DDR506112002KQ-SCONN288_DDR506112002KQ,SMA    I22 @T6G_MB_LIB.T6G(SCH_1):PAGE106

M_J_CPU1_SA_CB<5> @T6G_MB_LIB.T6G(SCH_1):M_J_CPU1_SA_CB(5)
   U26 AP18 MJA_CHECK5 GENOA_SP5-SOCKET6096_13568-001,SMLF,IO,DGA^6000030   I159 @T6G_MB_LIB.T6G(SCH_1):PAGE46
   J29   60  CB5_A SCONN288_DDR506112002KQ-SCONN288_DDR506112002KQ,SMA    I22 @T6G_MB_LIB.T6G(SCH_1):PAGE106

M_J_CPU1_SA_CB<6> @T6G_MB_LIB.T6G(SCH_1):M_J_CPU1_SA_CB(6)
   U26 AP16 MJA_CHECK6 GENOA_SP5-SOCKET6096_13568-001,SMLF,IO,DGA^6000030   I159 @T6G_MB_LIB.T6G(SCH_1):PAGE46
   J29  203  CB6_A SCONN288_DDR506112002KQ-SCONN288_DDR506112002KQ,SMA    I22 @T6G_MB_LIB.T6G(SCH_1):PAGE106

M_J_CPU1_SA_CB<7> @T6G_MB_LIB.T6G(SCH_1):M_J_CPU1_SA_CB(7)
   U26 AR17 MJA_CHECK7 GENOA_SP5-SOCKET6096_13568-001,SMLF,IO,DGA^6000030   I159 @T6G_MB_LIB.T6G(SCH_1):PAGE46
   J29  205  CB7_A SCONN288_DDR506112002KQ-SCONN288_DDR506112002KQ,SMA    I22 @T6G_MB_LIB.T6G(SCH_1):PAGE106

M_J_CPU1_SA_CS_N<0> @T6G_MB_LIB.T6G(SCH_1):M_J_CPU1_SA_CS_N(0)
   U26 AU16 MJA0_CS_L0 GENOA_SP5-SOCKET6096_13568-001,SMLF,IO,DGA^6000030   I159 @T6G_MB_LIB.T6G(SCH_1):PAGE46
   J29   64 CS0_A_N SCONN288_DDR506112002KQ-SCONN288_DDR506112002KQ,SMA    I22 @T6G_MB_LIB.T6G(SCH_1):PAGE106

M_J_CPU1_SA_CS_N<1> @T6G_MB_LIB.T6G(SCH_1):M_J_CPU1_SA_CS_N(1)
   U26 AV18 MJA0_CS_L1 GENOA_SP5-SOCKET6096_13568-001,SMLF,IO,DGA^6000030   I159 @T6G_MB_LIB.T6G(SCH_1):PAGE46
   J29  209 CS1_A_N SCONN288_DDR506112002KQ-SCONN288_DDR506112002KQ,SMA    I22 @T6G_MB_LIB.T6G(SCH_1):PAGE106

M_J_CPU1_SA_DQ<0> @T6G_MB_LIB.T6G(SCH_1):M_J_CPU1_SA_DQ(0)
   U26  E16 MJA_DATA0 GENOA_SP5-SOCKET6096_13568-001,SMLF,IO,DGA^6000030   I159 @T6G_MB_LIB.T6G(SCH_1):PAGE46
   J29    7  DQ0_A SCONN288_DDR506112002KQ-SCONN288_DDR506112002KQ,SMA    I22 @T6G_MB_LIB.T6G(SCH_1):PAGE106

M_J_CPU1_SA_DQ<10> @T6G_MB_LIB.T6G(SCH_1):M_J_CPU1_SA_DQ(10)
   U26  M16 MJA_DATA10 GENOA_SP5-SOCKET6096_13568-001,SMLF,IO,DGA^6000030   I159 @T6G_MB_LIB.T6G(SCH_1):PAGE46
   J29  163 DQ10_A SCONN288_DDR506112002KQ-SCONN288_DDR506112002KQ,SMA    I22 @T6G_MB_LIB.T6G(SCH_1):PAGE106

M_J_CPU1_SA_DQ<11> @T6G_MB_LIB.T6G(SCH_1):M_J_CPU1_SA_DQ(11)
   U26  N17 MJA_DATA11 GENOA_SP5-SOCKET6096_13568-001,SMLF,IO,DGA^6000030   I159 @T6G_MB_LIB.T6G(SCH_1):PAGE46
   J29  165 DQ11_A SCONN288_DDR506112002KQ-SCONN288_DDR506112002KQ,SMA    I22 @T6G_MB_LIB.T6G(SCH_1):PAGE106

M_J_CPU1_SA_DQ<12> @T6G_MB_LIB.T6G(SCH_1):M_J_CPU1_SA_DQ(12)
   U26  R16 MJA_DATA12 GENOA_SP5-SOCKET6096_13568-001,SMLF,IO,DGA^6000030   I159 @T6G_MB_LIB.T6G(SCH_1):PAGE46
   J29   25 DQ12_A SCONN288_DDR506112002KQ-SCONN288_DDR506112002KQ,SMA    I22 @T6G_MB_LIB.T6G(SCH_1):PAGE106

M_J_CPU1_SA_DQ<13> @T6G_MB_LIB.T6G(SCH_1):M_J_CPU1_SA_DQ(13)
   U26  T18 MJA_DATA13 GENOA_SP5-SOCKET6096_13568-001,SMLF,IO,DGA^6000030   I159 @T6G_MB_LIB.T6G(SCH_1):PAGE46
   J29   27 DQ13_A SCONN288_DDR506112002KQ-SCONN288_DDR506112002KQ,SMA    I22 @T6G_MB_LIB.T6G(SCH_1):PAGE106

M_J_CPU1_SA_DQ<14> @T6G_MB_LIB.T6G(SCH_1):M_J_CPU1_SA_DQ(14)
   U26  T16 MJA_DATA14 GENOA_SP5-SOCKET6096_13568-001,SMLF,IO,DGA^6000030   I159 @T6G_MB_LIB.T6G(SCH_1):PAGE46
   J29  170 DQ14_A SCONN288_DDR506112002KQ-SCONN288_DDR506112002KQ,SMA    I22 @T6G_MB_LIB.T6G(SCH_1):PAGE106

M_J_CPU1_SA_DQ<15> @T6G_MB_LIB.T6G(SCH_1):M_J_CPU1_SA_DQ(15)
   U26  U17 MJA_DATA15 GENOA_SP5-SOCKET6096_13568-001,SMLF,IO,DGA^6000030   I159 @T6G_MB_LIB.T6G(SCH_1):PAGE46
   J29  172 DQ15_A SCONN288_DDR506112002KQ-SCONN288_DDR506112002KQ,SMA    I22 @T6G_MB_LIB.T6G(SCH_1):PAGE106

M_J_CPU1_SA_DQ<16> @T6G_MB_LIB.T6G(SCH_1):M_J_CPU1_SA_DQ(16)
   U26  U16 MJA_DATA16 GENOA_SP5-SOCKET6096_13568-001,SMLF,IO,DGA^6000030   I159 @T6G_MB_LIB.T6G(SCH_1):PAGE46
   J29   29 DQ16_A SCONN288_DDR506112002KQ-SCONN288_DDR506112002KQ,SMA    I22 @T6G_MB_LIB.T6G(SCH_1):PAGE106

M_J_CPU1_SA_DQ<17> @T6G_MB_LIB.T6G(SCH_1):M_J_CPU1_SA_DQ(17)
   U26  V18 MJA_DATA17 GENOA_SP5-SOCKET6096_13568-001,SMLF,IO,DGA^6000030   I159 @T6G_MB_LIB.T6G(SCH_1):PAGE46
   J29   31 DQ17_A SCONN288_DDR506112002KQ-SCONN288_DDR506112002KQ,SMA    I22 @T6G_MB_LIB.T6G(SCH_1):PAGE106

M_J_CPU1_SA_DQ<18> @T6G_MB_LIB.T6G(SCH_1):M_J_CPU1_SA_DQ(18)
   U26  V16 MJA_DATA18 GENOA_SP5-SOCKET6096_13568-001,SMLF,IO,DGA^6000030   I159 @T6G_MB_LIB.T6G(SCH_1):PAGE46
   J29  174 DQ18_A SCONN288_DDR506112002KQ-SCONN288_DDR506112002KQ,SMA    I22 @T6G_MB_LIB.T6G(SCH_1):PAGE106

M_J_CPU1_SA_DQ<19> @T6G_MB_LIB.T6G(SCH_1):M_J_CPU1_SA_DQ(19)
   U26  W17 MJA_DATA19 GENOA_SP5-SOCKET6096_13568-001,SMLF,IO,DGA^6000030   I159 @T6G_MB_LIB.T6G(SCH_1):PAGE46
   J29  176 DQ19_A SCONN288_DDR506112002KQ-SCONN288_DDR506112002KQ,SMA    I22 @T6G_MB_LIB.T6G(SCH_1):PAGE106

M_J_CPU1_SA_DQ<1> @T6G_MB_LIB.T6G(SCH_1):M_J_CPU1_SA_DQ(1)
   U26  F18 MJA_DATA1 GENOA_SP5-SOCKET6096_13568-001,SMLF,IO,DGA^6000030   I159 @T6G_MB_LIB.T6G(SCH_1):PAGE46
   J29    9  DQ1_A SCONN288_DDR506112002KQ-SCONN288_DDR506112002KQ,SMA    I22 @T6G_MB_LIB.T6G(SCH_1):PAGE106

M_J_CPU1_SA_DQ<20> @T6G_MB_LIB.T6G(SCH_1):M_J_CPU1_SA_DQ(20)
   U26 AA16 MJA_DATA20 GENOA_SP5-SOCKET6096_13568-001,SMLF,IO,DGA^6000030   I159 @T6G_MB_LIB.T6G(SCH_1):PAGE46
   J29   36 DQ20_A SCONN288_DDR506112002KQ-SCONN288_DDR506112002KQ,SMA    I22 @T6G_MB_LIB.T6G(SCH_1):PAGE106

M_J_CPU1_SA_DQ<21> @T6G_MB_LIB.T6G(SCH_1):M_J_CPU1_SA_DQ(21)
   U26 AB18 MJA_DATA21 GENOA_SP5-SOCKET6096_13568-001,SMLF,IO,DGA^6000030   I159 @T6G_MB_LIB.T6G(SCH_1):PAGE46
   J29   38 DQ21_A SCONN288_DDR506112002KQ-SCONN288_DDR506112002KQ,SMA    I22 @T6G_MB_LIB.T6G(SCH_1):PAGE106

M_J_CPU1_SA_DQ<22> @T6G_MB_LIB.T6G(SCH_1):M_J_CPU1_SA_DQ(22)
   U26 AB16 MJA_DATA22 GENOA_SP5-SOCKET6096_13568-001,SMLF,IO,DGA^6000030   I159 @T6G_MB_LIB.T6G(SCH_1):PAGE46
   J29  181 DQ22_A SCONN288_DDR506112002KQ-SCONN288_DDR506112002KQ,SMA    I22 @T6G_MB_LIB.T6G(SCH_1):PAGE106

M_J_CPU1_SA_DQ<23> @T6G_MB_LIB.T6G(SCH_1):M_J_CPU1_SA_DQ(23)
   U26 AC17 MJA_DATA23 GENOA_SP5-SOCKET6096_13568-001,SMLF,IO,DGA^6000030   I159 @T6G_MB_LIB.T6G(SCH_1):PAGE46
   J29  183 DQ23_A SCONN288_DDR506112002KQ-SCONN288_DDR506112002KQ,SMA    I22 @T6G_MB_LIB.T6G(SCH_1):PAGE106

M_J_CPU1_SA_DQ<24> @T6G_MB_LIB.T6G(SCH_1):M_J_CPU1_SA_DQ(24)
   U26 AC16 MJA_DATA24 GENOA_SP5-SOCKET6096_13568-001,SMLF,IO,DGA^6000030   I159 @T6G_MB_LIB.T6G(SCH_1):PAGE46
   J29   40 DQ24_A SCONN288_DDR506112002KQ-SCONN288_DDR506112002KQ,SMA    I22 @T6G_MB_LIB.T6G(SCH_1):PAGE106

M_J_CPU1_SA_DQ<25> @T6G_MB_LIB.T6G(SCH_1):M_J_CPU1_SA_DQ(25)
   U26 AD18 MJA_DATA25 GENOA_SP5-SOCKET6096_13568-001,SMLF,IO,DGA^6000030   I159 @T6G_MB_LIB.T6G(SCH_1):PAGE46
   J29   42 DQ25_A SCONN288_DDR506112002KQ-SCONN288_DDR506112002KQ,SMA    I22 @T6G_MB_LIB.T6G(SCH_1):PAGE106

M_J_CPU1_SA_DQ<26> @T6G_MB_LIB.T6G(SCH_1):M_J_CPU1_SA_DQ(26)
   U26 AD16 MJA_DATA26 GENOA_SP5-SOCKET6096_13568-001,SMLF,IO,DGA^6000030   I159 @T6G_MB_LIB.T6G(SCH_1):PAGE46
   J29  185 DQ26_A SCONN288_DDR506112002KQ-SCONN288_DDR506112002KQ,SMA    I22 @T6G_MB_LIB.T6G(SCH_1):PAGE106

M_J_CPU1_SA_DQ<27> @T6G_MB_LIB.T6G(SCH_1):M_J_CPU1_SA_DQ(27)
   U26 AE17 MJA_DATA27 GENOA_SP5-SOCKET6096_13568-001,SMLF,IO,DGA^6000030   I159 @T6G_MB_LIB.T6G(SCH_1):PAGE46
   J29  187 DQ27_A SCONN288_DDR506112002KQ-SCONN288_DDR506112002KQ,SMA    I22 @T6G_MB_LIB.T6G(SCH_1):PAGE106

M_J_CPU1_SA_DQ<28> @T6G_MB_LIB.T6G(SCH_1):M_J_CPU1_SA_DQ(28)
   U26 AG16 MJA_DATA28 GENOA_SP5-SOCKET6096_13568-001,SMLF,IO,DGA^6000030   I159 @T6G_MB_LIB.T6G(SCH_1):PAGE46
   J29   47 DQ28_A SCONN288_DDR506112002KQ-SCONN288_DDR506112002KQ,SMA    I22 @T6G_MB_LIB.T6G(SCH_1):PAGE106

M_J_CPU1_SA_DQ<29> @T6G_MB_LIB.T6G(SCH_1):M_J_CPU1_SA_DQ(29)
   U26 AH18 MJA_DATA29 GENOA_SP5-SOCKET6096_13568-001,SMLF,IO,DGA^6000030   I159 @T6G_MB_LIB.T6G(SCH_1):PAGE46
   J29   49 DQ29_A SCONN288_DDR506112002KQ-SCONN288_DDR506112002KQ,SMA    I22 @T6G_MB_LIB.T6G(SCH_1):PAGE106

M_J_CPU1_SA_DQ<2> @T6G_MB_LIB.T6G(SCH_1):M_J_CPU1_SA_DQ(2)
   U26  F16 MJA_DATA2 GENOA_SP5-SOCKET6096_13568-001,SMLF,IO,DGA^6000030   I159 @T6G_MB_LIB.T6G(SCH_1):PAGE46
   J29  152  DQ2_A SCONN288_DDR506112002KQ-SCONN288_DDR506112002KQ,SMA    I22 @T6G_MB_LIB.T6G(SCH_1):PAGE106

M_J_CPU1_SA_DQ<30> @T6G_MB_LIB.T6G(SCH_1):M_J_CPU1_SA_DQ(30)
   U26 AH16 MJA_DATA30 GENOA_SP5-SOCKET6096_13568-001,SMLF,IO,DGA^6000030   I159 @T6G_MB_LIB.T6G(SCH_1):PAGE46
   J29  192 DQ30_A SCONN288_DDR506112002KQ-SCONN288_DDR506112002KQ,SMA    I22 @T6G_MB_LIB.T6G(SCH_1):PAGE106

M_J_CPU1_SA_DQ<31> @T6G_MB_LIB.T6G(SCH_1):M_J_CPU1_SA_DQ(31)
   U26 AJ17 MJA_DATA31 GENOA_SP5-SOCKET6096_13568-001,SMLF,IO,DGA^6000030   I159 @T6G_MB_LIB.T6G(SCH_1):PAGE46
   J29  194 DQ31_A SCONN288_DDR506112002KQ-SCONN288_DDR506112002KQ,SMA    I22 @T6G_MB_LIB.T6G(SCH_1):PAGE106

M_J_CPU1_SA_DQ<3> @T6G_MB_LIB.T6G(SCH_1):M_J_CPU1_SA_DQ(3)
   U26  G17 MJA_DATA3 GENOA_SP5-SOCKET6096_13568-001,SMLF,IO,DGA^6000030   I159 @T6G_MB_LIB.T6G(SCH_1):PAGE46
   J29  154  DQ3_A SCONN288_DDR506112002KQ-SCONN288_DDR506112002KQ,SMA    I22 @T6G_MB_LIB.T6G(SCH_1):PAGE106

M_J_CPU1_SA_DQ<4> @T6G_MB_LIB.T6G(SCH_1):M_J_CPU1_SA_DQ(4)
   U26  J16 MJA_DATA4 GENOA_SP5-SOCKET6096_13568-001,SMLF,IO,DGA^6000030   I159 @T6G_MB_LIB.T6G(SCH_1):PAGE46
   J29   14  DQ4_A SCONN288_DDR506112002KQ-SCONN288_DDR506112002KQ,SMA    I22 @T6G_MB_LIB.T6G(SCH_1):PAGE106

M_J_CPU1_SA_DQ<5> @T6G_MB_LIB.T6G(SCH_1):M_J_CPU1_SA_DQ(5)
   U26  K18 MJA_DATA5 GENOA_SP5-SOCKET6096_13568-001,SMLF,IO,DGA^6000030   I159 @T6G_MB_LIB.T6G(SCH_1):PAGE46
   J29   16  DQ5_A SCONN288_DDR506112002KQ-SCONN288_DDR506112002KQ,SMA    I22 @T6G_MB_LIB.T6G(SCH_1):PAGE106

M_J_CPU1_SA_DQ<6> @T6G_MB_LIB.T6G(SCH_1):M_J_CPU1_SA_DQ(6)
   U26  K16 MJA_DATA6 GENOA_SP5-SOCKET6096_13568-001,SMLF,IO,DGA^6000030   I159 @T6G_MB_LIB.T6G(SCH_1):PAGE46
   J29  159  DQ6_A SCONN288_DDR506112002KQ-SCONN288_DDR506112002KQ,SMA    I22 @T6G_MB_LIB.T6G(SCH_1):PAGE106

M_J_CPU1_SA_DQ<7> @T6G_MB_LIB.T6G(SCH_1):M_J_CPU1_SA_DQ(7)
   U26  L17 MJA_DATA7 GENOA_SP5-SOCKET6096_13568-001,SMLF,IO,DGA^6000030   I159 @T6G_MB_LIB.T6G(SCH_1):PAGE46
   J29  161  DQ7_A SCONN288_DDR506112002KQ-SCONN288_DDR506112002KQ,SMA    I22 @T6G_MB_LIB.T6G(SCH_1):PAGE106

M_J_CPU1_SA_DQ<8> @T6G_MB_LIB.T6G(SCH_1):M_J_CPU1_SA_DQ(8)
   U26  L16 MJA_DATA8 GENOA_SP5-SOCKET6096_13568-001,SMLF,IO,DGA^6000030   I159 @T6G_MB_LIB.T6G(SCH_1):PAGE46
   J29   18  DQ8_A SCONN288_DDR506112002KQ-SCONN288_DDR506112002KQ,SMA    I22 @T6G_MB_LIB.T6G(SCH_1):PAGE106

M_J_CPU1_SA_DQ<9> @T6G_MB_LIB.T6G(SCH_1):M_J_CPU1_SA_DQ(9)
   U26  M18 MJA_DATA9 GENOA_SP5-SOCKET6096_13568-001,SMLF,IO,DGA^6000030   I159 @T6G_MB_LIB.T6G(SCH_1):PAGE46
   J29   20  DQ9_A SCONN288_DDR506112002KQ-SCONN288_DDR506112002KQ,SMA    I22 @T6G_MB_LIB.T6G(SCH_1):PAGE106

M_J_CPU1_SA_DQS_DN<0> @T6G_MB_LIB.T6G(SCH_1):M_J_CPU1_SA_DQS_DN(0)
   U26  H16 MJA_DQS_L0 GENOA_SP5-SOCKET6096_13568-001,SMLF,IO,DGA^6000030   I159 @T6G_MB_LIB.T6G(SCH_1):PAGE46
   J29   12 DQS0_A_C SCONN288_DDR506112002KQ-SCONN288_DDR506112002KQ,SMA   I236 @T6G_MB_LIB.T6G(SCH_1):PAGE106

M_J_CPU1_SA_DQS_DN<1> @T6G_MB_LIB.T6G(SCH_1):M_J_CPU1_SA_DQS_DN(1)
   U26  P16 MJA_DQS_L1 GENOA_SP5-SOCKET6096_13568-001,SMLF,IO,DGA^6000030   I159 @T6G_MB_LIB.T6G(SCH_1):PAGE46
   J29   23 DQS1_A_C SCONN288_DDR506112002KQ-SCONN288_DDR506112002KQ,SMA   I236 @T6G_MB_LIB.T6G(SCH_1):PAGE106

M_J_CPU1_SA_DQS_DN<2> @T6G_MB_LIB.T6G(SCH_1):M_J_CPU1_SA_DQS_DN(2)
   U26  Y16 MJA_DQS_L2 GENOA_SP5-SOCKET6096_13568-001,SMLF,IO,DGA^6000030   I159 @T6G_MB_LIB.T6G(SCH_1):PAGE46
   J29   34 DQS2_A_C SCONN288_DDR506112002KQ-SCONN288_DDR506112002KQ,SMA   I236 @T6G_MB_LIB.T6G(SCH_1):PAGE106

M_J_CPU1_SA_DQS_DN<3> @T6G_MB_LIB.T6G(SCH_1):M_J_CPU1_SA_DQS_DN(3)
   U26 AF16 MJA_DQS_L3 GENOA_SP5-SOCKET6096_13568-001,SMLF,IO,DGA^6000030   I159 @T6G_MB_LIB.T6G(SCH_1):PAGE46
   J29   45 DQS3_A_C SCONN288_DDR506112002KQ-SCONN288_DDR506112002KQ,SMA   I236 @T6G_MB_LIB.T6G(SCH_1):PAGE106

M_J_CPU1_SA_DQS_DN<4> @T6G_MB_LIB.T6G(SCH_1):M_J_CPU1_SA_DQS_DN(4)
   U26 AM16 MJA_DQS_L4 GENOA_SP5-SOCKET6096_13568-001,SMLF,IO,DGA^6000030   I159 @T6G_MB_LIB.T6G(SCH_1):PAGE46
   J29   56 DQS4_A_C SCONN288_DDR506112002KQ-SCONN288_DDR506112002KQ,SMA   I236 @T6G_MB_LIB.T6G(SCH_1):PAGE106

M_J_CPU1_SA_DQS_DN<5> @T6G_MB_LIB.T6G(SCH_1):M_J_CPU1_SA_DQS_DN(5)
   U26  H18 MJA_DQS_L5 GENOA_SP5-SOCKET6096_13568-001,SMLF,IO,DGA^6000030   I159 @T6G_MB_LIB.T6G(SCH_1):PAGE46
   J29  156 DQS5_A_C||TDQS5_A_C||DQS5_A_T||TDQS5_A_T SCONN288_DDR506112002KQ-SCONN288_DDR506112002KQ,SMA   I236 @T6G_MB_LIB.T6G(SCH_1):PAGE106

M_J_CPU1_SA_DQS_DN<6> @T6G_MB_LIB.T6G(SCH_1):M_J_CPU1_SA_DQS_DN(6)
   U26  P18 MJA_DQS_L6 GENOA_SP5-SOCKET6096_13568-001,SMLF,IO,DGA^6000030   I159 @T6G_MB_LIB.T6G(SCH_1):PAGE46
   J29  167 DQS6_A_C||TDQS6_A_C||DQS6_A_T||TDQS6_A_T SCONN288_DDR506112002KQ-SCONN288_DDR506112002KQ,SMA   I236 @T6G_MB_LIB.T6G(SCH_1):PAGE106

M_J_CPU1_SA_DQS_DN<7> @T6G_MB_LIB.T6G(SCH_1):M_J_CPU1_SA_DQS_DN(7)
   U26  Y18 MJA_DQS_L7 GENOA_SP5-SOCKET6096_13568-001,SMLF,IO,DGA^6000030   I159 @T6G_MB_LIB.T6G(SCH_1):PAGE46
   J29  178 DQS7_A_C||TDQS7_A_C SCONN288_DDR506112002KQ-SCONN288_DDR506112002KQ,SMA   I236 @T6G_MB_LIB.T6G(SCH_1):PAGE106

M_J_CPU1_SA_DQS_DN<8> @T6G_MB_LIB.T6G(SCH_1):M_J_CPU1_SA_DQS_DN(8)
   U26 AF18 MJA_DQS_L8 GENOA_SP5-SOCKET6096_13568-001,SMLF,IO,DGA^6000030   I159 @T6G_MB_LIB.T6G(SCH_1):PAGE46
   J29  189 DQS8_A_C||TDQS8_A_C SCONN288_DDR506112002KQ-SCONN288_DDR506112002KQ,SMA   I236 @T6G_MB_LIB.T6G(SCH_1):PAGE106

M_J_CPU1_SA_DQS_DN<9> @T6G_MB_LIB.T6G(SCH_1):M_J_CPU1_SA_DQS_DN(9)
   U26 AM18 MJA_DQS_L9 GENOA_SP5-SOCKET6096_13568-001,SMLF,IO,DGA^6000030   I159 @T6G_MB_LIB.T6G(SCH_1):PAGE46
   J29  200 DQS9_A_C||TDQS9_A_C SCONN288_DDR506112002KQ-SCONN288_DDR506112002KQ,SMA   I236 @T6G_MB_LIB.T6G(SCH_1):PAGE106

M_J_CPU1_SA_DQS_DP<0> @T6G_MB_LIB.T6G(SCH_1):M_J_CPU1_SA_DQS_DP(0)
   U26  G16 MJA_DQS_H0 GENOA_SP5-SOCKET6096_13568-001,SMLF,IO,DGA^6000030   I159 @T6G_MB_LIB.T6G(SCH_1):PAGE46
   J29   11 DQS0_A_T SCONN288_DDR506112002KQ-SCONN288_DDR506112002KQ,SMA   I236 @T6G_MB_LIB.T6G(SCH_1):PAGE106

M_J_CPU1_SA_DQS_DP<1> @T6G_MB_LIB.T6G(SCH_1):M_J_CPU1_SA_DQS_DP(1)
   U26  N16 MJA_DQS_H1 GENOA_SP5-SOCKET6096_13568-001,SMLF,IO,DGA^6000030   I159 @T6G_MB_LIB.T6G(SCH_1):PAGE46
   J29   22 DQS1_A_T SCONN288_DDR506112002KQ-SCONN288_DDR506112002KQ,SMA   I236 @T6G_MB_LIB.T6G(SCH_1):PAGE106

M_J_CPU1_SA_DQS_DP<2> @T6G_MB_LIB.T6G(SCH_1):M_J_CPU1_SA_DQS_DP(2)
   U26  W16 MJA_DQS_H2 GENOA_SP5-SOCKET6096_13568-001,SMLF,IO,DGA^6000030   I159 @T6G_MB_LIB.T6G(SCH_1):PAGE46
   J29   33 DQS2_A_T SCONN288_DDR506112002KQ-SCONN288_DDR506112002KQ,SMA   I236 @T6G_MB_LIB.T6G(SCH_1):PAGE106

M_J_CPU1_SA_DQS_DP<3> @T6G_MB_LIB.T6G(SCH_1):M_J_CPU1_SA_DQS_DP(3)
   U26 AE16 MJA_DQS_H3 GENOA_SP5-SOCKET6096_13568-001,SMLF,IO,DGA^6000030   I159 @T6G_MB_LIB.T6G(SCH_1):PAGE46
   J29   44 DQS3_A_T SCONN288_DDR506112002KQ-SCONN288_DDR506112002KQ,SMA   I236 @T6G_MB_LIB.T6G(SCH_1):PAGE106

M_J_CPU1_SA_DQS_DP<4> @T6G_MB_LIB.T6G(SCH_1):M_J_CPU1_SA_DQS_DP(4)
   U26 AL16 MJA_DQS_H4 GENOA_SP5-SOCKET6096_13568-001,SMLF,IO,DGA^6000030   I159 @T6G_MB_LIB.T6G(SCH_1):PAGE46
   J29   55 DQS4_A_T SCONN288_DDR506112002KQ-SCONN288_DDR506112002KQ,SMA   I236 @T6G_MB_LIB.T6G(SCH_1):PAGE106

M_J_CPU1_SA_DQS_DP<5> @T6G_MB_LIB.T6G(SCH_1):M_J_CPU1_SA_DQS_DP(5)
   U26  J17 MJA_DQS_H5 GENOA_SP5-SOCKET6096_13568-001,SMLF,IO,DGA^6000030   I159 @T6G_MB_LIB.T6G(SCH_1):PAGE46
   J29  157 DQS5_A_T||TDQS5_A_T SCONN288_DDR506112002KQ-SCONN288_DDR506112002KQ,SMA   I236 @T6G_MB_LIB.T6G(SCH_1):PAGE106

M_J_CPU1_SA_DQS_DP<6> @T6G_MB_LIB.T6G(SCH_1):M_J_CPU1_SA_DQS_DP(6)
   U26  R17 MJA_DQS_H6 GENOA_SP5-SOCKET6096_13568-001,SMLF,IO,DGA^6000030   I159 @T6G_MB_LIB.T6G(SCH_1):PAGE46
   J29  168 DQS6_A_T||TDQS6_A_T SCONN288_DDR506112002KQ-SCONN288_DDR506112002KQ,SMA   I236 @T6G_MB_LIB.T6G(SCH_1):PAGE106

M_J_CPU1_SA_DQS_DP<7> @T6G_MB_LIB.T6G(SCH_1):M_J_CPU1_SA_DQS_DP(7)
   U26 AA17 MJA_DQS_H7 GENOA_SP5-SOCKET6096_13568-001,SMLF,IO,DGA^6000030   I159 @T6G_MB_LIB.T6G(SCH_1):PAGE46
   J29  179 DQS7_A_T||TDQS7_A_T SCONN288_DDR506112002KQ-SCONN288_DDR506112002KQ,SMA   I236 @T6G_MB_LIB.T6G(SCH_1):PAGE106

M_J_CPU1_SA_DQS_DP<8> @T6G_MB_LIB.T6G(SCH_1):M_J_CPU1_SA_DQS_DP(8)
   U26 AG17 MJA_DQS_H8 GENOA_SP5-SOCKET6096_13568-001,SMLF,IO,DGA^6000030   I159 @T6G_MB_LIB.T6G(SCH_1):PAGE46
   J29  190 DQS8_A_T||TDQS8_A_T SCONN288_DDR506112002KQ-SCONN288_DDR506112002KQ,SMA   I236 @T6G_MB_LIB.T6G(SCH_1):PAGE106

M_J_CPU1_SA_DQS_DP<9> @T6G_MB_LIB.T6G(SCH_1):M_J_CPU1_SA_DQS_DP(9)
   U26 AN17 MJA_DQS_H9 GENOA_SP5-SOCKET6096_13568-001,SMLF,IO,DGA^6000030   I159 @T6G_MB_LIB.T6G(SCH_1):PAGE46
   J29  201 DQS9_A_T||TDQS9_A_T SCONN288_DDR506112002KQ-SCONN288_DDR506112002KQ,SMA   I236 @T6G_MB_LIB.T6G(SCH_1):PAGE106

M_J_CPU1_SA_PAR @T6G_MB_LIB.T6G(SCH_1):M_J_CPU1_SA_PAR
   U26 BC17 MJA_PAR GENOA_SP5-SOCKET6096_13568-001,SMLF,IO,DGA^6000030   I159 @T6G_MB_LIB.T6G(SCH_1):PAGE46
   J29   74  PAR_A SCONN288_DDR506112002KQ-SCONN288_DDR506112002KQ,SMA    I22 @T6G_MB_LIB.T6G(SCH_1):PAGE106

M_J_CPU1_SA_RSP<0> @T6G_MB_LIB.T6G(SCH_1):M_J_CPU1_SA_RSP(0)
   U26 BN17 MJA0_RSP_L GENOA_SP5-SOCKET6096_13568-001,SMLF,IO,DGA^6000030   I159 @T6G_MB_LIB.T6G(SCH_1):PAGE46
   J29   86 LBD||RSP_A_N SCONN288_DDR506112002KQ-SCONN288_DDR506112002KQ,SMA    I22 @T6G_MB_LIB.T6G(SCH_1):PAGE106

M_J_CPU1_SB_CA<0> @T6G_MB_LIB.T6G(SCH_1):M_J_CPU1_SB_CA(0)
   U26 BG17 MJB_CA0 GENOA_SP5-SOCKET6096_13568-001,SMLF,IO,DGA^6000030   I159 @T6G_MB_LIB.T6G(SCH_1):PAGE46
   J29   76  CA0_B SCONN288_DDR506112002KQ-SCONN288_DDR506112002KQ,SMA    I22 @T6G_MB_LIB.T6G(SCH_1):PAGE106

M_J_CPU1_SB_CA<1> @T6G_MB_LIB.T6G(SCH_1):M_J_CPU1_SB_CA(1)
   U26 BH18 MJB_CA1 GENOA_SP5-SOCKET6096_13568-001,SMLF,IO,DGA^6000030   I159 @T6G_MB_LIB.T6G(SCH_1):PAGE46
   J29  221  CA1_B SCONN288_DDR506112002KQ-SCONN288_DDR506112002KQ,SMA    I22 @T6G_MB_LIB.T6G(SCH_1):PAGE106

M_J_CPU1_SB_CA<2> @T6G_MB_LIB.T6G(SCH_1):M_J_CPU1_SB_CA(2)
   U26 BH16 MJB_CA2 GENOA_SP5-SOCKET6096_13568-001,SMLF,IO,DGA^6000030   I159 @T6G_MB_LIB.T6G(SCH_1):PAGE46
   J29   78  CA2_B SCONN288_DDR506112002KQ-SCONN288_DDR506112002KQ,SMA    I22 @T6G_MB_LIB.T6G(SCH_1):PAGE106

M_J_CPU1_SB_CA<3> @T6G_MB_LIB.T6G(SCH_1):M_J_CPU1_SB_CA(3)
   U26 BJ16 MJB_CA3 GENOA_SP5-SOCKET6096_13568-001,SMLF,IO,DGA^6000030   I159 @T6G_MB_LIB.T6G(SCH_1):PAGE46
   J29  223  CA3_B SCONN288_DDR506112002KQ-SCONN288_DDR506112002KQ,SMA    I22 @T6G_MB_LIB.T6G(SCH_1):PAGE106

M_J_CPU1_SB_CA<4> @T6G_MB_LIB.T6G(SCH_1):M_J_CPU1_SB_CA(4)
   U26 BJ17 MJB_CA4 GENOA_SP5-SOCKET6096_13568-001,SMLF,IO,DGA^6000030   I159 @T6G_MB_LIB.T6G(SCH_1):PAGE46
   J29   80  CA4_B SCONN288_DDR506112002KQ-SCONN288_DDR506112002KQ,SMA    I22 @T6G_MB_LIB.T6G(SCH_1):PAGE106

M_J_CPU1_SB_CA<5> @T6G_MB_LIB.T6G(SCH_1):M_J_CPU1_SB_CA(5)
   U26 BK18 MJB_CA5 GENOA_SP5-SOCKET6096_13568-001,SMLF,IO,DGA^6000030   I159 @T6G_MB_LIB.T6G(SCH_1):PAGE46
   J29  225  CA5_B SCONN288_DDR506112002KQ-SCONN288_DDR506112002KQ,SMA    I22 @T6G_MB_LIB.T6G(SCH_1):PAGE106

M_J_CPU1_SB_CA<6> @T6G_MB_LIB.T6G(SCH_1):M_J_CPU1_SB_CA(6)
   U26 BK16 MJB_CA6 GENOA_SP5-SOCKET6096_13568-001,SMLF,IO,DGA^6000030   I159 @T6G_MB_LIB.T6G(SCH_1):PAGE46
   J29   82  CA6_B SCONN288_DDR506112002KQ-SCONN288_DDR506112002KQ,SMA    I22 @T6G_MB_LIB.T6G(SCH_1):PAGE106

M_J_CPU1_SB_CB<0> @T6G_MB_LIB.T6G(SCH_1):M_J_CPU1_SB_CB(0)
   U26 BY16 MJB_CHECK0 GENOA_SP5-SOCKET6096_13568-001,SMLF,IO,DGA^6000030   I159 @T6G_MB_LIB.T6G(SCH_1):PAGE46
   J29   96  CB0_B SCONN288_DDR506112002KQ-SCONN288_DDR506112002KQ,SMA    I22 @T6G_MB_LIB.T6G(SCH_1):PAGE106

M_J_CPU1_SB_CB<1> @T6G_MB_LIB.T6G(SCH_1):M_J_CPU1_SB_CB(1)
   U26 CA17 MJB_CHECK1 GENOA_SP5-SOCKET6096_13568-001,SMLF,IO,DGA^6000030   I159 @T6G_MB_LIB.T6G(SCH_1):PAGE46
   J29   98  CB1_B SCONN288_DDR506112002KQ-SCONN288_DDR506112002KQ,SMA    I22 @T6G_MB_LIB.T6G(SCH_1):PAGE106

M_J_CPU1_SB_CB<2> @T6G_MB_LIB.T6G(SCH_1):M_J_CPU1_SB_CB(2)
   U26 CA16 MJB_CHECK2 GENOA_SP5-SOCKET6096_13568-001,SMLF,IO,DGA^6000030   I159 @T6G_MB_LIB.T6G(SCH_1):PAGE46
   J29  241  CB2_B SCONN288_DDR506112002KQ-SCONN288_DDR506112002KQ,SMA    I22 @T6G_MB_LIB.T6G(SCH_1):PAGE106

M_J_CPU1_SB_CB<3> @T6G_MB_LIB.T6G(SCH_1):M_J_CPU1_SB_CB(3)
   U26 CB18 MJB_CHECK3 GENOA_SP5-SOCKET6096_13568-001,SMLF,IO,DGA^6000030   I159 @T6G_MB_LIB.T6G(SCH_1):PAGE46
   J29  243  CB3_B SCONN288_DDR506112002KQ-SCONN288_DDR506112002KQ,SMA    I22 @T6G_MB_LIB.T6G(SCH_1):PAGE106

M_J_CPU1_SB_CB<4> @T6G_MB_LIB.T6G(SCH_1):M_J_CPU1_SB_CB(4)
   U26 BT16 MJB_CHECK4 GENOA_SP5-SOCKET6096_13568-001,SMLF,IO,DGA^6000030   I159 @T6G_MB_LIB.T6G(SCH_1):PAGE46
   J29   89  CB4_B SCONN288_DDR506112002KQ-SCONN288_DDR506112002KQ,SMA    I22 @T6G_MB_LIB.T6G(SCH_1):PAGE106

M_J_CPU1_SB_CB<5> @T6G_MB_LIB.T6G(SCH_1):M_J_CPU1_SB_CB(5)
   U26 BU17 MJB_CHECK5 GENOA_SP5-SOCKET6096_13568-001,SMLF,IO,DGA^6000030   I159 @T6G_MB_LIB.T6G(SCH_1):PAGE46
   J29   91  CB5_B SCONN288_DDR506112002KQ-SCONN288_DDR506112002KQ,SMA    I22 @T6G_MB_LIB.T6G(SCH_1):PAGE106

M_J_CPU1_SB_CB<6> @T6G_MB_LIB.T6G(SCH_1):M_J_CPU1_SB_CB(6)
   U26 BU16 MJB_CHECK6 GENOA_SP5-SOCKET6096_13568-001,SMLF,IO,DGA^6000030   I159 @T6G_MB_LIB.T6G(SCH_1):PAGE46
   J29  234  CB6_B SCONN288_DDR506112002KQ-SCONN288_DDR506112002KQ,SMA    I22 @T6G_MB_LIB.T6G(SCH_1):PAGE106

M_J_CPU1_SB_CB<7> @T6G_MB_LIB.T6G(SCH_1):M_J_CPU1_SB_CB(7)
   U26 BV18 MJB_CHECK7 GENOA_SP5-SOCKET6096_13568-001,SMLF,IO,DGA^6000030   I159 @T6G_MB_LIB.T6G(SCH_1):PAGE46
   J29  236  CB7_B SCONN288_DDR506112002KQ-SCONN288_DDR506112002KQ,SMA    I22 @T6G_MB_LIB.T6G(SCH_1):PAGE106

M_J_CPU1_SB_CS_N<0> @T6G_MB_LIB.T6G(SCH_1):M_J_CPU1_SB_CS_N(0)
   U26 BM18 MJB0_CS_L0 GENOA_SP5-SOCKET6096_13568-001,SMLF,IO,DGA^6000030   I159 @T6G_MB_LIB.T6G(SCH_1):PAGE46
   J29   84 CS0_B_N SCONN288_DDR506112002KQ-SCONN288_DDR506112002KQ,SMA    I22 @T6G_MB_LIB.T6G(SCH_1):PAGE106

M_J_CPU1_SB_CS_N<1> @T6G_MB_LIB.T6G(SCH_1):M_J_CPU1_SB_CS_N(1)
   U26 BN16 MJB0_CS_L1 GENOA_SP5-SOCKET6096_13568-001,SMLF,IO,DGA^6000030   I159 @T6G_MB_LIB.T6G(SCH_1):PAGE46
   J29  229 CS1_B_N SCONN288_DDR506112002KQ-SCONN288_DDR506112002KQ,SMA    I22 @T6G_MB_LIB.T6G(SCH_1):PAGE106

M_J_CPU1_SB_DQ<0> @T6G_MB_LIB.T6G(SCH_1):M_J_CPU1_SB_DQ(0)
   U26 CB16 MJB_DATA0 GENOA_SP5-SOCKET6096_13568-001,SMLF,IO,DGA^6000030   I159 @T6G_MB_LIB.T6G(SCH_1):PAGE46
   J29  100  DQ0_B SCONN288_DDR506112002KQ-SCONN288_DDR506112002KQ,SMA    I22 @T6G_MB_LIB.T6G(SCH_1):PAGE106

M_J_CPU1_SB_DQ<10> @T6G_MB_LIB.T6G(SCH_1):M_J_CPU1_SB_DQ(10)
   U26 CJ16 MJB_DATA10 GENOA_SP5-SOCKET6096_13568-001,SMLF,IO,DGA^6000030   I159 @T6G_MB_LIB.T6G(SCH_1):PAGE46
   J29  256 DQ10_B SCONN288_DDR506112002KQ-SCONN288_DDR506112002KQ,SMA    I22 @T6G_MB_LIB.T6G(SCH_1):PAGE106

M_J_CPU1_SB_DQ<11> @T6G_MB_LIB.T6G(SCH_1):M_J_CPU1_SB_DQ(11)
   U26 CK18 MJB_DATA11 GENOA_SP5-SOCKET6096_13568-001,SMLF,IO,DGA^6000030   I159 @T6G_MB_LIB.T6G(SCH_1):PAGE46
   J29  258 DQ11_B SCONN288_DDR506112002KQ-SCONN288_DDR506112002KQ,SMA    I22 @T6G_MB_LIB.T6G(SCH_1):PAGE106

M_J_CPU1_SB_DQ<12> @T6G_MB_LIB.T6G(SCH_1):M_J_CPU1_SB_DQ(12)
   U26 CM16 MJB_DATA12 GENOA_SP5-SOCKET6096_13568-001,SMLF,IO,DGA^6000030   I159 @T6G_MB_LIB.T6G(SCH_1):PAGE46
   J29  118 DQ12_B SCONN288_DDR506112002KQ-SCONN288_DDR506112002KQ,SMA    I22 @T6G_MB_LIB.T6G(SCH_1):PAGE106

M_J_CPU1_SB_DQ<13> @T6G_MB_LIB.T6G(SCH_1):M_J_CPU1_SB_DQ(13)
   U26 CN17 MJB_DATA13 GENOA_SP5-SOCKET6096_13568-001,SMLF,IO,DGA^6000030   I159 @T6G_MB_LIB.T6G(SCH_1):PAGE46
   J29  120 DQ13_B SCONN288_DDR506112002KQ-SCONN288_DDR506112002KQ,SMA    I22 @T6G_MB_LIB.T6G(SCH_1):PAGE106

M_J_CPU1_SB_DQ<14> @T6G_MB_LIB.T6G(SCH_1):M_J_CPU1_SB_DQ(14)
   U26 CN16 MJB_DATA14 GENOA_SP5-SOCKET6096_13568-001,SMLF,IO,DGA^6000030   I159 @T6G_MB_LIB.T6G(SCH_1):PAGE46
   J29  263 DQ14_B SCONN288_DDR506112002KQ-SCONN288_DDR506112002KQ,SMA    I22 @T6G_MB_LIB.T6G(SCH_1):PAGE106

M_J_CPU1_SB_DQ<15> @T6G_MB_LIB.T6G(SCH_1):M_J_CPU1_SB_DQ(15)
   U26 CP18 MJB_DATA15 GENOA_SP5-SOCKET6096_13568-001,SMLF,IO,DGA^6000030   I159 @T6G_MB_LIB.T6G(SCH_1):PAGE46
   J29  265 DQ15_B SCONN288_DDR506112002KQ-SCONN288_DDR506112002KQ,SMA    I22 @T6G_MB_LIB.T6G(SCH_1):PAGE106

M_J_CPU1_SB_DQ<16> @T6G_MB_LIB.T6G(SCH_1):M_J_CPU1_SB_DQ(16)
   U26 CP16 MJB_DATA16 GENOA_SP5-SOCKET6096_13568-001,SMLF,IO,DGA^6000030   I159 @T6G_MB_LIB.T6G(SCH_1):PAGE46
   J29  122 DQ16_B SCONN288_DDR506112002KQ-SCONN288_DDR506112002KQ,SMA    I22 @T6G_MB_LIB.T6G(SCH_1):PAGE106

M_J_CPU1_SB_DQ<17> @T6G_MB_LIB.T6G(SCH_1):M_J_CPU1_SB_DQ(17)
   U26 CR17 MJB_DATA17 GENOA_SP5-SOCKET6096_13568-001,SMLF,IO,DGA^6000030   I159 @T6G_MB_LIB.T6G(SCH_1):PAGE46
   J29  124 DQ17_B SCONN288_DDR506112002KQ-SCONN288_DDR506112002KQ,SMA    I22 @T6G_MB_LIB.T6G(SCH_1):PAGE106

M_J_CPU1_SB_DQ<18> @T6G_MB_LIB.T6G(SCH_1):M_J_CPU1_SB_DQ(18)
   U26 CR16 MJB_DATA18 GENOA_SP5-SOCKET6096_13568-001,SMLF,IO,DGA^6000030   I159 @T6G_MB_LIB.T6G(SCH_1):PAGE46
   J29  267 DQ18_B SCONN288_DDR506112002KQ-SCONN288_DDR506112002KQ,SMA    I22 @T6G_MB_LIB.T6G(SCH_1):PAGE106

M_J_CPU1_SB_DQ<19> @T6G_MB_LIB.T6G(SCH_1):M_J_CPU1_SB_DQ(19)
   U26 CT18 MJB_DATA19 GENOA_SP5-SOCKET6096_13568-001,SMLF,IO,DGA^6000030   I159 @T6G_MB_LIB.T6G(SCH_1):PAGE46
   J29  269 DQ19_B SCONN288_DDR506112002KQ-SCONN288_DDR506112002KQ,SMA    I22 @T6G_MB_LIB.T6G(SCH_1):PAGE106

M_J_CPU1_SB_DQ<1> @T6G_MB_LIB.T6G(SCH_1):M_J_CPU1_SB_DQ(1)
   U26 CC17 MJB_DATA1 GENOA_SP5-SOCKET6096_13568-001,SMLF,IO,DGA^6000030   I159 @T6G_MB_LIB.T6G(SCH_1):PAGE46
   J29  102  DQ1_B SCONN288_DDR506112002KQ-SCONN288_DDR506112002KQ,SMA    I22 @T6G_MB_LIB.T6G(SCH_1):PAGE106

M_J_CPU1_SB_DQ<20> @T6G_MB_LIB.T6G(SCH_1):M_J_CPU1_SB_DQ(20)
   U26 CV16 MJB_DATA20 GENOA_SP5-SOCKET6096_13568-001,SMLF,IO,DGA^6000030   I159 @T6G_MB_LIB.T6G(SCH_1):PAGE46
   J29  129 DQ20_B SCONN288_DDR506112002KQ-SCONN288_DDR506112002KQ,SMA    I22 @T6G_MB_LIB.T6G(SCH_1):PAGE106

M_J_CPU1_SB_DQ<21> @T6G_MB_LIB.T6G(SCH_1):M_J_CPU1_SB_DQ(21)
   U26 CW17 MJB_DATA21 GENOA_SP5-SOCKET6096_13568-001,SMLF,IO,DGA^6000030   I159 @T6G_MB_LIB.T6G(SCH_1):PAGE46
   J29  131 DQ21_B SCONN288_DDR506112002KQ-SCONN288_DDR506112002KQ,SMA    I22 @T6G_MB_LIB.T6G(SCH_1):PAGE106

M_J_CPU1_SB_DQ<22> @T6G_MB_LIB.T6G(SCH_1):M_J_CPU1_SB_DQ(22)
   U26 CW16 MJB_DATA22 GENOA_SP5-SOCKET6096_13568-001,SMLF,IO,DGA^6000030   I159 @T6G_MB_LIB.T6G(SCH_1):PAGE46
   J29  274 DQ22_B SCONN288_DDR506112002KQ-SCONN288_DDR506112002KQ,SMA    I22 @T6G_MB_LIB.T6G(SCH_1):PAGE106

M_J_CPU1_SB_DQ<23> @T6G_MB_LIB.T6G(SCH_1):M_J_CPU1_SB_DQ(23)
   U26 CY18 MJB_DATA23 GENOA_SP5-SOCKET6096_13568-001,SMLF,IO,DGA^6000030   I159 @T6G_MB_LIB.T6G(SCH_1):PAGE46
   J29  276 DQ23_B SCONN288_DDR506112002KQ-SCONN288_DDR506112002KQ,SMA    I22 @T6G_MB_LIB.T6G(SCH_1):PAGE106

M_J_CPU1_SB_DQ<24> @T6G_MB_LIB.T6G(SCH_1):M_J_CPU1_SB_DQ(24)
   U26 CY16 MJB_DATA24 GENOA_SP5-SOCKET6096_13568-001,SMLF,IO,DGA^6000030   I159 @T6G_MB_LIB.T6G(SCH_1):PAGE46
   J29  133 DQ24_B SCONN288_DDR506112002KQ-SCONN288_DDR506112002KQ,SMA    I22 @T6G_MB_LIB.T6G(SCH_1):PAGE106

M_J_CPU1_SB_DQ<25> @T6G_MB_LIB.T6G(SCH_1):M_J_CPU1_SB_DQ(25)
   U26 DA17 MJB_DATA25 GENOA_SP5-SOCKET6096_13568-001,SMLF,IO,DGA^6000030   I159 @T6G_MB_LIB.T6G(SCH_1):PAGE46
   J29  135 DQ25_B SCONN288_DDR506112002KQ-SCONN288_DDR506112002KQ,SMA    I22 @T6G_MB_LIB.T6G(SCH_1):PAGE106

M_J_CPU1_SB_DQ<26> @T6G_MB_LIB.T6G(SCH_1):M_J_CPU1_SB_DQ(26)
   U26 DA16 MJB_DATA26 GENOA_SP5-SOCKET6096_13568-001,SMLF,IO,DGA^6000030   I159 @T6G_MB_LIB.T6G(SCH_1):PAGE46
   J29  278 DQ26_B SCONN288_DDR506112002KQ-SCONN288_DDR506112002KQ,SMA    I22 @T6G_MB_LIB.T6G(SCH_1):PAGE106

M_J_CPU1_SB_DQ<27> @T6G_MB_LIB.T6G(SCH_1):M_J_CPU1_SB_DQ(27)
   U26 DB18 MJB_DATA27 GENOA_SP5-SOCKET6096_13568-001,SMLF,IO,DGA^6000030   I159 @T6G_MB_LIB.T6G(SCH_1):PAGE46
   J29  280 DQ27_B SCONN288_DDR506112002KQ-SCONN288_DDR506112002KQ,SMA    I22 @T6G_MB_LIB.T6G(SCH_1):PAGE106

M_J_CPU1_SB_DQ<28> @T6G_MB_LIB.T6G(SCH_1):M_J_CPU1_SB_DQ(28)
   U26 DD16 MJB_DATA28 GENOA_SP5-SOCKET6096_13568-001,SMLF,IO,DGA^6000030   I159 @T6G_MB_LIB.T6G(SCH_1):PAGE46
   J29  140 DQ28_B SCONN288_DDR506112002KQ-SCONN288_DDR506112002KQ,SMA    I22 @T6G_MB_LIB.T6G(SCH_1):PAGE106

M_J_CPU1_SB_DQ<29> @T6G_MB_LIB.T6G(SCH_1):M_J_CPU1_SB_DQ(29)
   U26 DE17 MJB_DATA29 GENOA_SP5-SOCKET6096_13568-001,SMLF,IO,DGA^6000030   I159 @T6G_MB_LIB.T6G(SCH_1):PAGE46
   J29  142 DQ29_B SCONN288_DDR506112002KQ-SCONN288_DDR506112002KQ,SMA    I22 @T6G_MB_LIB.T6G(SCH_1):PAGE106

M_J_CPU1_SB_DQ<2> @T6G_MB_LIB.T6G(SCH_1):M_J_CPU1_SB_DQ(2)
   U26 CC16 MJB_DATA2 GENOA_SP5-SOCKET6096_13568-001,SMLF,IO,DGA^6000030   I159 @T6G_MB_LIB.T6G(SCH_1):PAGE46
   J29  245  DQ2_B SCONN288_DDR506112002KQ-SCONN288_DDR506112002KQ,SMA    I22 @T6G_MB_LIB.T6G(SCH_1):PAGE106

M_J_CPU1_SB_DQ<30> @T6G_MB_LIB.T6G(SCH_1):M_J_CPU1_SB_DQ(30)
   U26 DE16 MJB_DATA30 GENOA_SP5-SOCKET6096_13568-001,SMLF,IO,DGA^6000030   I159 @T6G_MB_LIB.T6G(SCH_1):PAGE46
   J29  285 DQ30_B SCONN288_DDR506112002KQ-SCONN288_DDR506112002KQ,SMA    I22 @T6G_MB_LIB.T6G(SCH_1):PAGE106

M_J_CPU1_SB_DQ<31> @T6G_MB_LIB.T6G(SCH_1):M_J_CPU1_SB_DQ(31)
   U26 DF16 MJB_DATA31 GENOA_SP5-SOCKET6096_13568-001,SMLF,IO,DGA^6000030   I159 @T6G_MB_LIB.T6G(SCH_1):PAGE46
   J29  287 DQ31_B SCONN288_DDR506112002KQ-SCONN288_DDR506112002KQ,SMA    I22 @T6G_MB_LIB.T6G(SCH_1):PAGE106

M_J_CPU1_SB_DQ<3> @T6G_MB_LIB.T6G(SCH_1):M_J_CPU1_SB_DQ(3)
   U26 CD18 MJB_DATA3 GENOA_SP5-SOCKET6096_13568-001,SMLF,IO,DGA^6000030   I159 @T6G_MB_LIB.T6G(SCH_1):PAGE46
   J29  247  DQ3_B SCONN288_DDR506112002KQ-SCONN288_DDR506112002KQ,SMA    I22 @T6G_MB_LIB.T6G(SCH_1):PAGE106

M_J_CPU1_SB_DQ<4> @T6G_MB_LIB.T6G(SCH_1):M_J_CPU1_SB_DQ(4)
   U26 CF16 MJB_DATA4 GENOA_SP5-SOCKET6096_13568-001,SMLF,IO,DGA^6000030   I159 @T6G_MB_LIB.T6G(SCH_1):PAGE46
   J29  107  DQ4_B SCONN288_DDR506112002KQ-SCONN288_DDR506112002KQ,SMA    I22 @T6G_MB_LIB.T6G(SCH_1):PAGE106

M_J_CPU1_SB_DQ<5> @T6G_MB_LIB.T6G(SCH_1):M_J_CPU1_SB_DQ(5)
   U26 CG17 MJB_DATA5 GENOA_SP5-SOCKET6096_13568-001,SMLF,IO,DGA^6000030   I159 @T6G_MB_LIB.T6G(SCH_1):PAGE46
   J29  109  DQ5_B SCONN288_DDR506112002KQ-SCONN288_DDR506112002KQ,SMA    I22 @T6G_MB_LIB.T6G(SCH_1):PAGE106

M_J_CPU1_SB_DQ<6> @T6G_MB_LIB.T6G(SCH_1):M_J_CPU1_SB_DQ(6)
   U26 CG16 MJB_DATA6 GENOA_SP5-SOCKET6096_13568-001,SMLF,IO,DGA^6000030   I159 @T6G_MB_LIB.T6G(SCH_1):PAGE46
   J29  252  DQ6_B SCONN288_DDR506112002KQ-SCONN288_DDR506112002KQ,SMA    I22 @T6G_MB_LIB.T6G(SCH_1):PAGE106

M_J_CPU1_SB_DQ<7> @T6G_MB_LIB.T6G(SCH_1):M_J_CPU1_SB_DQ(7)
   U26 CH18 MJB_DATA7 GENOA_SP5-SOCKET6096_13568-001,SMLF,IO,DGA^6000030   I159 @T6G_MB_LIB.T6G(SCH_1):PAGE46
   J29  254  DQ7_B SCONN288_DDR506112002KQ-SCONN288_DDR506112002KQ,SMA    I22 @T6G_MB_LIB.T6G(SCH_1):PAGE106

M_J_CPU1_SB_DQ<8> @T6G_MB_LIB.T6G(SCH_1):M_J_CPU1_SB_DQ(8)
   U26 CH16 MJB_DATA8 GENOA_SP5-SOCKET6096_13568-001,SMLF,IO,DGA^6000030   I159 @T6G_MB_LIB.T6G(SCH_1):PAGE46
   J29  111  DQ8_B SCONN288_DDR506112002KQ-SCONN288_DDR506112002KQ,SMA    I22 @T6G_MB_LIB.T6G(SCH_1):PAGE106

M_J_CPU1_SB_DQ<9> @T6G_MB_LIB.T6G(SCH_1):M_J_CPU1_SB_DQ(9)
   U26 CJ17 MJB_DATA9 GENOA_SP5-SOCKET6096_13568-001,SMLF,IO,DGA^6000030   I159 @T6G_MB_LIB.T6G(SCH_1):PAGE46
   J29  113  DQ9_B SCONN288_DDR506112002KQ-SCONN288_DDR506112002KQ,SMA    I22 @T6G_MB_LIB.T6G(SCH_1):PAGE106

M_J_CPU1_SB_DQS_DN<0> @T6G_MB_LIB.T6G(SCH_1):M_J_CPU1_SB_DQS_DN(0)
   U26 CE16 MJB_DQS_L0 GENOA_SP5-SOCKET6096_13568-001,SMLF,IO,DGA^6000030   I159 @T6G_MB_LIB.T6G(SCH_1):PAGE46
   J29  105 DQS0_B_C SCONN288_DDR506112002KQ-SCONN288_DDR506112002KQ,SMA   I236 @T6G_MB_LIB.T6G(SCH_1):PAGE106

M_J_CPU1_SB_DQS_DN<1> @T6G_MB_LIB.T6G(SCH_1):M_J_CPU1_SB_DQS_DN(1)
   U26 CL16 MJB_DQS_L1 GENOA_SP5-SOCKET6096_13568-001,SMLF,IO,DGA^6000030   I159 @T6G_MB_LIB.T6G(SCH_1):PAGE46
   J29  116 DQS1_B_C SCONN288_DDR506112002KQ-SCONN288_DDR506112002KQ,SMA   I236 @T6G_MB_LIB.T6G(SCH_1):PAGE106

M_J_CPU1_SB_DQS_DN<2> @T6G_MB_LIB.T6G(SCH_1):M_J_CPU1_SB_DQS_DN(2)
   U26 CU16 MJB_DQS_L2 GENOA_SP5-SOCKET6096_13568-001,SMLF,IO,DGA^6000030   I159 @T6G_MB_LIB.T6G(SCH_1):PAGE46
   J29  127 DQS2_B_C SCONN288_DDR506112002KQ-SCONN288_DDR506112002KQ,SMA   I236 @T6G_MB_LIB.T6G(SCH_1):PAGE106

M_J_CPU1_SB_DQS_DN<3> @T6G_MB_LIB.T6G(SCH_1):M_J_CPU1_SB_DQS_DN(3)
   U26 DC16 MJB_DQS_L3 GENOA_SP5-SOCKET6096_13568-001,SMLF,IO,DGA^6000030   I159 @T6G_MB_LIB.T6G(SCH_1):PAGE46
   J29  138 DQS3_B_C SCONN288_DDR506112002KQ-SCONN288_DDR506112002KQ,SMA   I236 @T6G_MB_LIB.T6G(SCH_1):PAGE106

M_J_CPU1_SB_DQS_DN<4> @T6G_MB_LIB.T6G(SCH_1):M_J_CPU1_SB_DQS_DN(4)
   U26 BW17 MJB_DQS_L4 GENOA_SP5-SOCKET6096_13568-001,SMLF,IO,DGA^6000030   I159 @T6G_MB_LIB.T6G(SCH_1):PAGE46
   J29  238 DQS4_B_C SCONN288_DDR506112002KQ-SCONN288_DDR506112002KQ,SMA   I236 @T6G_MB_LIB.T6G(SCH_1):PAGE106

M_J_CPU1_SB_DQS_DN<5> @T6G_MB_LIB.T6G(SCH_1):M_J_CPU1_SB_DQS_DN(5)
   U26 CE17 MJB_DQS_L5 GENOA_SP5-SOCKET6096_13568-001,SMLF,IO,DGA^6000030   I159 @T6G_MB_LIB.T6G(SCH_1):PAGE46
   J29  249 DQS5_B_C||TDQS5_B_C SCONN288_DDR506112002KQ-SCONN288_DDR506112002KQ,SMA   I236 @T6G_MB_LIB.T6G(SCH_1):PAGE106

M_J_CPU1_SB_DQS_DN<6> @T6G_MB_LIB.T6G(SCH_1):M_J_CPU1_SB_DQS_DN(6)
   U26 CL17 MJB_DQS_L6 GENOA_SP5-SOCKET6096_13568-001,SMLF,IO,DGA^6000030   I159 @T6G_MB_LIB.T6G(SCH_1):PAGE46
   J29  260 DQS6_B_C||TDQS6_B_C SCONN288_DDR506112002KQ-SCONN288_DDR506112002KQ,SMA   I236 @T6G_MB_LIB.T6G(SCH_1):PAGE106

M_J_CPU1_SB_DQS_DN<7> @T6G_MB_LIB.T6G(SCH_1):M_J_CPU1_SB_DQS_DN(7)
   U26 CU17 MJB_DQS_L7 GENOA_SP5-SOCKET6096_13568-001,SMLF,IO,DGA^6000030   I159 @T6G_MB_LIB.T6G(SCH_1):PAGE46
   J29  271 DQS7_B_C||TDQS7_B_C SCONN288_DDR506112002KQ-SCONN288_DDR506112002KQ,SMA   I236 @T6G_MB_LIB.T6G(SCH_1):PAGE106

M_J_CPU1_SB_DQS_DN<8> @T6G_MB_LIB.T6G(SCH_1):M_J_CPU1_SB_DQS_DN(8)
   U26 DC17 MJB_DQS_L8 GENOA_SP5-SOCKET6096_13568-001,SMLF,IO,DGA^6000030   I159 @T6G_MB_LIB.T6G(SCH_1):PAGE46
   J29  282 DQS8_B_C||TDQS8_B_C SCONN288_DDR506112002KQ-SCONN288_DDR506112002KQ,SMA   I236 @T6G_MB_LIB.T6G(SCH_1):PAGE106

M_J_CPU1_SB_DQS_DN<9> @T6G_MB_LIB.T6G(SCH_1):M_J_CPU1_SB_DQS_DN(9)
   U26 BW16 MJB_DQS_L9 GENOA_SP5-SOCKET6096_13568-001,SMLF,IO,DGA^6000030   I159 @T6G_MB_LIB.T6G(SCH_1):PAGE46
   J29   94 DQS9_B_C||TDQS9_B_C SCONN288_DDR506112002KQ-SCONN288_DDR506112002KQ,SMA   I236 @T6G_MB_LIB.T6G(SCH_1):PAGE106

M_J_CPU1_SB_DQS_DP<0> @T6G_MB_LIB.T6G(SCH_1):M_J_CPU1_SB_DQS_DP(0)
   U26 CD16 MJB_DQS_H0 GENOA_SP5-SOCKET6096_13568-001,SMLF,IO,DGA^6000030   I159 @T6G_MB_LIB.T6G(SCH_1):PAGE46
   J29  104 DQS0_B_T SCONN288_DDR506112002KQ-SCONN288_DDR506112002KQ,SMA   I236 @T6G_MB_LIB.T6G(SCH_1):PAGE106

M_J_CPU1_SB_DQS_DP<1> @T6G_MB_LIB.T6G(SCH_1):M_J_CPU1_SB_DQS_DP(1)
   U26 CK16 MJB_DQS_H1 GENOA_SP5-SOCKET6096_13568-001,SMLF,IO,DGA^6000030   I159 @T6G_MB_LIB.T6G(SCH_1):PAGE46
   J29  115 DQS1_B_T SCONN288_DDR506112002KQ-SCONN288_DDR506112002KQ,SMA   I236 @T6G_MB_LIB.T6G(SCH_1):PAGE106

M_J_CPU1_SB_DQS_DP<2> @T6G_MB_LIB.T6G(SCH_1):M_J_CPU1_SB_DQS_DP(2)
   U26 CT16 MJB_DQS_H2 GENOA_SP5-SOCKET6096_13568-001,SMLF,IO,DGA^6000030   I159 @T6G_MB_LIB.T6G(SCH_1):PAGE46
   J29  126 DQS2_B_T SCONN288_DDR506112002KQ-SCONN288_DDR506112002KQ,SMA   I236 @T6G_MB_LIB.T6G(SCH_1):PAGE106

M_J_CPU1_SB_DQS_DP<3> @T6G_MB_LIB.T6G(SCH_1):M_J_CPU1_SB_DQS_DP(3)
   U26 DB16 MJB_DQS_H3 GENOA_SP5-SOCKET6096_13568-001,SMLF,IO,DGA^6000030   I159 @T6G_MB_LIB.T6G(SCH_1):PAGE46
   J29  137 DQS3_B_T SCONN288_DDR506112002KQ-SCONN288_DDR506112002KQ,SMA   I236 @T6G_MB_LIB.T6G(SCH_1):PAGE106

M_J_CPU1_SB_DQS_DP<4> @T6G_MB_LIB.T6G(SCH_1):M_J_CPU1_SB_DQS_DP(4)
   U26 BY18 MJB_DQS_H4 GENOA_SP5-SOCKET6096_13568-001,SMLF,IO,DGA^6000030   I159 @T6G_MB_LIB.T6G(SCH_1):PAGE46
   J29  239 DQS4_B_T SCONN288_DDR506112002KQ-SCONN288_DDR506112002KQ,SMA   I236 @T6G_MB_LIB.T6G(SCH_1):PAGE106

M_J_CPU1_SB_DQS_DP<5> @T6G_MB_LIB.T6G(SCH_1):M_J_CPU1_SB_DQS_DP(5)
   U26 CF18 MJB_DQS_H5 GENOA_SP5-SOCKET6096_13568-001,SMLF,IO,DGA^6000030   I159 @T6G_MB_LIB.T6G(SCH_1):PAGE46
   J29  250 DQS5_B_T||TDQS5_B_T SCONN288_DDR506112002KQ-SCONN288_DDR506112002KQ,SMA   I236 @T6G_MB_LIB.T6G(SCH_1):PAGE106

M_J_CPU1_SB_DQS_DP<6> @T6G_MB_LIB.T6G(SCH_1):M_J_CPU1_SB_DQS_DP(6)
   U26 CM18 MJB_DQS_H6 GENOA_SP5-SOCKET6096_13568-001,SMLF,IO,DGA^6000030   I159 @T6G_MB_LIB.T6G(SCH_1):PAGE46
   J29  261 DQS6_B_T||TDQS6_B_T SCONN288_DDR506112002KQ-SCONN288_DDR506112002KQ,SMA   I236 @T6G_MB_LIB.T6G(SCH_1):PAGE106

M_J_CPU1_SB_DQS_DP<7> @T6G_MB_LIB.T6G(SCH_1):M_J_CPU1_SB_DQS_DP(7)
   U26 CV18 MJB_DQS_H7 GENOA_SP5-SOCKET6096_13568-001,SMLF,IO,DGA^6000030   I159 @T6G_MB_LIB.T6G(SCH_1):PAGE46
   J29  272 DQS7_B_T||TDQS7_B_T SCONN288_DDR506112002KQ-SCONN288_DDR506112002KQ,SMA   I236 @T6G_MB_LIB.T6G(SCH_1):PAGE106

M_J_CPU1_SB_DQS_DP<8> @T6G_MB_LIB.T6G(SCH_1):M_J_CPU1_SB_DQS_DP(8)
   U26 DD18 MJB_DQS_H8 GENOA_SP5-SOCKET6096_13568-001,SMLF,IO,DGA^6000030   I159 @T6G_MB_LIB.T6G(SCH_1):PAGE46
   J29  283 DQS8_B_T||TDQS8_B_T SCONN288_DDR506112002KQ-SCONN288_DDR506112002KQ,SMA   I236 @T6G_MB_LIB.T6G(SCH_1):PAGE106

M_J_CPU1_SB_DQS_DP<9> @T6G_MB_LIB.T6G(SCH_1):M_J_CPU1_SB_DQS_DP(9)
   U26 BV16 MJB_DQS_H9 GENOA_SP5-SOCKET6096_13568-001,SMLF,IO,DGA^6000030   I159 @T6G_MB_LIB.T6G(SCH_1):PAGE46
   J29   93 DQS9_B_T||TDQS9_B_T||DBI4_B_N SCONN288_DDR506112002KQ-SCONN288_DDR506112002KQ,SMA   I236 @T6G_MB_LIB.T6G(SCH_1):PAGE106

M_J_CPU1_SB_PAR @T6G_MB_LIB.T6G(SCH_1):M_J_CPU1_SB_PAR
   U26 BL17 MJB_PAR GENOA_SP5-SOCKET6096_13568-001,SMLF,IO,DGA^6000030   I159 @T6G_MB_LIB.T6G(SCH_1):PAGE46
   J29  227  PAR_B SCONN288_DDR506112002KQ-SCONN288_DDR506112002KQ,SMA    I22 @T6G_MB_LIB.T6G(SCH_1):PAGE106

M_J_CPU1_SB_RSP<0> @T6G_MB_LIB.T6G(SCH_1):M_J_CPU1_SB_RSP(0)
   U26 BP16 MJB0_RSP_L GENOA_SP5-SOCKET6096_13568-001,SMLF,IO,DGA^6000030   I159 @T6G_MB_LIB.T6G(SCH_1):PAGE46
   J29   87 LBS||RSP_B_N SCONN288_DDR506112002KQ-SCONN288_DDR506112002KQ,SMA    I22 @T6G_MB_LIB.T6G(SCH_1):PAGE106

M_K_CPU0_ALERT_N @T6G_MB_LIB.T6G(SCH_1):M_K_CPU0_ALERT_N
  R385    1      A Q_RES_0402LF-15,1%,1/16W,CHIP,CS01502FB03   I314 @T6G_MB_LIB.T6G(SCH_1):PAGE20
   J20   62 ALERT_N SCONN288_DDR506112002KQ-SCONN288_DDR506112002KQ,SMA    I22 @T6G_MB_LIB.T6G(SCH_1):PAGE95

M_K_CPU0_ALERT_R_N @T6G_MB_LIB.T6G(SCH_1):M_K_CPU0_ALERT_R_N
   U25  AT7 MK_ALERT_L GENOA_SP5-SOCKET6096_13568-001,SMLF,IO,DGA^6000030   I159 @T6G_MB_LIB.T6G(SCH_1):PAGE20
  R385    2      B Q_RES_0402LF-15,1%,1/16W,CHIP,CS01502FB03   I314 @T6G_MB_LIB.T6G(SCH_1):PAGE20

M_K_CPU0_CLK_DN<0> @T6G_MB_LIB.T6G(SCH_1):M_K_CPU0_CLK_DN(0)
   U25  BD6 MK0_CLK_L GENOA_SP5-SOCKET6096_13568-001,SMLF,IO,DGA^6000030   I159 @T6G_MB_LIB.T6G(SCH_1):PAGE20
   J20  218   CK_C SCONN288_DDR506112002KQ-SCONN288_DDR506112002KQ,SMA    I22 @T6G_MB_LIB.T6G(SCH_1):PAGE95

M_K_CPU0_CLK_DP<0> @T6G_MB_LIB.T6G(SCH_1):M_K_CPU0_CLK_DP(0)
   U25  BC5 MK0_CLK_H GENOA_SP5-SOCKET6096_13568-001,SMLF,IO,DGA^6000030   I159 @T6G_MB_LIB.T6G(SCH_1):PAGE20
   J20  217   CK_T SCONN288_DDR506112002KQ-SCONN288_DDR506112002KQ,SMA    I22 @T6G_MB_LIB.T6G(SCH_1):PAGE95

M_K_CPU0_RESET_N @T6G_MB_LIB.T6G(SCH_1):M_K_CPU0_RESET_N
   U25  AU7 MK_RESET_L GENOA_SP5-SOCKET6096_13568-001,SMLF,IO,DGA^6000030   I159 @T6G_MB_LIB.T6G(SCH_1):PAGE20
   J20  207 RESET_N SCONN288_DDR506112002KQ-SCONN288_DDR506112002KQ,SMA    I22 @T6G_MB_LIB.T6G(SCH_1):PAGE95

M_K_CPU0_SA_CA<0> @T6G_MB_LIB.T6G(SCH_1):M_K_CPU0_SA_CA(0)
   U25  AW5 MKA_CA0 GENOA_SP5-SOCKET6096_13568-001,SMLF,IO,DGA^6000030   I159 @T6G_MB_LIB.T6G(SCH_1):PAGE20
   J20   66  CA0_A SCONN288_DDR506112002KQ-SCONN288_DDR506112002KQ,SMA    I22 @T6G_MB_LIB.T6G(SCH_1):PAGE95

M_K_CPU0_SA_CA<1> @T6G_MB_LIB.T6G(SCH_1):M_K_CPU0_SA_CA(1)
   U25  AY6 MKA_CA1 GENOA_SP5-SOCKET6096_13568-001,SMLF,IO,DGA^6000030   I159 @T6G_MB_LIB.T6G(SCH_1):PAGE20
   J20  211  CA1_A SCONN288_DDR506112002KQ-SCONN288_DDR506112002KQ,SMA    I22 @T6G_MB_LIB.T6G(SCH_1):PAGE95

M_K_CPU0_SA_CA<2> @T6G_MB_LIB.T6G(SCH_1):M_K_CPU0_SA_CA(2)
   U25  AY7 MKA_CA2 GENOA_SP5-SOCKET6096_13568-001,SMLF,IO,DGA^6000030   I159 @T6G_MB_LIB.T6G(SCH_1):PAGE20
   J20   68  CA2_A SCONN288_DDR506112002KQ-SCONN288_DDR506112002KQ,SMA    I22 @T6G_MB_LIB.T6G(SCH_1):PAGE95

M_K_CPU0_SA_CA<3> @T6G_MB_LIB.T6G(SCH_1):M_K_CPU0_SA_CA(3)
   U25  BA7 MKA_CA3 GENOA_SP5-SOCKET6096_13568-001,SMLF,IO,DGA^6000030   I159 @T6G_MB_LIB.T6G(SCH_1):PAGE20
   J20  213  CA3_A SCONN288_DDR506112002KQ-SCONN288_DDR506112002KQ,SMA    I22 @T6G_MB_LIB.T6G(SCH_1):PAGE95

M_K_CPU0_SA_CA<4> @T6G_MB_LIB.T6G(SCH_1):M_K_CPU0_SA_CA(4)
   U25  BA5 MKA_CA4 GENOA_SP5-SOCKET6096_13568-001,SMLF,IO,DGA^6000030   I159 @T6G_MB_LIB.T6G(SCH_1):PAGE20
   J20   70  CA4_A SCONN288_DDR506112002KQ-SCONN288_DDR506112002KQ,SMA    I22 @T6G_MB_LIB.T6G(SCH_1):PAGE95

M_K_CPU0_SA_CA<5> @T6G_MB_LIB.T6G(SCH_1):M_K_CPU0_SA_CA(5)
   U25  BB6 MKA_CA5 GENOA_SP5-SOCKET6096_13568-001,SMLF,IO,DGA^6000030   I159 @T6G_MB_LIB.T6G(SCH_1):PAGE20
   J20  215  CA5_A SCONN288_DDR506112002KQ-SCONN288_DDR506112002KQ,SMA    I22 @T6G_MB_LIB.T6G(SCH_1):PAGE95

M_K_CPU0_SA_CA<6> @T6G_MB_LIB.T6G(SCH_1):M_K_CPU0_SA_CA(6)
   U25  BB7 MKA_CA6 GENOA_SP5-SOCKET6096_13568-001,SMLF,IO,DGA^6000030   I159 @T6G_MB_LIB.T6G(SCH_1):PAGE20
   J20   72  CA6_A SCONN288_DDR506112002KQ-SCONN288_DDR506112002KQ,SMA    I22 @T6G_MB_LIB.T6G(SCH_1):PAGE95

M_K_CPU0_SA_CB<0> @T6G_MB_LIB.T6G(SCH_1):M_K_CPU0_SA_CB(0)
   U25  AJ5 MKA_CHECK0 GENOA_SP5-SOCKET6096_13568-001,SMLF,IO,DGA^6000030   I159 @T6G_MB_LIB.T6G(SCH_1):PAGE20
   J20   51  CB0_A SCONN288_DDR506112002KQ-SCONN288_DDR506112002KQ,SMA    I22 @T6G_MB_LIB.T6G(SCH_1):PAGE95

M_K_CPU0_SA_CB<1> @T6G_MB_LIB.T6G(SCH_1):M_K_CPU0_SA_CB(1)
   U25  AK7 MKA_CHECK1 GENOA_SP5-SOCKET6096_13568-001,SMLF,IO,DGA^6000030   I159 @T6G_MB_LIB.T6G(SCH_1):PAGE20
   J20   53  CB1_A SCONN288_DDR506112002KQ-SCONN288_DDR506112002KQ,SMA    I22 @T6G_MB_LIB.T6G(SCH_1):PAGE95

M_K_CPU0_SA_CB<2> @T6G_MB_LIB.T6G(SCH_1):M_K_CPU0_SA_CB(2)
   U25  AK6 MKA_CHECK2 GENOA_SP5-SOCKET6096_13568-001,SMLF,IO,DGA^6000030   I159 @T6G_MB_LIB.T6G(SCH_1):PAGE20
   J20  196  CB2_A SCONN288_DDR506112002KQ-SCONN288_DDR506112002KQ,SMA    I22 @T6G_MB_LIB.T6G(SCH_1):PAGE95

M_K_CPU0_SA_CB<3> @T6G_MB_LIB.T6G(SCH_1):M_K_CPU0_SA_CB(3)
   U25  AL7 MKA_CHECK3 GENOA_SP5-SOCKET6096_13568-001,SMLF,IO,DGA^6000030   I159 @T6G_MB_LIB.T6G(SCH_1):PAGE20
   J20  198  CB3_A SCONN288_DDR506112002KQ-SCONN288_DDR506112002KQ,SMA    I22 @T6G_MB_LIB.T6G(SCH_1):PAGE95

M_K_CPU0_SA_CB<4> @T6G_MB_LIB.T6G(SCH_1):M_K_CPU0_SA_CB(4)
   U25  AN5 MKA_CHECK4 GENOA_SP5-SOCKET6096_13568-001,SMLF,IO,DGA^6000030   I159 @T6G_MB_LIB.T6G(SCH_1):PAGE20
   J20   58  CB4_A SCONN288_DDR506112002KQ-SCONN288_DDR506112002KQ,SMA    I22 @T6G_MB_LIB.T6G(SCH_1):PAGE95

M_K_CPU0_SA_CB<5> @T6G_MB_LIB.T6G(SCH_1):M_K_CPU0_SA_CB(5)
   U25  AP7 MKA_CHECK5 GENOA_SP5-SOCKET6096_13568-001,SMLF,IO,DGA^6000030   I159 @T6G_MB_LIB.T6G(SCH_1):PAGE20
   J20   60  CB5_A SCONN288_DDR506112002KQ-SCONN288_DDR506112002KQ,SMA    I22 @T6G_MB_LIB.T6G(SCH_1):PAGE95

M_K_CPU0_SA_CB<6> @T6G_MB_LIB.T6G(SCH_1):M_K_CPU0_SA_CB(6)
   U25  AP6 MKA_CHECK6 GENOA_SP5-SOCKET6096_13568-001,SMLF,IO,DGA^6000030   I159 @T6G_MB_LIB.T6G(SCH_1):PAGE20
   J20  203  CB6_A SCONN288_DDR506112002KQ-SCONN288_DDR506112002KQ,SMA    I22 @T6G_MB_LIB.T6G(SCH_1):PAGE95

M_K_CPU0_SA_CB<7> @T6G_MB_LIB.T6G(SCH_1):M_K_CPU0_SA_CB(7)
   U25  AR7 MKA_CHECK7 GENOA_SP5-SOCKET6096_13568-001,SMLF,IO,DGA^6000030   I159 @T6G_MB_LIB.T6G(SCH_1):PAGE20
   J20  205  CB7_A SCONN288_DDR506112002KQ-SCONN288_DDR506112002KQ,SMA    I22 @T6G_MB_LIB.T6G(SCH_1):PAGE95

M_K_CPU0_SA_CS_N<0> @T6G_MB_LIB.T6G(SCH_1):M_K_CPU0_SA_CS_N(0)
   U25  AU5 MKA0_CS_L0 GENOA_SP5-SOCKET6096_13568-001,SMLF,IO,DGA^6000030   I159 @T6G_MB_LIB.T6G(SCH_1):PAGE20
   J20   64 CS0_A_N SCONN288_DDR506112002KQ-SCONN288_DDR506112002KQ,SMA    I22 @T6G_MB_LIB.T6G(SCH_1):PAGE95

M_K_CPU0_SA_CS_N<1> @T6G_MB_LIB.T6G(SCH_1):M_K_CPU0_SA_CS_N(1)
   U25  AV7 MKA0_CS_L1 GENOA_SP5-SOCKET6096_13568-001,SMLF,IO,DGA^6000030   I159 @T6G_MB_LIB.T6G(SCH_1):PAGE20
   J20  209 CS1_A_N SCONN288_DDR506112002KQ-SCONN288_DDR506112002KQ,SMA    I22 @T6G_MB_LIB.T6G(SCH_1):PAGE95

M_K_CPU0_SA_DQ<0> @T6G_MB_LIB.T6G(SCH_1):M_K_CPU0_SA_DQ(0)
   U25   E5 MKA_DATA0 GENOA_SP5-SOCKET6096_13568-001,SMLF,IO,DGA^6000030   I159 @T6G_MB_LIB.T6G(SCH_1):PAGE20
   J20    7  DQ0_A SCONN288_DDR506112002KQ-SCONN288_DDR506112002KQ,SMA    I22 @T6G_MB_LIB.T6G(SCH_1):PAGE95

M_K_CPU0_SA_DQ<10> @T6G_MB_LIB.T6G(SCH_1):M_K_CPU0_SA_DQ(10)
   U25   M6 MKA_DATA10 GENOA_SP5-SOCKET6096_13568-001,SMLF,IO,DGA^6000030   I159 @T6G_MB_LIB.T6G(SCH_1):PAGE20
   J20  163 DQ10_A SCONN288_DDR506112002KQ-SCONN288_DDR506112002KQ,SMA    I22 @T6G_MB_LIB.T6G(SCH_1):PAGE95

M_K_CPU0_SA_DQ<11> @T6G_MB_LIB.T6G(SCH_1):M_K_CPU0_SA_DQ(11)
   U25   N7 MKA_DATA11 GENOA_SP5-SOCKET6096_13568-001,SMLF,IO,DGA^6000030   I159 @T6G_MB_LIB.T6G(SCH_1):PAGE20
   J20  165 DQ11_A SCONN288_DDR506112002KQ-SCONN288_DDR506112002KQ,SMA    I22 @T6G_MB_LIB.T6G(SCH_1):PAGE95

M_K_CPU0_SA_DQ<12> @T6G_MB_LIB.T6G(SCH_1):M_K_CPU0_SA_DQ(12)
   U25   R5 MKA_DATA12 GENOA_SP5-SOCKET6096_13568-001,SMLF,IO,DGA^6000030   I159 @T6G_MB_LIB.T6G(SCH_1):PAGE20
   J20   25 DQ12_A SCONN288_DDR506112002KQ-SCONN288_DDR506112002KQ,SMA    I22 @T6G_MB_LIB.T6G(SCH_1):PAGE95

M_K_CPU0_SA_DQ<13> @T6G_MB_LIB.T6G(SCH_1):M_K_CPU0_SA_DQ(13)
   U25   T7 MKA_DATA13 GENOA_SP5-SOCKET6096_13568-001,SMLF,IO,DGA^6000030   I159 @T6G_MB_LIB.T6G(SCH_1):PAGE20
   J20   27 DQ13_A SCONN288_DDR506112002KQ-SCONN288_DDR506112002KQ,SMA    I22 @T6G_MB_LIB.T6G(SCH_1):PAGE95

M_K_CPU0_SA_DQ<14> @T6G_MB_LIB.T6G(SCH_1):M_K_CPU0_SA_DQ(14)
   U25   T6 MKA_DATA14 GENOA_SP5-SOCKET6096_13568-001,SMLF,IO,DGA^6000030   I159 @T6G_MB_LIB.T6G(SCH_1):PAGE20
   J20  170 DQ14_A SCONN288_DDR506112002KQ-SCONN288_DDR506112002KQ,SMA    I22 @T6G_MB_LIB.T6G(SCH_1):PAGE95

M_K_CPU0_SA_DQ<15> @T6G_MB_LIB.T6G(SCH_1):M_K_CPU0_SA_DQ(15)
   U25   U7 MKA_DATA15 GENOA_SP5-SOCKET6096_13568-001,SMLF,IO,DGA^6000030   I159 @T6G_MB_LIB.T6G(SCH_1):PAGE20
   J20  172 DQ15_A SCONN288_DDR506112002KQ-SCONN288_DDR506112002KQ,SMA    I22 @T6G_MB_LIB.T6G(SCH_1):PAGE95

M_K_CPU0_SA_DQ<16> @T6G_MB_LIB.T6G(SCH_1):M_K_CPU0_SA_DQ(16)
   U25   U5 MKA_DATA16 GENOA_SP5-SOCKET6096_13568-001,SMLF,IO,DGA^6000030   I159 @T6G_MB_LIB.T6G(SCH_1):PAGE20
   J20   29 DQ16_A SCONN288_DDR506112002KQ-SCONN288_DDR506112002KQ,SMA    I22 @T6G_MB_LIB.T6G(SCH_1):PAGE95

M_K_CPU0_SA_DQ<17> @T6G_MB_LIB.T6G(SCH_1):M_K_CPU0_SA_DQ(17)
   U25   V7 MKA_DATA17 GENOA_SP5-SOCKET6096_13568-001,SMLF,IO,DGA^6000030   I159 @T6G_MB_LIB.T6G(SCH_1):PAGE20
   J20   31 DQ17_A SCONN288_DDR506112002KQ-SCONN288_DDR506112002KQ,SMA    I22 @T6G_MB_LIB.T6G(SCH_1):PAGE95

M_K_CPU0_SA_DQ<18> @T6G_MB_LIB.T6G(SCH_1):M_K_CPU0_SA_DQ(18)
   U25   V6 MKA_DATA18 GENOA_SP5-SOCKET6096_13568-001,SMLF,IO,DGA^6000030   I159 @T6G_MB_LIB.T6G(SCH_1):PAGE20
   J20  174 DQ18_A SCONN288_DDR506112002KQ-SCONN288_DDR506112002KQ,SMA    I22 @T6G_MB_LIB.T6G(SCH_1):PAGE95

M_K_CPU0_SA_DQ<19> @T6G_MB_LIB.T6G(SCH_1):M_K_CPU0_SA_DQ(19)
   U25   W7 MKA_DATA19 GENOA_SP5-SOCKET6096_13568-001,SMLF,IO,DGA^6000030   I159 @T6G_MB_LIB.T6G(SCH_1):PAGE20
   J20  176 DQ19_A SCONN288_DDR506112002KQ-SCONN288_DDR506112002KQ,SMA    I22 @T6G_MB_LIB.T6G(SCH_1):PAGE95

M_K_CPU0_SA_DQ<1> @T6G_MB_LIB.T6G(SCH_1):M_K_CPU0_SA_DQ(1)
   U25   F7 MKA_DATA1 GENOA_SP5-SOCKET6096_13568-001,SMLF,IO,DGA^6000030   I159 @T6G_MB_LIB.T6G(SCH_1):PAGE20
   J20    9  DQ1_A SCONN288_DDR506112002KQ-SCONN288_DDR506112002KQ,SMA    I22 @T6G_MB_LIB.T6G(SCH_1):PAGE95

M_K_CPU0_SA_DQ<20> @T6G_MB_LIB.T6G(SCH_1):M_K_CPU0_SA_DQ(20)
   U25  AA5 MKA_DATA20 GENOA_SP5-SOCKET6096_13568-001,SMLF,IO,DGA^6000030   I159 @T6G_MB_LIB.T6G(SCH_1):PAGE20
   J20   36 DQ20_A SCONN288_DDR506112002KQ-SCONN288_DDR506112002KQ,SMA    I22 @T6G_MB_LIB.T6G(SCH_1):PAGE95

M_K_CPU0_SA_DQ<21> @T6G_MB_LIB.T6G(SCH_1):M_K_CPU0_SA_DQ(21)
   U25  AB7 MKA_DATA21 GENOA_SP5-SOCKET6096_13568-001,SMLF,IO,DGA^6000030   I159 @T6G_MB_LIB.T6G(SCH_1):PAGE20
   J20   38 DQ21_A SCONN288_DDR506112002KQ-SCONN288_DDR506112002KQ,SMA    I22 @T6G_MB_LIB.T6G(SCH_1):PAGE95

M_K_CPU0_SA_DQ<22> @T6G_MB_LIB.T6G(SCH_1):M_K_CPU0_SA_DQ(22)
   U25  AB6 MKA_DATA22 GENOA_SP5-SOCKET6096_13568-001,SMLF,IO,DGA^6000030   I159 @T6G_MB_LIB.T6G(SCH_1):PAGE20
   J20  181 DQ22_A SCONN288_DDR506112002KQ-SCONN288_DDR506112002KQ,SMA    I22 @T6G_MB_LIB.T6G(SCH_1):PAGE95

M_K_CPU0_SA_DQ<23> @T6G_MB_LIB.T6G(SCH_1):M_K_CPU0_SA_DQ(23)
   U25  AC7 MKA_DATA23 GENOA_SP5-SOCKET6096_13568-001,SMLF,IO,DGA^6000030   I159 @T6G_MB_LIB.T6G(SCH_1):PAGE20
   J20  183 DQ23_A SCONN288_DDR506112002KQ-SCONN288_DDR506112002KQ,SMA    I22 @T6G_MB_LIB.T6G(SCH_1):PAGE95

M_K_CPU0_SA_DQ<24> @T6G_MB_LIB.T6G(SCH_1):M_K_CPU0_SA_DQ(24)
   U25  AC5 MKA_DATA24 GENOA_SP5-SOCKET6096_13568-001,SMLF,IO,DGA^6000030   I159 @T6G_MB_LIB.T6G(SCH_1):PAGE20
   J20   40 DQ24_A SCONN288_DDR506112002KQ-SCONN288_DDR506112002KQ,SMA    I22 @T6G_MB_LIB.T6G(SCH_1):PAGE95

M_K_CPU0_SA_DQ<25> @T6G_MB_LIB.T6G(SCH_1):M_K_CPU0_SA_DQ(25)
   U25  AD7 MKA_DATA25 GENOA_SP5-SOCKET6096_13568-001,SMLF,IO,DGA^6000030   I159 @T6G_MB_LIB.T6G(SCH_1):PAGE20
   J20   42 DQ25_A SCONN288_DDR506112002KQ-SCONN288_DDR506112002KQ,SMA    I22 @T6G_MB_LIB.T6G(SCH_1):PAGE95

M_K_CPU0_SA_DQ<26> @T6G_MB_LIB.T6G(SCH_1):M_K_CPU0_SA_DQ(26)
   U25  AD6 MKA_DATA26 GENOA_SP5-SOCKET6096_13568-001,SMLF,IO,DGA^6000030   I159 @T6G_MB_LIB.T6G(SCH_1):PAGE20
   J20  185 DQ26_A SCONN288_DDR506112002KQ-SCONN288_DDR506112002KQ,SMA    I22 @T6G_MB_LIB.T6G(SCH_1):PAGE95

M_K_CPU0_SA_DQ<27> @T6G_MB_LIB.T6G(SCH_1):M_K_CPU0_SA_DQ(27)
   U25  AE7 MKA_DATA27 GENOA_SP5-SOCKET6096_13568-001,SMLF,IO,DGA^6000030   I159 @T6G_MB_LIB.T6G(SCH_1):PAGE20
   J20  187 DQ27_A SCONN288_DDR506112002KQ-SCONN288_DDR506112002KQ,SMA    I22 @T6G_MB_LIB.T6G(SCH_1):PAGE95

M_K_CPU0_SA_DQ<28> @T6G_MB_LIB.T6G(SCH_1):M_K_CPU0_SA_DQ(28)
   U25  AG5 MKA_DATA28 GENOA_SP5-SOCKET6096_13568-001,SMLF,IO,DGA^6000030   I159 @T6G_MB_LIB.T6G(SCH_1):PAGE20
   J20   47 DQ28_A SCONN288_DDR506112002KQ-SCONN288_DDR506112002KQ,SMA    I22 @T6G_MB_LIB.T6G(SCH_1):PAGE95

M_K_CPU0_SA_DQ<29> @T6G_MB_LIB.T6G(SCH_1):M_K_CPU0_SA_DQ(29)
   U25  AH7 MKA_DATA29 GENOA_SP5-SOCKET6096_13568-001,SMLF,IO,DGA^6000030   I159 @T6G_MB_LIB.T6G(SCH_1):PAGE20
   J20   49 DQ29_A SCONN288_DDR506112002KQ-SCONN288_DDR506112002KQ,SMA    I22 @T6G_MB_LIB.T6G(SCH_1):PAGE95

M_K_CPU0_SA_DQ<2> @T6G_MB_LIB.T6G(SCH_1):M_K_CPU0_SA_DQ(2)
   U25   F6 MKA_DATA2 GENOA_SP5-SOCKET6096_13568-001,SMLF,IO,DGA^6000030   I159 @T6G_MB_LIB.T6G(SCH_1):PAGE20
   J20  152  DQ2_A SCONN288_DDR506112002KQ-SCONN288_DDR506112002KQ,SMA    I22 @T6G_MB_LIB.T6G(SCH_1):PAGE95

M_K_CPU0_SA_DQ<30> @T6G_MB_LIB.T6G(SCH_1):M_K_CPU0_SA_DQ(30)
   U25  AH6 MKA_DATA30 GENOA_SP5-SOCKET6096_13568-001,SMLF,IO,DGA^6000030   I159 @T6G_MB_LIB.T6G(SCH_1):PAGE20
   J20  192 DQ30_A SCONN288_DDR506112002KQ-SCONN288_DDR506112002KQ,SMA    I22 @T6G_MB_LIB.T6G(SCH_1):PAGE95

M_K_CPU0_SA_DQ<31> @T6G_MB_LIB.T6G(SCH_1):M_K_CPU0_SA_DQ(31)
   U25  AJ7 MKA_DATA31 GENOA_SP5-SOCKET6096_13568-001,SMLF,IO,DGA^6000030   I159 @T6G_MB_LIB.T6G(SCH_1):PAGE20
   J20  194 DQ31_A SCONN288_DDR506112002KQ-SCONN288_DDR506112002KQ,SMA    I22 @T6G_MB_LIB.T6G(SCH_1):PAGE95

M_K_CPU0_SA_DQ<3> @T6G_MB_LIB.T6G(SCH_1):M_K_CPU0_SA_DQ(3)
   U25   G7 MKA_DATA3 GENOA_SP5-SOCKET6096_13568-001,SMLF,IO,DGA^6000030   I159 @T6G_MB_LIB.T6G(SCH_1):PAGE20
   J20  154  DQ3_A SCONN288_DDR506112002KQ-SCONN288_DDR506112002KQ,SMA    I22 @T6G_MB_LIB.T6G(SCH_1):PAGE95

M_K_CPU0_SA_DQ<4> @T6G_MB_LIB.T6G(SCH_1):M_K_CPU0_SA_DQ(4)
   U25   J5 MKA_DATA4 GENOA_SP5-SOCKET6096_13568-001,SMLF,IO,DGA^6000030   I159 @T6G_MB_LIB.T6G(SCH_1):PAGE20
   J20   14  DQ4_A SCONN288_DDR506112002KQ-SCONN288_DDR506112002KQ,SMA    I22 @T6G_MB_LIB.T6G(SCH_1):PAGE95

M_K_CPU0_SA_DQ<5> @T6G_MB_LIB.T6G(SCH_1):M_K_CPU0_SA_DQ(5)
   U25   K7 MKA_DATA5 GENOA_SP5-SOCKET6096_13568-001,SMLF,IO,DGA^6000030   I159 @T6G_MB_LIB.T6G(SCH_1):PAGE20
   J20   16  DQ5_A SCONN288_DDR506112002KQ-SCONN288_DDR506112002KQ,SMA    I22 @T6G_MB_LIB.T6G(SCH_1):PAGE95

M_K_CPU0_SA_DQ<6> @T6G_MB_LIB.T6G(SCH_1):M_K_CPU0_SA_DQ(6)
   U25   K6 MKA_DATA6 GENOA_SP5-SOCKET6096_13568-001,SMLF,IO,DGA^6000030   I159 @T6G_MB_LIB.T6G(SCH_1):PAGE20
   J20  159  DQ6_A SCONN288_DDR506112002KQ-SCONN288_DDR506112002KQ,SMA    I22 @T6G_MB_LIB.T6G(SCH_1):PAGE95

M_K_CPU0_SA_DQ<7> @T6G_MB_LIB.T6G(SCH_1):M_K_CPU0_SA_DQ(7)
   U25   L7 MKA_DATA7 GENOA_SP5-SOCKET6096_13568-001,SMLF,IO,DGA^6000030   I159 @T6G_MB_LIB.T6G(SCH_1):PAGE20
   J20  161  DQ7_A SCONN288_DDR506112002KQ-SCONN288_DDR506112002KQ,SMA    I22 @T6G_MB_LIB.T6G(SCH_1):PAGE95

M_K_CPU0_SA_DQ<8> @T6G_MB_LIB.T6G(SCH_1):M_K_CPU0_SA_DQ(8)
   U25   L5 MKA_DATA8 GENOA_SP5-SOCKET6096_13568-001,SMLF,IO,DGA^6000030   I159 @T6G_MB_LIB.T6G(SCH_1):PAGE20
   J20   18  DQ8_A SCONN288_DDR506112002KQ-SCONN288_DDR506112002KQ,SMA    I22 @T6G_MB_LIB.T6G(SCH_1):PAGE95

M_K_CPU0_SA_DQ<9> @T6G_MB_LIB.T6G(SCH_1):M_K_CPU0_SA_DQ(9)
   U25   M7 MKA_DATA9 GENOA_SP5-SOCKET6096_13568-001,SMLF,IO,DGA^6000030   I159 @T6G_MB_LIB.T6G(SCH_1):PAGE20
   J20   20  DQ9_A SCONN288_DDR506112002KQ-SCONN288_DDR506112002KQ,SMA    I22 @T6G_MB_LIB.T6G(SCH_1):PAGE95

M_K_CPU0_SA_DQS_DN<0> @T6G_MB_LIB.T6G(SCH_1):M_K_CPU0_SA_DQS_DN(0)
   U25   H6 MKA_DQS_L0 GENOA_SP5-SOCKET6096_13568-001,SMLF,IO,DGA^6000030   I159 @T6G_MB_LIB.T6G(SCH_1):PAGE20
   J20   12 DQS0_A_C SCONN288_DDR506112002KQ-SCONN288_DDR506112002KQ,SMA   I236 @T6G_MB_LIB.T6G(SCH_1):PAGE95

M_K_CPU0_SA_DQS_DN<1> @T6G_MB_LIB.T6G(SCH_1):M_K_CPU0_SA_DQS_DN(1)
   U25   P6 MKA_DQS_L1 GENOA_SP5-SOCKET6096_13568-001,SMLF,IO,DGA^6000030   I159 @T6G_MB_LIB.T6G(SCH_1):PAGE20
   J20   23 DQS1_A_C SCONN288_DDR506112002KQ-SCONN288_DDR506112002KQ,SMA   I236 @T6G_MB_LIB.T6G(SCH_1):PAGE95

M_K_CPU0_SA_DQS_DN<2> @T6G_MB_LIB.T6G(SCH_1):M_K_CPU0_SA_DQS_DN(2)
   U25   Y6 MKA_DQS_L2 GENOA_SP5-SOCKET6096_13568-001,SMLF,IO,DGA^6000030   I159 @T6G_MB_LIB.T6G(SCH_1):PAGE20
   J20   34 DQS2_A_C SCONN288_DDR506112002KQ-SCONN288_DDR506112002KQ,SMA   I236 @T6G_MB_LIB.T6G(SCH_1):PAGE95

M_K_CPU0_SA_DQS_DN<3> @T6G_MB_LIB.T6G(SCH_1):M_K_CPU0_SA_DQS_DN(3)
   U25  AF6 MKA_DQS_L3 GENOA_SP5-SOCKET6096_13568-001,SMLF,IO,DGA^6000030   I159 @T6G_MB_LIB.T6G(SCH_1):PAGE20
   J20   45 DQS3_A_C SCONN288_DDR506112002KQ-SCONN288_DDR506112002KQ,SMA   I236 @T6G_MB_LIB.T6G(SCH_1):PAGE95

M_K_CPU0_SA_DQS_DN<4> @T6G_MB_LIB.T6G(SCH_1):M_K_CPU0_SA_DQS_DN(4)
   U25  AM6 MKA_DQS_L4 GENOA_SP5-SOCKET6096_13568-001,SMLF,IO,DGA^6000030   I159 @T6G_MB_LIB.T6G(SCH_1):PAGE20
   J20   56 DQS4_A_C SCONN288_DDR506112002KQ-SCONN288_DDR506112002KQ,SMA   I236 @T6G_MB_LIB.T6G(SCH_1):PAGE95

M_K_CPU0_SA_DQS_DN<5> @T6G_MB_LIB.T6G(SCH_1):M_K_CPU0_SA_DQS_DN(5)
   U25   H7 MKA_DQS_L5 GENOA_SP5-SOCKET6096_13568-001,SMLF,IO,DGA^6000030   I159 @T6G_MB_LIB.T6G(SCH_1):PAGE20
   J20  156 DQS5_A_C||TDQS5_A_C||DQS5_A_T||TDQS5_A_T SCONN288_DDR506112002KQ-SCONN288_DDR506112002KQ,SMA   I236 @T6G_MB_LIB.T6G(SCH_1):PAGE95

M_K_CPU0_SA_DQS_DN<6> @T6G_MB_LIB.T6G(SCH_1):M_K_CPU0_SA_DQS_DN(6)
   U25   P7 MKA_DQS_L6 GENOA_SP5-SOCKET6096_13568-001,SMLF,IO,DGA^6000030   I159 @T6G_MB_LIB.T6G(SCH_1):PAGE20
   J20  167 DQS6_A_C||TDQS6_A_C||DQS6_A_T||TDQS6_A_T SCONN288_DDR506112002KQ-SCONN288_DDR506112002KQ,SMA   I236 @T6G_MB_LIB.T6G(SCH_1):PAGE95

M_K_CPU0_SA_DQS_DN<7> @T6G_MB_LIB.T6G(SCH_1):M_K_CPU0_SA_DQS_DN(7)
   U25   Y7 MKA_DQS_L7 GENOA_SP5-SOCKET6096_13568-001,SMLF,IO,DGA^6000030   I159 @T6G_MB_LIB.T6G(SCH_1):PAGE20
   J20  178 DQS7_A_C||TDQS7_A_C SCONN288_DDR506112002KQ-SCONN288_DDR506112002KQ,SMA   I236 @T6G_MB_LIB.T6G(SCH_1):PAGE95

M_K_CPU0_SA_DQS_DN<8> @T6G_MB_LIB.T6G(SCH_1):M_K_CPU0_SA_DQS_DN(8)
   U25  AF7 MKA_DQS_L8 GENOA_SP5-SOCKET6096_13568-001,SMLF,IO,DGA^6000030   I159 @T6G_MB_LIB.T6G(SCH_1):PAGE20
   J20  189 DQS8_A_C||TDQS8_A_C SCONN288_DDR506112002KQ-SCONN288_DDR506112002KQ,SMA   I236 @T6G_MB_LIB.T6G(SCH_1):PAGE95

M_K_CPU0_SA_DQS_DN<9> @T6G_MB_LIB.T6G(SCH_1):M_K_CPU0_SA_DQS_DN(9)
   U25  AM7 MKA_DQS_L9 GENOA_SP5-SOCKET6096_13568-001,SMLF,IO,DGA^6000030   I159 @T6G_MB_LIB.T6G(SCH_1):PAGE20
   J20  200 DQS9_A_C||TDQS9_A_C SCONN288_DDR506112002KQ-SCONN288_DDR506112002KQ,SMA   I236 @T6G_MB_LIB.T6G(SCH_1):PAGE95

M_K_CPU0_SA_DQS_DP<0> @T6G_MB_LIB.T6G(SCH_1):M_K_CPU0_SA_DQS_DP(0)
   U25   G5 MKA_DQS_H0 GENOA_SP5-SOCKET6096_13568-001,SMLF,IO,DGA^6000030   I159 @T6G_MB_LIB.T6G(SCH_1):PAGE20
   J20   11 DQS0_A_T SCONN288_DDR506112002KQ-SCONN288_DDR506112002KQ,SMA   I236 @T6G_MB_LIB.T6G(SCH_1):PAGE95

M_K_CPU0_SA_DQS_DP<1> @T6G_MB_LIB.T6G(SCH_1):M_K_CPU0_SA_DQS_DP(1)
   U25   N5 MKA_DQS_H1 GENOA_SP5-SOCKET6096_13568-001,SMLF,IO,DGA^6000030   I159 @T6G_MB_LIB.T6G(SCH_1):PAGE20
   J20   22 DQS1_A_T SCONN288_DDR506112002KQ-SCONN288_DDR506112002KQ,SMA   I236 @T6G_MB_LIB.T6G(SCH_1):PAGE95

M_K_CPU0_SA_DQS_DP<2> @T6G_MB_LIB.T6G(SCH_1):M_K_CPU0_SA_DQS_DP(2)
   U25   W5 MKA_DQS_H2 GENOA_SP5-SOCKET6096_13568-001,SMLF,IO,DGA^6000030   I159 @T6G_MB_LIB.T6G(SCH_1):PAGE20
   J20   33 DQS2_A_T SCONN288_DDR506112002KQ-SCONN288_DDR506112002KQ,SMA   I236 @T6G_MB_LIB.T6G(SCH_1):PAGE95

M_K_CPU0_SA_DQS_DP<3> @T6G_MB_LIB.T6G(SCH_1):M_K_CPU0_SA_DQS_DP(3)
   U25  AE5 MKA_DQS_H3 GENOA_SP5-SOCKET6096_13568-001,SMLF,IO,DGA^6000030   I159 @T6G_MB_LIB.T6G(SCH_1):PAGE20
   J20   44 DQS3_A_T SCONN288_DDR506112002KQ-SCONN288_DDR506112002KQ,SMA   I236 @T6G_MB_LIB.T6G(SCH_1):PAGE95

M_K_CPU0_SA_DQS_DP<4> @T6G_MB_LIB.T6G(SCH_1):M_K_CPU0_SA_DQS_DP(4)
   U25  AL5 MKA_DQS_H4 GENOA_SP5-SOCKET6096_13568-001,SMLF,IO,DGA^6000030   I159 @T6G_MB_LIB.T6G(SCH_1):PAGE20
   J20   55 DQS4_A_T SCONN288_DDR506112002KQ-SCONN288_DDR506112002KQ,SMA   I236 @T6G_MB_LIB.T6G(SCH_1):PAGE95

M_K_CPU0_SA_DQS_DP<5> @T6G_MB_LIB.T6G(SCH_1):M_K_CPU0_SA_DQS_DP(5)
   U25   J7 MKA_DQS_H5 GENOA_SP5-SOCKET6096_13568-001,SMLF,IO,DGA^6000030   I159 @T6G_MB_LIB.T6G(SCH_1):PAGE20
   J20  157 DQS5_A_T||TDQS5_A_T SCONN288_DDR506112002KQ-SCONN288_DDR506112002KQ,SMA   I236 @T6G_MB_LIB.T6G(SCH_1):PAGE95

M_K_CPU0_SA_DQS_DP<6> @T6G_MB_LIB.T6G(SCH_1):M_K_CPU0_SA_DQS_DP(6)
   U25   R7 MKA_DQS_H6 GENOA_SP5-SOCKET6096_13568-001,SMLF,IO,DGA^6000030   I159 @T6G_MB_LIB.T6G(SCH_1):PAGE20
   J20  168 DQS6_A_T||TDQS6_A_T SCONN288_DDR506112002KQ-SCONN288_DDR506112002KQ,SMA   I236 @T6G_MB_LIB.T6G(SCH_1):PAGE95

M_K_CPU0_SA_DQS_DP<7> @T6G_MB_LIB.T6G(SCH_1):M_K_CPU0_SA_DQS_DP(7)
   U25  AA7 MKA_DQS_H7 GENOA_SP5-SOCKET6096_13568-001,SMLF,IO,DGA^6000030   I159 @T6G_MB_LIB.T6G(SCH_1):PAGE20
   J20  179 DQS7_A_T||TDQS7_A_T SCONN288_DDR506112002KQ-SCONN288_DDR506112002KQ,SMA   I236 @T6G_MB_LIB.T6G(SCH_1):PAGE95

M_K_CPU0_SA_DQS_DP<8> @T6G_MB_LIB.T6G(SCH_1):M_K_CPU0_SA_DQS_DP(8)
   U25  AG7 MKA_DQS_H8 GENOA_SP5-SOCKET6096_13568-001,SMLF,IO,DGA^6000030   I159 @T6G_MB_LIB.T6G(SCH_1):PAGE20
   J20  190 DQS8_A_T||TDQS8_A_T SCONN288_DDR506112002KQ-SCONN288_DDR506112002KQ,SMA   I236 @T6G_MB_LIB.T6G(SCH_1):PAGE95

M_K_CPU0_SA_DQS_DP<9> @T6G_MB_LIB.T6G(SCH_1):M_K_CPU0_SA_DQS_DP(9)
   U25  AN7 MKA_DQS_H9 GENOA_SP5-SOCKET6096_13568-001,SMLF,IO,DGA^6000030   I159 @T6G_MB_LIB.T6G(SCH_1):PAGE20
   J20  201 DQS9_A_T||TDQS9_A_T SCONN288_DDR506112002KQ-SCONN288_DDR506112002KQ,SMA   I236 @T6G_MB_LIB.T6G(SCH_1):PAGE95

M_K_CPU0_SA_PAR @T6G_MB_LIB.T6G(SCH_1):M_K_CPU0_SA_PAR
   U25  BC7 MKA_PAR GENOA_SP5-SOCKET6096_13568-001,SMLF,IO,DGA^6000030   I159 @T6G_MB_LIB.T6G(SCH_1):PAGE20
   J20   74  PAR_A SCONN288_DDR506112002KQ-SCONN288_DDR506112002KQ,SMA    I22 @T6G_MB_LIB.T6G(SCH_1):PAGE95

M_K_CPU0_SA_RSP<0> @T6G_MB_LIB.T6G(SCH_1):M_K_CPU0_SA_RSP(0)
   U25  BN7 MKA0_RSP_L GENOA_SP5-SOCKET6096_13568-001,SMLF,IO,DGA^6000030   I159 @T6G_MB_LIB.T6G(SCH_1):PAGE20
   J20   86 LBD||RSP_A_N SCONN288_DDR506112002KQ-SCONN288_DDR506112002KQ,SMA    I22 @T6G_MB_LIB.T6G(SCH_1):PAGE95

M_K_CPU0_SB_CA<0> @T6G_MB_LIB.T6G(SCH_1):M_K_CPU0_SB_CA(0)
   U25  BG7 MKB_CA0 GENOA_SP5-SOCKET6096_13568-001,SMLF,IO,DGA^6000030   I159 @T6G_MB_LIB.T6G(SCH_1):PAGE20
   J20   76  CA0_B SCONN288_DDR506112002KQ-SCONN288_DDR506112002KQ,SMA    I22 @T6G_MB_LIB.T6G(SCH_1):PAGE95

M_K_CPU0_SB_CA<1> @T6G_MB_LIB.T6G(SCH_1):M_K_CPU0_SB_CA(1)
   U25  BH7 MKB_CA1 GENOA_SP5-SOCKET6096_13568-001,SMLF,IO,DGA^6000030   I159 @T6G_MB_LIB.T6G(SCH_1):PAGE20
   J20  221  CA1_B SCONN288_DDR506112002KQ-SCONN288_DDR506112002KQ,SMA    I22 @T6G_MB_LIB.T6G(SCH_1):PAGE95

M_K_CPU0_SB_CA<2> @T6G_MB_LIB.T6G(SCH_1):M_K_CPU0_SB_CA(2)
   U25  BH6 MKB_CA2 GENOA_SP5-SOCKET6096_13568-001,SMLF,IO,DGA^6000030   I159 @T6G_MB_LIB.T6G(SCH_1):PAGE20
   J20   78  CA2_B SCONN288_DDR506112002KQ-SCONN288_DDR506112002KQ,SMA    I22 @T6G_MB_LIB.T6G(SCH_1):PAGE95

M_K_CPU0_SB_CA<3> @T6G_MB_LIB.T6G(SCH_1):M_K_CPU0_SB_CA(3)
   U25  BJ5 MKB_CA3 GENOA_SP5-SOCKET6096_13568-001,SMLF,IO,DGA^6000030   I159 @T6G_MB_LIB.T6G(SCH_1):PAGE20
   J20  223  CA3_B SCONN288_DDR506112002KQ-SCONN288_DDR506112002KQ,SMA    I22 @T6G_MB_LIB.T6G(SCH_1):PAGE95

M_K_CPU0_SB_CA<4> @T6G_MB_LIB.T6G(SCH_1):M_K_CPU0_SB_CA(4)
   U25  BJ7 MKB_CA4 GENOA_SP5-SOCKET6096_13568-001,SMLF,IO,DGA^6000030   I159 @T6G_MB_LIB.T6G(SCH_1):PAGE20
   J20   80  CA4_B SCONN288_DDR506112002KQ-SCONN288_DDR506112002KQ,SMA    I22 @T6G_MB_LIB.T6G(SCH_1):PAGE95

M_K_CPU0_SB_CA<5> @T6G_MB_LIB.T6G(SCH_1):M_K_CPU0_SB_CA(5)
   U25  BK7 MKB_CA5 GENOA_SP5-SOCKET6096_13568-001,SMLF,IO,DGA^6000030   I159 @T6G_MB_LIB.T6G(SCH_1):PAGE20
   J20  225  CA5_B SCONN288_DDR506112002KQ-SCONN288_DDR506112002KQ,SMA    I22 @T6G_MB_LIB.T6G(SCH_1):PAGE95

M_K_CPU0_SB_CA<6> @T6G_MB_LIB.T6G(SCH_1):M_K_CPU0_SB_CA(6)
   U25  BK6 MKB_CA6 GENOA_SP5-SOCKET6096_13568-001,SMLF,IO,DGA^6000030   I159 @T6G_MB_LIB.T6G(SCH_1):PAGE20
   J20   82  CA6_B SCONN288_DDR506112002KQ-SCONN288_DDR506112002KQ,SMA    I22 @T6G_MB_LIB.T6G(SCH_1):PAGE95

M_K_CPU0_SB_CB<0> @T6G_MB_LIB.T6G(SCH_1):M_K_CPU0_SB_CB(0)
   U25  BY6 MKB_CHECK0 GENOA_SP5-SOCKET6096_13568-001,SMLF,IO,DGA^6000030   I159 @T6G_MB_LIB.T6G(SCH_1):PAGE20
   J20   96  CB0_B SCONN288_DDR506112002KQ-SCONN288_DDR506112002KQ,SMA    I22 @T6G_MB_LIB.T6G(SCH_1):PAGE95

M_K_CPU0_SB_CB<1> @T6G_MB_LIB.T6G(SCH_1):M_K_CPU0_SB_CB(1)
   U25  CA7 MKB_CHECK1 GENOA_SP5-SOCKET6096_13568-001,SMLF,IO,DGA^6000030   I159 @T6G_MB_LIB.T6G(SCH_1):PAGE20
   J20   98  CB1_B SCONN288_DDR506112002KQ-SCONN288_DDR506112002KQ,SMA    I22 @T6G_MB_LIB.T6G(SCH_1):PAGE95

M_K_CPU0_SB_CB<2> @T6G_MB_LIB.T6G(SCH_1):M_K_CPU0_SB_CB(2)
   U25  CA5 MKB_CHECK2 GENOA_SP5-SOCKET6096_13568-001,SMLF,IO,DGA^6000030   I159 @T6G_MB_LIB.T6G(SCH_1):PAGE20
   J20  241  CB2_B SCONN288_DDR506112002KQ-SCONN288_DDR506112002KQ,SMA    I22 @T6G_MB_LIB.T6G(SCH_1):PAGE95

M_K_CPU0_SB_CB<3> @T6G_MB_LIB.T6G(SCH_1):M_K_CPU0_SB_CB(3)
   U25  CB7 MKB_CHECK3 GENOA_SP5-SOCKET6096_13568-001,SMLF,IO,DGA^6000030   I159 @T6G_MB_LIB.T6G(SCH_1):PAGE20
   J20  243  CB3_B SCONN288_DDR506112002KQ-SCONN288_DDR506112002KQ,SMA    I22 @T6G_MB_LIB.T6G(SCH_1):PAGE95

M_K_CPU0_SB_CB<4> @T6G_MB_LIB.T6G(SCH_1):M_K_CPU0_SB_CB(4)
   U25  BT6 MKB_CHECK4 GENOA_SP5-SOCKET6096_13568-001,SMLF,IO,DGA^6000030   I159 @T6G_MB_LIB.T6G(SCH_1):PAGE20
   J20   89  CB4_B SCONN288_DDR506112002KQ-SCONN288_DDR506112002KQ,SMA    I22 @T6G_MB_LIB.T6G(SCH_1):PAGE95

M_K_CPU0_SB_CB<5> @T6G_MB_LIB.T6G(SCH_1):M_K_CPU0_SB_CB(5)
   U25  BU7 MKB_CHECK5 GENOA_SP5-SOCKET6096_13568-001,SMLF,IO,DGA^6000030   I159 @T6G_MB_LIB.T6G(SCH_1):PAGE20
   J20   91  CB5_B SCONN288_DDR506112002KQ-SCONN288_DDR506112002KQ,SMA    I22 @T6G_MB_LIB.T6G(SCH_1):PAGE95

M_K_CPU0_SB_CB<6> @T6G_MB_LIB.T6G(SCH_1):M_K_CPU0_SB_CB(6)
   U25  BU5 MKB_CHECK6 GENOA_SP5-SOCKET6096_13568-001,SMLF,IO,DGA^6000030   I159 @T6G_MB_LIB.T6G(SCH_1):PAGE20
   J20  234  CB6_B SCONN288_DDR506112002KQ-SCONN288_DDR506112002KQ,SMA    I22 @T6G_MB_LIB.T6G(SCH_1):PAGE95

M_K_CPU0_SB_CB<7> @T6G_MB_LIB.T6G(SCH_1):M_K_CPU0_SB_CB(7)
   U25  BV7 MKB_CHECK7 GENOA_SP5-SOCKET6096_13568-001,SMLF,IO,DGA^6000030   I159 @T6G_MB_LIB.T6G(SCH_1):PAGE20
   J20  236  CB7_B SCONN288_DDR506112002KQ-SCONN288_DDR506112002KQ,SMA    I22 @T6G_MB_LIB.T6G(SCH_1):PAGE95

M_K_CPU0_SB_CS_N<0> @T6G_MB_LIB.T6G(SCH_1):M_K_CPU0_SB_CS_N(0)
   U25  BM7 MKB0_CS_L0 GENOA_SP5-SOCKET6096_13568-001,SMLF,IO,DGA^6000030   I159 @T6G_MB_LIB.T6G(SCH_1):PAGE20
   J20   84 CS0_B_N SCONN288_DDR506112002KQ-SCONN288_DDR506112002KQ,SMA    I22 @T6G_MB_LIB.T6G(SCH_1):PAGE95

M_K_CPU0_SB_CS_N<1> @T6G_MB_LIB.T6G(SCH_1):M_K_CPU0_SB_CS_N(1)
   U25  BN5 MKB0_CS_L1 GENOA_SP5-SOCKET6096_13568-001,SMLF,IO,DGA^6000030   I159 @T6G_MB_LIB.T6G(SCH_1):PAGE20
   J20  229 CS1_B_N SCONN288_DDR506112002KQ-SCONN288_DDR506112002KQ,SMA    I22 @T6G_MB_LIB.T6G(SCH_1):PAGE95

M_K_CPU0_SB_DQ<0> @T6G_MB_LIB.T6G(SCH_1):M_K_CPU0_SB_DQ(0)
   U25  CB6 MKB_DATA0 GENOA_SP5-SOCKET6096_13568-001,SMLF,IO,DGA^6000030   I159 @T6G_MB_LIB.T6G(SCH_1):PAGE20
   J20  100  DQ0_B SCONN288_DDR506112002KQ-SCONN288_DDR506112002KQ,SMA    I22 @T6G_MB_LIB.T6G(SCH_1):PAGE95

M_K_CPU0_SB_DQ<10> @T6G_MB_LIB.T6G(SCH_1):M_K_CPU0_SB_DQ(10)
   U25  CJ5 MKB_DATA10 GENOA_SP5-SOCKET6096_13568-001,SMLF,IO,DGA^6000030   I159 @T6G_MB_LIB.T6G(SCH_1):PAGE20
   J20  256 DQ10_B SCONN288_DDR506112002KQ-SCONN288_DDR506112002KQ,SMA    I22 @T6G_MB_LIB.T6G(SCH_1):PAGE95

M_K_CPU0_SB_DQ<11> @T6G_MB_LIB.T6G(SCH_1):M_K_CPU0_SB_DQ(11)
   U25  CK7 MKB_DATA11 GENOA_SP5-SOCKET6096_13568-001,SMLF,IO,DGA^6000030   I159 @T6G_MB_LIB.T6G(SCH_1):PAGE20
   J20  258 DQ11_B SCONN288_DDR506112002KQ-SCONN288_DDR506112002KQ,SMA    I22 @T6G_MB_LIB.T6G(SCH_1):PAGE95

M_K_CPU0_SB_DQ<12> @T6G_MB_LIB.T6G(SCH_1):M_K_CPU0_SB_DQ(12)
   U25  CM6 MKB_DATA12 GENOA_SP5-SOCKET6096_13568-001,SMLF,IO,DGA^6000030   I159 @T6G_MB_LIB.T6G(SCH_1):PAGE20
   J20  118 DQ12_B SCONN288_DDR506112002KQ-SCONN288_DDR506112002KQ,SMA    I22 @T6G_MB_LIB.T6G(SCH_1):PAGE95

M_K_CPU0_SB_DQ<13> @T6G_MB_LIB.T6G(SCH_1):M_K_CPU0_SB_DQ(13)
   U25  CN7 MKB_DATA13 GENOA_SP5-SOCKET6096_13568-001,SMLF,IO,DGA^6000030   I159 @T6G_MB_LIB.T6G(SCH_1):PAGE20
   J20  120 DQ13_B SCONN288_DDR506112002KQ-SCONN288_DDR506112002KQ,SMA    I22 @T6G_MB_LIB.T6G(SCH_1):PAGE95

M_K_CPU0_SB_DQ<14> @T6G_MB_LIB.T6G(SCH_1):M_K_CPU0_SB_DQ(14)
   U25  CN5 MKB_DATA14 GENOA_SP5-SOCKET6096_13568-001,SMLF,IO,DGA^6000030   I159 @T6G_MB_LIB.T6G(SCH_1):PAGE20
   J20  263 DQ14_B SCONN288_DDR506112002KQ-SCONN288_DDR506112002KQ,SMA    I22 @T6G_MB_LIB.T6G(SCH_1):PAGE95

M_K_CPU0_SB_DQ<15> @T6G_MB_LIB.T6G(SCH_1):M_K_CPU0_SB_DQ(15)
   U25  CP7 MKB_DATA15 GENOA_SP5-SOCKET6096_13568-001,SMLF,IO,DGA^6000030   I159 @T6G_MB_LIB.T6G(SCH_1):PAGE20
   J20  265 DQ15_B SCONN288_DDR506112002KQ-SCONN288_DDR506112002KQ,SMA    I22 @T6G_MB_LIB.T6G(SCH_1):PAGE95

M_K_CPU0_SB_DQ<16> @T6G_MB_LIB.T6G(SCH_1):M_K_CPU0_SB_DQ(16)
   U25  CP6 MKB_DATA16 GENOA_SP5-SOCKET6096_13568-001,SMLF,IO,DGA^6000030   I159 @T6G_MB_LIB.T6G(SCH_1):PAGE20
   J20  122 DQ16_B SCONN288_DDR506112002KQ-SCONN288_DDR506112002KQ,SMA    I22 @T6G_MB_LIB.T6G(SCH_1):PAGE95

M_K_CPU0_SB_DQ<17> @T6G_MB_LIB.T6G(SCH_1):M_K_CPU0_SB_DQ(17)
   U25  CR7 MKB_DATA17 GENOA_SP5-SOCKET6096_13568-001,SMLF,IO,DGA^6000030   I159 @T6G_MB_LIB.T6G(SCH_1):PAGE20
   J20  124 DQ17_B SCONN288_DDR506112002KQ-SCONN288_DDR506112002KQ,SMA    I22 @T6G_MB_LIB.T6G(SCH_1):PAGE95

M_K_CPU0_SB_DQ<18> @T6G_MB_LIB.T6G(SCH_1):M_K_CPU0_SB_DQ(18)
   U25  CR5 MKB_DATA18 GENOA_SP5-SOCKET6096_13568-001,SMLF,IO,DGA^6000030   I159 @T6G_MB_LIB.T6G(SCH_1):PAGE20
   J20  267 DQ18_B SCONN288_DDR506112002KQ-SCONN288_DDR506112002KQ,SMA    I22 @T6G_MB_LIB.T6G(SCH_1):PAGE95

M_K_CPU0_SB_DQ<19> @T6G_MB_LIB.T6G(SCH_1):M_K_CPU0_SB_DQ(19)
   U25  CT7 MKB_DATA19 GENOA_SP5-SOCKET6096_13568-001,SMLF,IO,DGA^6000030   I159 @T6G_MB_LIB.T6G(SCH_1):PAGE20
   J20  269 DQ19_B SCONN288_DDR506112002KQ-SCONN288_DDR506112002KQ,SMA    I22 @T6G_MB_LIB.T6G(SCH_1):PAGE95

M_K_CPU0_SB_DQ<1> @T6G_MB_LIB.T6G(SCH_1):M_K_CPU0_SB_DQ(1)
   U25  CC7 MKB_DATA1 GENOA_SP5-SOCKET6096_13568-001,SMLF,IO,DGA^6000030   I159 @T6G_MB_LIB.T6G(SCH_1):PAGE20
   J20  102  DQ1_B SCONN288_DDR506112002KQ-SCONN288_DDR506112002KQ,SMA    I22 @T6G_MB_LIB.T6G(SCH_1):PAGE95

M_K_CPU0_SB_DQ<20> @T6G_MB_LIB.T6G(SCH_1):M_K_CPU0_SB_DQ(20)
   U25  CV6 MKB_DATA20 GENOA_SP5-SOCKET6096_13568-001,SMLF,IO,DGA^6000030   I159 @T6G_MB_LIB.T6G(SCH_1):PAGE20
   J20  129 DQ20_B SCONN288_DDR506112002KQ-SCONN288_DDR506112002KQ,SMA    I22 @T6G_MB_LIB.T6G(SCH_1):PAGE95

M_K_CPU0_SB_DQ<21> @T6G_MB_LIB.T6G(SCH_1):M_K_CPU0_SB_DQ(21)
   U25  CW7 MKB_DATA21 GENOA_SP5-SOCKET6096_13568-001,SMLF,IO,DGA^6000030   I159 @T6G_MB_LIB.T6G(SCH_1):PAGE20
   J20  131 DQ21_B SCONN288_DDR506112002KQ-SCONN288_DDR506112002KQ,SMA    I22 @T6G_MB_LIB.T6G(SCH_1):PAGE95

M_K_CPU0_SB_DQ<22> @T6G_MB_LIB.T6G(SCH_1):M_K_CPU0_SB_DQ(22)
   U25  CW5 MKB_DATA22 GENOA_SP5-SOCKET6096_13568-001,SMLF,IO,DGA^6000030   I159 @T6G_MB_LIB.T6G(SCH_1):PAGE20
   J20  274 DQ22_B SCONN288_DDR506112002KQ-SCONN288_DDR506112002KQ,SMA    I22 @T6G_MB_LIB.T6G(SCH_1):PAGE95

M_K_CPU0_SB_DQ<23> @T6G_MB_LIB.T6G(SCH_1):M_K_CPU0_SB_DQ(23)
   U25  CY7 MKB_DATA23 GENOA_SP5-SOCKET6096_13568-001,SMLF,IO,DGA^6000030   I159 @T6G_MB_LIB.T6G(SCH_1):PAGE20
   J20  276 DQ23_B SCONN288_DDR506112002KQ-SCONN288_DDR506112002KQ,SMA    I22 @T6G_MB_LIB.T6G(SCH_1):PAGE95

M_K_CPU0_SB_DQ<24> @T6G_MB_LIB.T6G(SCH_1):M_K_CPU0_SB_DQ(24)
   U25  CY6 MKB_DATA24 GENOA_SP5-SOCKET6096_13568-001,SMLF,IO,DGA^6000030   I159 @T6G_MB_LIB.T6G(SCH_1):PAGE20
   J20  133 DQ24_B SCONN288_DDR506112002KQ-SCONN288_DDR506112002KQ,SMA    I22 @T6G_MB_LIB.T6G(SCH_1):PAGE95

M_K_CPU0_SB_DQ<25> @T6G_MB_LIB.T6G(SCH_1):M_K_CPU0_SB_DQ(25)
   U25  DA7 MKB_DATA25 GENOA_SP5-SOCKET6096_13568-001,SMLF,IO,DGA^6000030   I159 @T6G_MB_LIB.T6G(SCH_1):PAGE20
   J20  135 DQ25_B SCONN288_DDR506112002KQ-SCONN288_DDR506112002KQ,SMA    I22 @T6G_MB_LIB.T6G(SCH_1):PAGE95

M_K_CPU0_SB_DQ<26> @T6G_MB_LIB.T6G(SCH_1):M_K_CPU0_SB_DQ(26)
   U25  DA5 MKB_DATA26 GENOA_SP5-SOCKET6096_13568-001,SMLF,IO,DGA^6000030   I159 @T6G_MB_LIB.T6G(SCH_1):PAGE20
   J20  278 DQ26_B SCONN288_DDR506112002KQ-SCONN288_DDR506112002KQ,SMA    I22 @T6G_MB_LIB.T6G(SCH_1):PAGE95

M_K_CPU0_SB_DQ<27> @T6G_MB_LIB.T6G(SCH_1):M_K_CPU0_SB_DQ(27)
   U25  DB7 MKB_DATA27 GENOA_SP5-SOCKET6096_13568-001,SMLF,IO,DGA^6000030   I159 @T6G_MB_LIB.T6G(SCH_1):PAGE20
   J20  280 DQ27_B SCONN288_DDR506112002KQ-SCONN288_DDR506112002KQ,SMA    I22 @T6G_MB_LIB.T6G(SCH_1):PAGE95

M_K_CPU0_SB_DQ<28> @T6G_MB_LIB.T6G(SCH_1):M_K_CPU0_SB_DQ(28)
   U25  DD6 MKB_DATA28 GENOA_SP5-SOCKET6096_13568-001,SMLF,IO,DGA^6000030   I159 @T6G_MB_LIB.T6G(SCH_1):PAGE20
   J20  140 DQ28_B SCONN288_DDR506112002KQ-SCONN288_DDR506112002KQ,SMA    I22 @T6G_MB_LIB.T6G(SCH_1):PAGE95

M_K_CPU0_SB_DQ<29> @T6G_MB_LIB.T6G(SCH_1):M_K_CPU0_SB_DQ(29)
   U25  DE7 MKB_DATA29 GENOA_SP5-SOCKET6096_13568-001,SMLF,IO,DGA^6000030   I159 @T6G_MB_LIB.T6G(SCH_1):PAGE20
   J20  142 DQ29_B SCONN288_DDR506112002KQ-SCONN288_DDR506112002KQ,SMA    I22 @T6G_MB_LIB.T6G(SCH_1):PAGE95

M_K_CPU0_SB_DQ<2> @T6G_MB_LIB.T6G(SCH_1):M_K_CPU0_SB_DQ(2)
   U25  CC5 MKB_DATA2 GENOA_SP5-SOCKET6096_13568-001,SMLF,IO,DGA^6000030   I159 @T6G_MB_LIB.T6G(SCH_1):PAGE20
   J20  245  DQ2_B SCONN288_DDR506112002KQ-SCONN288_DDR506112002KQ,SMA    I22 @T6G_MB_LIB.T6G(SCH_1):PAGE95

M_K_CPU0_SB_DQ<30> @T6G_MB_LIB.T6G(SCH_1):M_K_CPU0_SB_DQ(30)
   U25  DE5 MKB_DATA30 GENOA_SP5-SOCKET6096_13568-001,SMLF,IO,DGA^6000030   I159 @T6G_MB_LIB.T6G(SCH_1):PAGE20
   J20  285 DQ30_B SCONN288_DDR506112002KQ-SCONN288_DDR506112002KQ,SMA    I22 @T6G_MB_LIB.T6G(SCH_1):PAGE95

M_K_CPU0_SB_DQ<31> @T6G_MB_LIB.T6G(SCH_1):M_K_CPU0_SB_DQ(31)
   U25  DF7 MKB_DATA31 GENOA_SP5-SOCKET6096_13568-001,SMLF,IO,DGA^6000030   I159 @T6G_MB_LIB.T6G(SCH_1):PAGE20
   J20  287 DQ31_B SCONN288_DDR506112002KQ-SCONN288_DDR506112002KQ,SMA    I22 @T6G_MB_LIB.T6G(SCH_1):PAGE95

M_K_CPU0_SB_DQ<3> @T6G_MB_LIB.T6G(SCH_1):M_K_CPU0_SB_DQ(3)
   U25  CD7 MKB_DATA3 GENOA_SP5-SOCKET6096_13568-001,SMLF,IO,DGA^6000030   I159 @T6G_MB_LIB.T6G(SCH_1):PAGE20
   J20  247  DQ3_B SCONN288_DDR506112002KQ-SCONN288_DDR506112002KQ,SMA    I22 @T6G_MB_LIB.T6G(SCH_1):PAGE95

M_K_CPU0_SB_DQ<4> @T6G_MB_LIB.T6G(SCH_1):M_K_CPU0_SB_DQ(4)
   U25  CF6 MKB_DATA4 GENOA_SP5-SOCKET6096_13568-001,SMLF,IO,DGA^6000030   I159 @T6G_MB_LIB.T6G(SCH_1):PAGE20
   J20  107  DQ4_B SCONN288_DDR506112002KQ-SCONN288_DDR506112002KQ,SMA    I22 @T6G_MB_LIB.T6G(SCH_1):PAGE95

M_K_CPU0_SB_DQ<5> @T6G_MB_LIB.T6G(SCH_1):M_K_CPU0_SB_DQ(5)
   U25  CG7 MKB_DATA5 GENOA_SP5-SOCKET6096_13568-001,SMLF,IO,DGA^6000030   I159 @T6G_MB_LIB.T6G(SCH_1):PAGE20
   J20  109  DQ5_B SCONN288_DDR506112002KQ-SCONN288_DDR506112002KQ,SMA    I22 @T6G_MB_LIB.T6G(SCH_1):PAGE95

M_K_CPU0_SB_DQ<6> @T6G_MB_LIB.T6G(SCH_1):M_K_CPU0_SB_DQ(6)
   U25  CG5 MKB_DATA6 GENOA_SP5-SOCKET6096_13568-001,SMLF,IO,DGA^6000030   I159 @T6G_MB_LIB.T6G(SCH_1):PAGE20
   J20  252  DQ6_B SCONN288_DDR506112002KQ-SCONN288_DDR506112002KQ,SMA    I22 @T6G_MB_LIB.T6G(SCH_1):PAGE95

M_K_CPU0_SB_DQ<7> @T6G_MB_LIB.T6G(SCH_1):M_K_CPU0_SB_DQ(7)
   U25  CH7 MKB_DATA7 GENOA_SP5-SOCKET6096_13568-001,SMLF,IO,DGA^6000030   I159 @T6G_MB_LIB.T6G(SCH_1):PAGE20
   J20  254  DQ7_B SCONN288_DDR506112002KQ-SCONN288_DDR506112002KQ,SMA    I22 @T6G_MB_LIB.T6G(SCH_1):PAGE95

M_K_CPU0_SB_DQ<8> @T6G_MB_LIB.T6G(SCH_1):M_K_CPU0_SB_DQ(8)
   U25  CH6 MKB_DATA8 GENOA_SP5-SOCKET6096_13568-001,SMLF,IO,DGA^6000030   I159 @T6G_MB_LIB.T6G(SCH_1):PAGE20
   J20  111  DQ8_B SCONN288_DDR506112002KQ-SCONN288_DDR506112002KQ,SMA    I22 @T6G_MB_LIB.T6G(SCH_1):PAGE95

M_K_CPU0_SB_DQ<9> @T6G_MB_LIB.T6G(SCH_1):M_K_CPU0_SB_DQ(9)
   U25  CJ7 MKB_DATA9 GENOA_SP5-SOCKET6096_13568-001,SMLF,IO,DGA^6000030   I159 @T6G_MB_LIB.T6G(SCH_1):PAGE20
   J20  113  DQ9_B SCONN288_DDR506112002KQ-SCONN288_DDR506112002KQ,SMA    I22 @T6G_MB_LIB.T6G(SCH_1):PAGE95

M_K_CPU0_SB_DQS_DN<0> @T6G_MB_LIB.T6G(SCH_1):M_K_CPU0_SB_DQS_DN(0)
   U25  CE5 MKB_DQS_L0 GENOA_SP5-SOCKET6096_13568-001,SMLF,IO,DGA^6000030   I159 @T6G_MB_LIB.T6G(SCH_1):PAGE20
   J20  105 DQS0_B_C SCONN288_DDR506112002KQ-SCONN288_DDR506112002KQ,SMA   I236 @T6G_MB_LIB.T6G(SCH_1):PAGE95

M_K_CPU0_SB_DQS_DN<1> @T6G_MB_LIB.T6G(SCH_1):M_K_CPU0_SB_DQS_DN(1)
   U25  CL5 MKB_DQS_L1 GENOA_SP5-SOCKET6096_13568-001,SMLF,IO,DGA^6000030   I159 @T6G_MB_LIB.T6G(SCH_1):PAGE20
   J20  116 DQS1_B_C SCONN288_DDR506112002KQ-SCONN288_DDR506112002KQ,SMA   I236 @T6G_MB_LIB.T6G(SCH_1):PAGE95

M_K_CPU0_SB_DQS_DN<2> @T6G_MB_LIB.T6G(SCH_1):M_K_CPU0_SB_DQS_DN(2)
   U25  CU5 MKB_DQS_L2 GENOA_SP5-SOCKET6096_13568-001,SMLF,IO,DGA^6000030   I159 @T6G_MB_LIB.T6G(SCH_1):PAGE20
   J20  127 DQS2_B_C SCONN288_DDR506112002KQ-SCONN288_DDR506112002KQ,SMA   I236 @T6G_MB_LIB.T6G(SCH_1):PAGE95

M_K_CPU0_SB_DQS_DN<3> @T6G_MB_LIB.T6G(SCH_1):M_K_CPU0_SB_DQS_DN(3)
   U25  DC5 MKB_DQS_L3 GENOA_SP5-SOCKET6096_13568-001,SMLF,IO,DGA^6000030   I159 @T6G_MB_LIB.T6G(SCH_1):PAGE20
   J20  138 DQS3_B_C SCONN288_DDR506112002KQ-SCONN288_DDR506112002KQ,SMA   I236 @T6G_MB_LIB.T6G(SCH_1):PAGE95

M_K_CPU0_SB_DQS_DN<4> @T6G_MB_LIB.T6G(SCH_1):M_K_CPU0_SB_DQS_DN(4)
   U25  BW7 MKB_DQS_L4 GENOA_SP5-SOCKET6096_13568-001,SMLF,IO,DGA^6000030   I159 @T6G_MB_LIB.T6G(SCH_1):PAGE20
   J20  238 DQS4_B_C SCONN288_DDR506112002KQ-SCONN288_DDR506112002KQ,SMA   I236 @T6G_MB_LIB.T6G(SCH_1):PAGE95

M_K_CPU0_SB_DQS_DN<5> @T6G_MB_LIB.T6G(SCH_1):M_K_CPU0_SB_DQS_DN(5)
   U25  CE7 MKB_DQS_L5 GENOA_SP5-SOCKET6096_13568-001,SMLF,IO,DGA^6000030   I159 @T6G_MB_LIB.T6G(SCH_1):PAGE20
   J20  249 DQS5_B_C||TDQS5_B_C SCONN288_DDR506112002KQ-SCONN288_DDR506112002KQ,SMA   I236 @T6G_MB_LIB.T6G(SCH_1):PAGE95

M_K_CPU0_SB_DQS_DN<6> @T6G_MB_LIB.T6G(SCH_1):M_K_CPU0_SB_DQS_DN(6)
   U25  CL7 MKB_DQS_L6 GENOA_SP5-SOCKET6096_13568-001,SMLF,IO,DGA^6000030   I159 @T6G_MB_LIB.T6G(SCH_1):PAGE20
   J20  260 DQS6_B_C||TDQS6_B_C SCONN288_DDR506112002KQ-SCONN288_DDR506112002KQ,SMA   I236 @T6G_MB_LIB.T6G(SCH_1):PAGE95

M_K_CPU0_SB_DQS_DN<7> @T6G_MB_LIB.T6G(SCH_1):M_K_CPU0_SB_DQS_DN(7)
   U25  CU7 MKB_DQS_L7 GENOA_SP5-SOCKET6096_13568-001,SMLF,IO,DGA^6000030   I159 @T6G_MB_LIB.T6G(SCH_1):PAGE20
   J20  271 DQS7_B_C||TDQS7_B_C SCONN288_DDR506112002KQ-SCONN288_DDR506112002KQ,SMA   I236 @T6G_MB_LIB.T6G(SCH_1):PAGE95

M_K_CPU0_SB_DQS_DN<8> @T6G_MB_LIB.T6G(SCH_1):M_K_CPU0_SB_DQS_DN(8)
   U25  DC7 MKB_DQS_L8 GENOA_SP5-SOCKET6096_13568-001,SMLF,IO,DGA^6000030   I159 @T6G_MB_LIB.T6G(SCH_1):PAGE20
   J20  282 DQS8_B_C||TDQS8_B_C SCONN288_DDR506112002KQ-SCONN288_DDR506112002KQ,SMA   I236 @T6G_MB_LIB.T6G(SCH_1):PAGE95

M_K_CPU0_SB_DQS_DN<9> @T6G_MB_LIB.T6G(SCH_1):M_K_CPU0_SB_DQS_DN(9)
   U25  BW5 MKB_DQS_L9 GENOA_SP5-SOCKET6096_13568-001,SMLF,IO,DGA^6000030   I159 @T6G_MB_LIB.T6G(SCH_1):PAGE20
   J20   94 DQS9_B_C||TDQS9_B_C SCONN288_DDR506112002KQ-SCONN288_DDR506112002KQ,SMA   I236 @T6G_MB_LIB.T6G(SCH_1):PAGE95

M_K_CPU0_SB_DQS_DP<0> @T6G_MB_LIB.T6G(SCH_1):M_K_CPU0_SB_DQS_DP(0)
   U25  CD6 MKB_DQS_H0 GENOA_SP5-SOCKET6096_13568-001,SMLF,IO,DGA^6000030   I159 @T6G_MB_LIB.T6G(SCH_1):PAGE20
   J20  104 DQS0_B_T SCONN288_DDR506112002KQ-SCONN288_DDR506112002KQ,SMA   I236 @T6G_MB_LIB.T6G(SCH_1):PAGE95

M_K_CPU0_SB_DQS_DP<1> @T6G_MB_LIB.T6G(SCH_1):M_K_CPU0_SB_DQS_DP(1)
   U25  CK6 MKB_DQS_H1 GENOA_SP5-SOCKET6096_13568-001,SMLF,IO,DGA^6000030   I159 @T6G_MB_LIB.T6G(SCH_1):PAGE20
   J20  115 DQS1_B_T SCONN288_DDR506112002KQ-SCONN288_DDR506112002KQ,SMA   I236 @T6G_MB_LIB.T6G(SCH_1):PAGE95

M_K_CPU0_SB_DQS_DP<2> @T6G_MB_LIB.T6G(SCH_1):M_K_CPU0_SB_DQS_DP(2)
   U25  CT6 MKB_DQS_H2 GENOA_SP5-SOCKET6096_13568-001,SMLF,IO,DGA^6000030   I159 @T6G_MB_LIB.T6G(SCH_1):PAGE20
   J20  126 DQS2_B_T SCONN288_DDR506112002KQ-SCONN288_DDR506112002KQ,SMA   I236 @T6G_MB_LIB.T6G(SCH_1):PAGE95

M_K_CPU0_SB_DQS_DP<3> @T6G_MB_LIB.T6G(SCH_1):M_K_CPU0_SB_DQS_DP(3)
   U25  DB6 MKB_DQS_H3 GENOA_SP5-SOCKET6096_13568-001,SMLF,IO,DGA^6000030   I159 @T6G_MB_LIB.T6G(SCH_1):PAGE20
   J20  137 DQS3_B_T SCONN288_DDR506112002KQ-SCONN288_DDR506112002KQ,SMA   I236 @T6G_MB_LIB.T6G(SCH_1):PAGE95

M_K_CPU0_SB_DQS_DP<4> @T6G_MB_LIB.T6G(SCH_1):M_K_CPU0_SB_DQS_DP(4)
   U25  BY7 MKB_DQS_H4 GENOA_SP5-SOCKET6096_13568-001,SMLF,IO,DGA^6000030   I159 @T6G_MB_LIB.T6G(SCH_1):PAGE20
   J20  239 DQS4_B_T SCONN288_DDR506112002KQ-SCONN288_DDR506112002KQ,SMA   I236 @T6G_MB_LIB.T6G(SCH_1):PAGE95

M_K_CPU0_SB_DQS_DP<5> @T6G_MB_LIB.T6G(SCH_1):M_K_CPU0_SB_DQS_DP(5)
   U25  CF7 MKB_DQS_H5 GENOA_SP5-SOCKET6096_13568-001,SMLF,IO,DGA^6000030   I159 @T6G_MB_LIB.T6G(SCH_1):PAGE20
   J20  250 DQS5_B_T||TDQS5_B_T SCONN288_DDR506112002KQ-SCONN288_DDR506112002KQ,SMA   I236 @T6G_MB_LIB.T6G(SCH_1):PAGE95

M_K_CPU0_SB_DQS_DP<6> @T6G_MB_LIB.T6G(SCH_1):M_K_CPU0_SB_DQS_DP(6)
   U25  CM7 MKB_DQS_H6 GENOA_SP5-SOCKET6096_13568-001,SMLF,IO,DGA^6000030   I159 @T6G_MB_LIB.T6G(SCH_1):PAGE20
   J20  261 DQS6_B_T||TDQS6_B_T SCONN288_DDR506112002KQ-SCONN288_DDR506112002KQ,SMA   I236 @T6G_MB_LIB.T6G(SCH_1):PAGE95

M_K_CPU0_SB_DQS_DP<7> @T6G_MB_LIB.T6G(SCH_1):M_K_CPU0_SB_DQS_DP(7)
   U25  CV7 MKB_DQS_H7 GENOA_SP5-SOCKET6096_13568-001,SMLF,IO,DGA^6000030   I159 @T6G_MB_LIB.T6G(SCH_1):PAGE20
   J20  272 DQS7_B_T||TDQS7_B_T SCONN288_DDR506112002KQ-SCONN288_DDR506112002KQ,SMA   I236 @T6G_MB_LIB.T6G(SCH_1):PAGE95

M_K_CPU0_SB_DQS_DP<8> @T6G_MB_LIB.T6G(SCH_1):M_K_CPU0_SB_DQS_DP(8)
   U25  DD7 MKB_DQS_H8 GENOA_SP5-SOCKET6096_13568-001,SMLF,IO,DGA^6000030   I159 @T6G_MB_LIB.T6G(SCH_1):PAGE20
   J20  283 DQS8_B_T||TDQS8_B_T SCONN288_DDR506112002KQ-SCONN288_DDR506112002KQ,SMA   I236 @T6G_MB_LIB.T6G(SCH_1):PAGE95

M_K_CPU0_SB_DQS_DP<9> @T6G_MB_LIB.T6G(SCH_1):M_K_CPU0_SB_DQS_DP(9)
   U25  BV6 MKB_DQS_H9 GENOA_SP5-SOCKET6096_13568-001,SMLF,IO,DGA^6000030   I159 @T6G_MB_LIB.T6G(SCH_1):PAGE20
   J20   93 DQS9_B_T||TDQS9_B_T||DBI4_B_N SCONN288_DDR506112002KQ-SCONN288_DDR506112002KQ,SMA   I236 @T6G_MB_LIB.T6G(SCH_1):PAGE95

M_K_CPU0_SB_PAR @T6G_MB_LIB.T6G(SCH_1):M_K_CPU0_SB_PAR
   U25  BL7 MKB_PAR GENOA_SP5-SOCKET6096_13568-001,SMLF,IO,DGA^6000030   I159 @T6G_MB_LIB.T6G(SCH_1):PAGE20
   J20  227  PAR_B SCONN288_DDR506112002KQ-SCONN288_DDR506112002KQ,SMA    I22 @T6G_MB_LIB.T6G(SCH_1):PAGE95

M_K_CPU0_SB_RSP<0> @T6G_MB_LIB.T6G(SCH_1):M_K_CPU0_SB_RSP(0)
   U25  BP6 MKB0_RSP_L GENOA_SP5-SOCKET6096_13568-001,SMLF,IO,DGA^6000030   I159 @T6G_MB_LIB.T6G(SCH_1):PAGE20
   J20   87 LBS||RSP_B_N SCONN288_DDR506112002KQ-SCONN288_DDR506112002KQ,SMA    I22 @T6G_MB_LIB.T6G(SCH_1):PAGE95

M_K_CPU1_ALERT_N @T6G_MB_LIB.T6G(SCH_1):M_K_CPU1_ALERT_N
  R510    1      A Q_RES_0402LF-15,1%,1/16W,CHIP,CS01502FB03   I314 @T6G_MB_LIB.T6G(SCH_1):PAGE47
   J99   62 ALERT_N SCONN288_DDR506112002KQ-SCONN288_DDR506112002KQ,SMA    I22 @T6G_MB_LIB.T6G(SCH_1):PAGE107

M_K_CPU1_ALERT_R_N @T6G_MB_LIB.T6G(SCH_1):M_K_CPU1_ALERT_R_N
   U26  AT7 MK_ALERT_L GENOA_SP5-SOCKET6096_13568-001,SMLF,IO,DGA^6000030   I159 @T6G_MB_LIB.T6G(SCH_1):PAGE47
  R510    2      B Q_RES_0402LF-15,1%,1/16W,CHIP,CS01502FB03   I314 @T6G_MB_LIB.T6G(SCH_1):PAGE47

M_K_CPU1_CLK_DN<0> @T6G_MB_LIB.T6G(SCH_1):M_K_CPU1_CLK_DN(0)
   U26  BD6 MK0_CLK_L GENOA_SP5-SOCKET6096_13568-001,SMLF,IO,DGA^6000030   I159 @T6G_MB_LIB.T6G(SCH_1):PAGE47
   J99  218   CK_C SCONN288_DDR506112002KQ-SCONN288_DDR506112002KQ,SMA    I22 @T6G_MB_LIB.T6G(SCH_1):PAGE107

M_K_CPU1_CLK_DP<0> @T6G_MB_LIB.T6G(SCH_1):M_K_CPU1_CLK_DP(0)
   U26  BC5 MK0_CLK_H GENOA_SP5-SOCKET6096_13568-001,SMLF,IO,DGA^6000030   I159 @T6G_MB_LIB.T6G(SCH_1):PAGE47
   J99  217   CK_T SCONN288_DDR506112002KQ-SCONN288_DDR506112002KQ,SMA    I22 @T6G_MB_LIB.T6G(SCH_1):PAGE107

M_K_CPU1_RESET_N @T6G_MB_LIB.T6G(SCH_1):M_K_CPU1_RESET_N
   U26  AU7 MK_RESET_L GENOA_SP5-SOCKET6096_13568-001,SMLF,IO,DGA^6000030   I159 @T6G_MB_LIB.T6G(SCH_1):PAGE47
   J99  207 RESET_N SCONN288_DDR506112002KQ-SCONN288_DDR506112002KQ,SMA    I22 @T6G_MB_LIB.T6G(SCH_1):PAGE107

M_K_CPU1_SA_CA<0> @T6G_MB_LIB.T6G(SCH_1):M_K_CPU1_SA_CA(0)
   U26  AW5 MKA_CA0 GENOA_SP5-SOCKET6096_13568-001,SMLF,IO,DGA^6000030   I159 @T6G_MB_LIB.T6G(SCH_1):PAGE47
   J99   66  CA0_A SCONN288_DDR506112002KQ-SCONN288_DDR506112002KQ,SMA    I22 @T6G_MB_LIB.T6G(SCH_1):PAGE107

M_K_CPU1_SA_CA<1> @T6G_MB_LIB.T6G(SCH_1):M_K_CPU1_SA_CA(1)
   U26  AY6 MKA_CA1 GENOA_SP5-SOCKET6096_13568-001,SMLF,IO,DGA^6000030   I159 @T6G_MB_LIB.T6G(SCH_1):PAGE47
   J99  211  CA1_A SCONN288_DDR506112002KQ-SCONN288_DDR506112002KQ,SMA    I22 @T6G_MB_LIB.T6G(SCH_1):PAGE107

M_K_CPU1_SA_CA<2> @T6G_MB_LIB.T6G(SCH_1):M_K_CPU1_SA_CA(2)
   U26  AY7 MKA_CA2 GENOA_SP5-SOCKET6096_13568-001,SMLF,IO,DGA^6000030   I159 @T6G_MB_LIB.T6G(SCH_1):PAGE47
   J99   68  CA2_A SCONN288_DDR506112002KQ-SCONN288_DDR506112002KQ,SMA    I22 @T6G_MB_LIB.T6G(SCH_1):PAGE107

M_K_CPU1_SA_CA<3> @T6G_MB_LIB.T6G(SCH_1):M_K_CPU1_SA_CA(3)
   U26  BA7 MKA_CA3 GENOA_SP5-SOCKET6096_13568-001,SMLF,IO,DGA^6000030   I159 @T6G_MB_LIB.T6G(SCH_1):PAGE47
   J99  213  CA3_A SCONN288_DDR506112002KQ-SCONN288_DDR506112002KQ,SMA    I22 @T6G_MB_LIB.T6G(SCH_1):PAGE107

M_K_CPU1_SA_CA<4> @T6G_MB_LIB.T6G(SCH_1):M_K_CPU1_SA_CA(4)
   U26  BA5 MKA_CA4 GENOA_SP5-SOCKET6096_13568-001,SMLF,IO,DGA^6000030   I159 @T6G_MB_LIB.T6G(SCH_1):PAGE47
   J99   70  CA4_A SCONN288_DDR506112002KQ-SCONN288_DDR506112002KQ,SMA    I22 @T6G_MB_LIB.T6G(SCH_1):PAGE107

M_K_CPU1_SA_CA<5> @T6G_MB_LIB.T6G(SCH_1):M_K_CPU1_SA_CA(5)
   U26  BB6 MKA_CA5 GENOA_SP5-SOCKET6096_13568-001,SMLF,IO,DGA^6000030   I159 @T6G_MB_LIB.T6G(SCH_1):PAGE47
   J99  215  CA5_A SCONN288_DDR506112002KQ-SCONN288_DDR506112002KQ,SMA    I22 @T6G_MB_LIB.T6G(SCH_1):PAGE107

M_K_CPU1_SA_CA<6> @T6G_MB_LIB.T6G(SCH_1):M_K_CPU1_SA_CA(6)
   U26  BB7 MKA_CA6 GENOA_SP5-SOCKET6096_13568-001,SMLF,IO,DGA^6000030   I159 @T6G_MB_LIB.T6G(SCH_1):PAGE47
   J99   72  CA6_A SCONN288_DDR506112002KQ-SCONN288_DDR506112002KQ,SMA    I22 @T6G_MB_LIB.T6G(SCH_1):PAGE107

M_K_CPU1_SA_CB<0> @T6G_MB_LIB.T6G(SCH_1):M_K_CPU1_SA_CB(0)
   U26  AJ5 MKA_CHECK0 GENOA_SP5-SOCKET6096_13568-001,SMLF,IO,DGA^6000030   I159 @T6G_MB_LIB.T6G(SCH_1):PAGE47
   J99   51  CB0_A SCONN288_DDR506112002KQ-SCONN288_DDR506112002KQ,SMA    I22 @T6G_MB_LIB.T6G(SCH_1):PAGE107

M_K_CPU1_SA_CB<1> @T6G_MB_LIB.T6G(SCH_1):M_K_CPU1_SA_CB(1)
   U26  AK7 MKA_CHECK1 GENOA_SP5-SOCKET6096_13568-001,SMLF,IO,DGA^6000030   I159 @T6G_MB_LIB.T6G(SCH_1):PAGE47
   J99   53  CB1_A SCONN288_DDR506112002KQ-SCONN288_DDR506112002KQ,SMA    I22 @T6G_MB_LIB.T6G(SCH_1):PAGE107

M_K_CPU1_SA_CB<2> @T6G_MB_LIB.T6G(SCH_1):M_K_CPU1_SA_CB(2)
   U26  AK6 MKA_CHECK2 GENOA_SP5-SOCKET6096_13568-001,SMLF,IO,DGA^6000030   I159 @T6G_MB_LIB.T6G(SCH_1):PAGE47
   J99  196  CB2_A SCONN288_DDR506112002KQ-SCONN288_DDR506112002KQ,SMA    I22 @T6G_MB_LIB.T6G(SCH_1):PAGE107

M_K_CPU1_SA_CB<3> @T6G_MB_LIB.T6G(SCH_1):M_K_CPU1_SA_CB(3)
   U26  AL7 MKA_CHECK3 GENOA_SP5-SOCKET6096_13568-001,SMLF,IO,DGA^6000030   I159 @T6G_MB_LIB.T6G(SCH_1):PAGE47
   J99  198  CB3_A SCONN288_DDR506112002KQ-SCONN288_DDR506112002KQ,SMA    I22 @T6G_MB_LIB.T6G(SCH_1):PAGE107

M_K_CPU1_SA_CB<4> @T6G_MB_LIB.T6G(SCH_1):M_K_CPU1_SA_CB(4)
   U26  AN5 MKA_CHECK4 GENOA_SP5-SOCKET6096_13568-001,SMLF,IO,DGA^6000030   I159 @T6G_MB_LIB.T6G(SCH_1):PAGE47
   J99   58  CB4_A SCONN288_DDR506112002KQ-SCONN288_DDR506112002KQ,SMA    I22 @T6G_MB_LIB.T6G(SCH_1):PAGE107

M_K_CPU1_SA_CB<5> @T6G_MB_LIB.T6G(SCH_1):M_K_CPU1_SA_CB(5)
   U26  AP7 MKA_CHECK5 GENOA_SP5-SOCKET6096_13568-001,SMLF,IO,DGA^6000030   I159 @T6G_MB_LIB.T6G(SCH_1):PAGE47
   J99   60  CB5_A SCONN288_DDR506112002KQ-SCONN288_DDR506112002KQ,SMA    I22 @T6G_MB_LIB.T6G(SCH_1):PAGE107

M_K_CPU1_SA_CB<6> @T6G_MB_LIB.T6G(SCH_1):M_K_CPU1_SA_CB(6)
   U26  AP6 MKA_CHECK6 GENOA_SP5-SOCKET6096_13568-001,SMLF,IO,DGA^6000030   I159 @T6G_MB_LIB.T6G(SCH_1):PAGE47
   J99  203  CB6_A SCONN288_DDR506112002KQ-SCONN288_DDR506112002KQ,SMA    I22 @T6G_MB_LIB.T6G(SCH_1):PAGE107

M_K_CPU1_SA_CB<7> @T6G_MB_LIB.T6G(SCH_1):M_K_CPU1_SA_CB(7)
   U26  AR7 MKA_CHECK7 GENOA_SP5-SOCKET6096_13568-001,SMLF,IO,DGA^6000030   I159 @T6G_MB_LIB.T6G(SCH_1):PAGE47
   J99  205  CB7_A SCONN288_DDR506112002KQ-SCONN288_DDR506112002KQ,SMA    I22 @T6G_MB_LIB.T6G(SCH_1):PAGE107

M_K_CPU1_SA_CS_N<0> @T6G_MB_LIB.T6G(SCH_1):M_K_CPU1_SA_CS_N(0)
   U26  AU5 MKA0_CS_L0 GENOA_SP5-SOCKET6096_13568-001,SMLF,IO,DGA^6000030   I159 @T6G_MB_LIB.T6G(SCH_1):PAGE47
   J99   64 CS0_A_N SCONN288_DDR506112002KQ-SCONN288_DDR506112002KQ,SMA    I22 @T6G_MB_LIB.T6G(SCH_1):PAGE107

M_K_CPU1_SA_CS_N<1> @T6G_MB_LIB.T6G(SCH_1):M_K_CPU1_SA_CS_N(1)
   U26  AV7 MKA0_CS_L1 GENOA_SP5-SOCKET6096_13568-001,SMLF,IO,DGA^6000030   I159 @T6G_MB_LIB.T6G(SCH_1):PAGE47
   J99  209 CS1_A_N SCONN288_DDR506112002KQ-SCONN288_DDR506112002KQ,SMA    I22 @T6G_MB_LIB.T6G(SCH_1):PAGE107

M_K_CPU1_SA_DQ<0> @T6G_MB_LIB.T6G(SCH_1):M_K_CPU1_SA_DQ(0)
   U26   E5 MKA_DATA0 GENOA_SP5-SOCKET6096_13568-001,SMLF,IO,DGA^6000030   I159 @T6G_MB_LIB.T6G(SCH_1):PAGE47
   J99    7  DQ0_A SCONN288_DDR506112002KQ-SCONN288_DDR506112002KQ,SMA    I22 @T6G_MB_LIB.T6G(SCH_1):PAGE107

M_K_CPU1_SA_DQ<10> @T6G_MB_LIB.T6G(SCH_1):M_K_CPU1_SA_DQ(10)
   U26   M6 MKA_DATA10 GENOA_SP5-SOCKET6096_13568-001,SMLF,IO,DGA^6000030   I159 @T6G_MB_LIB.T6G(SCH_1):PAGE47
   J99  163 DQ10_A SCONN288_DDR506112002KQ-SCONN288_DDR506112002KQ,SMA    I22 @T6G_MB_LIB.T6G(SCH_1):PAGE107

M_K_CPU1_SA_DQ<11> @T6G_MB_LIB.T6G(SCH_1):M_K_CPU1_SA_DQ(11)
   U26   N7 MKA_DATA11 GENOA_SP5-SOCKET6096_13568-001,SMLF,IO,DGA^6000030   I159 @T6G_MB_LIB.T6G(SCH_1):PAGE47
   J99  165 DQ11_A SCONN288_DDR506112002KQ-SCONN288_DDR506112002KQ,SMA    I22 @T6G_MB_LIB.T6G(SCH_1):PAGE107

M_K_CPU1_SA_DQ<12> @T6G_MB_LIB.T6G(SCH_1):M_K_CPU1_SA_DQ(12)
   U26   R5 MKA_DATA12 GENOA_SP5-SOCKET6096_13568-001,SMLF,IO,DGA^6000030   I159 @T6G_MB_LIB.T6G(SCH_1):PAGE47
   J99   25 DQ12_A SCONN288_DDR506112002KQ-SCONN288_DDR506112002KQ,SMA    I22 @T6G_MB_LIB.T6G(SCH_1):PAGE107

M_K_CPU1_SA_DQ<13> @T6G_MB_LIB.T6G(SCH_1):M_K_CPU1_SA_DQ(13)
   U26   T7 MKA_DATA13 GENOA_SP5-SOCKET6096_13568-001,SMLF,IO,DGA^6000030   I159 @T6G_MB_LIB.T6G(SCH_1):PAGE47
   J99   27 DQ13_A SCONN288_DDR506112002KQ-SCONN288_DDR506112002KQ,SMA    I22 @T6G_MB_LIB.T6G(SCH_1):PAGE107

M_K_CPU1_SA_DQ<14> @T6G_MB_LIB.T6G(SCH_1):M_K_CPU1_SA_DQ(14)
   U26   T6 MKA_DATA14 GENOA_SP5-SOCKET6096_13568-001,SMLF,IO,DGA^6000030   I159 @T6G_MB_LIB.T6G(SCH_1):PAGE47
   J99  170 DQ14_A SCONN288_DDR506112002KQ-SCONN288_DDR506112002KQ,SMA    I22 @T6G_MB_LIB.T6G(SCH_1):PAGE107

M_K_CPU1_SA_DQ<15> @T6G_MB_LIB.T6G(SCH_1):M_K_CPU1_SA_DQ(15)
   U26   U7 MKA_DATA15 GENOA_SP5-SOCKET6096_13568-001,SMLF,IO,DGA^6000030   I159 @T6G_MB_LIB.T6G(SCH_1):PAGE47
   J99  172 DQ15_A SCONN288_DDR506112002KQ-SCONN288_DDR506112002KQ,SMA    I22 @T6G_MB_LIB.T6G(SCH_1):PAGE107

M_K_CPU1_SA_DQ<16> @T6G_MB_LIB.T6G(SCH_1):M_K_CPU1_SA_DQ(16)
   U26   U5 MKA_DATA16 GENOA_SP5-SOCKET6096_13568-001,SMLF,IO,DGA^6000030   I159 @T6G_MB_LIB.T6G(SCH_1):PAGE47
   J99   29 DQ16_A SCONN288_DDR506112002KQ-SCONN288_DDR506112002KQ,SMA    I22 @T6G_MB_LIB.T6G(SCH_1):PAGE107

M_K_CPU1_SA_DQ<17> @T6G_MB_LIB.T6G(SCH_1):M_K_CPU1_SA_DQ(17)
   U26   V7 MKA_DATA17 GENOA_SP5-SOCKET6096_13568-001,SMLF,IO,DGA^6000030   I159 @T6G_MB_LIB.T6G(SCH_1):PAGE47
   J99   31 DQ17_A SCONN288_DDR506112002KQ-SCONN288_DDR506112002KQ,SMA    I22 @T6G_MB_LIB.T6G(SCH_1):PAGE107

M_K_CPU1_SA_DQ<18> @T6G_MB_LIB.T6G(SCH_1):M_K_CPU1_SA_DQ(18)
   U26   V6 MKA_DATA18 GENOA_SP5-SOCKET6096_13568-001,SMLF,IO,DGA^6000030   I159 @T6G_MB_LIB.T6G(SCH_1):PAGE47
   J99  174 DQ18_A SCONN288_DDR506112002KQ-SCONN288_DDR506112002KQ,SMA    I22 @T6G_MB_LIB.T6G(SCH_1):PAGE107

M_K_CPU1_SA_DQ<19> @T6G_MB_LIB.T6G(SCH_1):M_K_CPU1_SA_DQ(19)
   U26   W7 MKA_DATA19 GENOA_SP5-SOCKET6096_13568-001,SMLF,IO,DGA^6000030   I159 @T6G_MB_LIB.T6G(SCH_1):PAGE47
   J99  176 DQ19_A SCONN288_DDR506112002KQ-SCONN288_DDR506112002KQ,SMA    I22 @T6G_MB_LIB.T6G(SCH_1):PAGE107

M_K_CPU1_SA_DQ<1> @T6G_MB_LIB.T6G(SCH_1):M_K_CPU1_SA_DQ(1)
   U26   F7 MKA_DATA1 GENOA_SP5-SOCKET6096_13568-001,SMLF,IO,DGA^6000030   I159 @T6G_MB_LIB.T6G(SCH_1):PAGE47
   J99    9  DQ1_A SCONN288_DDR506112002KQ-SCONN288_DDR506112002KQ,SMA    I22 @T6G_MB_LIB.T6G(SCH_1):PAGE107

M_K_CPU1_SA_DQ<20> @T6G_MB_LIB.T6G(SCH_1):M_K_CPU1_SA_DQ(20)
   U26  AA5 MKA_DATA20 GENOA_SP5-SOCKET6096_13568-001,SMLF,IO,DGA^6000030   I159 @T6G_MB_LIB.T6G(SCH_1):PAGE47
   J99   36 DQ20_A SCONN288_DDR506112002KQ-SCONN288_DDR506112002KQ,SMA    I22 @T6G_MB_LIB.T6G(SCH_1):PAGE107

M_K_CPU1_SA_DQ<21> @T6G_MB_LIB.T6G(SCH_1):M_K_CPU1_SA_DQ(21)
   U26  AB7 MKA_DATA21 GENOA_SP5-SOCKET6096_13568-001,SMLF,IO,DGA^6000030   I159 @T6G_MB_LIB.T6G(SCH_1):PAGE47
   J99   38 DQ21_A SCONN288_DDR506112002KQ-SCONN288_DDR506112002KQ,SMA    I22 @T6G_MB_LIB.T6G(SCH_1):PAGE107

M_K_CPU1_SA_DQ<22> @T6G_MB_LIB.T6G(SCH_1):M_K_CPU1_SA_DQ(22)
   U26  AB6 MKA_DATA22 GENOA_SP5-SOCKET6096_13568-001,SMLF,IO,DGA^6000030   I159 @T6G_MB_LIB.T6G(SCH_1):PAGE47
   J99  181 DQ22_A SCONN288_DDR506112002KQ-SCONN288_DDR506112002KQ,SMA    I22 @T6G_MB_LIB.T6G(SCH_1):PAGE107

M_K_CPU1_SA_DQ<23> @T6G_MB_LIB.T6G(SCH_1):M_K_CPU1_SA_DQ(23)
   U26  AC7 MKA_DATA23 GENOA_SP5-SOCKET6096_13568-001,SMLF,IO,DGA^6000030   I159 @T6G_MB_LIB.T6G(SCH_1):PAGE47
   J99  183 DQ23_A SCONN288_DDR506112002KQ-SCONN288_DDR506112002KQ,SMA    I22 @T6G_MB_LIB.T6G(SCH_1):PAGE107

M_K_CPU1_SA_DQ<24> @T6G_MB_LIB.T6G(SCH_1):M_K_CPU1_SA_DQ(24)
   U26  AC5 MKA_DATA24 GENOA_SP5-SOCKET6096_13568-001,SMLF,IO,DGA^6000030   I159 @T6G_MB_LIB.T6G(SCH_1):PAGE47
   J99   40 DQ24_A SCONN288_DDR506112002KQ-SCONN288_DDR506112002KQ,SMA    I22 @T6G_MB_LIB.T6G(SCH_1):PAGE107

M_K_CPU1_SA_DQ<25> @T6G_MB_LIB.T6G(SCH_1):M_K_CPU1_SA_DQ(25)
   U26  AD7 MKA_DATA25 GENOA_SP5-SOCKET6096_13568-001,SMLF,IO,DGA^6000030   I159 @T6G_MB_LIB.T6G(SCH_1):PAGE47
   J99   42 DQ25_A SCONN288_DDR506112002KQ-SCONN288_DDR506112002KQ,SMA    I22 @T6G_MB_LIB.T6G(SCH_1):PAGE107

M_K_CPU1_SA_DQ<26> @T6G_MB_LIB.T6G(SCH_1):M_K_CPU1_SA_DQ(26)
   U26  AD6 MKA_DATA26 GENOA_SP5-SOCKET6096_13568-001,SMLF,IO,DGA^6000030   I159 @T6G_MB_LIB.T6G(SCH_1):PAGE47
   J99  185 DQ26_A SCONN288_DDR506112002KQ-SCONN288_DDR506112002KQ,SMA    I22 @T6G_MB_LIB.T6G(SCH_1):PAGE107

M_K_CPU1_SA_DQ<27> @T6G_MB_LIB.T6G(SCH_1):M_K_CPU1_SA_DQ(27)
   U26  AE7 MKA_DATA27 GENOA_SP5-SOCKET6096_13568-001,SMLF,IO,DGA^6000030   I159 @T6G_MB_LIB.T6G(SCH_1):PAGE47
   J99  187 DQ27_A SCONN288_DDR506112002KQ-SCONN288_DDR506112002KQ,SMA    I22 @T6G_MB_LIB.T6G(SCH_1):PAGE107

M_K_CPU1_SA_DQ<28> @T6G_MB_LIB.T6G(SCH_1):M_K_CPU1_SA_DQ(28)
   U26  AG5 MKA_DATA28 GENOA_SP5-SOCKET6096_13568-001,SMLF,IO,DGA^6000030   I159 @T6G_MB_LIB.T6G(SCH_1):PAGE47
   J99   47 DQ28_A SCONN288_DDR506112002KQ-SCONN288_DDR506112002KQ,SMA    I22 @T6G_MB_LIB.T6G(SCH_1):PAGE107

M_K_CPU1_SA_DQ<29> @T6G_MB_LIB.T6G(SCH_1):M_K_CPU1_SA_DQ(29)
   U26  AH7 MKA_DATA29 GENOA_SP5-SOCKET6096_13568-001,SMLF,IO,DGA^6000030   I159 @T6G_MB_LIB.T6G(SCH_1):PAGE47
   J99   49 DQ29_A SCONN288_DDR506112002KQ-SCONN288_DDR506112002KQ,SMA    I22 @T6G_MB_LIB.T6G(SCH_1):PAGE107

M_K_CPU1_SA_DQ<2> @T6G_MB_LIB.T6G(SCH_1):M_K_CPU1_SA_DQ(2)
   U26   F6 MKA_DATA2 GENOA_SP5-SOCKET6096_13568-001,SMLF,IO,DGA^6000030   I159 @T6G_MB_LIB.T6G(SCH_1):PAGE47
   J99  152  DQ2_A SCONN288_DDR506112002KQ-SCONN288_DDR506112002KQ,SMA    I22 @T6G_MB_LIB.T6G(SCH_1):PAGE107

M_K_CPU1_SA_DQ<30> @T6G_MB_LIB.T6G(SCH_1):M_K_CPU1_SA_DQ(30)
   U26  AH6 MKA_DATA30 GENOA_SP5-SOCKET6096_13568-001,SMLF,IO,DGA^6000030   I159 @T6G_MB_LIB.T6G(SCH_1):PAGE47
   J99  192 DQ30_A SCONN288_DDR506112002KQ-SCONN288_DDR506112002KQ,SMA    I22 @T6G_MB_LIB.T6G(SCH_1):PAGE107

M_K_CPU1_SA_DQ<31> @T6G_MB_LIB.T6G(SCH_1):M_K_CPU1_SA_DQ(31)
   U26  AJ7 MKA_DATA31 GENOA_SP5-SOCKET6096_13568-001,SMLF,IO,DGA^6000030   I159 @T6G_MB_LIB.T6G(SCH_1):PAGE47
   J99  194 DQ31_A SCONN288_DDR506112002KQ-SCONN288_DDR506112002KQ,SMA    I22 @T6G_MB_LIB.T6G(SCH_1):PAGE107

M_K_CPU1_SA_DQ<3> @T6G_MB_LIB.T6G(SCH_1):M_K_CPU1_SA_DQ(3)
   U26   G7 MKA_DATA3 GENOA_SP5-SOCKET6096_13568-001,SMLF,IO,DGA^6000030   I159 @T6G_MB_LIB.T6G(SCH_1):PAGE47
   J99  154  DQ3_A SCONN288_DDR506112002KQ-SCONN288_DDR506112002KQ,SMA    I22 @T6G_MB_LIB.T6G(SCH_1):PAGE107

M_K_CPU1_SA_DQ<4> @T6G_MB_LIB.T6G(SCH_1):M_K_CPU1_SA_DQ(4)
   U26   J5 MKA_DATA4 GENOA_SP5-SOCKET6096_13568-001,SMLF,IO,DGA^6000030   I159 @T6G_MB_LIB.T6G(SCH_1):PAGE47
   J99   14  DQ4_A SCONN288_DDR506112002KQ-SCONN288_DDR506112002KQ,SMA    I22 @T6G_MB_LIB.T6G(SCH_1):PAGE107

M_K_CPU1_SA_DQ<5> @T6G_MB_LIB.T6G(SCH_1):M_K_CPU1_SA_DQ(5)
   U26   K7 MKA_DATA5 GENOA_SP5-SOCKET6096_13568-001,SMLF,IO,DGA^6000030   I159 @T6G_MB_LIB.T6G(SCH_1):PAGE47
   J99   16  DQ5_A SCONN288_DDR506112002KQ-SCONN288_DDR506112002KQ,SMA    I22 @T6G_MB_LIB.T6G(SCH_1):PAGE107

M_K_CPU1_SA_DQ<6> @T6G_MB_LIB.T6G(SCH_1):M_K_CPU1_SA_DQ(6)
   U26   K6 MKA_DATA6 GENOA_SP5-SOCKET6096_13568-001,SMLF,IO,DGA^6000030   I159 @T6G_MB_LIB.T6G(SCH_1):PAGE47
   J99  159  DQ6_A SCONN288_DDR506112002KQ-SCONN288_DDR506112002KQ,SMA    I22 @T6G_MB_LIB.T6G(SCH_1):PAGE107

M_K_CPU1_SA_DQ<7> @T6G_MB_LIB.T6G(SCH_1):M_K_CPU1_SA_DQ(7)
   U26   L7 MKA_DATA7 GENOA_SP5-SOCKET6096_13568-001,SMLF,IO,DGA^6000030   I159 @T6G_MB_LIB.T6G(SCH_1):PAGE47
   J99  161  DQ7_A SCONN288_DDR506112002KQ-SCONN288_DDR506112002KQ,SMA    I22 @T6G_MB_LIB.T6G(SCH_1):PAGE107

M_K_CPU1_SA_DQ<8> @T6G_MB_LIB.T6G(SCH_1):M_K_CPU1_SA_DQ(8)
   U26   L5 MKA_DATA8 GENOA_SP5-SOCKET6096_13568-001,SMLF,IO,DGA^6000030   I159 @T6G_MB_LIB.T6G(SCH_1):PAGE47
   J99   18  DQ8_A SCONN288_DDR506112002KQ-SCONN288_DDR506112002KQ,SMA    I22 @T6G_MB_LIB.T6G(SCH_1):PAGE107

M_K_CPU1_SA_DQ<9> @T6G_MB_LIB.T6G(SCH_1):M_K_CPU1_SA_DQ(9)
   U26   M7 MKA_DATA9 GENOA_SP5-SOCKET6096_13568-001,SMLF,IO,DGA^6000030   I159 @T6G_MB_LIB.T6G(SCH_1):PAGE47
   J99   20  DQ9_A SCONN288_DDR506112002KQ-SCONN288_DDR506112002KQ,SMA    I22 @T6G_MB_LIB.T6G(SCH_1):PAGE107

M_K_CPU1_SA_DQS_DN<0> @T6G_MB_LIB.T6G(SCH_1):M_K_CPU1_SA_DQS_DN(0)
   U26   H6 MKA_DQS_L0 GENOA_SP5-SOCKET6096_13568-001,SMLF,IO,DGA^6000030   I159 @T6G_MB_LIB.T6G(SCH_1):PAGE47
   J99   12 DQS0_A_C SCONN288_DDR506112002KQ-SCONN288_DDR506112002KQ,SMA   I235 @T6G_MB_LIB.T6G(SCH_1):PAGE107

M_K_CPU1_SA_DQS_DN<1> @T6G_MB_LIB.T6G(SCH_1):M_K_CPU1_SA_DQS_DN(1)
   U26   P6 MKA_DQS_L1 GENOA_SP5-SOCKET6096_13568-001,SMLF,IO,DGA^6000030   I159 @T6G_MB_LIB.T6G(SCH_1):PAGE47
   J99   23 DQS1_A_C SCONN288_DDR506112002KQ-SCONN288_DDR506112002KQ,SMA   I235 @T6G_MB_LIB.T6G(SCH_1):PAGE107

M_K_CPU1_SA_DQS_DN<2> @T6G_MB_LIB.T6G(SCH_1):M_K_CPU1_SA_DQS_DN(2)
   U26   Y6 MKA_DQS_L2 GENOA_SP5-SOCKET6096_13568-001,SMLF,IO,DGA^6000030   I159 @T6G_MB_LIB.T6G(SCH_1):PAGE47
   J99   34 DQS2_A_C SCONN288_DDR506112002KQ-SCONN288_DDR506112002KQ,SMA   I235 @T6G_MB_LIB.T6G(SCH_1):PAGE107

M_K_CPU1_SA_DQS_DN<3> @T6G_MB_LIB.T6G(SCH_1):M_K_CPU1_SA_DQS_DN(3)
   U26  AF6 MKA_DQS_L3 GENOA_SP5-SOCKET6096_13568-001,SMLF,IO,DGA^6000030   I159 @T6G_MB_LIB.T6G(SCH_1):PAGE47
   J99   45 DQS3_A_C SCONN288_DDR506112002KQ-SCONN288_DDR506112002KQ,SMA   I235 @T6G_MB_LIB.T6G(SCH_1):PAGE107

M_K_CPU1_SA_DQS_DN<4> @T6G_MB_LIB.T6G(SCH_1):M_K_CPU1_SA_DQS_DN(4)
   U26  AM6 MKA_DQS_L4 GENOA_SP5-SOCKET6096_13568-001,SMLF,IO,DGA^6000030   I159 @T6G_MB_LIB.T6G(SCH_1):PAGE47
   J99   56 DQS4_A_C SCONN288_DDR506112002KQ-SCONN288_DDR506112002KQ,SMA   I235 @T6G_MB_LIB.T6G(SCH_1):PAGE107

M_K_CPU1_SA_DQS_DN<5> @T6G_MB_LIB.T6G(SCH_1):M_K_CPU1_SA_DQS_DN(5)
   U26   H7 MKA_DQS_L5 GENOA_SP5-SOCKET6096_13568-001,SMLF,IO,DGA^6000030   I159 @T6G_MB_LIB.T6G(SCH_1):PAGE47
   J99  156 DQS5_A_C||TDQS5_A_C||DQS5_A_T||TDQS5_A_T SCONN288_DDR506112002KQ-SCONN288_DDR506112002KQ,SMA   I235 @T6G_MB_LIB.T6G(SCH_1):PAGE107

M_K_CPU1_SA_DQS_DN<6> @T6G_MB_LIB.T6G(SCH_1):M_K_CPU1_SA_DQS_DN(6)
   U26   P7 MKA_DQS_L6 GENOA_SP5-SOCKET6096_13568-001,SMLF,IO,DGA^6000030   I159 @T6G_MB_LIB.T6G(SCH_1):PAGE47
   J99  167 DQS6_A_C||TDQS6_A_C||DQS6_A_T||TDQS6_A_T SCONN288_DDR506112002KQ-SCONN288_DDR506112002KQ,SMA   I235 @T6G_MB_LIB.T6G(SCH_1):PAGE107

M_K_CPU1_SA_DQS_DN<7> @T6G_MB_LIB.T6G(SCH_1):M_K_CPU1_SA_DQS_DN(7)
   U26   Y7 MKA_DQS_L7 GENOA_SP5-SOCKET6096_13568-001,SMLF,IO,DGA^6000030   I159 @T6G_MB_LIB.T6G(SCH_1):PAGE47
   J99  178 DQS7_A_C||TDQS7_A_C SCONN288_DDR506112002KQ-SCONN288_DDR506112002KQ,SMA   I235 @T6G_MB_LIB.T6G(SCH_1):PAGE107

M_K_CPU1_SA_DQS_DN<8> @T6G_MB_LIB.T6G(SCH_1):M_K_CPU1_SA_DQS_DN(8)
   U26  AF7 MKA_DQS_L8 GENOA_SP5-SOCKET6096_13568-001,SMLF,IO,DGA^6000030   I159 @T6G_MB_LIB.T6G(SCH_1):PAGE47
   J99  189 DQS8_A_C||TDQS8_A_C SCONN288_DDR506112002KQ-SCONN288_DDR506112002KQ,SMA   I235 @T6G_MB_LIB.T6G(SCH_1):PAGE107

M_K_CPU1_SA_DQS_DN<9> @T6G_MB_LIB.T6G(SCH_1):M_K_CPU1_SA_DQS_DN(9)
   U26  AM7 MKA_DQS_L9 GENOA_SP5-SOCKET6096_13568-001,SMLF,IO,DGA^6000030   I159 @T6G_MB_LIB.T6G(SCH_1):PAGE47
   J99  200 DQS9_A_C||TDQS9_A_C SCONN288_DDR506112002KQ-SCONN288_DDR506112002KQ,SMA   I235 @T6G_MB_LIB.T6G(SCH_1):PAGE107

M_K_CPU1_SA_DQS_DP<0> @T6G_MB_LIB.T6G(SCH_1):M_K_CPU1_SA_DQS_DP(0)
   U26   G5 MKA_DQS_H0 GENOA_SP5-SOCKET6096_13568-001,SMLF,IO,DGA^6000030   I159 @T6G_MB_LIB.T6G(SCH_1):PAGE47
   J99   11 DQS0_A_T SCONN288_DDR506112002KQ-SCONN288_DDR506112002KQ,SMA   I235 @T6G_MB_LIB.T6G(SCH_1):PAGE107

M_K_CPU1_SA_DQS_DP<1> @T6G_MB_LIB.T6G(SCH_1):M_K_CPU1_SA_DQS_DP(1)
   U26   N5 MKA_DQS_H1 GENOA_SP5-SOCKET6096_13568-001,SMLF,IO,DGA^6000030   I159 @T6G_MB_LIB.T6G(SCH_1):PAGE47
   J99   22 DQS1_A_T SCONN288_DDR506112002KQ-SCONN288_DDR506112002KQ,SMA   I235 @T6G_MB_LIB.T6G(SCH_1):PAGE107

M_K_CPU1_SA_DQS_DP<2> @T6G_MB_LIB.T6G(SCH_1):M_K_CPU1_SA_DQS_DP(2)
   U26   W5 MKA_DQS_H2 GENOA_SP5-SOCKET6096_13568-001,SMLF,IO,DGA^6000030   I159 @T6G_MB_LIB.T6G(SCH_1):PAGE47
   J99   33 DQS2_A_T SCONN288_DDR506112002KQ-SCONN288_DDR506112002KQ,SMA   I235 @T6G_MB_LIB.T6G(SCH_1):PAGE107

M_K_CPU1_SA_DQS_DP<3> @T6G_MB_LIB.T6G(SCH_1):M_K_CPU1_SA_DQS_DP(3)
   U26  AE5 MKA_DQS_H3 GENOA_SP5-SOCKET6096_13568-001,SMLF,IO,DGA^6000030   I159 @T6G_MB_LIB.T6G(SCH_1):PAGE47
   J99   44 DQS3_A_T SCONN288_DDR506112002KQ-SCONN288_DDR506112002KQ,SMA   I235 @T6G_MB_LIB.T6G(SCH_1):PAGE107

M_K_CPU1_SA_DQS_DP<4> @T6G_MB_LIB.T6G(SCH_1):M_K_CPU1_SA_DQS_DP(4)
   U26  AL5 MKA_DQS_H4 GENOA_SP5-SOCKET6096_13568-001,SMLF,IO,DGA^6000030   I159 @T6G_MB_LIB.T6G(SCH_1):PAGE47
   J99   55 DQS4_A_T SCONN288_DDR506112002KQ-SCONN288_DDR506112002KQ,SMA   I235 @T6G_MB_LIB.T6G(SCH_1):PAGE107

M_K_CPU1_SA_DQS_DP<5> @T6G_MB_LIB.T6G(SCH_1):M_K_CPU1_SA_DQS_DP(5)
   U26   J7 MKA_DQS_H5 GENOA_SP5-SOCKET6096_13568-001,SMLF,IO,DGA^6000030   I159 @T6G_MB_LIB.T6G(SCH_1):PAGE47
   J99  157 DQS5_A_T||TDQS5_A_T SCONN288_DDR506112002KQ-SCONN288_DDR506112002KQ,SMA   I235 @T6G_MB_LIB.T6G(SCH_1):PAGE107

M_K_CPU1_SA_DQS_DP<6> @T6G_MB_LIB.T6G(SCH_1):M_K_CPU1_SA_DQS_DP(6)
   U26   R7 MKA_DQS_H6 GENOA_SP5-SOCKET6096_13568-001,SMLF,IO,DGA^6000030   I159 @T6G_MB_LIB.T6G(SCH_1):PAGE47
   J99  168 DQS6_A_T||TDQS6_A_T SCONN288_DDR506112002KQ-SCONN288_DDR506112002KQ,SMA   I235 @T6G_MB_LIB.T6G(SCH_1):PAGE107

M_K_CPU1_SA_DQS_DP<7> @T6G_MB_LIB.T6G(SCH_1):M_K_CPU1_SA_DQS_DP(7)
   U26  AA7 MKA_DQS_H7 GENOA_SP5-SOCKET6096_13568-001,SMLF,IO,DGA^6000030   I159 @T6G_MB_LIB.T6G(SCH_1):PAGE47
   J99  179 DQS7_A_T||TDQS7_A_T SCONN288_DDR506112002KQ-SCONN288_DDR506112002KQ,SMA   I235 @T6G_MB_LIB.T6G(SCH_1):PAGE107

M_K_CPU1_SA_DQS_DP<8> @T6G_MB_LIB.T6G(SCH_1):M_K_CPU1_SA_DQS_DP(8)
   U26  AG7 MKA_DQS_H8 GENOA_SP5-SOCKET6096_13568-001,SMLF,IO,DGA^6000030   I159 @T6G_MB_LIB.T6G(SCH_1):PAGE47
   J99  190 DQS8_A_T||TDQS8_A_T SCONN288_DDR506112002KQ-SCONN288_DDR506112002KQ,SMA   I235 @T6G_MB_LIB.T6G(SCH_1):PAGE107

M_K_CPU1_SA_DQS_DP<9> @T6G_MB_LIB.T6G(SCH_1):M_K_CPU1_SA_DQS_DP(9)
   U26  AN7 MKA_DQS_H9 GENOA_SP5-SOCKET6096_13568-001,SMLF,IO,DGA^6000030   I159 @T6G_MB_LIB.T6G(SCH_1):PAGE47
   J99  201 DQS9_A_T||TDQS9_A_T SCONN288_DDR506112002KQ-SCONN288_DDR506112002KQ,SMA   I235 @T6G_MB_LIB.T6G(SCH_1):PAGE107

M_K_CPU1_SA_PAR @T6G_MB_LIB.T6G(SCH_1):M_K_CPU1_SA_PAR
   U26  BC7 MKA_PAR GENOA_SP5-SOCKET6096_13568-001,SMLF,IO,DGA^6000030   I159 @T6G_MB_LIB.T6G(SCH_1):PAGE47
   J99   74  PAR_A SCONN288_DDR506112002KQ-SCONN288_DDR506112002KQ,SMA    I22 @T6G_MB_LIB.T6G(SCH_1):PAGE107

M_K_CPU1_SA_RSP<0> @T6G_MB_LIB.T6G(SCH_1):M_K_CPU1_SA_RSP(0)
   U26  BN7 MKA0_RSP_L GENOA_SP5-SOCKET6096_13568-001,SMLF,IO,DGA^6000030   I159 @T6G_MB_LIB.T6G(SCH_1):PAGE47
   J99   86 LBD||RSP_A_N SCONN288_DDR506112002KQ-SCONN288_DDR506112002KQ,SMA    I22 @T6G_MB_LIB.T6G(SCH_1):PAGE107

M_K_CPU1_SB_CA<0> @T6G_MB_LIB.T6G(SCH_1):M_K_CPU1_SB_CA(0)
   U26  BG7 MKB_CA0 GENOA_SP5-SOCKET6096_13568-001,SMLF,IO,DGA^6000030   I159 @T6G_MB_LIB.T6G(SCH_1):PAGE47
   J99   76  CA0_B SCONN288_DDR506112002KQ-SCONN288_DDR506112002KQ,SMA    I22 @T6G_MB_LIB.T6G(SCH_1):PAGE107

M_K_CPU1_SB_CA<1> @T6G_MB_LIB.T6G(SCH_1):M_K_CPU1_SB_CA(1)
   U26  BH7 MKB_CA1 GENOA_SP5-SOCKET6096_13568-001,SMLF,IO,DGA^6000030   I159 @T6G_MB_LIB.T6G(SCH_1):PAGE47
   J99  221  CA1_B SCONN288_DDR506112002KQ-SCONN288_DDR506112002KQ,SMA    I22 @T6G_MB_LIB.T6G(SCH_1):PAGE107

M_K_CPU1_SB_CA<2> @T6G_MB_LIB.T6G(SCH_1):M_K_CPU1_SB_CA(2)
   U26  BH6 MKB_CA2 GENOA_SP5-SOCKET6096_13568-001,SMLF,IO,DGA^6000030   I159 @T6G_MB_LIB.T6G(SCH_1):PAGE47
   J99   78  CA2_B SCONN288_DDR506112002KQ-SCONN288_DDR506112002KQ,SMA    I22 @T6G_MB_LIB.T6G(SCH_1):PAGE107

M_K_CPU1_SB_CA<3> @T6G_MB_LIB.T6G(SCH_1):M_K_CPU1_SB_CA(3)
   U26  BJ5 MKB_CA3 GENOA_SP5-SOCKET6096_13568-001,SMLF,IO,DGA^6000030   I159 @T6G_MB_LIB.T6G(SCH_1):PAGE47
   J99  223  CA3_B SCONN288_DDR506112002KQ-SCONN288_DDR506112002KQ,SMA    I22 @T6G_MB_LIB.T6G(SCH_1):PAGE107

M_K_CPU1_SB_CA<4> @T6G_MB_LIB.T6G(SCH_1):M_K_CPU1_SB_CA(4)
   U26  BJ7 MKB_CA4 GENOA_SP5-SOCKET6096_13568-001,SMLF,IO,DGA^6000030   I159 @T6G_MB_LIB.T6G(SCH_1):PAGE47
   J99   80  CA4_B SCONN288_DDR506112002KQ-SCONN288_DDR506112002KQ,SMA    I22 @T6G_MB_LIB.T6G(SCH_1):PAGE107

M_K_CPU1_SB_CA<5> @T6G_MB_LIB.T6G(SCH_1):M_K_CPU1_SB_CA(5)
   U26  BK7 MKB_CA5 GENOA_SP5-SOCKET6096_13568-001,SMLF,IO,DGA^6000030   I159 @T6G_MB_LIB.T6G(SCH_1):PAGE47
   J99  225  CA5_B SCONN288_DDR506112002KQ-SCONN288_DDR506112002KQ,SMA    I22 @T6G_MB_LIB.T6G(SCH_1):PAGE107

M_K_CPU1_SB_CA<6> @T6G_MB_LIB.T6G(SCH_1):M_K_CPU1_SB_CA(6)
   U26  BK6 MKB_CA6 GENOA_SP5-SOCKET6096_13568-001,SMLF,IO,DGA^6000030   I159 @T6G_MB_LIB.T6G(SCH_1):PAGE47
   J99   82  CA6_B SCONN288_DDR506112002KQ-SCONN288_DDR506112002KQ,SMA    I22 @T6G_MB_LIB.T6G(SCH_1):PAGE107

M_K_CPU1_SB_CB<0> @T6G_MB_LIB.T6G(SCH_1):M_K_CPU1_SB_CB(0)
   U26  BY6 MKB_CHECK0 GENOA_SP5-SOCKET6096_13568-001,SMLF,IO,DGA^6000030   I159 @T6G_MB_LIB.T6G(SCH_1):PAGE47
   J99   96  CB0_B SCONN288_DDR506112002KQ-SCONN288_DDR506112002KQ,SMA    I22 @T6G_MB_LIB.T6G(SCH_1):PAGE107

M_K_CPU1_SB_CB<1> @T6G_MB_LIB.T6G(SCH_1):M_K_CPU1_SB_CB(1)
   U26  CA7 MKB_CHECK1 GENOA_SP5-SOCKET6096_13568-001,SMLF,IO,DGA^6000030   I159 @T6G_MB_LIB.T6G(SCH_1):PAGE47
   J99   98  CB1_B SCONN288_DDR506112002KQ-SCONN288_DDR506112002KQ,SMA    I22 @T6G_MB_LIB.T6G(SCH_1):PAGE107

M_K_CPU1_SB_CB<2> @T6G_MB_LIB.T6G(SCH_1):M_K_CPU1_SB_CB(2)
   U26  CA5 MKB_CHECK2 GENOA_SP5-SOCKET6096_13568-001,SMLF,IO,DGA^6000030   I159 @T6G_MB_LIB.T6G(SCH_1):PAGE47
   J99  241  CB2_B SCONN288_DDR506112002KQ-SCONN288_DDR506112002KQ,SMA    I22 @T6G_MB_LIB.T6G(SCH_1):PAGE107

M_K_CPU1_SB_CB<3> @T6G_MB_LIB.T6G(SCH_1):M_K_CPU1_SB_CB(3)
   U26  CB7 MKB_CHECK3 GENOA_SP5-SOCKET6096_13568-001,SMLF,IO,DGA^6000030   I159 @T6G_MB_LIB.T6G(SCH_1):PAGE47
   J99  243  CB3_B SCONN288_DDR506112002KQ-SCONN288_DDR506112002KQ,SMA    I22 @T6G_MB_LIB.T6G(SCH_1):PAGE107

M_K_CPU1_SB_CB<4> @T6G_MB_LIB.T6G(SCH_1):M_K_CPU1_SB_CB(4)
   U26  BT6 MKB_CHECK4 GENOA_SP5-SOCKET6096_13568-001,SMLF,IO,DGA^6000030   I159 @T6G_MB_LIB.T6G(SCH_1):PAGE47
   J99   89  CB4_B SCONN288_DDR506112002KQ-SCONN288_DDR506112002KQ,SMA    I22 @T6G_MB_LIB.T6G(SCH_1):PAGE107

M_K_CPU1_SB_CB<5> @T6G_MB_LIB.T6G(SCH_1):M_K_CPU1_SB_CB(5)
   U26  BU7 MKB_CHECK5 GENOA_SP5-SOCKET6096_13568-001,SMLF,IO,DGA^6000030   I159 @T6G_MB_LIB.T6G(SCH_1):PAGE47
   J99   91  CB5_B SCONN288_DDR506112002KQ-SCONN288_DDR506112002KQ,SMA    I22 @T6G_MB_LIB.T6G(SCH_1):PAGE107

M_K_CPU1_SB_CB<6> @T6G_MB_LIB.T6G(SCH_1):M_K_CPU1_SB_CB(6)
   U26  BU5 MKB_CHECK6 GENOA_SP5-SOCKET6096_13568-001,SMLF,IO,DGA^6000030   I159 @T6G_MB_LIB.T6G(SCH_1):PAGE47
   J99  234  CB6_B SCONN288_DDR506112002KQ-SCONN288_DDR506112002KQ,SMA    I22 @T6G_MB_LIB.T6G(SCH_1):PAGE107

M_K_CPU1_SB_CB<7> @T6G_MB_LIB.T6G(SCH_1):M_K_CPU1_SB_CB(7)
   U26  BV7 MKB_CHECK7 GENOA_SP5-SOCKET6096_13568-001,SMLF,IO,DGA^6000030   I159 @T6G_MB_LIB.T6G(SCH_1):PAGE47
   J99  236  CB7_B SCONN288_DDR506112002KQ-SCONN288_DDR506112002KQ,SMA    I22 @T6G_MB_LIB.T6G(SCH_1):PAGE107

M_K_CPU1_SB_CS_N<0> @T6G_MB_LIB.T6G(SCH_1):M_K_CPU1_SB_CS_N(0)
   U26  BM7 MKB0_CS_L0 GENOA_SP5-SOCKET6096_13568-001,SMLF,IO,DGA^6000030   I159 @T6G_MB_LIB.T6G(SCH_1):PAGE47
   J99   84 CS0_B_N SCONN288_DDR506112002KQ-SCONN288_DDR506112002KQ,SMA    I22 @T6G_MB_LIB.T6G(SCH_1):PAGE107

M_K_CPU1_SB_CS_N<1> @T6G_MB_LIB.T6G(SCH_1):M_K_CPU1_SB_CS_N(1)
   U26  BN5 MKB0_CS_L1 GENOA_SP5-SOCKET6096_13568-001,SMLF,IO,DGA^6000030   I159 @T6G_MB_LIB.T6G(SCH_1):PAGE47
   J99  229 CS1_B_N SCONN288_DDR506112002KQ-SCONN288_DDR506112002KQ,SMA    I22 @T6G_MB_LIB.T6G(SCH_1):PAGE107

M_K_CPU1_SB_DQ<0> @T6G_MB_LIB.T6G(SCH_1):M_K_CPU1_SB_DQ(0)
   U26  CB6 MKB_DATA0 GENOA_SP5-SOCKET6096_13568-001,SMLF,IO,DGA^6000030   I159 @T6G_MB_LIB.T6G(SCH_1):PAGE47
   J99  100  DQ0_B SCONN288_DDR506112002KQ-SCONN288_DDR506112002KQ,SMA    I22 @T6G_MB_LIB.T6G(SCH_1):PAGE107

M_K_CPU1_SB_DQ<10> @T6G_MB_LIB.T6G(SCH_1):M_K_CPU1_SB_DQ(10)
   U26  CJ5 MKB_DATA10 GENOA_SP5-SOCKET6096_13568-001,SMLF,IO,DGA^6000030   I159 @T6G_MB_LIB.T6G(SCH_1):PAGE47
   J99  256 DQ10_B SCONN288_DDR506112002KQ-SCONN288_DDR506112002KQ,SMA    I22 @T6G_MB_LIB.T6G(SCH_1):PAGE107

M_K_CPU1_SB_DQ<11> @T6G_MB_LIB.T6G(SCH_1):M_K_CPU1_SB_DQ(11)
   U26  CK7 MKB_DATA11 GENOA_SP5-SOCKET6096_13568-001,SMLF,IO,DGA^6000030   I159 @T6G_MB_LIB.T6G(SCH_1):PAGE47
   J99  258 DQ11_B SCONN288_DDR506112002KQ-SCONN288_DDR506112002KQ,SMA    I22 @T6G_MB_LIB.T6G(SCH_1):PAGE107

M_K_CPU1_SB_DQ<12> @T6G_MB_LIB.T6G(SCH_1):M_K_CPU1_SB_DQ(12)
   U26  CM6 MKB_DATA12 GENOA_SP5-SOCKET6096_13568-001,SMLF,IO,DGA^6000030   I159 @T6G_MB_LIB.T6G(SCH_1):PAGE47
   J99  118 DQ12_B SCONN288_DDR506112002KQ-SCONN288_DDR506112002KQ,SMA    I22 @T6G_MB_LIB.T6G(SCH_1):PAGE107

M_K_CPU1_SB_DQ<13> @T6G_MB_LIB.T6G(SCH_1):M_K_CPU1_SB_DQ(13)
   U26  CN7 MKB_DATA13 GENOA_SP5-SOCKET6096_13568-001,SMLF,IO,DGA^6000030   I159 @T6G_MB_LIB.T6G(SCH_1):PAGE47
   J99  120 DQ13_B SCONN288_DDR506112002KQ-SCONN288_DDR506112002KQ,SMA    I22 @T6G_MB_LIB.T6G(SCH_1):PAGE107

M_K_CPU1_SB_DQ<14> @T6G_MB_LIB.T6G(SCH_1):M_K_CPU1_SB_DQ(14)
   U26  CN5 MKB_DATA14 GENOA_SP5-SOCKET6096_13568-001,SMLF,IO,DGA^6000030   I159 @T6G_MB_LIB.T6G(SCH_1):PAGE47
   J99  263 DQ14_B SCONN288_DDR506112002KQ-SCONN288_DDR506112002KQ,SMA    I22 @T6G_MB_LIB.T6G(SCH_1):PAGE107

M_K_CPU1_SB_DQ<15> @T6G_MB_LIB.T6G(SCH_1):M_K_CPU1_SB_DQ(15)
   U26  CP7 MKB_DATA15 GENOA_SP5-SOCKET6096_13568-001,SMLF,IO,DGA^6000030   I159 @T6G_MB_LIB.T6G(SCH_1):PAGE47
   J99  265 DQ15_B SCONN288_DDR506112002KQ-SCONN288_DDR506112002KQ,SMA    I22 @T6G_MB_LIB.T6G(SCH_1):PAGE107

M_K_CPU1_SB_DQ<16> @T6G_MB_LIB.T6G(SCH_1):M_K_CPU1_SB_DQ(16)
   U26  CP6 MKB_DATA16 GENOA_SP5-SOCKET6096_13568-001,SMLF,IO,DGA^6000030   I159 @T6G_MB_LIB.T6G(SCH_1):PAGE47
   J99  122 DQ16_B SCONN288_DDR506112002KQ-SCONN288_DDR506112002KQ,SMA    I22 @T6G_MB_LIB.T6G(SCH_1):PAGE107

M_K_CPU1_SB_DQ<17> @T6G_MB_LIB.T6G(SCH_1):M_K_CPU1_SB_DQ(17)
   U26  CR7 MKB_DATA17 GENOA_SP5-SOCKET6096_13568-001,SMLF,IO,DGA^6000030   I159 @T6G_MB_LIB.T6G(SCH_1):PAGE47
   J99  124 DQ17_B SCONN288_DDR506112002KQ-SCONN288_DDR506112002KQ,SMA    I22 @T6G_MB_LIB.T6G(SCH_1):PAGE107

M_K_CPU1_SB_DQ<18> @T6G_MB_LIB.T6G(SCH_1):M_K_CPU1_SB_DQ(18)
   U26  CR5 MKB_DATA18 GENOA_SP5-SOCKET6096_13568-001,SMLF,IO,DGA^6000030   I159 @T6G_MB_LIB.T6G(SCH_1):PAGE47
   J99  267 DQ18_B SCONN288_DDR506112002KQ-SCONN288_DDR506112002KQ,SMA    I22 @T6G_MB_LIB.T6G(SCH_1):PAGE107

M_K_CPU1_SB_DQ<19> @T6G_MB_LIB.T6G(SCH_1):M_K_CPU1_SB_DQ(19)
   U26  CT7 MKB_DATA19 GENOA_SP5-SOCKET6096_13568-001,SMLF,IO,DGA^6000030   I159 @T6G_MB_LIB.T6G(SCH_1):PAGE47
   J99  269 DQ19_B SCONN288_DDR506112002KQ-SCONN288_DDR506112002KQ,SMA    I22 @T6G_MB_LIB.T6G(SCH_1):PAGE107

M_K_CPU1_SB_DQ<1> @T6G_MB_LIB.T6G(SCH_1):M_K_CPU1_SB_DQ(1)
   U26  CC7 MKB_DATA1 GENOA_SP5-SOCKET6096_13568-001,SMLF,IO,DGA^6000030   I159 @T6G_MB_LIB.T6G(SCH_1):PAGE47
   J99  102  DQ1_B SCONN288_DDR506112002KQ-SCONN288_DDR506112002KQ,SMA    I22 @T6G_MB_LIB.T6G(SCH_1):PAGE107

M_K_CPU1_SB_DQ<20> @T6G_MB_LIB.T6G(SCH_1):M_K_CPU1_SB_DQ(20)
   U26  CV6 MKB_DATA20 GENOA_SP5-SOCKET6096_13568-001,SMLF,IO,DGA^6000030   I159 @T6G_MB_LIB.T6G(SCH_1):PAGE47
   J99  129 DQ20_B SCONN288_DDR506112002KQ-SCONN288_DDR506112002KQ,SMA    I22 @T6G_MB_LIB.T6G(SCH_1):PAGE107

M_K_CPU1_SB_DQ<21> @T6G_MB_LIB.T6G(SCH_1):M_K_CPU1_SB_DQ(21)
   U26  CW7 MKB_DATA21 GENOA_SP5-SOCKET6096_13568-001,SMLF,IO,DGA^6000030   I159 @T6G_MB_LIB.T6G(SCH_1):PAGE47
   J99  131 DQ21_B SCONN288_DDR506112002KQ-SCONN288_DDR506112002KQ,SMA    I22 @T6G_MB_LIB.T6G(SCH_1):PAGE107

M_K_CPU1_SB_DQ<22> @T6G_MB_LIB.T6G(SCH_1):M_K_CPU1_SB_DQ(22)
   U26  CW5 MKB_DATA22 GENOA_SP5-SOCKET6096_13568-001,SMLF,IO,DGA^6000030   I159 @T6G_MB_LIB.T6G(SCH_1):PAGE47
   J99  274 DQ22_B SCONN288_DDR506112002KQ-SCONN288_DDR506112002KQ,SMA    I22 @T6G_MB_LIB.T6G(SCH_1):PAGE107

M_K_CPU1_SB_DQ<23> @T6G_MB_LIB.T6G(SCH_1):M_K_CPU1_SB_DQ(23)
   U26  CY7 MKB_DATA23 GENOA_SP5-SOCKET6096_13568-001,SMLF,IO,DGA^6000030   I159 @T6G_MB_LIB.T6G(SCH_1):PAGE47
   J99  276 DQ23_B SCONN288_DDR506112002KQ-SCONN288_DDR506112002KQ,SMA    I22 @T6G_MB_LIB.T6G(SCH_1):PAGE107

M_K_CPU1_SB_DQ<24> @T6G_MB_LIB.T6G(SCH_1):M_K_CPU1_SB_DQ(24)
   U26  CY6 MKB_DATA24 GENOA_SP5-SOCKET6096_13568-001,SMLF,IO,DGA^6000030   I159 @T6G_MB_LIB.T6G(SCH_1):PAGE47
   J99  133 DQ24_B SCONN288_DDR506112002KQ-SCONN288_DDR506112002KQ,SMA    I22 @T6G_MB_LIB.T6G(SCH_1):PAGE107

M_K_CPU1_SB_DQ<25> @T6G_MB_LIB.T6G(SCH_1):M_K_CPU1_SB_DQ(25)
   U26  DA7 MKB_DATA25 GENOA_SP5-SOCKET6096_13568-001,SMLF,IO,DGA^6000030   I159 @T6G_MB_LIB.T6G(SCH_1):PAGE47
   J99  135 DQ25_B SCONN288_DDR506112002KQ-SCONN288_DDR506112002KQ,SMA    I22 @T6G_MB_LIB.T6G(SCH_1):PAGE107

M_K_CPU1_SB_DQ<26> @T6G_MB_LIB.T6G(SCH_1):M_K_CPU1_SB_DQ(26)
   U26  DA5 MKB_DATA26 GENOA_SP5-SOCKET6096_13568-001,SMLF,IO,DGA^6000030   I159 @T6G_MB_LIB.T6G(SCH_1):PAGE47
   J99  278 DQ26_B SCONN288_DDR506112002KQ-SCONN288_DDR506112002KQ,SMA    I22 @T6G_MB_LIB.T6G(SCH_1):PAGE107

M_K_CPU1_SB_DQ<27> @T6G_MB_LIB.T6G(SCH_1):M_K_CPU1_SB_DQ(27)
   U26  DB7 MKB_DATA27 GENOA_SP5-SOCKET6096_13568-001,SMLF,IO,DGA^6000030   I159 @T6G_MB_LIB.T6G(SCH_1):PAGE47
   J99  280 DQ27_B SCONN288_DDR506112002KQ-SCONN288_DDR506112002KQ,SMA    I22 @T6G_MB_LIB.T6G(SCH_1):PAGE107

M_K_CPU1_SB_DQ<28> @T6G_MB_LIB.T6G(SCH_1):M_K_CPU1_SB_DQ(28)
   U26  DD6 MKB_DATA28 GENOA_SP5-SOCKET6096_13568-001,SMLF,IO,DGA^6000030   I159 @T6G_MB_LIB.T6G(SCH_1):PAGE47
   J99  140 DQ28_B SCONN288_DDR506112002KQ-SCONN288_DDR506112002KQ,SMA    I22 @T6G_MB_LIB.T6G(SCH_1):PAGE107

M_K_CPU1_SB_DQ<29> @T6G_MB_LIB.T6G(SCH_1):M_K_CPU1_SB_DQ(29)
   U26  DE7 MKB_DATA29 GENOA_SP5-SOCKET6096_13568-001,SMLF,IO,DGA^6000030   I159 @T6G_MB_LIB.T6G(SCH_1):PAGE47
   J99  142 DQ29_B SCONN288_DDR506112002KQ-SCONN288_DDR506112002KQ,SMA    I22 @T6G_MB_LIB.T6G(SCH_1):PAGE107

M_K_CPU1_SB_DQ<2> @T6G_MB_LIB.T6G(SCH_1):M_K_CPU1_SB_DQ(2)
   U26  CC5 MKB_DATA2 GENOA_SP5-SOCKET6096_13568-001,SMLF,IO,DGA^6000030   I159 @T6G_MB_LIB.T6G(SCH_1):PAGE47
   J99  245  DQ2_B SCONN288_DDR506112002KQ-SCONN288_DDR506112002KQ,SMA    I22 @T6G_MB_LIB.T6G(SCH_1):PAGE107

M_K_CPU1_SB_DQ<30> @T6G_MB_LIB.T6G(SCH_1):M_K_CPU1_SB_DQ(30)
   U26  DE5 MKB_DATA30 GENOA_SP5-SOCKET6096_13568-001,SMLF,IO,DGA^6000030   I159 @T6G_MB_LIB.T6G(SCH_1):PAGE47
   J99  285 DQ30_B SCONN288_DDR506112002KQ-SCONN288_DDR506112002KQ,SMA    I22 @T6G_MB_LIB.T6G(SCH_1):PAGE107

M_K_CPU1_SB_DQ<31> @T6G_MB_LIB.T6G(SCH_1):M_K_CPU1_SB_DQ(31)
   U26  DF7 MKB_DATA31 GENOA_SP5-SOCKET6096_13568-001,SMLF,IO,DGA^6000030   I159 @T6G_MB_LIB.T6G(SCH_1):PAGE47
   J99  287 DQ31_B SCONN288_DDR506112002KQ-SCONN288_DDR506112002KQ,SMA    I22 @T6G_MB_LIB.T6G(SCH_1):PAGE107

M_K_CPU1_SB_DQ<3> @T6G_MB_LIB.T6G(SCH_1):M_K_CPU1_SB_DQ(3)
   U26  CD7 MKB_DATA3 GENOA_SP5-SOCKET6096_13568-001,SMLF,IO,DGA^6000030   I159 @T6G_MB_LIB.T6G(SCH_1):PAGE47
   J99  247  DQ3_B SCONN288_DDR506112002KQ-SCONN288_DDR506112002KQ,SMA    I22 @T6G_MB_LIB.T6G(SCH_1):PAGE107

M_K_CPU1_SB_DQ<4> @T6G_MB_LIB.T6G(SCH_1):M_K_CPU1_SB_DQ(4)
   U26  CF6 MKB_DATA4 GENOA_SP5-SOCKET6096_13568-001,SMLF,IO,DGA^6000030   I159 @T6G_MB_LIB.T6G(SCH_1):PAGE47
   J99  107  DQ4_B SCONN288_DDR506112002KQ-SCONN288_DDR506112002KQ,SMA    I22 @T6G_MB_LIB.T6G(SCH_1):PAGE107

M_K_CPU1_SB_DQ<5> @T6G_MB_LIB.T6G(SCH_1):M_K_CPU1_SB_DQ(5)
   U26  CG7 MKB_DATA5 GENOA_SP5-SOCKET6096_13568-001,SMLF,IO,DGA^6000030   I159 @T6G_MB_LIB.T6G(SCH_1):PAGE47
   J99  109  DQ5_B SCONN288_DDR506112002KQ-SCONN288_DDR506112002KQ,SMA    I22 @T6G_MB_LIB.T6G(SCH_1):PAGE107

M_K_CPU1_SB_DQ<6> @T6G_MB_LIB.T6G(SCH_1):M_K_CPU1_SB_DQ(6)
   U26  CG5 MKB_DATA6 GENOA_SP5-SOCKET6096_13568-001,SMLF,IO,DGA^6000030   I159 @T6G_MB_LIB.T6G(SCH_1):PAGE47
   J99  252  DQ6_B SCONN288_DDR506112002KQ-SCONN288_DDR506112002KQ,SMA    I22 @T6G_MB_LIB.T6G(SCH_1):PAGE107

M_K_CPU1_SB_DQ<7> @T6G_MB_LIB.T6G(SCH_1):M_K_CPU1_SB_DQ(7)
   U26  CH7 MKB_DATA7 GENOA_SP5-SOCKET6096_13568-001,SMLF,IO,DGA^6000030   I159 @T6G_MB_LIB.T6G(SCH_1):PAGE47
   J99  254  DQ7_B SCONN288_DDR506112002KQ-SCONN288_DDR506112002KQ,SMA    I22 @T6G_MB_LIB.T6G(SCH_1):PAGE107

M_K_CPU1_SB_DQ<8> @T6G_MB_LIB.T6G(SCH_1):M_K_CPU1_SB_DQ(8)
   U26  CH6 MKB_DATA8 GENOA_SP5-SOCKET6096_13568-001,SMLF,IO,DGA^6000030   I159 @T6G_MB_LIB.T6G(SCH_1):PAGE47
   J99  111  DQ8_B SCONN288_DDR506112002KQ-SCONN288_DDR506112002KQ,SMA    I22 @T6G_MB_LIB.T6G(SCH_1):PAGE107

M_K_CPU1_SB_DQ<9> @T6G_MB_LIB.T6G(SCH_1):M_K_CPU1_SB_DQ(9)
   U26  CJ7 MKB_DATA9 GENOA_SP5-SOCKET6096_13568-001,SMLF,IO,DGA^6000030   I159 @T6G_MB_LIB.T6G(SCH_1):PAGE47
   J99  113  DQ9_B SCONN288_DDR506112002KQ-SCONN288_DDR506112002KQ,SMA    I22 @T6G_MB_LIB.T6G(SCH_1):PAGE107

M_K_CPU1_SB_DQS_DN<0> @T6G_MB_LIB.T6G(SCH_1):M_K_CPU1_SB_DQS_DN(0)
   U26  CE5 MKB_DQS_L0 GENOA_SP5-SOCKET6096_13568-001,SMLF,IO,DGA^6000030   I159 @T6G_MB_LIB.T6G(SCH_1):PAGE47
   J99  105 DQS0_B_C SCONN288_DDR506112002KQ-SCONN288_DDR506112002KQ,SMA   I235 @T6G_MB_LIB.T6G(SCH_1):PAGE107

M_K_CPU1_SB_DQS_DN<1> @T6G_MB_LIB.T6G(SCH_1):M_K_CPU1_SB_DQS_DN(1)
   U26  CL5 MKB_DQS_L1 GENOA_SP5-SOCKET6096_13568-001,SMLF,IO,DGA^6000030   I159 @T6G_MB_LIB.T6G(SCH_1):PAGE47
   J99  116 DQS1_B_C SCONN288_DDR506112002KQ-SCONN288_DDR506112002KQ,SMA   I235 @T6G_MB_LIB.T6G(SCH_1):PAGE107

M_K_CPU1_SB_DQS_DN<2> @T6G_MB_LIB.T6G(SCH_1):M_K_CPU1_SB_DQS_DN(2)
   U26  CU5 MKB_DQS_L2 GENOA_SP5-SOCKET6096_13568-001,SMLF,IO,DGA^6000030   I159 @T6G_MB_LIB.T6G(SCH_1):PAGE47
   J99  127 DQS2_B_C SCONN288_DDR506112002KQ-SCONN288_DDR506112002KQ,SMA   I235 @T6G_MB_LIB.T6G(SCH_1):PAGE107

M_K_CPU1_SB_DQS_DN<3> @T6G_MB_LIB.T6G(SCH_1):M_K_CPU1_SB_DQS_DN(3)
   U26  DC5 MKB_DQS_L3 GENOA_SP5-SOCKET6096_13568-001,SMLF,IO,DGA^6000030   I159 @T6G_MB_LIB.T6G(SCH_1):PAGE47
   J99  138 DQS3_B_C SCONN288_DDR506112002KQ-SCONN288_DDR506112002KQ,SMA   I235 @T6G_MB_LIB.T6G(SCH_1):PAGE107

M_K_CPU1_SB_DQS_DN<4> @T6G_MB_LIB.T6G(SCH_1):M_K_CPU1_SB_DQS_DN(4)
   U26  BW7 MKB_DQS_L4 GENOA_SP5-SOCKET6096_13568-001,SMLF,IO,DGA^6000030   I159 @T6G_MB_LIB.T6G(SCH_1):PAGE47
   J99  238 DQS4_B_C SCONN288_DDR506112002KQ-SCONN288_DDR506112002KQ,SMA   I235 @T6G_MB_LIB.T6G(SCH_1):PAGE107

M_K_CPU1_SB_DQS_DN<5> @T6G_MB_LIB.T6G(SCH_1):M_K_CPU1_SB_DQS_DN(5)
   U26  CE7 MKB_DQS_L5 GENOA_SP5-SOCKET6096_13568-001,SMLF,IO,DGA^6000030   I159 @T6G_MB_LIB.T6G(SCH_1):PAGE47
   J99  249 DQS5_B_C||TDQS5_B_C SCONN288_DDR506112002KQ-SCONN288_DDR506112002KQ,SMA   I235 @T6G_MB_LIB.T6G(SCH_1):PAGE107

M_K_CPU1_SB_DQS_DN<6> @T6G_MB_LIB.T6G(SCH_1):M_K_CPU1_SB_DQS_DN(6)
   U26  CL7 MKB_DQS_L6 GENOA_SP5-SOCKET6096_13568-001,SMLF,IO,DGA^6000030   I159 @T6G_MB_LIB.T6G(SCH_1):PAGE47
   J99  260 DQS6_B_C||TDQS6_B_C SCONN288_DDR506112002KQ-SCONN288_DDR506112002KQ,SMA   I235 @T6G_MB_LIB.T6G(SCH_1):PAGE107

M_K_CPU1_SB_DQS_DN<7> @T6G_MB_LIB.T6G(SCH_1):M_K_CPU1_SB_DQS_DN(7)
   U26  CU7 MKB_DQS_L7 GENOA_SP5-SOCKET6096_13568-001,SMLF,IO,DGA^6000030   I159 @T6G_MB_LIB.T6G(SCH_1):PAGE47
   J99  271 DQS7_B_C||TDQS7_B_C SCONN288_DDR506112002KQ-SCONN288_DDR506112002KQ,SMA   I235 @T6G_MB_LIB.T6G(SCH_1):PAGE107

M_K_CPU1_SB_DQS_DN<8> @T6G_MB_LIB.T6G(SCH_1):M_K_CPU1_SB_DQS_DN(8)
   U26  DC7 MKB_DQS_L8 GENOA_SP5-SOCKET6096_13568-001,SMLF,IO,DGA^6000030   I159 @T6G_MB_LIB.T6G(SCH_1):PAGE47
   J99  282 DQS8_B_C||TDQS8_B_C SCONN288_DDR506112002KQ-SCONN288_DDR506112002KQ,SMA   I235 @T6G_MB_LIB.T6G(SCH_1):PAGE107

M_K_CPU1_SB_DQS_DN<9> @T6G_MB_LIB.T6G(SCH_1):M_K_CPU1_SB_DQS_DN(9)
   U26  BW5 MKB_DQS_L9 GENOA_SP5-SOCKET6096_13568-001,SMLF,IO,DGA^6000030   I159 @T6G_MB_LIB.T6G(SCH_1):PAGE47
   J99   94 DQS9_B_C||TDQS9_B_C SCONN288_DDR506112002KQ-SCONN288_DDR506112002KQ,SMA   I235 @T6G_MB_LIB.T6G(SCH_1):PAGE107

M_K_CPU1_SB_DQS_DP<0> @T6G_MB_LIB.T6G(SCH_1):M_K_CPU1_SB_DQS_DP(0)
   U26  CD6 MKB_DQS_H0 GENOA_SP5-SOCKET6096_13568-001,SMLF,IO,DGA^6000030   I159 @T6G_MB_LIB.T6G(SCH_1):PAGE47
   J99  104 DQS0_B_T SCONN288_DDR506112002KQ-SCONN288_DDR506112002KQ,SMA   I235 @T6G_MB_LIB.T6G(SCH_1):PAGE107

M_K_CPU1_SB_DQS_DP<1> @T6G_MB_LIB.T6G(SCH_1):M_K_CPU1_SB_DQS_DP(1)
   U26  CK6 MKB_DQS_H1 GENOA_SP5-SOCKET6096_13568-001,SMLF,IO,DGA^6000030   I159 @T6G_MB_LIB.T6G(SCH_1):PAGE47
   J99  115 DQS1_B_T SCONN288_DDR506112002KQ-SCONN288_DDR506112002KQ,SMA   I235 @T6G_MB_LIB.T6G(SCH_1):PAGE107

M_K_CPU1_SB_DQS_DP<2> @T6G_MB_LIB.T6G(SCH_1):M_K_CPU1_SB_DQS_DP(2)
   U26  CT6 MKB_DQS_H2 GENOA_SP5-SOCKET6096_13568-001,SMLF,IO,DGA^6000030   I159 @T6G_MB_LIB.T6G(SCH_1):PAGE47
   J99  126 DQS2_B_T SCONN288_DDR506112002KQ-SCONN288_DDR506112002KQ,SMA   I235 @T6G_MB_LIB.T6G(SCH_1):PAGE107

M_K_CPU1_SB_DQS_DP<3> @T6G_MB_LIB.T6G(SCH_1):M_K_CPU1_SB_DQS_DP(3)
   U26  DB6 MKB_DQS_H3 GENOA_SP5-SOCKET6096_13568-001,SMLF,IO,DGA^6000030   I159 @T6G_MB_LIB.T6G(SCH_1):PAGE47
   J99  137 DQS3_B_T SCONN288_DDR506112002KQ-SCONN288_DDR506112002KQ,SMA   I235 @T6G_MB_LIB.T6G(SCH_1):PAGE107

M_K_CPU1_SB_DQS_DP<4> @T6G_MB_LIB.T6G(SCH_1):M_K_CPU1_SB_DQS_DP(4)
   U26  BY7 MKB_DQS_H4 GENOA_SP5-SOCKET6096_13568-001,SMLF,IO,DGA^6000030   I159 @T6G_MB_LIB.T6G(SCH_1):PAGE47
   J99  239 DQS4_B_T SCONN288_DDR506112002KQ-SCONN288_DDR506112002KQ,SMA   I235 @T6G_MB_LIB.T6G(SCH_1):PAGE107

M_K_CPU1_SB_DQS_DP<5> @T6G_MB_LIB.T6G(SCH_1):M_K_CPU1_SB_DQS_DP(5)
   U26  CF7 MKB_DQS_H5 GENOA_SP5-SOCKET6096_13568-001,SMLF,IO,DGA^6000030   I159 @T6G_MB_LIB.T6G(SCH_1):PAGE47
   J99  250 DQS5_B_T||TDQS5_B_T SCONN288_DDR506112002KQ-SCONN288_DDR506112002KQ,SMA   I235 @T6G_MB_LIB.T6G(SCH_1):PAGE107

M_K_CPU1_SB_DQS_DP<6> @T6G_MB_LIB.T6G(SCH_1):M_K_CPU1_SB_DQS_DP(6)
   U26  CM7 MKB_DQS_H6 GENOA_SP5-SOCKET6096_13568-001,SMLF,IO,DGA^6000030   I159 @T6G_MB_LIB.T6G(SCH_1):PAGE47
   J99  261 DQS6_B_T||TDQS6_B_T SCONN288_DDR506112002KQ-SCONN288_DDR506112002KQ,SMA   I235 @T6G_MB_LIB.T6G(SCH_1):PAGE107

M_K_CPU1_SB_DQS_DP<7> @T6G_MB_LIB.T6G(SCH_1):M_K_CPU1_SB_DQS_DP(7)
   U26  CV7 MKB_DQS_H7 GENOA_SP5-SOCKET6096_13568-001,SMLF,IO,DGA^6000030   I159 @T6G_MB_LIB.T6G(SCH_1):PAGE47
   J99  272 DQS7_B_T||TDQS7_B_T SCONN288_DDR506112002KQ-SCONN288_DDR506112002KQ,SMA   I235 @T6G_MB_LIB.T6G(SCH_1):PAGE107

M_K_CPU1_SB_DQS_DP<8> @T6G_MB_LIB.T6G(SCH_1):M_K_CPU1_SB_DQS_DP(8)
   U26  DD7 MKB_DQS_H8 GENOA_SP5-SOCKET6096_13568-001,SMLF,IO,DGA^6000030   I159 @T6G_MB_LIB.T6G(SCH_1):PAGE47
   J99  283 DQS8_B_T||TDQS8_B_T SCONN288_DDR506112002KQ-SCONN288_DDR506112002KQ,SMA   I235 @T6G_MB_LIB.T6G(SCH_1):PAGE107

M_K_CPU1_SB_DQS_DP<9> @T6G_MB_LIB.T6G(SCH_1):M_K_CPU1_SB_DQS_DP(9)
   U26  BV6 MKB_DQS_H9 GENOA_SP5-SOCKET6096_13568-001,SMLF,IO,DGA^6000030   I159 @T6G_MB_LIB.T6G(SCH_1):PAGE47
   J99   93 DQS9_B_T||TDQS9_B_T||DBI4_B_N SCONN288_DDR506112002KQ-SCONN288_DDR506112002KQ,SMA   I235 @T6G_MB_LIB.T6G(SCH_1):PAGE107

M_K_CPU1_SB_PAR @T6G_MB_LIB.T6G(SCH_1):M_K_CPU1_SB_PAR
   U26  BL7 MKB_PAR GENOA_SP5-SOCKET6096_13568-001,SMLF,IO,DGA^6000030   I159 @T6G_MB_LIB.T6G(SCH_1):PAGE47
   J99  227  PAR_B SCONN288_DDR506112002KQ-SCONN288_DDR506112002KQ,SMA    I22 @T6G_MB_LIB.T6G(SCH_1):PAGE107

M_K_CPU1_SB_RSP<0> @T6G_MB_LIB.T6G(SCH_1):M_K_CPU1_SB_RSP(0)
   U26  BP6 MKB0_RSP_L GENOA_SP5-SOCKET6096_13568-001,SMLF,IO,DGA^6000030   I159 @T6G_MB_LIB.T6G(SCH_1):PAGE47
   J99   87 LBS||RSP_B_N SCONN288_DDR506112002KQ-SCONN288_DDR506112002KQ,SMA    I22 @T6G_MB_LIB.T6G(SCH_1):PAGE107

M_L_CPU0_ALERT_N @T6G_MB_LIB.T6G(SCH_1):M_L_CPU0_ALERT_N
  R386    1      A Q_RES_0402LF-15,1%,1/16W,CHIP,CS01502FB03   I314 @T6G_MB_LIB.T6G(SCH_1):PAGE21
   J67   62 ALERT_N SCONN288_DDR506112002KQ-SCONN288_DDR506112002KQ,SMA    I22 @T6G_MB_LIB.T6G(SCH_1):PAGE96

M_L_CPU0_ALERT_R_N @T6G_MB_LIB.T6G(SCH_1):M_L_CPU0_ALERT_R_N
   U25 AT11 ML_ALERT_L GENOA_SP5-SOCKET6096_13568-001,SMLF,IO,DGA^6000030   I159 @T6G_MB_LIB.T6G(SCH_1):PAGE21
  R386    2      B Q_RES_0402LF-15,1%,1/16W,CHIP,CS01502FB03   I314 @T6G_MB_LIB.T6G(SCH_1):PAGE21

M_L_CPU0_CLK_DN<0> @T6G_MB_LIB.T6G(SCH_1):M_L_CPU0_CLK_DN(0)
   U25  BD9 ML0_CLK_L GENOA_SP5-SOCKET6096_13568-001,SMLF,IO,DGA^6000030   I159 @T6G_MB_LIB.T6G(SCH_1):PAGE21
   J67  218   CK_C SCONN288_DDR506112002KQ-SCONN288_DDR506112002KQ,SMA    I22 @T6G_MB_LIB.T6G(SCH_1):PAGE96

M_L_CPU0_CLK_DP<0> @T6G_MB_LIB.T6G(SCH_1):M_L_CPU0_CLK_DP(0)
   U25  BC9 ML0_CLK_H GENOA_SP5-SOCKET6096_13568-001,SMLF,IO,DGA^6000030   I159 @T6G_MB_LIB.T6G(SCH_1):PAGE21
   J67  217   CK_T SCONN288_DDR506112002KQ-SCONN288_DDR506112002KQ,SMA    I22 @T6G_MB_LIB.T6G(SCH_1):PAGE96

M_L_CPU0_RESET_N @T6G_MB_LIB.T6G(SCH_1):M_L_CPU0_RESET_N
   U25 AU10 ML_RESET_L GENOA_SP5-SOCKET6096_13568-001,SMLF,IO,DGA^6000030   I159 @T6G_MB_LIB.T6G(SCH_1):PAGE21
   J67  207 RESET_N SCONN288_DDR506112002KQ-SCONN288_DDR506112002KQ,SMA    I22 @T6G_MB_LIB.T6G(SCH_1):PAGE96

M_L_CPU0_SA_CA<0> @T6G_MB_LIB.T6G(SCH_1):M_L_CPU0_SA_CA(0)
   U25  AW9 MLA_CA0 GENOA_SP5-SOCKET6096_13568-001,SMLF,IO,DGA^6000030   I159 @T6G_MB_LIB.T6G(SCH_1):PAGE21
   J67   66  CA0_A SCONN288_DDR506112002KQ-SCONN288_DDR506112002KQ,SMA    I22 @T6G_MB_LIB.T6G(SCH_1):PAGE96

M_L_CPU0_SA_CA<1> @T6G_MB_LIB.T6G(SCH_1):M_L_CPU0_SA_CA(1)
   U25  AY9 MLA_CA1 GENOA_SP5-SOCKET6096_13568-001,SMLF,IO,DGA^6000030   I159 @T6G_MB_LIB.T6G(SCH_1):PAGE21
   J67  211  CA1_A SCONN288_DDR506112002KQ-SCONN288_DDR506112002KQ,SMA    I22 @T6G_MB_LIB.T6G(SCH_1):PAGE96

M_L_CPU0_SA_CA<2> @T6G_MB_LIB.T6G(SCH_1):M_L_CPU0_SA_CA(2)
   U25 AY11 MLA_CA2 GENOA_SP5-SOCKET6096_13568-001,SMLF,IO,DGA^6000030   I159 @T6G_MB_LIB.T6G(SCH_1):PAGE21
   J67   68  CA2_A SCONN288_DDR506112002KQ-SCONN288_DDR506112002KQ,SMA    I22 @T6G_MB_LIB.T6G(SCH_1):PAGE96

M_L_CPU0_SA_CA<3> @T6G_MB_LIB.T6G(SCH_1):M_L_CPU0_SA_CA(3)
   U25 BA10 MLA_CA3 GENOA_SP5-SOCKET6096_13568-001,SMLF,IO,DGA^6000030   I159 @T6G_MB_LIB.T6G(SCH_1):PAGE21
   J67  213  CA3_A SCONN288_DDR506112002KQ-SCONN288_DDR506112002KQ,SMA    I22 @T6G_MB_LIB.T6G(SCH_1):PAGE96

M_L_CPU0_SA_CA<4> @T6G_MB_LIB.T6G(SCH_1):M_L_CPU0_SA_CA(4)
   U25  BA9 MLA_CA4 GENOA_SP5-SOCKET6096_13568-001,SMLF,IO,DGA^6000030   I159 @T6G_MB_LIB.T6G(SCH_1):PAGE21
   J67   70  CA4_A SCONN288_DDR506112002KQ-SCONN288_DDR506112002KQ,SMA    I22 @T6G_MB_LIB.T6G(SCH_1):PAGE96

M_L_CPU0_SA_CA<5> @T6G_MB_LIB.T6G(SCH_1):M_L_CPU0_SA_CA(5)
   U25  BB9 MLA_CA5 GENOA_SP5-SOCKET6096_13568-001,SMLF,IO,DGA^6000030   I159 @T6G_MB_LIB.T6G(SCH_1):PAGE21
   J67  215  CA5_A SCONN288_DDR506112002KQ-SCONN288_DDR506112002KQ,SMA    I22 @T6G_MB_LIB.T6G(SCH_1):PAGE96

M_L_CPU0_SA_CA<6> @T6G_MB_LIB.T6G(SCH_1):M_L_CPU0_SA_CA(6)
   U25 BB11 MLA_CA6 GENOA_SP5-SOCKET6096_13568-001,SMLF,IO,DGA^6000030   I159 @T6G_MB_LIB.T6G(SCH_1):PAGE21
   J67   72  CA6_A SCONN288_DDR506112002KQ-SCONN288_DDR506112002KQ,SMA    I22 @T6G_MB_LIB.T6G(SCH_1):PAGE96

M_L_CPU0_SA_CB<0> @T6G_MB_LIB.T6G(SCH_1):M_L_CPU0_SA_CB(0)
   U25  AJ9 MLA_CHECK0 GENOA_SP5-SOCKET6096_13568-001,SMLF,IO,DGA^6000030   I159 @T6G_MB_LIB.T6G(SCH_1):PAGE21
   J67   51  CB0_A SCONN288_DDR506112002KQ-SCONN288_DDR506112002KQ,SMA    I22 @T6G_MB_LIB.T6G(SCH_1):PAGE96

M_L_CPU0_SA_CB<1> @T6G_MB_LIB.T6G(SCH_1):M_L_CPU0_SA_CB(1)
   U25 AK11 MLA_CHECK1 GENOA_SP5-SOCKET6096_13568-001,SMLF,IO,DGA^6000030   I159 @T6G_MB_LIB.T6G(SCH_1):PAGE21
   J67   53  CB1_A SCONN288_DDR506112002KQ-SCONN288_DDR506112002KQ,SMA    I22 @T6G_MB_LIB.T6G(SCH_1):PAGE96

M_L_CPU0_SA_CB<2> @T6G_MB_LIB.T6G(SCH_1):M_L_CPU0_SA_CB(2)
   U25  AK9 MLA_CHECK2 GENOA_SP5-SOCKET6096_13568-001,SMLF,IO,DGA^6000030   I159 @T6G_MB_LIB.T6G(SCH_1):PAGE21
   J67  196  CB2_A SCONN288_DDR506112002KQ-SCONN288_DDR506112002KQ,SMA    I22 @T6G_MB_LIB.T6G(SCH_1):PAGE96

M_L_CPU0_SA_CB<3> @T6G_MB_LIB.T6G(SCH_1):M_L_CPU0_SA_CB(3)
   U25 AL10 MLA_CHECK3 GENOA_SP5-SOCKET6096_13568-001,SMLF,IO,DGA^6000030   I159 @T6G_MB_LIB.T6G(SCH_1):PAGE21
   J67  198  CB3_A SCONN288_DDR506112002KQ-SCONN288_DDR506112002KQ,SMA    I22 @T6G_MB_LIB.T6G(SCH_1):PAGE96

M_L_CPU0_SA_CB<4> @T6G_MB_LIB.T6G(SCH_1):M_L_CPU0_SA_CB(4)
   U25  AN9 MLA_CHECK4 GENOA_SP5-SOCKET6096_13568-001,SMLF,IO,DGA^6000030   I159 @T6G_MB_LIB.T6G(SCH_1):PAGE21
   J67   58  CB4_A SCONN288_DDR506112002KQ-SCONN288_DDR506112002KQ,SMA    I22 @T6G_MB_LIB.T6G(SCH_1):PAGE96

M_L_CPU0_SA_CB<5> @T6G_MB_LIB.T6G(SCH_1):M_L_CPU0_SA_CB(5)
   U25 AP11 MLA_CHECK5 GENOA_SP5-SOCKET6096_13568-001,SMLF,IO,DGA^6000030   I159 @T6G_MB_LIB.T6G(SCH_1):PAGE21
   J67   60  CB5_A SCONN288_DDR506112002KQ-SCONN288_DDR506112002KQ,SMA    I22 @T6G_MB_LIB.T6G(SCH_1):PAGE96

M_L_CPU0_SA_CB<6> @T6G_MB_LIB.T6G(SCH_1):M_L_CPU0_SA_CB(6)
   U25  AP9 MLA_CHECK6 GENOA_SP5-SOCKET6096_13568-001,SMLF,IO,DGA^6000030   I159 @T6G_MB_LIB.T6G(SCH_1):PAGE21
   J67  203  CB6_A SCONN288_DDR506112002KQ-SCONN288_DDR506112002KQ,SMA    I22 @T6G_MB_LIB.T6G(SCH_1):PAGE96

M_L_CPU0_SA_CB<7> @T6G_MB_LIB.T6G(SCH_1):M_L_CPU0_SA_CB(7)
   U25 AR10 MLA_CHECK7 GENOA_SP5-SOCKET6096_13568-001,SMLF,IO,DGA^6000030   I159 @T6G_MB_LIB.T6G(SCH_1):PAGE21
   J67  205  CB7_A SCONN288_DDR506112002KQ-SCONN288_DDR506112002KQ,SMA    I22 @T6G_MB_LIB.T6G(SCH_1):PAGE96

M_L_CPU0_SA_CS_N<0> @T6G_MB_LIB.T6G(SCH_1):M_L_CPU0_SA_CS_N(0)
   U25  AU9 MLA0_CS_L0 GENOA_SP5-SOCKET6096_13568-001,SMLF,IO,DGA^6000030   I159 @T6G_MB_LIB.T6G(SCH_1):PAGE21
   J67   64 CS0_A_N SCONN288_DDR506112002KQ-SCONN288_DDR506112002KQ,SMA    I22 @T6G_MB_LIB.T6G(SCH_1):PAGE96

M_L_CPU0_SA_CS_N<1> @T6G_MB_LIB.T6G(SCH_1):M_L_CPU0_SA_CS_N(1)
   U25 AV11 MLA0_CS_L1 GENOA_SP5-SOCKET6096_13568-001,SMLF,IO,DGA^6000030   I159 @T6G_MB_LIB.T6G(SCH_1):PAGE21
   J67  209 CS1_A_N SCONN288_DDR506112002KQ-SCONN288_DDR506112002KQ,SMA    I22 @T6G_MB_LIB.T6G(SCH_1):PAGE96

M_L_CPU0_SA_DQ<0> @T6G_MB_LIB.T6G(SCH_1):M_L_CPU0_SA_DQ(0)
   U25   E9 MLA_DATA0 GENOA_SP5-SOCKET6096_13568-001,SMLF,IO,DGA^6000030   I159 @T6G_MB_LIB.T6G(SCH_1):PAGE21
   J67    7  DQ0_A SCONN288_DDR506112002KQ-SCONN288_DDR506112002KQ,SMA    I22 @T6G_MB_LIB.T6G(SCH_1):PAGE96

M_L_CPU0_SA_DQ<10> @T6G_MB_LIB.T6G(SCH_1):M_L_CPU0_SA_DQ(10)
   U25   M9 MLA_DATA10 GENOA_SP5-SOCKET6096_13568-001,SMLF,IO,DGA^6000030   I159 @T6G_MB_LIB.T6G(SCH_1):PAGE21
   J67  163 DQ10_A SCONN288_DDR506112002KQ-SCONN288_DDR506112002KQ,SMA    I22 @T6G_MB_LIB.T6G(SCH_1):PAGE96

M_L_CPU0_SA_DQ<11> @T6G_MB_LIB.T6G(SCH_1):M_L_CPU0_SA_DQ(11)
   U25  N10 MLA_DATA11 GENOA_SP5-SOCKET6096_13568-001,SMLF,IO,DGA^6000030   I159 @T6G_MB_LIB.T6G(SCH_1):PAGE21
   J67  165 DQ11_A SCONN288_DDR506112002KQ-SCONN288_DDR506112002KQ,SMA    I22 @T6G_MB_LIB.T6G(SCH_1):PAGE96

M_L_CPU0_SA_DQ<12> @T6G_MB_LIB.T6G(SCH_1):M_L_CPU0_SA_DQ(12)
   U25   R9 MLA_DATA12 GENOA_SP5-SOCKET6096_13568-001,SMLF,IO,DGA^6000030   I159 @T6G_MB_LIB.T6G(SCH_1):PAGE21
   J67   25 DQ12_A SCONN288_DDR506112002KQ-SCONN288_DDR506112002KQ,SMA    I22 @T6G_MB_LIB.T6G(SCH_1):PAGE96

M_L_CPU0_SA_DQ<13> @T6G_MB_LIB.T6G(SCH_1):M_L_CPU0_SA_DQ(13)
   U25  T11 MLA_DATA13 GENOA_SP5-SOCKET6096_13568-001,SMLF,IO,DGA^6000030   I159 @T6G_MB_LIB.T6G(SCH_1):PAGE21
   J67   27 DQ13_A SCONN288_DDR506112002KQ-SCONN288_DDR506112002KQ,SMA    I22 @T6G_MB_LIB.T6G(SCH_1):PAGE96

M_L_CPU0_SA_DQ<14> @T6G_MB_LIB.T6G(SCH_1):M_L_CPU0_SA_DQ(14)
   U25   T9 MLA_DATA14 GENOA_SP5-SOCKET6096_13568-001,SMLF,IO,DGA^6000030   I159 @T6G_MB_LIB.T6G(SCH_1):PAGE21
   J67  170 DQ14_A SCONN288_DDR506112002KQ-SCONN288_DDR506112002KQ,SMA    I22 @T6G_MB_LIB.T6G(SCH_1):PAGE96

M_L_CPU0_SA_DQ<15> @T6G_MB_LIB.T6G(SCH_1):M_L_CPU0_SA_DQ(15)
   U25  U10 MLA_DATA15 GENOA_SP5-SOCKET6096_13568-001,SMLF,IO,DGA^6000030   I159 @T6G_MB_LIB.T6G(SCH_1):PAGE21
   J67  172 DQ15_A SCONN288_DDR506112002KQ-SCONN288_DDR506112002KQ,SMA    I22 @T6G_MB_LIB.T6G(SCH_1):PAGE96

M_L_CPU0_SA_DQ<16> @T6G_MB_LIB.T6G(SCH_1):M_L_CPU0_SA_DQ(16)
   U25   U9 MLA_DATA16 GENOA_SP5-SOCKET6096_13568-001,SMLF,IO,DGA^6000030   I159 @T6G_MB_LIB.T6G(SCH_1):PAGE21
   J67   29 DQ16_A SCONN288_DDR506112002KQ-SCONN288_DDR506112002KQ,SMA    I22 @T6G_MB_LIB.T6G(SCH_1):PAGE96

M_L_CPU0_SA_DQ<17> @T6G_MB_LIB.T6G(SCH_1):M_L_CPU0_SA_DQ(17)
   U25  V11 MLA_DATA17 GENOA_SP5-SOCKET6096_13568-001,SMLF,IO,DGA^6000030   I159 @T6G_MB_LIB.T6G(SCH_1):PAGE21
   J67   31 DQ17_A SCONN288_DDR506112002KQ-SCONN288_DDR506112002KQ,SMA    I22 @T6G_MB_LIB.T6G(SCH_1):PAGE96

M_L_CPU0_SA_DQ<18> @T6G_MB_LIB.T6G(SCH_1):M_L_CPU0_SA_DQ(18)
   U25   V9 MLA_DATA18 GENOA_SP5-SOCKET6096_13568-001,SMLF,IO,DGA^6000030   I159 @T6G_MB_LIB.T6G(SCH_1):PAGE21
   J67  174 DQ18_A SCONN288_DDR506112002KQ-SCONN288_DDR506112002KQ,SMA    I22 @T6G_MB_LIB.T6G(SCH_1):PAGE96

M_L_CPU0_SA_DQ<19> @T6G_MB_LIB.T6G(SCH_1):M_L_CPU0_SA_DQ(19)
   U25  W10 MLA_DATA19 GENOA_SP5-SOCKET6096_13568-001,SMLF,IO,DGA^6000030   I159 @T6G_MB_LIB.T6G(SCH_1):PAGE21
   J67  176 DQ19_A SCONN288_DDR506112002KQ-SCONN288_DDR506112002KQ,SMA    I22 @T6G_MB_LIB.T6G(SCH_1):PAGE96

M_L_CPU0_SA_DQ<1> @T6G_MB_LIB.T6G(SCH_1):M_L_CPU0_SA_DQ(1)
   U25  F11 MLA_DATA1 GENOA_SP5-SOCKET6096_13568-001,SMLF,IO,DGA^6000030   I159 @T6G_MB_LIB.T6G(SCH_1):PAGE21
   J67    9  DQ1_A SCONN288_DDR506112002KQ-SCONN288_DDR506112002KQ,SMA    I22 @T6G_MB_LIB.T6G(SCH_1):PAGE96

M_L_CPU0_SA_DQ<20> @T6G_MB_LIB.T6G(SCH_1):M_L_CPU0_SA_DQ(20)
   U25  AA9 MLA_DATA20 GENOA_SP5-SOCKET6096_13568-001,SMLF,IO,DGA^6000030   I159 @T6G_MB_LIB.T6G(SCH_1):PAGE21
   J67   36 DQ20_A SCONN288_DDR506112002KQ-SCONN288_DDR506112002KQ,SMA    I22 @T6G_MB_LIB.T6G(SCH_1):PAGE96

M_L_CPU0_SA_DQ<21> @T6G_MB_LIB.T6G(SCH_1):M_L_CPU0_SA_DQ(21)
   U25 AB11 MLA_DATA21 GENOA_SP5-SOCKET6096_13568-001,SMLF,IO,DGA^6000030   I159 @T6G_MB_LIB.T6G(SCH_1):PAGE21
   J67   38 DQ21_A SCONN288_DDR506112002KQ-SCONN288_DDR506112002KQ,SMA    I22 @T6G_MB_LIB.T6G(SCH_1):PAGE96

M_L_CPU0_SA_DQ<22> @T6G_MB_LIB.T6G(SCH_1):M_L_CPU0_SA_DQ(22)
   U25  AB9 MLA_DATA22 GENOA_SP5-SOCKET6096_13568-001,SMLF,IO,DGA^6000030   I159 @T6G_MB_LIB.T6G(SCH_1):PAGE21
   J67  181 DQ22_A SCONN288_DDR506112002KQ-SCONN288_DDR506112002KQ,SMA    I22 @T6G_MB_LIB.T6G(SCH_1):PAGE96

M_L_CPU0_SA_DQ<23> @T6G_MB_LIB.T6G(SCH_1):M_L_CPU0_SA_DQ(23)
   U25 AC10 MLA_DATA23 GENOA_SP5-SOCKET6096_13568-001,SMLF,IO,DGA^6000030   I159 @T6G_MB_LIB.T6G(SCH_1):PAGE21
   J67  183 DQ23_A SCONN288_DDR506112002KQ-SCONN288_DDR506112002KQ,SMA    I22 @T6G_MB_LIB.T6G(SCH_1):PAGE96

M_L_CPU0_SA_DQ<24> @T6G_MB_LIB.T6G(SCH_1):M_L_CPU0_SA_DQ(24)
   U25  AC9 MLA_DATA24 GENOA_SP5-SOCKET6096_13568-001,SMLF,IO,DGA^6000030   I159 @T6G_MB_LIB.T6G(SCH_1):PAGE21
   J67   40 DQ24_A SCONN288_DDR506112002KQ-SCONN288_DDR506112002KQ,SMA    I22 @T6G_MB_LIB.T6G(SCH_1):PAGE96

M_L_CPU0_SA_DQ<25> @T6G_MB_LIB.T6G(SCH_1):M_L_CPU0_SA_DQ(25)
   U25 AD11 MLA_DATA25 GENOA_SP5-SOCKET6096_13568-001,SMLF,IO,DGA^6000030   I159 @T6G_MB_LIB.T6G(SCH_1):PAGE21
   J67   42 DQ25_A SCONN288_DDR506112002KQ-SCONN288_DDR506112002KQ,SMA    I22 @T6G_MB_LIB.T6G(SCH_1):PAGE96

M_L_CPU0_SA_DQ<26> @T6G_MB_LIB.T6G(SCH_1):M_L_CPU0_SA_DQ(26)
   U25  AD9 MLA_DATA26 GENOA_SP5-SOCKET6096_13568-001,SMLF,IO,DGA^6000030   I159 @T6G_MB_LIB.T6G(SCH_1):PAGE21
   J67  185 DQ26_A SCONN288_DDR506112002KQ-SCONN288_DDR506112002KQ,SMA    I22 @T6G_MB_LIB.T6G(SCH_1):PAGE96

M_L_CPU0_SA_DQ<27> @T6G_MB_LIB.T6G(SCH_1):M_L_CPU0_SA_DQ(27)
   U25 AE10 MLA_DATA27 GENOA_SP5-SOCKET6096_13568-001,SMLF,IO,DGA^6000030   I159 @T6G_MB_LIB.T6G(SCH_1):PAGE21
   J67  187 DQ27_A SCONN288_DDR506112002KQ-SCONN288_DDR506112002KQ,SMA    I22 @T6G_MB_LIB.T6G(SCH_1):PAGE96

M_L_CPU0_SA_DQ<28> @T6G_MB_LIB.T6G(SCH_1):M_L_CPU0_SA_DQ(28)
   U25  AG9 MLA_DATA28 GENOA_SP5-SOCKET6096_13568-001,SMLF,IO,DGA^6000030   I159 @T6G_MB_LIB.T6G(SCH_1):PAGE21
   J67   47 DQ28_A SCONN288_DDR506112002KQ-SCONN288_DDR506112002KQ,SMA    I22 @T6G_MB_LIB.T6G(SCH_1):PAGE96

M_L_CPU0_SA_DQ<29> @T6G_MB_LIB.T6G(SCH_1):M_L_CPU0_SA_DQ(29)
   U25 AH11 MLA_DATA29 GENOA_SP5-SOCKET6096_13568-001,SMLF,IO,DGA^6000030   I159 @T6G_MB_LIB.T6G(SCH_1):PAGE21
   J67   49 DQ29_A SCONN288_DDR506112002KQ-SCONN288_DDR506112002KQ,SMA    I22 @T6G_MB_LIB.T6G(SCH_1):PAGE96

M_L_CPU0_SA_DQ<2> @T6G_MB_LIB.T6G(SCH_1):M_L_CPU0_SA_DQ(2)
   U25   F9 MLA_DATA2 GENOA_SP5-SOCKET6096_13568-001,SMLF,IO,DGA^6000030   I159 @T6G_MB_LIB.T6G(SCH_1):PAGE21
   J67  152  DQ2_A SCONN288_DDR506112002KQ-SCONN288_DDR506112002KQ,SMA    I22 @T6G_MB_LIB.T6G(SCH_1):PAGE96

M_L_CPU0_SA_DQ<30> @T6G_MB_LIB.T6G(SCH_1):M_L_CPU0_SA_DQ(30)
   U25  AH9 MLA_DATA30 GENOA_SP5-SOCKET6096_13568-001,SMLF,IO,DGA^6000030   I159 @T6G_MB_LIB.T6G(SCH_1):PAGE21
   J67  192 DQ30_A SCONN288_DDR506112002KQ-SCONN288_DDR506112002KQ,SMA    I22 @T6G_MB_LIB.T6G(SCH_1):PAGE96

M_L_CPU0_SA_DQ<31> @T6G_MB_LIB.T6G(SCH_1):M_L_CPU0_SA_DQ(31)
   U25 AJ10 MLA_DATA31 GENOA_SP5-SOCKET6096_13568-001,SMLF,IO,DGA^6000030   I159 @T6G_MB_LIB.T6G(SCH_1):PAGE21
   J67  194 DQ31_A SCONN288_DDR506112002KQ-SCONN288_DDR506112002KQ,SMA    I22 @T6G_MB_LIB.T6G(SCH_1):PAGE96

M_L_CPU0_SA_DQ<3> @T6G_MB_LIB.T6G(SCH_1):M_L_CPU0_SA_DQ(3)
   U25  G10 MLA_DATA3 GENOA_SP5-SOCKET6096_13568-001,SMLF,IO,DGA^6000030   I159 @T6G_MB_LIB.T6G(SCH_1):PAGE21
   J67  154  DQ3_A SCONN288_DDR506112002KQ-SCONN288_DDR506112002KQ,SMA    I22 @T6G_MB_LIB.T6G(SCH_1):PAGE96

M_L_CPU0_SA_DQ<4> @T6G_MB_LIB.T6G(SCH_1):M_L_CPU0_SA_DQ(4)
   U25   J9 MLA_DATA4 GENOA_SP5-SOCKET6096_13568-001,SMLF,IO,DGA^6000030   I159 @T6G_MB_LIB.T6G(SCH_1):PAGE21
   J67   14  DQ4_A SCONN288_DDR506112002KQ-SCONN288_DDR506112002KQ,SMA    I22 @T6G_MB_LIB.T6G(SCH_1):PAGE96

M_L_CPU0_SA_DQ<5> @T6G_MB_LIB.T6G(SCH_1):M_L_CPU0_SA_DQ(5)
   U25  K11 MLA_DATA5 GENOA_SP5-SOCKET6096_13568-001,SMLF,IO,DGA^6000030   I159 @T6G_MB_LIB.T6G(SCH_1):PAGE21
   J67   16  DQ5_A SCONN288_DDR506112002KQ-SCONN288_DDR506112002KQ,SMA    I22 @T6G_MB_LIB.T6G(SCH_1):PAGE96

M_L_CPU0_SA_DQ<6> @T6G_MB_LIB.T6G(SCH_1):M_L_CPU0_SA_DQ(6)
   U25   K9 MLA_DATA6 GENOA_SP5-SOCKET6096_13568-001,SMLF,IO,DGA^6000030   I159 @T6G_MB_LIB.T6G(SCH_1):PAGE21
   J67  159  DQ6_A SCONN288_DDR506112002KQ-SCONN288_DDR506112002KQ,SMA    I22 @T6G_MB_LIB.T6G(SCH_1):PAGE96

M_L_CPU0_SA_DQ<7> @T6G_MB_LIB.T6G(SCH_1):M_L_CPU0_SA_DQ(7)
   U25  L10 MLA_DATA7 GENOA_SP5-SOCKET6096_13568-001,SMLF,IO,DGA^6000030   I159 @T6G_MB_LIB.T6G(SCH_1):PAGE21
   J67  161  DQ7_A SCONN288_DDR506112002KQ-SCONN288_DDR506112002KQ,SMA    I22 @T6G_MB_LIB.T6G(SCH_1):PAGE96

M_L_CPU0_SA_DQ<8> @T6G_MB_LIB.T6G(SCH_1):M_L_CPU0_SA_DQ(8)
   U25   L9 MLA_DATA8 GENOA_SP5-SOCKET6096_13568-001,SMLF,IO,DGA^6000030   I159 @T6G_MB_LIB.T6G(SCH_1):PAGE21
   J67   18  DQ8_A SCONN288_DDR506112002KQ-SCONN288_DDR506112002KQ,SMA    I22 @T6G_MB_LIB.T6G(SCH_1):PAGE96

M_L_CPU0_SA_DQ<9> @T6G_MB_LIB.T6G(SCH_1):M_L_CPU0_SA_DQ(9)
   U25  M11 MLA_DATA9 GENOA_SP5-SOCKET6096_13568-001,SMLF,IO,DGA^6000030   I159 @T6G_MB_LIB.T6G(SCH_1):PAGE21
   J67   20  DQ9_A SCONN288_DDR506112002KQ-SCONN288_DDR506112002KQ,SMA    I22 @T6G_MB_LIB.T6G(SCH_1):PAGE96

M_L_CPU0_SA_DQS_DN<0> @T6G_MB_LIB.T6G(SCH_1):M_L_CPU0_SA_DQS_DN(0)
   U25   H9 MLA_DQS_L0 GENOA_SP5-SOCKET6096_13568-001,SMLF,IO,DGA^6000030   I159 @T6G_MB_LIB.T6G(SCH_1):PAGE21
   J67   12 DQS0_A_C SCONN288_DDR506112002KQ-SCONN288_DDR506112002KQ,SMA   I236 @T6G_MB_LIB.T6G(SCH_1):PAGE96

M_L_CPU0_SA_DQS_DN<1> @T6G_MB_LIB.T6G(SCH_1):M_L_CPU0_SA_DQS_DN(1)
   U25   P9 MLA_DQS_L1 GENOA_SP5-SOCKET6096_13568-001,SMLF,IO,DGA^6000030   I159 @T6G_MB_LIB.T6G(SCH_1):PAGE21
   J67   23 DQS1_A_C SCONN288_DDR506112002KQ-SCONN288_DDR506112002KQ,SMA   I236 @T6G_MB_LIB.T6G(SCH_1):PAGE96

M_L_CPU0_SA_DQS_DN<2> @T6G_MB_LIB.T6G(SCH_1):M_L_CPU0_SA_DQS_DN(2)
   U25   Y9 MLA_DQS_L2 GENOA_SP5-SOCKET6096_13568-001,SMLF,IO,DGA^6000030   I159 @T6G_MB_LIB.T6G(SCH_1):PAGE21
   J67   34 DQS2_A_C SCONN288_DDR506112002KQ-SCONN288_DDR506112002KQ,SMA   I236 @T6G_MB_LIB.T6G(SCH_1):PAGE96

M_L_CPU0_SA_DQS_DN<3> @T6G_MB_LIB.T6G(SCH_1):M_L_CPU0_SA_DQS_DN(3)
   U25  AF9 MLA_DQS_L3 GENOA_SP5-SOCKET6096_13568-001,SMLF,IO,DGA^6000030   I159 @T6G_MB_LIB.T6G(SCH_1):PAGE21
   J67   45 DQS3_A_C SCONN288_DDR506112002KQ-SCONN288_DDR506112002KQ,SMA   I236 @T6G_MB_LIB.T6G(SCH_1):PAGE96

M_L_CPU0_SA_DQS_DN<4> @T6G_MB_LIB.T6G(SCH_1):M_L_CPU0_SA_DQS_DN(4)
   U25  AM9 MLA_DQS_L4 GENOA_SP5-SOCKET6096_13568-001,SMLF,IO,DGA^6000030   I159 @T6G_MB_LIB.T6G(SCH_1):PAGE21
   J67   56 DQS4_A_C SCONN288_DDR506112002KQ-SCONN288_DDR506112002KQ,SMA   I236 @T6G_MB_LIB.T6G(SCH_1):PAGE96

M_L_CPU0_SA_DQS_DN<5> @T6G_MB_LIB.T6G(SCH_1):M_L_CPU0_SA_DQS_DN(5)
   U25  H11 MLA_DQS_L5 GENOA_SP5-SOCKET6096_13568-001,SMLF,IO,DGA^6000030   I159 @T6G_MB_LIB.T6G(SCH_1):PAGE21
   J67  156 DQS5_A_C||TDQS5_A_C||DQS5_A_T||TDQS5_A_T SCONN288_DDR506112002KQ-SCONN288_DDR506112002KQ,SMA   I236 @T6G_MB_LIB.T6G(SCH_1):PAGE96

M_L_CPU0_SA_DQS_DN<6> @T6G_MB_LIB.T6G(SCH_1):M_L_CPU0_SA_DQS_DN(6)
   U25  P11 MLA_DQS_L6 GENOA_SP5-SOCKET6096_13568-001,SMLF,IO,DGA^6000030   I159 @T6G_MB_LIB.T6G(SCH_1):PAGE21
   J67  167 DQS6_A_C||TDQS6_A_C||DQS6_A_T||TDQS6_A_T SCONN288_DDR506112002KQ-SCONN288_DDR506112002KQ,SMA   I236 @T6G_MB_LIB.T6G(SCH_1):PAGE96

M_L_CPU0_SA_DQS_DN<7> @T6G_MB_LIB.T6G(SCH_1):M_L_CPU0_SA_DQS_DN(7)
   U25  Y11 MLA_DQS_L7 GENOA_SP5-SOCKET6096_13568-001,SMLF,IO,DGA^6000030   I159 @T6G_MB_LIB.T6G(SCH_1):PAGE21
   J67  178 DQS7_A_C||TDQS7_A_C SCONN288_DDR506112002KQ-SCONN288_DDR506112002KQ,SMA   I236 @T6G_MB_LIB.T6G(SCH_1):PAGE96

M_L_CPU0_SA_DQS_DN<8> @T6G_MB_LIB.T6G(SCH_1):M_L_CPU0_SA_DQS_DN(8)
   U25 AF11 MLA_DQS_L8 GENOA_SP5-SOCKET6096_13568-001,SMLF,IO,DGA^6000030   I159 @T6G_MB_LIB.T6G(SCH_1):PAGE21
   J67  189 DQS8_A_C||TDQS8_A_C SCONN288_DDR506112002KQ-SCONN288_DDR506112002KQ,SMA   I236 @T6G_MB_LIB.T6G(SCH_1):PAGE96

M_L_CPU0_SA_DQS_DN<9> @T6G_MB_LIB.T6G(SCH_1):M_L_CPU0_SA_DQS_DN(9)
   U25 AM11 MLA_DQS_L9 GENOA_SP5-SOCKET6096_13568-001,SMLF,IO,DGA^6000030   I159 @T6G_MB_LIB.T6G(SCH_1):PAGE21
   J67  200 DQS9_A_C||TDQS9_A_C SCONN288_DDR506112002KQ-SCONN288_DDR506112002KQ,SMA   I236 @T6G_MB_LIB.T6G(SCH_1):PAGE96

M_L_CPU0_SA_DQS_DP<0> @T6G_MB_LIB.T6G(SCH_1):M_L_CPU0_SA_DQS_DP(0)
   U25   G9 MLA_DQS_H0 GENOA_SP5-SOCKET6096_13568-001,SMLF,IO,DGA^6000030   I159 @T6G_MB_LIB.T6G(SCH_1):PAGE21
   J67   11 DQS0_A_T SCONN288_DDR506112002KQ-SCONN288_DDR506112002KQ,SMA   I236 @T6G_MB_LIB.T6G(SCH_1):PAGE96

M_L_CPU0_SA_DQS_DP<1> @T6G_MB_LIB.T6G(SCH_1):M_L_CPU0_SA_DQS_DP(1)
   U25   N9 MLA_DQS_H1 GENOA_SP5-SOCKET6096_13568-001,SMLF,IO,DGA^6000030   I159 @T6G_MB_LIB.T6G(SCH_1):PAGE21
   J67   22 DQS1_A_T SCONN288_DDR506112002KQ-SCONN288_DDR506112002KQ,SMA   I236 @T6G_MB_LIB.T6G(SCH_1):PAGE96

M_L_CPU0_SA_DQS_DP<2> @T6G_MB_LIB.T6G(SCH_1):M_L_CPU0_SA_DQS_DP(2)
   U25   W9 MLA_DQS_H2 GENOA_SP5-SOCKET6096_13568-001,SMLF,IO,DGA^6000030   I159 @T6G_MB_LIB.T6G(SCH_1):PAGE21
   J67   33 DQS2_A_T SCONN288_DDR506112002KQ-SCONN288_DDR506112002KQ,SMA   I236 @T6G_MB_LIB.T6G(SCH_1):PAGE96

M_L_CPU0_SA_DQS_DP<3> @T6G_MB_LIB.T6G(SCH_1):M_L_CPU0_SA_DQS_DP(3)
   U25  AE9 MLA_DQS_H3 GENOA_SP5-SOCKET6096_13568-001,SMLF,IO,DGA^6000030   I159 @T6G_MB_LIB.T6G(SCH_1):PAGE21
   J67   44 DQS3_A_T SCONN288_DDR506112002KQ-SCONN288_DDR506112002KQ,SMA   I236 @T6G_MB_LIB.T6G(SCH_1):PAGE96

M_L_CPU0_SA_DQS_DP<4> @T6G_MB_LIB.T6G(SCH_1):M_L_CPU0_SA_DQS_DP(4)
   U25  AL9 MLA_DQS_H4 GENOA_SP5-SOCKET6096_13568-001,SMLF,IO,DGA^6000030   I159 @T6G_MB_LIB.T6G(SCH_1):PAGE21
   J67   55 DQS4_A_T SCONN288_DDR506112002KQ-SCONN288_DDR506112002KQ,SMA   I236 @T6G_MB_LIB.T6G(SCH_1):PAGE96

M_L_CPU0_SA_DQS_DP<5> @T6G_MB_LIB.T6G(SCH_1):M_L_CPU0_SA_DQS_DP(5)
   U25  J10 MLA_DQS_H5 GENOA_SP5-SOCKET6096_13568-001,SMLF,IO,DGA^6000030   I159 @T6G_MB_LIB.T6G(SCH_1):PAGE21
   J67  157 DQS5_A_T||TDQS5_A_T SCONN288_DDR506112002KQ-SCONN288_DDR506112002KQ,SMA   I236 @T6G_MB_LIB.T6G(SCH_1):PAGE96

M_L_CPU0_SA_DQS_DP<6> @T6G_MB_LIB.T6G(SCH_1):M_L_CPU0_SA_DQS_DP(6)
   U25  R10 MLA_DQS_H6 GENOA_SP5-SOCKET6096_13568-001,SMLF,IO,DGA^6000030   I159 @T6G_MB_LIB.T6G(SCH_1):PAGE21
   J67  168 DQS6_A_T||TDQS6_A_T SCONN288_DDR506112002KQ-SCONN288_DDR506112002KQ,SMA   I236 @T6G_MB_LIB.T6G(SCH_1):PAGE96

M_L_CPU0_SA_DQS_DP<7> @T6G_MB_LIB.T6G(SCH_1):M_L_CPU0_SA_DQS_DP(7)
   U25 AA10 MLA_DQS_H7 GENOA_SP5-SOCKET6096_13568-001,SMLF,IO,DGA^6000030   I159 @T6G_MB_LIB.T6G(SCH_1):PAGE21
   J67  179 DQS7_A_T||TDQS7_A_T SCONN288_DDR506112002KQ-SCONN288_DDR506112002KQ,SMA   I236 @T6G_MB_LIB.T6G(SCH_1):PAGE96

M_L_CPU0_SA_DQS_DP<8> @T6G_MB_LIB.T6G(SCH_1):M_L_CPU0_SA_DQS_DP(8)
   U25 AG10 MLA_DQS_H8 GENOA_SP5-SOCKET6096_13568-001,SMLF,IO,DGA^6000030   I159 @T6G_MB_LIB.T6G(SCH_1):PAGE21
   J67  190 DQS8_A_T||TDQS8_A_T SCONN288_DDR506112002KQ-SCONN288_DDR506112002KQ,SMA   I236 @T6G_MB_LIB.T6G(SCH_1):PAGE96

M_L_CPU0_SA_DQS_DP<9> @T6G_MB_LIB.T6G(SCH_1):M_L_CPU0_SA_DQS_DP(9)
   U25 AN10 MLA_DQS_H9 GENOA_SP5-SOCKET6096_13568-001,SMLF,IO,DGA^6000030   I159 @T6G_MB_LIB.T6G(SCH_1):PAGE21
   J67  201 DQS9_A_T||TDQS9_A_T SCONN288_DDR506112002KQ-SCONN288_DDR506112002KQ,SMA   I236 @T6G_MB_LIB.T6G(SCH_1):PAGE96

M_L_CPU0_SA_PAR @T6G_MB_LIB.T6G(SCH_1):M_L_CPU0_SA_PAR
   U25 BC10 MLA_PAR GENOA_SP5-SOCKET6096_13568-001,SMLF,IO,DGA^6000030   I159 @T6G_MB_LIB.T6G(SCH_1):PAGE21
   J67   74  PAR_A SCONN288_DDR506112002KQ-SCONN288_DDR506112002KQ,SMA    I22 @T6G_MB_LIB.T6G(SCH_1):PAGE96

M_L_CPU0_SA_RSP<0> @T6G_MB_LIB.T6G(SCH_1):M_L_CPU0_SA_RSP(0)
   U25 BN10 MLA0_RSP_L GENOA_SP5-SOCKET6096_13568-001,SMLF,IO,DGA^6000030   I159 @T6G_MB_LIB.T6G(SCH_1):PAGE21
   J67   86 LBD||RSP_A_N SCONN288_DDR506112002KQ-SCONN288_DDR506112002KQ,SMA    I22 @T6G_MB_LIB.T6G(SCH_1):PAGE96

M_L_CPU0_SB_CA<0> @T6G_MB_LIB.T6G(SCH_1):M_L_CPU0_SB_CA(0)
   U25 BG10 MLB_CA0 GENOA_SP5-SOCKET6096_13568-001,SMLF,IO,DGA^6000030   I159 @T6G_MB_LIB.T6G(SCH_1):PAGE21
   J67   76  CA0_B SCONN288_DDR506112002KQ-SCONN288_DDR506112002KQ,SMA    I22 @T6G_MB_LIB.T6G(SCH_1):PAGE96

M_L_CPU0_SB_CA<1> @T6G_MB_LIB.T6G(SCH_1):M_L_CPU0_SB_CA(1)
   U25 BH11 MLB_CA1 GENOA_SP5-SOCKET6096_13568-001,SMLF,IO,DGA^6000030   I159 @T6G_MB_LIB.T6G(SCH_1):PAGE21
   J67  221  CA1_B SCONN288_DDR506112002KQ-SCONN288_DDR506112002KQ,SMA    I22 @T6G_MB_LIB.T6G(SCH_1):PAGE96

M_L_CPU0_SB_CA<2> @T6G_MB_LIB.T6G(SCH_1):M_L_CPU0_SB_CA(2)
   U25  BH9 MLB_CA2 GENOA_SP5-SOCKET6096_13568-001,SMLF,IO,DGA^6000030   I159 @T6G_MB_LIB.T6G(SCH_1):PAGE21
   J67   78  CA2_B SCONN288_DDR506112002KQ-SCONN288_DDR506112002KQ,SMA    I22 @T6G_MB_LIB.T6G(SCH_1):PAGE96

M_L_CPU0_SB_CA<3> @T6G_MB_LIB.T6G(SCH_1):M_L_CPU0_SB_CA(3)
   U25  BJ9 MLB_CA3 GENOA_SP5-SOCKET6096_13568-001,SMLF,IO,DGA^6000030   I159 @T6G_MB_LIB.T6G(SCH_1):PAGE21
   J67  223  CA3_B SCONN288_DDR506112002KQ-SCONN288_DDR506112002KQ,SMA    I22 @T6G_MB_LIB.T6G(SCH_1):PAGE96

M_L_CPU0_SB_CA<4> @T6G_MB_LIB.T6G(SCH_1):M_L_CPU0_SB_CA(4)
   U25 BJ10 MLB_CA4 GENOA_SP5-SOCKET6096_13568-001,SMLF,IO,DGA^6000030   I159 @T6G_MB_LIB.T6G(SCH_1):PAGE21
   J67   80  CA4_B SCONN288_DDR506112002KQ-SCONN288_DDR506112002KQ,SMA    I22 @T6G_MB_LIB.T6G(SCH_1):PAGE96

M_L_CPU0_SB_CA<5> @T6G_MB_LIB.T6G(SCH_1):M_L_CPU0_SB_CA(5)
   U25 BK11 MLB_CA5 GENOA_SP5-SOCKET6096_13568-001,SMLF,IO,DGA^6000030   I159 @T6G_MB_LIB.T6G(SCH_1):PAGE21
   J67  225  CA5_B SCONN288_DDR506112002KQ-SCONN288_DDR506112002KQ,SMA    I22 @T6G_MB_LIB.T6G(SCH_1):PAGE96

M_L_CPU0_SB_CA<6> @T6G_MB_LIB.T6G(SCH_1):M_L_CPU0_SB_CA(6)
   U25  BK9 MLB_CA6 GENOA_SP5-SOCKET6096_13568-001,SMLF,IO,DGA^6000030   I159 @T6G_MB_LIB.T6G(SCH_1):PAGE21
   J67   82  CA6_B SCONN288_DDR506112002KQ-SCONN288_DDR506112002KQ,SMA    I22 @T6G_MB_LIB.T6G(SCH_1):PAGE96

M_L_CPU0_SB_CB<0> @T6G_MB_LIB.T6G(SCH_1):M_L_CPU0_SB_CB(0)
   U25  BY9 MLB_CHECK0 GENOA_SP5-SOCKET6096_13568-001,SMLF,IO,DGA^6000030   I159 @T6G_MB_LIB.T6G(SCH_1):PAGE21
   J67   96  CB0_B SCONN288_DDR506112002KQ-SCONN288_DDR506112002KQ,SMA    I22 @T6G_MB_LIB.T6G(SCH_1):PAGE96

M_L_CPU0_SB_CB<1> @T6G_MB_LIB.T6G(SCH_1):M_L_CPU0_SB_CB(1)
   U25 CA10 MLB_CHECK1 GENOA_SP5-SOCKET6096_13568-001,SMLF,IO,DGA^6000030   I159 @T6G_MB_LIB.T6G(SCH_1):PAGE21
   J67   98  CB1_B SCONN288_DDR506112002KQ-SCONN288_DDR506112002KQ,SMA    I22 @T6G_MB_LIB.T6G(SCH_1):PAGE96

M_L_CPU0_SB_CB<2> @T6G_MB_LIB.T6G(SCH_1):M_L_CPU0_SB_CB(2)
   U25  CA9 MLB_CHECK2 GENOA_SP5-SOCKET6096_13568-001,SMLF,IO,DGA^6000030   I159 @T6G_MB_LIB.T6G(SCH_1):PAGE21
   J67  241  CB2_B SCONN288_DDR506112002KQ-SCONN288_DDR506112002KQ,SMA    I22 @T6G_MB_LIB.T6G(SCH_1):PAGE96

M_L_CPU0_SB_CB<3> @T6G_MB_LIB.T6G(SCH_1):M_L_CPU0_SB_CB(3)
   U25 CB11 MLB_CHECK3 GENOA_SP5-SOCKET6096_13568-001,SMLF,IO,DGA^6000030   I159 @T6G_MB_LIB.T6G(SCH_1):PAGE21
   J67  243  CB3_B SCONN288_DDR506112002KQ-SCONN288_DDR506112002KQ,SMA    I22 @T6G_MB_LIB.T6G(SCH_1):PAGE96

M_L_CPU0_SB_CB<4> @T6G_MB_LIB.T6G(SCH_1):M_L_CPU0_SB_CB(4)
   U25  BT9 MLB_CHECK4 GENOA_SP5-SOCKET6096_13568-001,SMLF,IO,DGA^6000030   I159 @T6G_MB_LIB.T6G(SCH_1):PAGE21
   J67   89  CB4_B SCONN288_DDR506112002KQ-SCONN288_DDR506112002KQ,SMA    I22 @T6G_MB_LIB.T6G(SCH_1):PAGE96

M_L_CPU0_SB_CB<5> @T6G_MB_LIB.T6G(SCH_1):M_L_CPU0_SB_CB(5)
   U25 BU10 MLB_CHECK5 GENOA_SP5-SOCKET6096_13568-001,SMLF,IO,DGA^6000030   I159 @T6G_MB_LIB.T6G(SCH_1):PAGE21
   J67   91  CB5_B SCONN288_DDR506112002KQ-SCONN288_DDR506112002KQ,SMA    I22 @T6G_MB_LIB.T6G(SCH_1):PAGE96

M_L_CPU0_SB_CB<6> @T6G_MB_LIB.T6G(SCH_1):M_L_CPU0_SB_CB(6)
   U25  BU9 MLB_CHECK6 GENOA_SP5-SOCKET6096_13568-001,SMLF,IO,DGA^6000030   I159 @T6G_MB_LIB.T6G(SCH_1):PAGE21
   J67  234  CB6_B SCONN288_DDR506112002KQ-SCONN288_DDR506112002KQ,SMA    I22 @T6G_MB_LIB.T6G(SCH_1):PAGE96

M_L_CPU0_SB_CB<7> @T6G_MB_LIB.T6G(SCH_1):M_L_CPU0_SB_CB(7)
   U25 BV11 MLB_CHECK7 GENOA_SP5-SOCKET6096_13568-001,SMLF,IO,DGA^6000030   I159 @T6G_MB_LIB.T6G(SCH_1):PAGE21
   J67  236  CB7_B SCONN288_DDR506112002KQ-SCONN288_DDR506112002KQ,SMA    I22 @T6G_MB_LIB.T6G(SCH_1):PAGE96

M_L_CPU0_SB_CS_N<0> @T6G_MB_LIB.T6G(SCH_1):M_L_CPU0_SB_CS_N(0)
   U25 BM11 MLB0_CS_L0 GENOA_SP5-SOCKET6096_13568-001,SMLF,IO,DGA^6000030   I159 @T6G_MB_LIB.T6G(SCH_1):PAGE21
   J67   84 CS0_B_N SCONN288_DDR506112002KQ-SCONN288_DDR506112002KQ,SMA    I22 @T6G_MB_LIB.T6G(SCH_1):PAGE96

M_L_CPU0_SB_CS_N<1> @T6G_MB_LIB.T6G(SCH_1):M_L_CPU0_SB_CS_N(1)
   U25  BN9 MLB0_CS_L1 GENOA_SP5-SOCKET6096_13568-001,SMLF,IO,DGA^6000030   I159 @T6G_MB_LIB.T6G(SCH_1):PAGE21
   J67  229 CS1_B_N SCONN288_DDR506112002KQ-SCONN288_DDR506112002KQ,SMA    I22 @T6G_MB_LIB.T6G(SCH_1):PAGE96

M_L_CPU0_SB_DQ<0> @T6G_MB_LIB.T6G(SCH_1):M_L_CPU0_SB_DQ(0)
   U25  CB9 MLB_DATA0 GENOA_SP5-SOCKET6096_13568-001,SMLF,IO,DGA^6000030   I159 @T6G_MB_LIB.T6G(SCH_1):PAGE21
   J67  100  DQ0_B SCONN288_DDR506112002KQ-SCONN288_DDR506112002KQ,SMA    I22 @T6G_MB_LIB.T6G(SCH_1):PAGE96

M_L_CPU0_SB_DQ<10> @T6G_MB_LIB.T6G(SCH_1):M_L_CPU0_SB_DQ(10)
   U25  CJ9 MLB_DATA10 GENOA_SP5-SOCKET6096_13568-001,SMLF,IO,DGA^6000030   I159 @T6G_MB_LIB.T6G(SCH_1):PAGE21
   J67  256 DQ10_B SCONN288_DDR506112002KQ-SCONN288_DDR506112002KQ,SMA    I22 @T6G_MB_LIB.T6G(SCH_1):PAGE96

M_L_CPU0_SB_DQ<11> @T6G_MB_LIB.T6G(SCH_1):M_L_CPU0_SB_DQ(11)
   U25 CK11 MLB_DATA11 GENOA_SP5-SOCKET6096_13568-001,SMLF,IO,DGA^6000030   I159 @T6G_MB_LIB.T6G(SCH_1):PAGE21
   J67  258 DQ11_B SCONN288_DDR506112002KQ-SCONN288_DDR506112002KQ,SMA    I22 @T6G_MB_LIB.T6G(SCH_1):PAGE96

M_L_CPU0_SB_DQ<12> @T6G_MB_LIB.T6G(SCH_1):M_L_CPU0_SB_DQ(12)
   U25  CM9 MLB_DATA12 GENOA_SP5-SOCKET6096_13568-001,SMLF,IO,DGA^6000030   I159 @T6G_MB_LIB.T6G(SCH_1):PAGE21
   J67  118 DQ12_B SCONN288_DDR506112002KQ-SCONN288_DDR506112002KQ,SMA    I22 @T6G_MB_LIB.T6G(SCH_1):PAGE96

M_L_CPU0_SB_DQ<13> @T6G_MB_LIB.T6G(SCH_1):M_L_CPU0_SB_DQ(13)
   U25 CN10 MLB_DATA13 GENOA_SP5-SOCKET6096_13568-001,SMLF,IO,DGA^6000030   I159 @T6G_MB_LIB.T6G(SCH_1):PAGE21
   J67  120 DQ13_B SCONN288_DDR506112002KQ-SCONN288_DDR506112002KQ,SMA    I22 @T6G_MB_LIB.T6G(SCH_1):PAGE96

M_L_CPU0_SB_DQ<14> @T6G_MB_LIB.T6G(SCH_1):M_L_CPU0_SB_DQ(14)
   U25  CN9 MLB_DATA14 GENOA_SP5-SOCKET6096_13568-001,SMLF,IO,DGA^6000030   I159 @T6G_MB_LIB.T6G(SCH_1):PAGE21
   J67  263 DQ14_B SCONN288_DDR506112002KQ-SCONN288_DDR506112002KQ,SMA    I22 @T6G_MB_LIB.T6G(SCH_1):PAGE96

M_L_CPU0_SB_DQ<15> @T6G_MB_LIB.T6G(SCH_1):M_L_CPU0_SB_DQ(15)
   U25 CP11 MLB_DATA15 GENOA_SP5-SOCKET6096_13568-001,SMLF,IO,DGA^6000030   I159 @T6G_MB_LIB.T6G(SCH_1):PAGE21
   J67  265 DQ15_B SCONN288_DDR506112002KQ-SCONN288_DDR506112002KQ,SMA    I22 @T6G_MB_LIB.T6G(SCH_1):PAGE96

M_L_CPU0_SB_DQ<16> @T6G_MB_LIB.T6G(SCH_1):M_L_CPU0_SB_DQ(16)
   U25  CP9 MLB_DATA16 GENOA_SP5-SOCKET6096_13568-001,SMLF,IO,DGA^6000030   I159 @T6G_MB_LIB.T6G(SCH_1):PAGE21
   J67  122 DQ16_B SCONN288_DDR506112002KQ-SCONN288_DDR506112002KQ,SMA    I22 @T6G_MB_LIB.T6G(SCH_1):PAGE96

M_L_CPU0_SB_DQ<17> @T6G_MB_LIB.T6G(SCH_1):M_L_CPU0_SB_DQ(17)
   U25 CR10 MLB_DATA17 GENOA_SP5-SOCKET6096_13568-001,SMLF,IO,DGA^6000030   I159 @T6G_MB_LIB.T6G(SCH_1):PAGE21
   J67  124 DQ17_B SCONN288_DDR506112002KQ-SCONN288_DDR506112002KQ,SMA    I22 @T6G_MB_LIB.T6G(SCH_1):PAGE96

M_L_CPU0_SB_DQ<18> @T6G_MB_LIB.T6G(SCH_1):M_L_CPU0_SB_DQ(18)
   U25  CR9 MLB_DATA18 GENOA_SP5-SOCKET6096_13568-001,SMLF,IO,DGA^6000030   I159 @T6G_MB_LIB.T6G(SCH_1):PAGE21
   J67  267 DQ18_B SCONN288_DDR506112002KQ-SCONN288_DDR506112002KQ,SMA    I22 @T6G_MB_LIB.T6G(SCH_1):PAGE96

M_L_CPU0_SB_DQ<19> @T6G_MB_LIB.T6G(SCH_1):M_L_CPU0_SB_DQ(19)
   U25 CT11 MLB_DATA19 GENOA_SP5-SOCKET6096_13568-001,SMLF,IO,DGA^6000030   I159 @T6G_MB_LIB.T6G(SCH_1):PAGE21
   J67  269 DQ19_B SCONN288_DDR506112002KQ-SCONN288_DDR506112002KQ,SMA    I22 @T6G_MB_LIB.T6G(SCH_1):PAGE96

M_L_CPU0_SB_DQ<1> @T6G_MB_LIB.T6G(SCH_1):M_L_CPU0_SB_DQ(1)
   U25 CC10 MLB_DATA1 GENOA_SP5-SOCKET6096_13568-001,SMLF,IO,DGA^6000030   I159 @T6G_MB_LIB.T6G(SCH_1):PAGE21
   J67  102  DQ1_B SCONN288_DDR506112002KQ-SCONN288_DDR506112002KQ,SMA    I22 @T6G_MB_LIB.T6G(SCH_1):PAGE96

M_L_CPU0_SB_DQ<20> @T6G_MB_LIB.T6G(SCH_1):M_L_CPU0_SB_DQ(20)
   U25  CV9 MLB_DATA20 GENOA_SP5-SOCKET6096_13568-001,SMLF,IO,DGA^6000030   I159 @T6G_MB_LIB.T6G(SCH_1):PAGE21
   J67  129 DQ20_B SCONN288_DDR506112002KQ-SCONN288_DDR506112002KQ,SMA    I22 @T6G_MB_LIB.T6G(SCH_1):PAGE96

M_L_CPU0_SB_DQ<21> @T6G_MB_LIB.T6G(SCH_1):M_L_CPU0_SB_DQ(21)
   U25 CW10 MLB_DATA21 GENOA_SP5-SOCKET6096_13568-001,SMLF,IO,DGA^6000030   I159 @T6G_MB_LIB.T6G(SCH_1):PAGE21
   J67  131 DQ21_B SCONN288_DDR506112002KQ-SCONN288_DDR506112002KQ,SMA    I22 @T6G_MB_LIB.T6G(SCH_1):PAGE96

M_L_CPU0_SB_DQ<22> @T6G_MB_LIB.T6G(SCH_1):M_L_CPU0_SB_DQ(22)
   U25  CW9 MLB_DATA22 GENOA_SP5-SOCKET6096_13568-001,SMLF,IO,DGA^6000030   I159 @T6G_MB_LIB.T6G(SCH_1):PAGE21
   J67  274 DQ22_B SCONN288_DDR506112002KQ-SCONN288_DDR506112002KQ,SMA    I22 @T6G_MB_LIB.T6G(SCH_1):PAGE96

M_L_CPU0_SB_DQ<23> @T6G_MB_LIB.T6G(SCH_1):M_L_CPU0_SB_DQ(23)
   U25 CY11 MLB_DATA23 GENOA_SP5-SOCKET6096_13568-001,SMLF,IO,DGA^6000030   I159 @T6G_MB_LIB.T6G(SCH_1):PAGE21
   J67  276 DQ23_B SCONN288_DDR506112002KQ-SCONN288_DDR506112002KQ,SMA    I22 @T6G_MB_LIB.T6G(SCH_1):PAGE96

M_L_CPU0_SB_DQ<24> @T6G_MB_LIB.T6G(SCH_1):M_L_CPU0_SB_DQ(24)
   U25  CY9 MLB_DATA24 GENOA_SP5-SOCKET6096_13568-001,SMLF,IO,DGA^6000030   I159 @T6G_MB_LIB.T6G(SCH_1):PAGE21
   J67  133 DQ24_B SCONN288_DDR506112002KQ-SCONN288_DDR506112002KQ,SMA    I22 @T6G_MB_LIB.T6G(SCH_1):PAGE96

M_L_CPU0_SB_DQ<25> @T6G_MB_LIB.T6G(SCH_1):M_L_CPU0_SB_DQ(25)
   U25 DA10 MLB_DATA25 GENOA_SP5-SOCKET6096_13568-001,SMLF,IO,DGA^6000030   I159 @T6G_MB_LIB.T6G(SCH_1):PAGE21
   J67  135 DQ25_B SCONN288_DDR506112002KQ-SCONN288_DDR506112002KQ,SMA    I22 @T6G_MB_LIB.T6G(SCH_1):PAGE96

M_L_CPU0_SB_DQ<26> @T6G_MB_LIB.T6G(SCH_1):M_L_CPU0_SB_DQ(26)
   U25  DA9 MLB_DATA26 GENOA_SP5-SOCKET6096_13568-001,SMLF,IO,DGA^6000030   I159 @T6G_MB_LIB.T6G(SCH_1):PAGE21
   J67  278 DQ26_B SCONN288_DDR506112002KQ-SCONN288_DDR506112002KQ,SMA    I22 @T6G_MB_LIB.T6G(SCH_1):PAGE96

M_L_CPU0_SB_DQ<27> @T6G_MB_LIB.T6G(SCH_1):M_L_CPU0_SB_DQ(27)
   U25 DB11 MLB_DATA27 GENOA_SP5-SOCKET6096_13568-001,SMLF,IO,DGA^6000030   I159 @T6G_MB_LIB.T6G(SCH_1):PAGE21
   J67  280 DQ27_B SCONN288_DDR506112002KQ-SCONN288_DDR506112002KQ,SMA    I22 @T6G_MB_LIB.T6G(SCH_1):PAGE96

M_L_CPU0_SB_DQ<28> @T6G_MB_LIB.T6G(SCH_1):M_L_CPU0_SB_DQ(28)
   U25  DD9 MLB_DATA28 GENOA_SP5-SOCKET6096_13568-001,SMLF,IO,DGA^6000030   I159 @T6G_MB_LIB.T6G(SCH_1):PAGE21
   J67  140 DQ28_B SCONN288_DDR506112002KQ-SCONN288_DDR506112002KQ,SMA    I22 @T6G_MB_LIB.T6G(SCH_1):PAGE96

M_L_CPU0_SB_DQ<29> @T6G_MB_LIB.T6G(SCH_1):M_L_CPU0_SB_DQ(29)
   U25 DE10 MLB_DATA29 GENOA_SP5-SOCKET6096_13568-001,SMLF,IO,DGA^6000030   I159 @T6G_MB_LIB.T6G(SCH_1):PAGE21
   J67  142 DQ29_B SCONN288_DDR506112002KQ-SCONN288_DDR506112002KQ,SMA    I22 @T6G_MB_LIB.T6G(SCH_1):PAGE96

M_L_CPU0_SB_DQ<2> @T6G_MB_LIB.T6G(SCH_1):M_L_CPU0_SB_DQ(2)
   U25  CC9 MLB_DATA2 GENOA_SP5-SOCKET6096_13568-001,SMLF,IO,DGA^6000030   I159 @T6G_MB_LIB.T6G(SCH_1):PAGE21
   J67  245  DQ2_B SCONN288_DDR506112002KQ-SCONN288_DDR506112002KQ,SMA    I22 @T6G_MB_LIB.T6G(SCH_1):PAGE96

M_L_CPU0_SB_DQ<30> @T6G_MB_LIB.T6G(SCH_1):M_L_CPU0_SB_DQ(30)
   U25  DE9 MLB_DATA30 GENOA_SP5-SOCKET6096_13568-001,SMLF,IO,DGA^6000030   I159 @T6G_MB_LIB.T6G(SCH_1):PAGE21
   J67  285 DQ30_B SCONN288_DDR506112002KQ-SCONN288_DDR506112002KQ,SMA    I22 @T6G_MB_LIB.T6G(SCH_1):PAGE96

M_L_CPU0_SB_DQ<31> @T6G_MB_LIB.T6G(SCH_1):M_L_CPU0_SB_DQ(31)
   U25  DF9 MLB_DATA31 GENOA_SP5-SOCKET6096_13568-001,SMLF,IO,DGA^6000030   I159 @T6G_MB_LIB.T6G(SCH_1):PAGE21
   J67  287 DQ31_B SCONN288_DDR506112002KQ-SCONN288_DDR506112002KQ,SMA    I22 @T6G_MB_LIB.T6G(SCH_1):PAGE96

M_L_CPU0_SB_DQ<3> @T6G_MB_LIB.T6G(SCH_1):M_L_CPU0_SB_DQ(3)
   U25 CD11 MLB_DATA3 GENOA_SP5-SOCKET6096_13568-001,SMLF,IO,DGA^6000030   I159 @T6G_MB_LIB.T6G(SCH_1):PAGE21
   J67  247  DQ3_B SCONN288_DDR506112002KQ-SCONN288_DDR506112002KQ,SMA    I22 @T6G_MB_LIB.T6G(SCH_1):PAGE96

M_L_CPU0_SB_DQ<4> @T6G_MB_LIB.T6G(SCH_1):M_L_CPU0_SB_DQ(4)
   U25  CF9 MLB_DATA4 GENOA_SP5-SOCKET6096_13568-001,SMLF,IO,DGA^6000030   I159 @T6G_MB_LIB.T6G(SCH_1):PAGE21
   J67  107  DQ4_B SCONN288_DDR506112002KQ-SCONN288_DDR506112002KQ,SMA    I22 @T6G_MB_LIB.T6G(SCH_1):PAGE96

M_L_CPU0_SB_DQ<5> @T6G_MB_LIB.T6G(SCH_1):M_L_CPU0_SB_DQ(5)
   U25 CG10 MLB_DATA5 GENOA_SP5-SOCKET6096_13568-001,SMLF,IO,DGA^6000030   I159 @T6G_MB_LIB.T6G(SCH_1):PAGE21
   J67  109  DQ5_B SCONN288_DDR506112002KQ-SCONN288_DDR506112002KQ,SMA    I22 @T6G_MB_LIB.T6G(SCH_1):PAGE96

M_L_CPU0_SB_DQ<6> @T6G_MB_LIB.T6G(SCH_1):M_L_CPU0_SB_DQ(6)
   U25  CG9 MLB_DATA6 GENOA_SP5-SOCKET6096_13568-001,SMLF,IO,DGA^6000030   I159 @T6G_MB_LIB.T6G(SCH_1):PAGE21
   J67  252  DQ6_B SCONN288_DDR506112002KQ-SCONN288_DDR506112002KQ,SMA    I22 @T6G_MB_LIB.T6G(SCH_1):PAGE96

M_L_CPU0_SB_DQ<7> @T6G_MB_LIB.T6G(SCH_1):M_L_CPU0_SB_DQ(7)
   U25 CH11 MLB_DATA7 GENOA_SP5-SOCKET6096_13568-001,SMLF,IO,DGA^6000030   I159 @T6G_MB_LIB.T6G(SCH_1):PAGE21
   J67  254  DQ7_B SCONN288_DDR506112002KQ-SCONN288_DDR506112002KQ,SMA    I22 @T6G_MB_LIB.T6G(SCH_1):PAGE96

M_L_CPU0_SB_DQ<8> @T6G_MB_LIB.T6G(SCH_1):M_L_CPU0_SB_DQ(8)
   U25  CH9 MLB_DATA8 GENOA_SP5-SOCKET6096_13568-001,SMLF,IO,DGA^6000030   I159 @T6G_MB_LIB.T6G(SCH_1):PAGE21
   J67  111  DQ8_B SCONN288_DDR506112002KQ-SCONN288_DDR506112002KQ,SMA    I22 @T6G_MB_LIB.T6G(SCH_1):PAGE96

M_L_CPU0_SB_DQ<9> @T6G_MB_LIB.T6G(SCH_1):M_L_CPU0_SB_DQ(9)
   U25 CJ10 MLB_DATA9 GENOA_SP5-SOCKET6096_13568-001,SMLF,IO,DGA^6000030   I159 @T6G_MB_LIB.T6G(SCH_1):PAGE21
   J67  113  DQ9_B SCONN288_DDR506112002KQ-SCONN288_DDR506112002KQ,SMA    I22 @T6G_MB_LIB.T6G(SCH_1):PAGE96

M_L_CPU0_SB_DQS_DN<0> @T6G_MB_LIB.T6G(SCH_1):M_L_CPU0_SB_DQS_DN(0)
   U25  CE9 MLB_DQS_L0 GENOA_SP5-SOCKET6096_13568-001,SMLF,IO,DGA^6000030   I159 @T6G_MB_LIB.T6G(SCH_1):PAGE21
   J67  105 DQS0_B_C SCONN288_DDR506112002KQ-SCONN288_DDR506112002KQ,SMA   I236 @T6G_MB_LIB.T6G(SCH_1):PAGE96

M_L_CPU0_SB_DQS_DN<1> @T6G_MB_LIB.T6G(SCH_1):M_L_CPU0_SB_DQS_DN(1)
   U25  CL9 MLB_DQS_L1 GENOA_SP5-SOCKET6096_13568-001,SMLF,IO,DGA^6000030   I159 @T6G_MB_LIB.T6G(SCH_1):PAGE21
   J67  116 DQS1_B_C SCONN288_DDR506112002KQ-SCONN288_DDR506112002KQ,SMA   I236 @T6G_MB_LIB.T6G(SCH_1):PAGE96

M_L_CPU0_SB_DQS_DN<2> @T6G_MB_LIB.T6G(SCH_1):M_L_CPU0_SB_DQS_DN(2)
   U25  CU9 MLB_DQS_L2 GENOA_SP5-SOCKET6096_13568-001,SMLF,IO,DGA^6000030   I159 @T6G_MB_LIB.T6G(SCH_1):PAGE21
   J67  127 DQS2_B_C SCONN288_DDR506112002KQ-SCONN288_DDR506112002KQ,SMA   I236 @T6G_MB_LIB.T6G(SCH_1):PAGE96

M_L_CPU0_SB_DQS_DN<3> @T6G_MB_LIB.T6G(SCH_1):M_L_CPU0_SB_DQS_DN(3)
   U25  DC9 MLB_DQS_L3 GENOA_SP5-SOCKET6096_13568-001,SMLF,IO,DGA^6000030   I159 @T6G_MB_LIB.T6G(SCH_1):PAGE21
   J67  138 DQS3_B_C SCONN288_DDR506112002KQ-SCONN288_DDR506112002KQ,SMA   I236 @T6G_MB_LIB.T6G(SCH_1):PAGE96

M_L_CPU0_SB_DQS_DN<4> @T6G_MB_LIB.T6G(SCH_1):M_L_CPU0_SB_DQS_DN(4)
   U25 BW10 MLB_DQS_L4 GENOA_SP5-SOCKET6096_13568-001,SMLF,IO,DGA^6000030   I159 @T6G_MB_LIB.T6G(SCH_1):PAGE21
   J67  238 DQS4_B_C SCONN288_DDR506112002KQ-SCONN288_DDR506112002KQ,SMA   I236 @T6G_MB_LIB.T6G(SCH_1):PAGE96

M_L_CPU0_SB_DQS_DN<5> @T6G_MB_LIB.T6G(SCH_1):M_L_CPU0_SB_DQS_DN(5)
   U25 CE10 MLB_DQS_L5 GENOA_SP5-SOCKET6096_13568-001,SMLF,IO,DGA^6000030   I159 @T6G_MB_LIB.T6G(SCH_1):PAGE21
   J67  249 DQS5_B_C||TDQS5_B_C SCONN288_DDR506112002KQ-SCONN288_DDR506112002KQ,SMA   I236 @T6G_MB_LIB.T6G(SCH_1):PAGE96

M_L_CPU0_SB_DQS_DN<6> @T6G_MB_LIB.T6G(SCH_1):M_L_CPU0_SB_DQS_DN(6)
   U25 CL10 MLB_DQS_L6 GENOA_SP5-SOCKET6096_13568-001,SMLF,IO,DGA^6000030   I159 @T6G_MB_LIB.T6G(SCH_1):PAGE21
   J67  260 DQS6_B_C||TDQS6_B_C SCONN288_DDR506112002KQ-SCONN288_DDR506112002KQ,SMA   I236 @T6G_MB_LIB.T6G(SCH_1):PAGE96

M_L_CPU0_SB_DQS_DN<7> @T6G_MB_LIB.T6G(SCH_1):M_L_CPU0_SB_DQS_DN(7)
   U25 CU10 MLB_DQS_L7 GENOA_SP5-SOCKET6096_13568-001,SMLF,IO,DGA^6000030   I159 @T6G_MB_LIB.T6G(SCH_1):PAGE21
   J67  271 DQS7_B_C||TDQS7_B_C SCONN288_DDR506112002KQ-SCONN288_DDR506112002KQ,SMA   I236 @T6G_MB_LIB.T6G(SCH_1):PAGE96

M_L_CPU0_SB_DQS_DN<8> @T6G_MB_LIB.T6G(SCH_1):M_L_CPU0_SB_DQS_DN(8)
   U25 DC10 MLB_DQS_L8 GENOA_SP5-SOCKET6096_13568-001,SMLF,IO,DGA^6000030   I159 @T6G_MB_LIB.T6G(SCH_1):PAGE21
   J67  282 DQS8_B_C||TDQS8_B_C SCONN288_DDR506112002KQ-SCONN288_DDR506112002KQ,SMA   I236 @T6G_MB_LIB.T6G(SCH_1):PAGE96

M_L_CPU0_SB_DQS_DN<9> @T6G_MB_LIB.T6G(SCH_1):M_L_CPU0_SB_DQS_DN(9)
   U25  BW9 MLB_DQS_L9 GENOA_SP5-SOCKET6096_13568-001,SMLF,IO,DGA^6000030   I159 @T6G_MB_LIB.T6G(SCH_1):PAGE21
   J67   94 DQS9_B_C||TDQS9_B_C SCONN288_DDR506112002KQ-SCONN288_DDR506112002KQ,SMA   I236 @T6G_MB_LIB.T6G(SCH_1):PAGE96

M_L_CPU0_SB_DQS_DP<0> @T6G_MB_LIB.T6G(SCH_1):M_L_CPU0_SB_DQS_DP(0)
   U25  CD9 MLB_DQS_H0 GENOA_SP5-SOCKET6096_13568-001,SMLF,IO,DGA^6000030   I159 @T6G_MB_LIB.T6G(SCH_1):PAGE21
   J67  104 DQS0_B_T SCONN288_DDR506112002KQ-SCONN288_DDR506112002KQ,SMA   I236 @T6G_MB_LIB.T6G(SCH_1):PAGE96

M_L_CPU0_SB_DQS_DP<1> @T6G_MB_LIB.T6G(SCH_1):M_L_CPU0_SB_DQS_DP(1)
   U25  CK9 MLB_DQS_H1 GENOA_SP5-SOCKET6096_13568-001,SMLF,IO,DGA^6000030   I159 @T6G_MB_LIB.T6G(SCH_1):PAGE21
   J67  115 DQS1_B_T SCONN288_DDR506112002KQ-SCONN288_DDR506112002KQ,SMA   I236 @T6G_MB_LIB.T6G(SCH_1):PAGE96

M_L_CPU0_SB_DQS_DP<2> @T6G_MB_LIB.T6G(SCH_1):M_L_CPU0_SB_DQS_DP(2)
   U25  CT9 MLB_DQS_H2 GENOA_SP5-SOCKET6096_13568-001,SMLF,IO,DGA^6000030   I159 @T6G_MB_LIB.T6G(SCH_1):PAGE21
   J67  126 DQS2_B_T SCONN288_DDR506112002KQ-SCONN288_DDR506112002KQ,SMA   I236 @T6G_MB_LIB.T6G(SCH_1):PAGE96

M_L_CPU0_SB_DQS_DP<3> @T6G_MB_LIB.T6G(SCH_1):M_L_CPU0_SB_DQS_DP(3)
   U25  DB9 MLB_DQS_H3 GENOA_SP5-SOCKET6096_13568-001,SMLF,IO,DGA^6000030   I159 @T6G_MB_LIB.T6G(SCH_1):PAGE21
   J67  137 DQS3_B_T SCONN288_DDR506112002KQ-SCONN288_DDR506112002KQ,SMA   I236 @T6G_MB_LIB.T6G(SCH_1):PAGE96

M_L_CPU0_SB_DQS_DP<4> @T6G_MB_LIB.T6G(SCH_1):M_L_CPU0_SB_DQS_DP(4)
   U25 BY11 MLB_DQS_H4 GENOA_SP5-SOCKET6096_13568-001,SMLF,IO,DGA^6000030   I159 @T6G_MB_LIB.T6G(SCH_1):PAGE21
   J67  239 DQS4_B_T SCONN288_DDR506112002KQ-SCONN288_DDR506112002KQ,SMA   I236 @T6G_MB_LIB.T6G(SCH_1):PAGE96

M_L_CPU0_SB_DQS_DP<5> @T6G_MB_LIB.T6G(SCH_1):M_L_CPU0_SB_DQS_DP(5)
   U25 CF11 MLB_DQS_H5 GENOA_SP5-SOCKET6096_13568-001,SMLF,IO,DGA^6000030   I159 @T6G_MB_LIB.T6G(SCH_1):PAGE21
   J67  250 DQS5_B_T||TDQS5_B_T SCONN288_DDR506112002KQ-SCONN288_DDR506112002KQ,SMA   I236 @T6G_MB_LIB.T6G(SCH_1):PAGE96

M_L_CPU0_SB_DQS_DP<6> @T6G_MB_LIB.T6G(SCH_1):M_L_CPU0_SB_DQS_DP(6)
   U25 CM11 MLB_DQS_H6 GENOA_SP5-SOCKET6096_13568-001,SMLF,IO,DGA^6000030   I159 @T6G_MB_LIB.T6G(SCH_1):PAGE21
   J67  261 DQS6_B_T||TDQS6_B_T SCONN288_DDR506112002KQ-SCONN288_DDR506112002KQ,SMA   I236 @T6G_MB_LIB.T6G(SCH_1):PAGE96

M_L_CPU0_SB_DQS_DP<7> @T6G_MB_LIB.T6G(SCH_1):M_L_CPU0_SB_DQS_DP(7)
   U25 CV11 MLB_DQS_H7 GENOA_SP5-SOCKET6096_13568-001,SMLF,IO,DGA^6000030   I159 @T6G_MB_LIB.T6G(SCH_1):PAGE21
   J67  272 DQS7_B_T||TDQS7_B_T SCONN288_DDR506112002KQ-SCONN288_DDR506112002KQ,SMA   I236 @T6G_MB_LIB.T6G(SCH_1):PAGE96

M_L_CPU0_SB_DQS_DP<8> @T6G_MB_LIB.T6G(SCH_1):M_L_CPU0_SB_DQS_DP(8)
   U25 DD11 MLB_DQS_H8 GENOA_SP5-SOCKET6096_13568-001,SMLF,IO,DGA^6000030   I159 @T6G_MB_LIB.T6G(SCH_1):PAGE21
   J67  283 DQS8_B_T||TDQS8_B_T SCONN288_DDR506112002KQ-SCONN288_DDR506112002KQ,SMA   I236 @T6G_MB_LIB.T6G(SCH_1):PAGE96

M_L_CPU0_SB_DQS_DP<9> @T6G_MB_LIB.T6G(SCH_1):M_L_CPU0_SB_DQS_DP(9)
   U25  BV9 MLB_DQS_H9 GENOA_SP5-SOCKET6096_13568-001,SMLF,IO,DGA^6000030   I159 @T6G_MB_LIB.T6G(SCH_1):PAGE21
   J67   93 DQS9_B_T||TDQS9_B_T||DBI4_B_N SCONN288_DDR506112002KQ-SCONN288_DDR506112002KQ,SMA   I236 @T6G_MB_LIB.T6G(SCH_1):PAGE96

M_L_CPU0_SB_PAR @T6G_MB_LIB.T6G(SCH_1):M_L_CPU0_SB_PAR
   U25 BL10 MLB_PAR GENOA_SP5-SOCKET6096_13568-001,SMLF,IO,DGA^6000030   I159 @T6G_MB_LIB.T6G(SCH_1):PAGE21
   J67  227  PAR_B SCONN288_DDR506112002KQ-SCONN288_DDR506112002KQ,SMA    I22 @T6G_MB_LIB.T6G(SCH_1):PAGE96

M_L_CPU0_SB_RSP<0> @T6G_MB_LIB.T6G(SCH_1):M_L_CPU0_SB_RSP(0)
   U25  BP9 MLB0_RSP_L GENOA_SP5-SOCKET6096_13568-001,SMLF,IO,DGA^6000030   I159 @T6G_MB_LIB.T6G(SCH_1):PAGE21
   J67   87 LBS||RSP_B_N SCONN288_DDR506112002KQ-SCONN288_DDR506112002KQ,SMA    I22 @T6G_MB_LIB.T6G(SCH_1):PAGE96

M_L_CPU1_ALERT_N @T6G_MB_LIB.T6G(SCH_1):M_L_CPU1_ALERT_N
  R511    1      A Q_RES_0402LF-15,1%,1/16W,CHIP,CS01502FB03   I313 @T6G_MB_LIB.T6G(SCH_1):PAGE48
   J37   62 ALERT_N SCONN288_DDR506112002KQ-SCONN288_DDR506112002KQ,SMA    I22 @T6G_MB_LIB.T6G(SCH_1):PAGE108

M_L_CPU1_ALERT_R_N @T6G_MB_LIB.T6G(SCH_1):M_L_CPU1_ALERT_R_N
   U26 AT11 ML_ALERT_L GENOA_SP5-SOCKET6096_13568-001,SMLF,IO,DGA^6000030   I159 @T6G_MB_LIB.T6G(SCH_1):PAGE48
  R511    2      B Q_RES_0402LF-15,1%,1/16W,CHIP,CS01502FB03   I313 @T6G_MB_LIB.T6G(SCH_1):PAGE48

M_L_CPU1_CLK_DN<0> @T6G_MB_LIB.T6G(SCH_1):M_L_CPU1_CLK_DN(0)
   U26  BD9 ML0_CLK_L GENOA_SP5-SOCKET6096_13568-001,SMLF,IO,DGA^6000030   I159 @T6G_MB_LIB.T6G(SCH_1):PAGE48
   J37  218   CK_C SCONN288_DDR506112002KQ-SCONN288_DDR506112002KQ,SMA    I22 @T6G_MB_LIB.T6G(SCH_1):PAGE108

M_L_CPU1_CLK_DP<0> @T6G_MB_LIB.T6G(SCH_1):M_L_CPU1_CLK_DP(0)
   U26  BC9 ML0_CLK_H GENOA_SP5-SOCKET6096_13568-001,SMLF,IO,DGA^6000030   I159 @T6G_MB_LIB.T6G(SCH_1):PAGE48
   J37  217   CK_T SCONN288_DDR506112002KQ-SCONN288_DDR506112002KQ,SMA    I22 @T6G_MB_LIB.T6G(SCH_1):PAGE108

M_L_CPU1_RESET_N @T6G_MB_LIB.T6G(SCH_1):M_L_CPU1_RESET_N
   U26 AU10 ML_RESET_L GENOA_SP5-SOCKET6096_13568-001,SMLF,IO,DGA^6000030   I159 @T6G_MB_LIB.T6G(SCH_1):PAGE48
   J37  207 RESET_N SCONN288_DDR506112002KQ-SCONN288_DDR506112002KQ,SMA    I22 @T6G_MB_LIB.T6G(SCH_1):PAGE108

M_L_CPU1_SA_CA<0> @T6G_MB_LIB.T6G(SCH_1):M_L_CPU1_SA_CA(0)
   U26  AW9 MLA_CA0 GENOA_SP5-SOCKET6096_13568-001,SMLF,IO,DGA^6000030   I159 @T6G_MB_LIB.T6G(SCH_1):PAGE48
   J37   66  CA0_A SCONN288_DDR506112002KQ-SCONN288_DDR506112002KQ,SMA    I22 @T6G_MB_LIB.T6G(SCH_1):PAGE108

M_L_CPU1_SA_CA<1> @T6G_MB_LIB.T6G(SCH_1):M_L_CPU1_SA_CA(1)
   U26  AY9 MLA_CA1 GENOA_SP5-SOCKET6096_13568-001,SMLF,IO,DGA^6000030   I159 @T6G_MB_LIB.T6G(SCH_1):PAGE48
   J37  211  CA1_A SCONN288_DDR506112002KQ-SCONN288_DDR506112002KQ,SMA    I22 @T6G_MB_LIB.T6G(SCH_1):PAGE108

M_L_CPU1_SA_CA<2> @T6G_MB_LIB.T6G(SCH_1):M_L_CPU1_SA_CA(2)
   U26 AY11 MLA_CA2 GENOA_SP5-SOCKET6096_13568-001,SMLF,IO,DGA^6000030   I159 @T6G_MB_LIB.T6G(SCH_1):PAGE48
   J37   68  CA2_A SCONN288_DDR506112002KQ-SCONN288_DDR506112002KQ,SMA    I22 @T6G_MB_LIB.T6G(SCH_1):PAGE108

M_L_CPU1_SA_CA<3> @T6G_MB_LIB.T6G(SCH_1):M_L_CPU1_SA_CA(3)
   U26 BA10 MLA_CA3 GENOA_SP5-SOCKET6096_13568-001,SMLF,IO,DGA^6000030   I159 @T6G_MB_LIB.T6G(SCH_1):PAGE48
   J37  213  CA3_A SCONN288_DDR506112002KQ-SCONN288_DDR506112002KQ,SMA    I22 @T6G_MB_LIB.T6G(SCH_1):PAGE108

M_L_CPU1_SA_CA<4> @T6G_MB_LIB.T6G(SCH_1):M_L_CPU1_SA_CA(4)
   U26  BA9 MLA_CA4 GENOA_SP5-SOCKET6096_13568-001,SMLF,IO,DGA^6000030   I159 @T6G_MB_LIB.T6G(SCH_1):PAGE48
   J37   70  CA4_A SCONN288_DDR506112002KQ-SCONN288_DDR506112002KQ,SMA    I22 @T6G_MB_LIB.T6G(SCH_1):PAGE108

M_L_CPU1_SA_CA<5> @T6G_MB_LIB.T6G(SCH_1):M_L_CPU1_SA_CA(5)
   U26  BB9 MLA_CA5 GENOA_SP5-SOCKET6096_13568-001,SMLF,IO,DGA^6000030   I159 @T6G_MB_LIB.T6G(SCH_1):PAGE48
   J37  215  CA5_A SCONN288_DDR506112002KQ-SCONN288_DDR506112002KQ,SMA    I22 @T6G_MB_LIB.T6G(SCH_1):PAGE108

M_L_CPU1_SA_CA<6> @T6G_MB_LIB.T6G(SCH_1):M_L_CPU1_SA_CA(6)
   U26 BB11 MLA_CA6 GENOA_SP5-SOCKET6096_13568-001,SMLF,IO,DGA^6000030   I159 @T6G_MB_LIB.T6G(SCH_1):PAGE48
   J37   72  CA6_A SCONN288_DDR506112002KQ-SCONN288_DDR506112002KQ,SMA    I22 @T6G_MB_LIB.T6G(SCH_1):PAGE108

M_L_CPU1_SA_CB<0> @T6G_MB_LIB.T6G(SCH_1):M_L_CPU1_SA_CB(0)
   U26  AJ9 MLA_CHECK0 GENOA_SP5-SOCKET6096_13568-001,SMLF,IO,DGA^6000030   I159 @T6G_MB_LIB.T6G(SCH_1):PAGE48
   J37   51  CB0_A SCONN288_DDR506112002KQ-SCONN288_DDR506112002KQ,SMA    I22 @T6G_MB_LIB.T6G(SCH_1):PAGE108

M_L_CPU1_SA_CB<1> @T6G_MB_LIB.T6G(SCH_1):M_L_CPU1_SA_CB(1)
   U26 AK11 MLA_CHECK1 GENOA_SP5-SOCKET6096_13568-001,SMLF,IO,DGA^6000030   I159 @T6G_MB_LIB.T6G(SCH_1):PAGE48
   J37   53  CB1_A SCONN288_DDR506112002KQ-SCONN288_DDR506112002KQ,SMA    I22 @T6G_MB_LIB.T6G(SCH_1):PAGE108

M_L_CPU1_SA_CB<2> @T6G_MB_LIB.T6G(SCH_1):M_L_CPU1_SA_CB(2)
   U26  AK9 MLA_CHECK2 GENOA_SP5-SOCKET6096_13568-001,SMLF,IO,DGA^6000030   I159 @T6G_MB_LIB.T6G(SCH_1):PAGE48
   J37  196  CB2_A SCONN288_DDR506112002KQ-SCONN288_DDR506112002KQ,SMA    I22 @T6G_MB_LIB.T6G(SCH_1):PAGE108

M_L_CPU1_SA_CB<3> @T6G_MB_LIB.T6G(SCH_1):M_L_CPU1_SA_CB(3)
   U26 AL10 MLA_CHECK3 GENOA_SP5-SOCKET6096_13568-001,SMLF,IO,DGA^6000030   I159 @T6G_MB_LIB.T6G(SCH_1):PAGE48
   J37  198  CB3_A SCONN288_DDR506112002KQ-SCONN288_DDR506112002KQ,SMA    I22 @T6G_MB_LIB.T6G(SCH_1):PAGE108

M_L_CPU1_SA_CB<4> @T6G_MB_LIB.T6G(SCH_1):M_L_CPU1_SA_CB(4)
   U26  AN9 MLA_CHECK4 GENOA_SP5-SOCKET6096_13568-001,SMLF,IO,DGA^6000030   I159 @T6G_MB_LIB.T6G(SCH_1):PAGE48
   J37   58  CB4_A SCONN288_DDR506112002KQ-SCONN288_DDR506112002KQ,SMA    I22 @T6G_MB_LIB.T6G(SCH_1):PAGE108

M_L_CPU1_SA_CB<5> @T6G_MB_LIB.T6G(SCH_1):M_L_CPU1_SA_CB(5)
   U26 AP11 MLA_CHECK5 GENOA_SP5-SOCKET6096_13568-001,SMLF,IO,DGA^6000030   I159 @T6G_MB_LIB.T6G(SCH_1):PAGE48
   J37   60  CB5_A SCONN288_DDR506112002KQ-SCONN288_DDR506112002KQ,SMA    I22 @T6G_MB_LIB.T6G(SCH_1):PAGE108

M_L_CPU1_SA_CB<6> @T6G_MB_LIB.T6G(SCH_1):M_L_CPU1_SA_CB(6)
   U26  AP9 MLA_CHECK6 GENOA_SP5-SOCKET6096_13568-001,SMLF,IO,DGA^6000030   I159 @T6G_MB_LIB.T6G(SCH_1):PAGE48
   J37  203  CB6_A SCONN288_DDR506112002KQ-SCONN288_DDR506112002KQ,SMA    I22 @T6G_MB_LIB.T6G(SCH_1):PAGE108

M_L_CPU1_SA_CB<7> @T6G_MB_LIB.T6G(SCH_1):M_L_CPU1_SA_CB(7)
   U26 AR10 MLA_CHECK7 GENOA_SP5-SOCKET6096_13568-001,SMLF,IO,DGA^6000030   I159 @T6G_MB_LIB.T6G(SCH_1):PAGE48
   J37  205  CB7_A SCONN288_DDR506112002KQ-SCONN288_DDR506112002KQ,SMA    I22 @T6G_MB_LIB.T6G(SCH_1):PAGE108

M_L_CPU1_SA_CS_N<0> @T6G_MB_LIB.T6G(SCH_1):M_L_CPU1_SA_CS_N(0)
   U26  AU9 MLA0_CS_L0 GENOA_SP5-SOCKET6096_13568-001,SMLF,IO,DGA^6000030   I159 @T6G_MB_LIB.T6G(SCH_1):PAGE48
   J37   64 CS0_A_N SCONN288_DDR506112002KQ-SCONN288_DDR506112002KQ,SMA    I22 @T6G_MB_LIB.T6G(SCH_1):PAGE108

M_L_CPU1_SA_CS_N<1> @T6G_MB_LIB.T6G(SCH_1):M_L_CPU1_SA_CS_N(1)
   U26 AV11 MLA0_CS_L1 GENOA_SP5-SOCKET6096_13568-001,SMLF,IO,DGA^6000030   I159 @T6G_MB_LIB.T6G(SCH_1):PAGE48
   J37  209 CS1_A_N SCONN288_DDR506112002KQ-SCONN288_DDR506112002KQ,SMA    I22 @T6G_MB_LIB.T6G(SCH_1):PAGE108

M_L_CPU1_SA_DQ<0> @T6G_MB_LIB.T6G(SCH_1):M_L_CPU1_SA_DQ(0)
   U26   E9 MLA_DATA0 GENOA_SP5-SOCKET6096_13568-001,SMLF,IO,DGA^6000030   I159 @T6G_MB_LIB.T6G(SCH_1):PAGE48
   J37    7  DQ0_A SCONN288_DDR506112002KQ-SCONN288_DDR506112002KQ,SMA    I22 @T6G_MB_LIB.T6G(SCH_1):PAGE108

M_L_CPU1_SA_DQ<10> @T6G_MB_LIB.T6G(SCH_1):M_L_CPU1_SA_DQ(10)
   U26   M9 MLA_DATA10 GENOA_SP5-SOCKET6096_13568-001,SMLF,IO,DGA^6000030   I159 @T6G_MB_LIB.T6G(SCH_1):PAGE48
   J37  163 DQ10_A SCONN288_DDR506112002KQ-SCONN288_DDR506112002KQ,SMA    I22 @T6G_MB_LIB.T6G(SCH_1):PAGE108

M_L_CPU1_SA_DQ<11> @T6G_MB_LIB.T6G(SCH_1):M_L_CPU1_SA_DQ(11)
   U26  N10 MLA_DATA11 GENOA_SP5-SOCKET6096_13568-001,SMLF,IO,DGA^6000030   I159 @T6G_MB_LIB.T6G(SCH_1):PAGE48
   J37  165 DQ11_A SCONN288_DDR506112002KQ-SCONN288_DDR506112002KQ,SMA    I22 @T6G_MB_LIB.T6G(SCH_1):PAGE108

M_L_CPU1_SA_DQ<12> @T6G_MB_LIB.T6G(SCH_1):M_L_CPU1_SA_DQ(12)
   U26   R9 MLA_DATA12 GENOA_SP5-SOCKET6096_13568-001,SMLF,IO,DGA^6000030   I159 @T6G_MB_LIB.T6G(SCH_1):PAGE48
   J37   25 DQ12_A SCONN288_DDR506112002KQ-SCONN288_DDR506112002KQ,SMA    I22 @T6G_MB_LIB.T6G(SCH_1):PAGE108

M_L_CPU1_SA_DQ<13> @T6G_MB_LIB.T6G(SCH_1):M_L_CPU1_SA_DQ(13)
   U26  T11 MLA_DATA13 GENOA_SP5-SOCKET6096_13568-001,SMLF,IO,DGA^6000030   I159 @T6G_MB_LIB.T6G(SCH_1):PAGE48
   J37   27 DQ13_A SCONN288_DDR506112002KQ-SCONN288_DDR506112002KQ,SMA    I22 @T6G_MB_LIB.T6G(SCH_1):PAGE108

M_L_CPU1_SA_DQ<14> @T6G_MB_LIB.T6G(SCH_1):M_L_CPU1_SA_DQ(14)
   U26   T9 MLA_DATA14 GENOA_SP5-SOCKET6096_13568-001,SMLF,IO,DGA^6000030   I159 @T6G_MB_LIB.T6G(SCH_1):PAGE48
   J37  170 DQ14_A SCONN288_DDR506112002KQ-SCONN288_DDR506112002KQ,SMA    I22 @T6G_MB_LIB.T6G(SCH_1):PAGE108

M_L_CPU1_SA_DQ<15> @T6G_MB_LIB.T6G(SCH_1):M_L_CPU1_SA_DQ(15)
   U26  U10 MLA_DATA15 GENOA_SP5-SOCKET6096_13568-001,SMLF,IO,DGA^6000030   I159 @T6G_MB_LIB.T6G(SCH_1):PAGE48
   J37  172 DQ15_A SCONN288_DDR506112002KQ-SCONN288_DDR506112002KQ,SMA    I22 @T6G_MB_LIB.T6G(SCH_1):PAGE108

M_L_CPU1_SA_DQ<16> @T6G_MB_LIB.T6G(SCH_1):M_L_CPU1_SA_DQ(16)
   U26   U9 MLA_DATA16 GENOA_SP5-SOCKET6096_13568-001,SMLF,IO,DGA^6000030   I159 @T6G_MB_LIB.T6G(SCH_1):PAGE48
   J37   29 DQ16_A SCONN288_DDR506112002KQ-SCONN288_DDR506112002KQ,SMA    I22 @T6G_MB_LIB.T6G(SCH_1):PAGE108

M_L_CPU1_SA_DQ<17> @T6G_MB_LIB.T6G(SCH_1):M_L_CPU1_SA_DQ(17)
   U26  V11 MLA_DATA17 GENOA_SP5-SOCKET6096_13568-001,SMLF,IO,DGA^6000030   I159 @T6G_MB_LIB.T6G(SCH_1):PAGE48
   J37   31 DQ17_A SCONN288_DDR506112002KQ-SCONN288_DDR506112002KQ,SMA    I22 @T6G_MB_LIB.T6G(SCH_1):PAGE108

M_L_CPU1_SA_DQ<18> @T6G_MB_LIB.T6G(SCH_1):M_L_CPU1_SA_DQ(18)
   U26   V9 MLA_DATA18 GENOA_SP5-SOCKET6096_13568-001,SMLF,IO,DGA^6000030   I159 @T6G_MB_LIB.T6G(SCH_1):PAGE48
   J37  174 DQ18_A SCONN288_DDR506112002KQ-SCONN288_DDR506112002KQ,SMA    I22 @T6G_MB_LIB.T6G(SCH_1):PAGE108

M_L_CPU1_SA_DQ<19> @T6G_MB_LIB.T6G(SCH_1):M_L_CPU1_SA_DQ(19)
   U26  W10 MLA_DATA19 GENOA_SP5-SOCKET6096_13568-001,SMLF,IO,DGA^6000030   I159 @T6G_MB_LIB.T6G(SCH_1):PAGE48
   J37  176 DQ19_A SCONN288_DDR506112002KQ-SCONN288_DDR506112002KQ,SMA    I22 @T6G_MB_LIB.T6G(SCH_1):PAGE108

M_L_CPU1_SA_DQ<1> @T6G_MB_LIB.T6G(SCH_1):M_L_CPU1_SA_DQ(1)
   U26  F11 MLA_DATA1 GENOA_SP5-SOCKET6096_13568-001,SMLF,IO,DGA^6000030   I159 @T6G_MB_LIB.T6G(SCH_1):PAGE48
   J37    9  DQ1_A SCONN288_DDR506112002KQ-SCONN288_DDR506112002KQ,SMA    I22 @T6G_MB_LIB.T6G(SCH_1):PAGE108

M_L_CPU1_SA_DQ<20> @T6G_MB_LIB.T6G(SCH_1):M_L_CPU1_SA_DQ(20)
   U26  AA9 MLA_DATA20 GENOA_SP5-SOCKET6096_13568-001,SMLF,IO,DGA^6000030   I159 @T6G_MB_LIB.T6G(SCH_1):PAGE48
   J37   36 DQ20_A SCONN288_DDR506112002KQ-SCONN288_DDR506112002KQ,SMA    I22 @T6G_MB_LIB.T6G(SCH_1):PAGE108

M_L_CPU1_SA_DQ<21> @T6G_MB_LIB.T6G(SCH_1):M_L_CPU1_SA_DQ(21)
   U26 AB11 MLA_DATA21 GENOA_SP5-SOCKET6096_13568-001,SMLF,IO,DGA^6000030   I159 @T6G_MB_LIB.T6G(SCH_1):PAGE48
   J37   38 DQ21_A SCONN288_DDR506112002KQ-SCONN288_DDR506112002KQ,SMA    I22 @T6G_MB_LIB.T6G(SCH_1):PAGE108

M_L_CPU1_SA_DQ<22> @T6G_MB_LIB.T6G(SCH_1):M_L_CPU1_SA_DQ(22)
   U26  AB9 MLA_DATA22 GENOA_SP5-SOCKET6096_13568-001,SMLF,IO,DGA^6000030   I159 @T6G_MB_LIB.T6G(SCH_1):PAGE48
   J37  181 DQ22_A SCONN288_DDR506112002KQ-SCONN288_DDR506112002KQ,SMA    I22 @T6G_MB_LIB.T6G(SCH_1):PAGE108

M_L_CPU1_SA_DQ<23> @T6G_MB_LIB.T6G(SCH_1):M_L_CPU1_SA_DQ(23)
   U26 AC10 MLA_DATA23 GENOA_SP5-SOCKET6096_13568-001,SMLF,IO,DGA^6000030   I159 @T6G_MB_LIB.T6G(SCH_1):PAGE48
   J37  183 DQ23_A SCONN288_DDR506112002KQ-SCONN288_DDR506112002KQ,SMA    I22 @T6G_MB_LIB.T6G(SCH_1):PAGE108

M_L_CPU1_SA_DQ<24> @T6G_MB_LIB.T6G(SCH_1):M_L_CPU1_SA_DQ(24)
   U26  AC9 MLA_DATA24 GENOA_SP5-SOCKET6096_13568-001,SMLF,IO,DGA^6000030   I159 @T6G_MB_LIB.T6G(SCH_1):PAGE48
   J37   40 DQ24_A SCONN288_DDR506112002KQ-SCONN288_DDR506112002KQ,SMA    I22 @T6G_MB_LIB.T6G(SCH_1):PAGE108

M_L_CPU1_SA_DQ<25> @T6G_MB_LIB.T6G(SCH_1):M_L_CPU1_SA_DQ(25)
   U26 AD11 MLA_DATA25 GENOA_SP5-SOCKET6096_13568-001,SMLF,IO,DGA^6000030   I159 @T6G_MB_LIB.T6G(SCH_1):PAGE48
   J37   42 DQ25_A SCONN288_DDR506112002KQ-SCONN288_DDR506112002KQ,SMA    I22 @T6G_MB_LIB.T6G(SCH_1):PAGE108

M_L_CPU1_SA_DQ<26> @T6G_MB_LIB.T6G(SCH_1):M_L_CPU1_SA_DQ(26)
   U26  AD9 MLA_DATA26 GENOA_SP5-SOCKET6096_13568-001,SMLF,IO,DGA^6000030   I159 @T6G_MB_LIB.T6G(SCH_1):PAGE48
   J37  185 DQ26_A SCONN288_DDR506112002KQ-SCONN288_DDR506112002KQ,SMA    I22 @T6G_MB_LIB.T6G(SCH_1):PAGE108

M_L_CPU1_SA_DQ<27> @T6G_MB_LIB.T6G(SCH_1):M_L_CPU1_SA_DQ(27)
   U26 AE10 MLA_DATA27 GENOA_SP5-SOCKET6096_13568-001,SMLF,IO,DGA^6000030   I159 @T6G_MB_LIB.T6G(SCH_1):PAGE48
   J37  187 DQ27_A SCONN288_DDR506112002KQ-SCONN288_DDR506112002KQ,SMA    I22 @T6G_MB_LIB.T6G(SCH_1):PAGE108

M_L_CPU1_SA_DQ<28> @T6G_MB_LIB.T6G(SCH_1):M_L_CPU1_SA_DQ(28)
   U26  AG9 MLA_DATA28 GENOA_SP5-SOCKET6096_13568-001,SMLF,IO,DGA^6000030   I159 @T6G_MB_LIB.T6G(SCH_1):PAGE48
   J37   47 DQ28_A SCONN288_DDR506112002KQ-SCONN288_DDR506112002KQ,SMA    I22 @T6G_MB_LIB.T6G(SCH_1):PAGE108

M_L_CPU1_SA_DQ<29> @T6G_MB_LIB.T6G(SCH_1):M_L_CPU1_SA_DQ(29)
   U26 AH11 MLA_DATA29 GENOA_SP5-SOCKET6096_13568-001,SMLF,IO,DGA^6000030   I159 @T6G_MB_LIB.T6G(SCH_1):PAGE48
   J37   49 DQ29_A SCONN288_DDR506112002KQ-SCONN288_DDR506112002KQ,SMA    I22 @T6G_MB_LIB.T6G(SCH_1):PAGE108

M_L_CPU1_SA_DQ<2> @T6G_MB_LIB.T6G(SCH_1):M_L_CPU1_SA_DQ(2)
   U26   F9 MLA_DATA2 GENOA_SP5-SOCKET6096_13568-001,SMLF,IO,DGA^6000030   I159 @T6G_MB_LIB.T6G(SCH_1):PAGE48
   J37  152  DQ2_A SCONN288_DDR506112002KQ-SCONN288_DDR506112002KQ,SMA    I22 @T6G_MB_LIB.T6G(SCH_1):PAGE108

M_L_CPU1_SA_DQ<30> @T6G_MB_LIB.T6G(SCH_1):M_L_CPU1_SA_DQ(30)
   U26  AH9 MLA_DATA30 GENOA_SP5-SOCKET6096_13568-001,SMLF,IO,DGA^6000030   I159 @T6G_MB_LIB.T6G(SCH_1):PAGE48
   J37  192 DQ30_A SCONN288_DDR506112002KQ-SCONN288_DDR506112002KQ,SMA    I22 @T6G_MB_LIB.T6G(SCH_1):PAGE108

M_L_CPU1_SA_DQ<31> @T6G_MB_LIB.T6G(SCH_1):M_L_CPU1_SA_DQ(31)
   U26 AJ10 MLA_DATA31 GENOA_SP5-SOCKET6096_13568-001,SMLF,IO,DGA^6000030   I159 @T6G_MB_LIB.T6G(SCH_1):PAGE48
   J37  194 DQ31_A SCONN288_DDR506112002KQ-SCONN288_DDR506112002KQ,SMA    I22 @T6G_MB_LIB.T6G(SCH_1):PAGE108

M_L_CPU1_SA_DQ<3> @T6G_MB_LIB.T6G(SCH_1):M_L_CPU1_SA_DQ(3)
   U26  G10 MLA_DATA3 GENOA_SP5-SOCKET6096_13568-001,SMLF,IO,DGA^6000030   I159 @T6G_MB_LIB.T6G(SCH_1):PAGE48
   J37  154  DQ3_A SCONN288_DDR506112002KQ-SCONN288_DDR506112002KQ,SMA    I22 @T6G_MB_LIB.T6G(SCH_1):PAGE108

M_L_CPU1_SA_DQ<4> @T6G_MB_LIB.T6G(SCH_1):M_L_CPU1_SA_DQ(4)
   U26   J9 MLA_DATA4 GENOA_SP5-SOCKET6096_13568-001,SMLF,IO,DGA^6000030   I159 @T6G_MB_LIB.T6G(SCH_1):PAGE48
   J37   14  DQ4_A SCONN288_DDR506112002KQ-SCONN288_DDR506112002KQ,SMA    I22 @T6G_MB_LIB.T6G(SCH_1):PAGE108

M_L_CPU1_SA_DQ<5> @T6G_MB_LIB.T6G(SCH_1):M_L_CPU1_SA_DQ(5)
   U26  K11 MLA_DATA5 GENOA_SP5-SOCKET6096_13568-001,SMLF,IO,DGA^6000030   I159 @T6G_MB_LIB.T6G(SCH_1):PAGE48
   J37   16  DQ5_A SCONN288_DDR506112002KQ-SCONN288_DDR506112002KQ,SMA    I22 @T6G_MB_LIB.T6G(SCH_1):PAGE108

M_L_CPU1_SA_DQ<6> @T6G_MB_LIB.T6G(SCH_1):M_L_CPU1_SA_DQ(6)
   U26   K9 MLA_DATA6 GENOA_SP5-SOCKET6096_13568-001,SMLF,IO,DGA^6000030   I159 @T6G_MB_LIB.T6G(SCH_1):PAGE48
   J37  159  DQ6_A SCONN288_DDR506112002KQ-SCONN288_DDR506112002KQ,SMA    I22 @T6G_MB_LIB.T6G(SCH_1):PAGE108

M_L_CPU1_SA_DQ<7> @T6G_MB_LIB.T6G(SCH_1):M_L_CPU1_SA_DQ(7)
   U26  L10 MLA_DATA7 GENOA_SP5-SOCKET6096_13568-001,SMLF,IO,DGA^6000030   I159 @T6G_MB_LIB.T6G(SCH_1):PAGE48
   J37  161  DQ7_A SCONN288_DDR506112002KQ-SCONN288_DDR506112002KQ,SMA    I22 @T6G_MB_LIB.T6G(SCH_1):PAGE108

M_L_CPU1_SA_DQ<8> @T6G_MB_LIB.T6G(SCH_1):M_L_CPU1_SA_DQ(8)
   U26   L9 MLA_DATA8 GENOA_SP5-SOCKET6096_13568-001,SMLF,IO,DGA^6000030   I159 @T6G_MB_LIB.T6G(SCH_1):PAGE48
   J37   18  DQ8_A SCONN288_DDR506112002KQ-SCONN288_DDR506112002KQ,SMA    I22 @T6G_MB_LIB.T6G(SCH_1):PAGE108

M_L_CPU1_SA_DQ<9> @T6G_MB_LIB.T6G(SCH_1):M_L_CPU1_SA_DQ(9)
   U26  M11 MLA_DATA9 GENOA_SP5-SOCKET6096_13568-001,SMLF,IO,DGA^6000030   I159 @T6G_MB_LIB.T6G(SCH_1):PAGE48
   J37   20  DQ9_A SCONN288_DDR506112002KQ-SCONN288_DDR506112002KQ,SMA    I22 @T6G_MB_LIB.T6G(SCH_1):PAGE108

M_L_CPU1_SA_DQS_DN<0> @T6G_MB_LIB.T6G(SCH_1):M_L_CPU1_SA_DQS_DN(0)
   U26   H9 MLA_DQS_L0 GENOA_SP5-SOCKET6096_13568-001,SMLF,IO,DGA^6000030   I159 @T6G_MB_LIB.T6G(SCH_1):PAGE48
   J37   12 DQS0_A_C SCONN288_DDR506112002KQ-SCONN288_DDR506112002KQ,SMA   I235 @T6G_MB_LIB.T6G(SCH_1):PAGE108

M_L_CPU1_SA_DQS_DN<1> @T6G_MB_LIB.T6G(SCH_1):M_L_CPU1_SA_DQS_DN(1)
   U26   P9 MLA_DQS_L1 GENOA_SP5-SOCKET6096_13568-001,SMLF,IO,DGA^6000030   I159 @T6G_MB_LIB.T6G(SCH_1):PAGE48
   J37   23 DQS1_A_C SCONN288_DDR506112002KQ-SCONN288_DDR506112002KQ,SMA   I235 @T6G_MB_LIB.T6G(SCH_1):PAGE108

M_L_CPU1_SA_DQS_DN<2> @T6G_MB_LIB.T6G(SCH_1):M_L_CPU1_SA_DQS_DN(2)
   U26   Y9 MLA_DQS_L2 GENOA_SP5-SOCKET6096_13568-001,SMLF,IO,DGA^6000030   I159 @T6G_MB_LIB.T6G(SCH_1):PAGE48
   J37   34 DQS2_A_C SCONN288_DDR506112002KQ-SCONN288_DDR506112002KQ,SMA   I235 @T6G_MB_LIB.T6G(SCH_1):PAGE108

M_L_CPU1_SA_DQS_DN<3> @T6G_MB_LIB.T6G(SCH_1):M_L_CPU1_SA_DQS_DN(3)
   U26  AF9 MLA_DQS_L3 GENOA_SP5-SOCKET6096_13568-001,SMLF,IO,DGA^6000030   I159 @T6G_MB_LIB.T6G(SCH_1):PAGE48
   J37   45 DQS3_A_C SCONN288_DDR506112002KQ-SCONN288_DDR506112002KQ,SMA   I235 @T6G_MB_LIB.T6G(SCH_1):PAGE108

M_L_CPU1_SA_DQS_DN<4> @T6G_MB_LIB.T6G(SCH_1):M_L_CPU1_SA_DQS_DN(4)
   U26  AM9 MLA_DQS_L4 GENOA_SP5-SOCKET6096_13568-001,SMLF,IO,DGA^6000030   I159 @T6G_MB_LIB.T6G(SCH_1):PAGE48
   J37   56 DQS4_A_C SCONN288_DDR506112002KQ-SCONN288_DDR506112002KQ,SMA   I235 @T6G_MB_LIB.T6G(SCH_1):PAGE108

M_L_CPU1_SA_DQS_DN<5> @T6G_MB_LIB.T6G(SCH_1):M_L_CPU1_SA_DQS_DN(5)
   U26  H11 MLA_DQS_L5 GENOA_SP5-SOCKET6096_13568-001,SMLF,IO,DGA^6000030   I159 @T6G_MB_LIB.T6G(SCH_1):PAGE48
   J37  156 DQS5_A_C||TDQS5_A_C||DQS5_A_T||TDQS5_A_T SCONN288_DDR506112002KQ-SCONN288_DDR506112002KQ,SMA   I235 @T6G_MB_LIB.T6G(SCH_1):PAGE108

M_L_CPU1_SA_DQS_DN<6> @T6G_MB_LIB.T6G(SCH_1):M_L_CPU1_SA_DQS_DN(6)
   U26  P11 MLA_DQS_L6 GENOA_SP5-SOCKET6096_13568-001,SMLF,IO,DGA^6000030   I159 @T6G_MB_LIB.T6G(SCH_1):PAGE48
   J37  167 DQS6_A_C||TDQS6_A_C||DQS6_A_T||TDQS6_A_T SCONN288_DDR506112002KQ-SCONN288_DDR506112002KQ,SMA   I235 @T6G_MB_LIB.T6G(SCH_1):PAGE108

M_L_CPU1_SA_DQS_DN<7> @T6G_MB_LIB.T6G(SCH_1):M_L_CPU1_SA_DQS_DN(7)
   U26  Y11 MLA_DQS_L7 GENOA_SP5-SOCKET6096_13568-001,SMLF,IO,DGA^6000030   I159 @T6G_MB_LIB.T6G(SCH_1):PAGE48
   J37  178 DQS7_A_C||TDQS7_A_C SCONN288_DDR506112002KQ-SCONN288_DDR506112002KQ,SMA   I235 @T6G_MB_LIB.T6G(SCH_1):PAGE108

M_L_CPU1_SA_DQS_DN<8> @T6G_MB_LIB.T6G(SCH_1):M_L_CPU1_SA_DQS_DN(8)
   U26 AF11 MLA_DQS_L8 GENOA_SP5-SOCKET6096_13568-001,SMLF,IO,DGA^6000030   I159 @T6G_MB_LIB.T6G(SCH_1):PAGE48
   J37  189 DQS8_A_C||TDQS8_A_C SCONN288_DDR506112002KQ-SCONN288_DDR506112002KQ,SMA   I235 @T6G_MB_LIB.T6G(SCH_1):PAGE108

M_L_CPU1_SA_DQS_DN<9> @T6G_MB_LIB.T6G(SCH_1):M_L_CPU1_SA_DQS_DN(9)
   U26 AM11 MLA_DQS_L9 GENOA_SP5-SOCKET6096_13568-001,SMLF,IO,DGA^6000030   I159 @T6G_MB_LIB.T6G(SCH_1):PAGE48
   J37  200 DQS9_A_C||TDQS9_A_C SCONN288_DDR506112002KQ-SCONN288_DDR506112002KQ,SMA   I235 @T6G_MB_LIB.T6G(SCH_1):PAGE108

M_L_CPU1_SA_DQS_DP<0> @T6G_MB_LIB.T6G(SCH_1):M_L_CPU1_SA_DQS_DP(0)
   U26   G9 MLA_DQS_H0 GENOA_SP5-SOCKET6096_13568-001,SMLF,IO,DGA^6000030   I159 @T6G_MB_LIB.T6G(SCH_1):PAGE48
   J37   11 DQS0_A_T SCONN288_DDR506112002KQ-SCONN288_DDR506112002KQ,SMA   I235 @T6G_MB_LIB.T6G(SCH_1):PAGE108

M_L_CPU1_SA_DQS_DP<1> @T6G_MB_LIB.T6G(SCH_1):M_L_CPU1_SA_DQS_DP(1)
   U26   N9 MLA_DQS_H1 GENOA_SP5-SOCKET6096_13568-001,SMLF,IO,DGA^6000030   I159 @T6G_MB_LIB.T6G(SCH_1):PAGE48
   J37   22 DQS1_A_T SCONN288_DDR506112002KQ-SCONN288_DDR506112002KQ,SMA   I235 @T6G_MB_LIB.T6G(SCH_1):PAGE108

M_L_CPU1_SA_DQS_DP<2> @T6G_MB_LIB.T6G(SCH_1):M_L_CPU1_SA_DQS_DP(2)
   U26   W9 MLA_DQS_H2 GENOA_SP5-SOCKET6096_13568-001,SMLF,IO,DGA^6000030   I159 @T6G_MB_LIB.T6G(SCH_1):PAGE48
   J37   33 DQS2_A_T SCONN288_DDR506112002KQ-SCONN288_DDR506112002KQ,SMA   I235 @T6G_MB_LIB.T6G(SCH_1):PAGE108

M_L_CPU1_SA_DQS_DP<3> @T6G_MB_LIB.T6G(SCH_1):M_L_CPU1_SA_DQS_DP(3)
   U26  AE9 MLA_DQS_H3 GENOA_SP5-SOCKET6096_13568-001,SMLF,IO,DGA^6000030   I159 @T6G_MB_LIB.T6G(SCH_1):PAGE48
   J37   44 DQS3_A_T SCONN288_DDR506112002KQ-SCONN288_DDR506112002KQ,SMA   I235 @T6G_MB_LIB.T6G(SCH_1):PAGE108

M_L_CPU1_SA_DQS_DP<4> @T6G_MB_LIB.T6G(SCH_1):M_L_CPU1_SA_DQS_DP(4)
   U26  AL9 MLA_DQS_H4 GENOA_SP5-SOCKET6096_13568-001,SMLF,IO,DGA^6000030   I159 @T6G_MB_LIB.T6G(SCH_1):PAGE48
   J37   55 DQS4_A_T SCONN288_DDR506112002KQ-SCONN288_DDR506112002KQ,SMA   I235 @T6G_MB_LIB.T6G(SCH_1):PAGE108

M_L_CPU1_SA_DQS_DP<5> @T6G_MB_LIB.T6G(SCH_1):M_L_CPU1_SA_DQS_DP(5)
   U26  J10 MLA_DQS_H5 GENOA_SP5-SOCKET6096_13568-001,SMLF,IO,DGA^6000030   I159 @T6G_MB_LIB.T6G(SCH_1):PAGE48
   J37  157 DQS5_A_T||TDQS5_A_T SCONN288_DDR506112002KQ-SCONN288_DDR506112002KQ,SMA   I235 @T6G_MB_LIB.T6G(SCH_1):PAGE108

M_L_CPU1_SA_DQS_DP<6> @T6G_MB_LIB.T6G(SCH_1):M_L_CPU1_SA_DQS_DP(6)
   U26  R10 MLA_DQS_H6 GENOA_SP5-SOCKET6096_13568-001,SMLF,IO,DGA^6000030   I159 @T6G_MB_LIB.T6G(SCH_1):PAGE48
   J37  168 DQS6_A_T||TDQS6_A_T SCONN288_DDR506112002KQ-SCONN288_DDR506112002KQ,SMA   I235 @T6G_MB_LIB.T6G(SCH_1):PAGE108

M_L_CPU1_SA_DQS_DP<7> @T6G_MB_LIB.T6G(SCH_1):M_L_CPU1_SA_DQS_DP(7)
   U26 AA10 MLA_DQS_H7 GENOA_SP5-SOCKET6096_13568-001,SMLF,IO,DGA^6000030   I159 @T6G_MB_LIB.T6G(SCH_1):PAGE48
   J37  179 DQS7_A_T||TDQS7_A_T SCONN288_DDR506112002KQ-SCONN288_DDR506112002KQ,SMA   I235 @T6G_MB_LIB.T6G(SCH_1):PAGE108

M_L_CPU1_SA_DQS_DP<8> @T6G_MB_LIB.T6G(SCH_1):M_L_CPU1_SA_DQS_DP(8)
   U26 AG10 MLA_DQS_H8 GENOA_SP5-SOCKET6096_13568-001,SMLF,IO,DGA^6000030   I159 @T6G_MB_LIB.T6G(SCH_1):PAGE48
   J37  190 DQS8_A_T||TDQS8_A_T SCONN288_DDR506112002KQ-SCONN288_DDR506112002KQ,SMA   I235 @T6G_MB_LIB.T6G(SCH_1):PAGE108

M_L_CPU1_SA_DQS_DP<9> @T6G_MB_LIB.T6G(SCH_1):M_L_CPU1_SA_DQS_DP(9)
   U26 AN10 MLA_DQS_H9 GENOA_SP5-SOCKET6096_13568-001,SMLF,IO,DGA^6000030   I159 @T6G_MB_LIB.T6G(SCH_1):PAGE48
   J37  201 DQS9_A_T||TDQS9_A_T SCONN288_DDR506112002KQ-SCONN288_DDR506112002KQ,SMA   I235 @T6G_MB_LIB.T6G(SCH_1):PAGE108

M_L_CPU1_SA_PAR @T6G_MB_LIB.T6G(SCH_1):M_L_CPU1_SA_PAR
   U26 BC10 MLA_PAR GENOA_SP5-SOCKET6096_13568-001,SMLF,IO,DGA^6000030   I159 @T6G_MB_LIB.T6G(SCH_1):PAGE48
   J37   74  PAR_A SCONN288_DDR506112002KQ-SCONN288_DDR506112002KQ,SMA    I22 @T6G_MB_LIB.T6G(SCH_1):PAGE108

M_L_CPU1_SA_RSP<0> @T6G_MB_LIB.T6G(SCH_1):M_L_CPU1_SA_RSP(0)
   U26 BN10 MLA0_RSP_L GENOA_SP5-SOCKET6096_13568-001,SMLF,IO,DGA^6000030   I159 @T6G_MB_LIB.T6G(SCH_1):PAGE48
   J37   86 LBD||RSP_A_N SCONN288_DDR506112002KQ-SCONN288_DDR506112002KQ,SMA    I22 @T6G_MB_LIB.T6G(SCH_1):PAGE108

M_L_CPU1_SB_CA<0> @T6G_MB_LIB.T6G(SCH_1):M_L_CPU1_SB_CA(0)
   U26 BG10 MLB_CA0 GENOA_SP5-SOCKET6096_13568-001,SMLF,IO,DGA^6000030   I159 @T6G_MB_LIB.T6G(SCH_1):PAGE48
   J37   76  CA0_B SCONN288_DDR506112002KQ-SCONN288_DDR506112002KQ,SMA    I22 @T6G_MB_LIB.T6G(SCH_1):PAGE108

M_L_CPU1_SB_CA<1> @T6G_MB_LIB.T6G(SCH_1):M_L_CPU1_SB_CA(1)
   U26 BH11 MLB_CA1 GENOA_SP5-SOCKET6096_13568-001,SMLF,IO,DGA^6000030   I159 @T6G_MB_LIB.T6G(SCH_1):PAGE48
   J37  221  CA1_B SCONN288_DDR506112002KQ-SCONN288_DDR506112002KQ,SMA    I22 @T6G_MB_LIB.T6G(SCH_1):PAGE108

M_L_CPU1_SB_CA<2> @T6G_MB_LIB.T6G(SCH_1):M_L_CPU1_SB_CA(2)
   U26  BH9 MLB_CA2 GENOA_SP5-SOCKET6096_13568-001,SMLF,IO,DGA^6000030   I159 @T6G_MB_LIB.T6G(SCH_1):PAGE48
   J37   78  CA2_B SCONN288_DDR506112002KQ-SCONN288_DDR506112002KQ,SMA    I22 @T6G_MB_LIB.T6G(SCH_1):PAGE108

M_L_CPU1_SB_CA<3> @T6G_MB_LIB.T6G(SCH_1):M_L_CPU1_SB_CA(3)
   U26  BJ9 MLB_CA3 GENOA_SP5-SOCKET6096_13568-001,SMLF,IO,DGA^6000030   I159 @T6G_MB_LIB.T6G(SCH_1):PAGE48
   J37  223  CA3_B SCONN288_DDR506112002KQ-SCONN288_DDR506112002KQ,SMA    I22 @T6G_MB_LIB.T6G(SCH_1):PAGE108

M_L_CPU1_SB_CA<4> @T6G_MB_LIB.T6G(SCH_1):M_L_CPU1_SB_CA(4)
   U26 BJ10 MLB_CA4 GENOA_SP5-SOCKET6096_13568-001,SMLF,IO,DGA^6000030   I159 @T6G_MB_LIB.T6G(SCH_1):PAGE48
   J37   80  CA4_B SCONN288_DDR506112002KQ-SCONN288_DDR506112002KQ,SMA    I22 @T6G_MB_LIB.T6G(SCH_1):PAGE108

M_L_CPU1_SB_CA<5> @T6G_MB_LIB.T6G(SCH_1):M_L_CPU1_SB_CA(5)
   U26 BK11 MLB_CA5 GENOA_SP5-SOCKET6096_13568-001,SMLF,IO,DGA^6000030   I159 @T6G_MB_LIB.T6G(SCH_1):PAGE48
   J37  225  CA5_B SCONN288_DDR506112002KQ-SCONN288_DDR506112002KQ,SMA    I22 @T6G_MB_LIB.T6G(SCH_1):PAGE108

M_L_CPU1_SB_CA<6> @T6G_MB_LIB.T6G(SCH_1):M_L_CPU1_SB_CA(6)
   U26  BK9 MLB_CA6 GENOA_SP5-SOCKET6096_13568-001,SMLF,IO,DGA^6000030   I159 @T6G_MB_LIB.T6G(SCH_1):PAGE48
   J37   82  CA6_B SCONN288_DDR506112002KQ-SCONN288_DDR506112002KQ,SMA    I22 @T6G_MB_LIB.T6G(SCH_1):PAGE108

M_L_CPU1_SB_CB<0> @T6G_MB_LIB.T6G(SCH_1):M_L_CPU1_SB_CB(0)
   U26  BY9 MLB_CHECK0 GENOA_SP5-SOCKET6096_13568-001,SMLF,IO,DGA^6000030   I159 @T6G_MB_LIB.T6G(SCH_1):PAGE48
   J37   96  CB0_B SCONN288_DDR506112002KQ-SCONN288_DDR506112002KQ,SMA    I22 @T6G_MB_LIB.T6G(SCH_1):PAGE108

M_L_CPU1_SB_CB<1> @T6G_MB_LIB.T6G(SCH_1):M_L_CPU1_SB_CB(1)
   U26 CA10 MLB_CHECK1 GENOA_SP5-SOCKET6096_13568-001,SMLF,IO,DGA^6000030   I159 @T6G_MB_LIB.T6G(SCH_1):PAGE48
   J37   98  CB1_B SCONN288_DDR506112002KQ-SCONN288_DDR506112002KQ,SMA    I22 @T6G_MB_LIB.T6G(SCH_1):PAGE108

M_L_CPU1_SB_CB<2> @T6G_MB_LIB.T6G(SCH_1):M_L_CPU1_SB_CB(2)
   U26  CA9 MLB_CHECK2 GENOA_SP5-SOCKET6096_13568-001,SMLF,IO,DGA^6000030   I159 @T6G_MB_LIB.T6G(SCH_1):PAGE48
   J37  241  CB2_B SCONN288_DDR506112002KQ-SCONN288_DDR506112002KQ,SMA    I22 @T6G_MB_LIB.T6G(SCH_1):PAGE108

M_L_CPU1_SB_CB<3> @T6G_MB_LIB.T6G(SCH_1):M_L_CPU1_SB_CB(3)
   U26 CB11 MLB_CHECK3 GENOA_SP5-SOCKET6096_13568-001,SMLF,IO,DGA^6000030   I159 @T6G_MB_LIB.T6G(SCH_1):PAGE48
   J37  243  CB3_B SCONN288_DDR506112002KQ-SCONN288_DDR506112002KQ,SMA    I22 @T6G_MB_LIB.T6G(SCH_1):PAGE108

M_L_CPU1_SB_CB<4> @T6G_MB_LIB.T6G(SCH_1):M_L_CPU1_SB_CB(4)
   U26  BT9 MLB_CHECK4 GENOA_SP5-SOCKET6096_13568-001,SMLF,IO,DGA^6000030   I159 @T6G_MB_LIB.T6G(SCH_1):PAGE48
   J37   89  CB4_B SCONN288_DDR506112002KQ-SCONN288_DDR506112002KQ,SMA    I22 @T6G_MB_LIB.T6G(SCH_1):PAGE108

M_L_CPU1_SB_CB<5> @T6G_MB_LIB.T6G(SCH_1):M_L_CPU1_SB_CB(5)
   U26 BU10 MLB_CHECK5 GENOA_SP5-SOCKET6096_13568-001,SMLF,IO,DGA^6000030   I159 @T6G_MB_LIB.T6G(SCH_1):PAGE48
   J37   91  CB5_B SCONN288_DDR506112002KQ-SCONN288_DDR506112002KQ,SMA    I22 @T6G_MB_LIB.T6G(SCH_1):PAGE108

M_L_CPU1_SB_CB<6> @T6G_MB_LIB.T6G(SCH_1):M_L_CPU1_SB_CB(6)
   U26  BU9 MLB_CHECK6 GENOA_SP5-SOCKET6096_13568-001,SMLF,IO,DGA^6000030   I159 @T6G_MB_LIB.T6G(SCH_1):PAGE48
   J37  234  CB6_B SCONN288_DDR506112002KQ-SCONN288_DDR506112002KQ,SMA    I22 @T6G_MB_LIB.T6G(SCH_1):PAGE108

M_L_CPU1_SB_CB<7> @T6G_MB_LIB.T6G(SCH_1):M_L_CPU1_SB_CB(7)
   U26 BV11 MLB_CHECK7 GENOA_SP5-SOCKET6096_13568-001,SMLF,IO,DGA^6000030   I159 @T6G_MB_LIB.T6G(SCH_1):PAGE48
   J37  236  CB7_B SCONN288_DDR506112002KQ-SCONN288_DDR506112002KQ,SMA    I22 @T6G_MB_LIB.T6G(SCH_1):PAGE108

M_L_CPU1_SB_CS_N<0> @T6G_MB_LIB.T6G(SCH_1):M_L_CPU1_SB_CS_N(0)
   U26 BM11 MLB0_CS_L0 GENOA_SP5-SOCKET6096_13568-001,SMLF,IO,DGA^6000030   I159 @T6G_MB_LIB.T6G(SCH_1):PAGE48
   J37   84 CS0_B_N SCONN288_DDR506112002KQ-SCONN288_DDR506112002KQ,SMA    I22 @T6G_MB_LIB.T6G(SCH_1):PAGE108

M_L_CPU1_SB_CS_N<1> @T6G_MB_LIB.T6G(SCH_1):M_L_CPU1_SB_CS_N(1)
   U26  BN9 MLB0_CS_L1 GENOA_SP5-SOCKET6096_13568-001,SMLF,IO,DGA^6000030   I159 @T6G_MB_LIB.T6G(SCH_1):PAGE48
   J37  229 CS1_B_N SCONN288_DDR506112002KQ-SCONN288_DDR506112002KQ,SMA    I22 @T6G_MB_LIB.T6G(SCH_1):PAGE108

M_L_CPU1_SB_DQ<0> @T6G_MB_LIB.T6G(SCH_1):M_L_CPU1_SB_DQ(0)
   U26  CB9 MLB_DATA0 GENOA_SP5-SOCKET6096_13568-001,SMLF,IO,DGA^6000030   I159 @T6G_MB_LIB.T6G(SCH_1):PAGE48
   J37  100  DQ0_B SCONN288_DDR506112002KQ-SCONN288_DDR506112002KQ,SMA    I22 @T6G_MB_LIB.T6G(SCH_1):PAGE108

M_L_CPU1_SB_DQ<10> @T6G_MB_LIB.T6G(SCH_1):M_L_CPU1_SB_DQ(10)
   U26  CJ9 MLB_DATA10 GENOA_SP5-SOCKET6096_13568-001,SMLF,IO,DGA^6000030   I159 @T6G_MB_LIB.T6G(SCH_1):PAGE48
   J37  256 DQ10_B SCONN288_DDR506112002KQ-SCONN288_DDR506112002KQ,SMA    I22 @T6G_MB_LIB.T6G(SCH_1):PAGE108

M_L_CPU1_SB_DQ<11> @T6G_MB_LIB.T6G(SCH_1):M_L_CPU1_SB_DQ(11)
   U26 CK11 MLB_DATA11 GENOA_SP5-SOCKET6096_13568-001,SMLF,IO,DGA^6000030   I159 @T6G_MB_LIB.T6G(SCH_1):PAGE48
   J37  258 DQ11_B SCONN288_DDR506112002KQ-SCONN288_DDR506112002KQ,SMA    I22 @T6G_MB_LIB.T6G(SCH_1):PAGE108

M_L_CPU1_SB_DQ<12> @T6G_MB_LIB.T6G(SCH_1):M_L_CPU1_SB_DQ(12)
   U26  CM9 MLB_DATA12 GENOA_SP5-SOCKET6096_13568-001,SMLF,IO,DGA^6000030   I159 @T6G_MB_LIB.T6G(SCH_1):PAGE48
   J37  118 DQ12_B SCONN288_DDR506112002KQ-SCONN288_DDR506112002KQ,SMA    I22 @T6G_MB_LIB.T6G(SCH_1):PAGE108

M_L_CPU1_SB_DQ<13> @T6G_MB_LIB.T6G(SCH_1):M_L_CPU1_SB_DQ(13)
   U26 CN10 MLB_DATA13 GENOA_SP5-SOCKET6096_13568-001,SMLF,IO,DGA^6000030   I159 @T6G_MB_LIB.T6G(SCH_1):PAGE48
   J37  120 DQ13_B SCONN288_DDR506112002KQ-SCONN288_DDR506112002KQ,SMA    I22 @T6G_MB_LIB.T6G(SCH_1):PAGE108

M_L_CPU1_SB_DQ<14> @T6G_MB_LIB.T6G(SCH_1):M_L_CPU1_SB_DQ(14)
   U26  CN9 MLB_DATA14 GENOA_SP5-SOCKET6096_13568-001,SMLF,IO,DGA^6000030   I159 @T6G_MB_LIB.T6G(SCH_1):PAGE48
   J37  263 DQ14_B SCONN288_DDR506112002KQ-SCONN288_DDR506112002KQ,SMA    I22 @T6G_MB_LIB.T6G(SCH_1):PAGE108

M_L_CPU1_SB_DQ<15> @T6G_MB_LIB.T6G(SCH_1):M_L_CPU1_SB_DQ(15)
   U26 CP11 MLB_DATA15 GENOA_SP5-SOCKET6096_13568-001,SMLF,IO,DGA^6000030   I159 @T6G_MB_LIB.T6G(SCH_1):PAGE48
   J37  265 DQ15_B SCONN288_DDR506112002KQ-SCONN288_DDR506112002KQ,SMA    I22 @T6G_MB_LIB.T6G(SCH_1):PAGE108

M_L_CPU1_SB_DQ<16> @T6G_MB_LIB.T6G(SCH_1):M_L_CPU1_SB_DQ(16)
   U26  CP9 MLB_DATA16 GENOA_SP5-SOCKET6096_13568-001,SMLF,IO,DGA^6000030   I159 @T6G_MB_LIB.T6G(SCH_1):PAGE48
   J37  122 DQ16_B SCONN288_DDR506112002KQ-SCONN288_DDR506112002KQ,SMA    I22 @T6G_MB_LIB.T6G(SCH_1):PAGE108

M_L_CPU1_SB_DQ<17> @T6G_MB_LIB.T6G(SCH_1):M_L_CPU1_SB_DQ(17)
   U26 CR10 MLB_DATA17 GENOA_SP5-SOCKET6096_13568-001,SMLF,IO,DGA^6000030   I159 @T6G_MB_LIB.T6G(SCH_1):PAGE48
   J37  124 DQ17_B SCONN288_DDR506112002KQ-SCONN288_DDR506112002KQ,SMA    I22 @T6G_MB_LIB.T6G(SCH_1):PAGE108

M_L_CPU1_SB_DQ<18> @T6G_MB_LIB.T6G(SCH_1):M_L_CPU1_SB_DQ(18)
   U26  CR9 MLB_DATA18 GENOA_SP5-SOCKET6096_13568-001,SMLF,IO,DGA^6000030   I159 @T6G_MB_LIB.T6G(SCH_1):PAGE48
   J37  267 DQ18_B SCONN288_DDR506112002KQ-SCONN288_DDR506112002KQ,SMA    I22 @T6G_MB_LIB.T6G(SCH_1):PAGE108

M_L_CPU1_SB_DQ<19> @T6G_MB_LIB.T6G(SCH_1):M_L_CPU1_SB_DQ(19)
   U26 CT11 MLB_DATA19 GENOA_SP5-SOCKET6096_13568-001,SMLF,IO,DGA^6000030   I159 @T6G_MB_LIB.T6G(SCH_1):PAGE48
   J37  269 DQ19_B SCONN288_DDR506112002KQ-SCONN288_DDR506112002KQ,SMA    I22 @T6G_MB_LIB.T6G(SCH_1):PAGE108

M_L_CPU1_SB_DQ<1> @T6G_MB_LIB.T6G(SCH_1):M_L_CPU1_SB_DQ(1)
   U26 CC10 MLB_DATA1 GENOA_SP5-SOCKET6096_13568-001,SMLF,IO,DGA^6000030   I159 @T6G_MB_LIB.T6G(SCH_1):PAGE48
   J37  102  DQ1_B SCONN288_DDR506112002KQ-SCONN288_DDR506112002KQ,SMA    I22 @T6G_MB_LIB.T6G(SCH_1):PAGE108

M_L_CPU1_SB_DQ<20> @T6G_MB_LIB.T6G(SCH_1):M_L_CPU1_SB_DQ(20)
   U26  CV9 MLB_DATA20 GENOA_SP5-SOCKET6096_13568-001,SMLF,IO,DGA^6000030   I159 @T6G_MB_LIB.T6G(SCH_1):PAGE48
   J37  129 DQ20_B SCONN288_DDR506112002KQ-SCONN288_DDR506112002KQ,SMA    I22 @T6G_MB_LIB.T6G(SCH_1):PAGE108

M_L_CPU1_SB_DQ<21> @T6G_MB_LIB.T6G(SCH_1):M_L_CPU1_SB_DQ(21)
   U26 CW10 MLB_DATA21 GENOA_SP5-SOCKET6096_13568-001,SMLF,IO,DGA^6000030   I159 @T6G_MB_LIB.T6G(SCH_1):PAGE48
   J37  131 DQ21_B SCONN288_DDR506112002KQ-SCONN288_DDR506112002KQ,SMA    I22 @T6G_MB_LIB.T6G(SCH_1):PAGE108

M_L_CPU1_SB_DQ<22> @T6G_MB_LIB.T6G(SCH_1):M_L_CPU1_SB_DQ(22)
   U26  CW9 MLB_DATA22 GENOA_SP5-SOCKET6096_13568-001,SMLF,IO,DGA^6000030   I159 @T6G_MB_LIB.T6G(SCH_1):PAGE48
   J37  274 DQ22_B SCONN288_DDR506112002KQ-SCONN288_DDR506112002KQ,SMA    I22 @T6G_MB_LIB.T6G(SCH_1):PAGE108

M_L_CPU1_SB_DQ<23> @T6G_MB_LIB.T6G(SCH_1):M_L_CPU1_SB_DQ(23)
   U26 CY11 MLB_DATA23 GENOA_SP5-SOCKET6096_13568-001,SMLF,IO,DGA^6000030   I159 @T6G_MB_LIB.T6G(SCH_1):PAGE48
   J37  276 DQ23_B SCONN288_DDR506112002KQ-SCONN288_DDR506112002KQ,SMA    I22 @T6G_MB_LIB.T6G(SCH_1):PAGE108

M_L_CPU1_SB_DQ<24> @T6G_MB_LIB.T6G(SCH_1):M_L_CPU1_SB_DQ(24)
   U26  CY9 MLB_DATA24 GENOA_SP5-SOCKET6096_13568-001,SMLF,IO,DGA^6000030   I159 @T6G_MB_LIB.T6G(SCH_1):PAGE48
   J37  133 DQ24_B SCONN288_DDR506112002KQ-SCONN288_DDR506112002KQ,SMA    I22 @T6G_MB_LIB.T6G(SCH_1):PAGE108

M_L_CPU1_SB_DQ<25> @T6G_MB_LIB.T6G(SCH_1):M_L_CPU1_SB_DQ(25)
   U26 DA10 MLB_DATA25 GENOA_SP5-SOCKET6096_13568-001,SMLF,IO,DGA^6000030   I159 @T6G_MB_LIB.T6G(SCH_1):PAGE48
   J37  135 DQ25_B SCONN288_DDR506112002KQ-SCONN288_DDR506112002KQ,SMA    I22 @T6G_MB_LIB.T6G(SCH_1):PAGE108

M_L_CPU1_SB_DQ<26> @T6G_MB_LIB.T6G(SCH_1):M_L_CPU1_SB_DQ(26)
   U26  DA9 MLB_DATA26 GENOA_SP5-SOCKET6096_13568-001,SMLF,IO,DGA^6000030   I159 @T6G_MB_LIB.T6G(SCH_1):PAGE48
   J37  278 DQ26_B SCONN288_DDR506112002KQ-SCONN288_DDR506112002KQ,SMA    I22 @T6G_MB_LIB.T6G(SCH_1):PAGE108

M_L_CPU1_SB_DQ<27> @T6G_MB_LIB.T6G(SCH_1):M_L_CPU1_SB_DQ(27)
   U26 DB11 MLB_DATA27 GENOA_SP5-SOCKET6096_13568-001,SMLF,IO,DGA^6000030   I159 @T6G_MB_LIB.T6G(SCH_1):PAGE48
   J37  280 DQ27_B SCONN288_DDR506112002KQ-SCONN288_DDR506112002KQ,SMA    I22 @T6G_MB_LIB.T6G(SCH_1):PAGE108

M_L_CPU1_SB_DQ<28> @T6G_MB_LIB.T6G(SCH_1):M_L_CPU1_SB_DQ(28)
   U26  DD9 MLB_DATA28 GENOA_SP5-SOCKET6096_13568-001,SMLF,IO,DGA^6000030   I159 @T6G_MB_LIB.T6G(SCH_1):PAGE48
   J37  140 DQ28_B SCONN288_DDR506112002KQ-SCONN288_DDR506112002KQ,SMA    I22 @T6G_MB_LIB.T6G(SCH_1):PAGE108

M_L_CPU1_SB_DQ<29> @T6G_MB_LIB.T6G(SCH_1):M_L_CPU1_SB_DQ(29)
   U26 DE10 MLB_DATA29 GENOA_SP5-SOCKET6096_13568-001,SMLF,IO,DGA^6000030   I159 @T6G_MB_LIB.T6G(SCH_1):PAGE48
   J37  142 DQ29_B SCONN288_DDR506112002KQ-SCONN288_DDR506112002KQ,SMA    I22 @T6G_MB_LIB.T6G(SCH_1):PAGE108

M_L_CPU1_SB_DQ<2> @T6G_MB_LIB.T6G(SCH_1):M_L_CPU1_SB_DQ(2)
   U26  CC9 MLB_DATA2 GENOA_SP5-SOCKET6096_13568-001,SMLF,IO,DGA^6000030   I159 @T6G_MB_LIB.T6G(SCH_1):PAGE48
   J37  245  DQ2_B SCONN288_DDR506112002KQ-SCONN288_DDR506112002KQ,SMA    I22 @T6G_MB_LIB.T6G(SCH_1):PAGE108

M_L_CPU1_SB_DQ<30> @T6G_MB_LIB.T6G(SCH_1):M_L_CPU1_SB_DQ(30)
   U26  DE9 MLB_DATA30 GENOA_SP5-SOCKET6096_13568-001,SMLF,IO,DGA^6000030   I159 @T6G_MB_LIB.T6G(SCH_1):PAGE48
   J37  285 DQ30_B SCONN288_DDR506112002KQ-SCONN288_DDR506112002KQ,SMA    I22 @T6G_MB_LIB.T6G(SCH_1):PAGE108

M_L_CPU1_SB_DQ<31> @T6G_MB_LIB.T6G(SCH_1):M_L_CPU1_SB_DQ(31)
   U26  DF9 MLB_DATA31 GENOA_SP5-SOCKET6096_13568-001,SMLF,IO,DGA^6000030   I159 @T6G_MB_LIB.T6G(SCH_1):PAGE48
   J37  287 DQ31_B SCONN288_DDR506112002KQ-SCONN288_DDR506112002KQ,SMA    I22 @T6G_MB_LIB.T6G(SCH_1):PAGE108

M_L_CPU1_SB_DQ<3> @T6G_MB_LIB.T6G(SCH_1):M_L_CPU1_SB_DQ(3)
   U26 CD11 MLB_DATA3 GENOA_SP5-SOCKET6096_13568-001,SMLF,IO,DGA^6000030   I159 @T6G_MB_LIB.T6G(SCH_1):PAGE48
   J37  247  DQ3_B SCONN288_DDR506112002KQ-SCONN288_DDR506112002KQ,SMA    I22 @T6G_MB_LIB.T6G(SCH_1):PAGE108

M_L_CPU1_SB_DQ<4> @T6G_MB_LIB.T6G(SCH_1):M_L_CPU1_SB_DQ(4)
   U26  CF9 MLB_DATA4 GENOA_SP5-SOCKET6096_13568-001,SMLF,IO,DGA^6000030   I159 @T6G_MB_LIB.T6G(SCH_1):PAGE48
   J37  107  DQ4_B SCONN288_DDR506112002KQ-SCONN288_DDR506112002KQ,SMA    I22 @T6G_MB_LIB.T6G(SCH_1):PAGE108

M_L_CPU1_SB_DQ<5> @T6G_MB_LIB.T6G(SCH_1):M_L_CPU1_SB_DQ(5)
   U26 CG10 MLB_DATA5 GENOA_SP5-SOCKET6096_13568-001,SMLF,IO,DGA^6000030   I159 @T6G_MB_LIB.T6G(SCH_1):PAGE48
   J37  109  DQ5_B SCONN288_DDR506112002KQ-SCONN288_DDR506112002KQ,SMA    I22 @T6G_MB_LIB.T6G(SCH_1):PAGE108

M_L_CPU1_SB_DQ<6> @T6G_MB_LIB.T6G(SCH_1):M_L_CPU1_SB_DQ(6)
   U26  CG9 MLB_DATA6 GENOA_SP5-SOCKET6096_13568-001,SMLF,IO,DGA^6000030   I159 @T6G_MB_LIB.T6G(SCH_1):PAGE48
   J37  252  DQ6_B SCONN288_DDR506112002KQ-SCONN288_DDR506112002KQ,SMA    I22 @T6G_MB_LIB.T6G(SCH_1):PAGE108

M_L_CPU1_SB_DQ<7> @T6G_MB_LIB.T6G(SCH_1):M_L_CPU1_SB_DQ(7)
   U26 CH11 MLB_DATA7 GENOA_SP5-SOCKET6096_13568-001,SMLF,IO,DGA^6000030   I159 @T6G_MB_LIB.T6G(SCH_1):PAGE48
   J37  254  DQ7_B SCONN288_DDR506112002KQ-SCONN288_DDR506112002KQ,SMA    I22 @T6G_MB_LIB.T6G(SCH_1):PAGE108

M_L_CPU1_SB_DQ<8> @T6G_MB_LIB.T6G(SCH_1):M_L_CPU1_SB_DQ(8)
   U26  CH9 MLB_DATA8 GENOA_SP5-SOCKET6096_13568-001,SMLF,IO,DGA^6000030   I159 @T6G_MB_LIB.T6G(SCH_1):PAGE48
   J37  111  DQ8_B SCONN288_DDR506112002KQ-SCONN288_DDR506112002KQ,SMA    I22 @T6G_MB_LIB.T6G(SCH_1):PAGE108

M_L_CPU1_SB_DQ<9> @T6G_MB_LIB.T6G(SCH_1):M_L_CPU1_SB_DQ(9)
   U26 CJ10 MLB_DATA9 GENOA_SP5-SOCKET6096_13568-001,SMLF,IO,DGA^6000030   I159 @T6G_MB_LIB.T6G(SCH_1):PAGE48
   J37  113  DQ9_B SCONN288_DDR506112002KQ-SCONN288_DDR506112002KQ,SMA    I22 @T6G_MB_LIB.T6G(SCH_1):PAGE108

M_L_CPU1_SB_DQS_DN<0> @T6G_MB_LIB.T6G(SCH_1):M_L_CPU1_SB_DQS_DN(0)
   U26  CE9 MLB_DQS_L0 GENOA_SP5-SOCKET6096_13568-001,SMLF,IO,DGA^6000030   I159 @T6G_MB_LIB.T6G(SCH_1):PAGE48
   J37  105 DQS0_B_C SCONN288_DDR506112002KQ-SCONN288_DDR506112002KQ,SMA   I235 @T6G_MB_LIB.T6G(SCH_1):PAGE108

M_L_CPU1_SB_DQS_DN<1> @T6G_MB_LIB.T6G(SCH_1):M_L_CPU1_SB_DQS_DN(1)
   U26  CL9 MLB_DQS_L1 GENOA_SP5-SOCKET6096_13568-001,SMLF,IO,DGA^6000030   I159 @T6G_MB_LIB.T6G(SCH_1):PAGE48
   J37  116 DQS1_B_C SCONN288_DDR506112002KQ-SCONN288_DDR506112002KQ,SMA   I235 @T6G_MB_LIB.T6G(SCH_1):PAGE108

M_L_CPU1_SB_DQS_DN<2> @T6G_MB_LIB.T6G(SCH_1):M_L_CPU1_SB_DQS_DN(2)
   U26  CU9 MLB_DQS_L2 GENOA_SP5-SOCKET6096_13568-001,SMLF,IO,DGA^6000030   I159 @T6G_MB_LIB.T6G(SCH_1):PAGE48
   J37  127 DQS2_B_C SCONN288_DDR506112002KQ-SCONN288_DDR506112002KQ,SMA   I235 @T6G_MB_LIB.T6G(SCH_1):PAGE108

M_L_CPU1_SB_DQS_DN<3> @T6G_MB_LIB.T6G(SCH_1):M_L_CPU1_SB_DQS_DN(3)
   U26  DC9 MLB_DQS_L3 GENOA_SP5-SOCKET6096_13568-001,SMLF,IO,DGA^6000030   I159 @T6G_MB_LIB.T6G(SCH_1):PAGE48
   J37  138 DQS3_B_C SCONN288_DDR506112002KQ-SCONN288_DDR506112002KQ,SMA   I235 @T6G_MB_LIB.T6G(SCH_1):PAGE108

M_L_CPU1_SB_DQS_DN<4> @T6G_MB_LIB.T6G(SCH_1):M_L_CPU1_SB_DQS_DN(4)
   U26 BW10 MLB_DQS_L4 GENOA_SP5-SOCKET6096_13568-001,SMLF,IO,DGA^6000030   I159 @T6G_MB_LIB.T6G(SCH_1):PAGE48
   J37  238 DQS4_B_C SCONN288_DDR506112002KQ-SCONN288_DDR506112002KQ,SMA   I235 @T6G_MB_LIB.T6G(SCH_1):PAGE108

M_L_CPU1_SB_DQS_DN<5> @T6G_MB_LIB.T6G(SCH_1):M_L_CPU1_SB_DQS_DN(5)
   U26 CE10 MLB_DQS_L5 GENOA_SP5-SOCKET6096_13568-001,SMLF,IO,DGA^6000030   I159 @T6G_MB_LIB.T6G(SCH_1):PAGE48
   J37  249 DQS5_B_C||TDQS5_B_C SCONN288_DDR506112002KQ-SCONN288_DDR506112002KQ,SMA   I235 @T6G_MB_LIB.T6G(SCH_1):PAGE108

M_L_CPU1_SB_DQS_DN<6> @T6G_MB_LIB.T6G(SCH_1):M_L_CPU1_SB_DQS_DN(6)
   U26 CL10 MLB_DQS_L6 GENOA_SP5-SOCKET6096_13568-001,SMLF,IO,DGA^6000030   I159 @T6G_MB_LIB.T6G(SCH_1):PAGE48
   J37  260 DQS6_B_C||TDQS6_B_C SCONN288_DDR506112002KQ-SCONN288_DDR506112002KQ,SMA   I235 @T6G_MB_LIB.T6G(SCH_1):PAGE108

M_L_CPU1_SB_DQS_DN<7> @T6G_MB_LIB.T6G(SCH_1):M_L_CPU1_SB_DQS_DN(7)
   U26 CU10 MLB_DQS_L7 GENOA_SP5-SOCKET6096_13568-001,SMLF,IO,DGA^6000030   I159 @T6G_MB_LIB.T6G(SCH_1):PAGE48
   J37  271 DQS7_B_C||TDQS7_B_C SCONN288_DDR506112002KQ-SCONN288_DDR506112002KQ,SMA   I235 @T6G_MB_LIB.T6G(SCH_1):PAGE108

M_L_CPU1_SB_DQS_DN<8> @T6G_MB_LIB.T6G(SCH_1):M_L_CPU1_SB_DQS_DN(8)
   U26 DC10 MLB_DQS_L8 GENOA_SP5-SOCKET6096_13568-001,SMLF,IO,DGA^6000030   I159 @T6G_MB_LIB.T6G(SCH_1):PAGE48
   J37  282 DQS8_B_C||TDQS8_B_C SCONN288_DDR506112002KQ-SCONN288_DDR506112002KQ,SMA   I235 @T6G_MB_LIB.T6G(SCH_1):PAGE108

M_L_CPU1_SB_DQS_DN<9> @T6G_MB_LIB.T6G(SCH_1):M_L_CPU1_SB_DQS_DN(9)
   U26  BW9 MLB_DQS_L9 GENOA_SP5-SOCKET6096_13568-001,SMLF,IO,DGA^6000030   I159 @T6G_MB_LIB.T6G(SCH_1):PAGE48
   J37   94 DQS9_B_C||TDQS9_B_C SCONN288_DDR506112002KQ-SCONN288_DDR506112002KQ,SMA   I235 @T6G_MB_LIB.T6G(SCH_1):PAGE108

M_L_CPU1_SB_DQS_DP<0> @T6G_MB_LIB.T6G(SCH_1):M_L_CPU1_SB_DQS_DP(0)
   U26  CD9 MLB_DQS_H0 GENOA_SP5-SOCKET6096_13568-001,SMLF,IO,DGA^6000030   I159 @T6G_MB_LIB.T6G(SCH_1):PAGE48
   J37  104 DQS0_B_T SCONN288_DDR506112002KQ-SCONN288_DDR506112002KQ,SMA   I235 @T6G_MB_LIB.T6G(SCH_1):PAGE108

M_L_CPU1_SB_DQS_DP<1> @T6G_MB_LIB.T6G(SCH_1):M_L_CPU1_SB_DQS_DP(1)
   U26  CK9 MLB_DQS_H1 GENOA_SP5-SOCKET6096_13568-001,SMLF,IO,DGA^6000030   I159 @T6G_MB_LIB.T6G(SCH_1):PAGE48
   J37  115 DQS1_B_T SCONN288_DDR506112002KQ-SCONN288_DDR506112002KQ,SMA   I235 @T6G_MB_LIB.T6G(SCH_1):PAGE108

M_L_CPU1_SB_DQS_DP<2> @T6G_MB_LIB.T6G(SCH_1):M_L_CPU1_SB_DQS_DP(2)
   U26  CT9 MLB_DQS_H2 GENOA_SP5-SOCKET6096_13568-001,SMLF,IO,DGA^6000030   I159 @T6G_MB_LIB.T6G(SCH_1):PAGE48
   J37  126 DQS2_B_T SCONN288_DDR506112002KQ-SCONN288_DDR506112002KQ,SMA   I235 @T6G_MB_LIB.T6G(SCH_1):PAGE108

M_L_CPU1_SB_DQS_DP<3> @T6G_MB_LIB.T6G(SCH_1):M_L_CPU1_SB_DQS_DP(3)
   U26  DB9 MLB_DQS_H3 GENOA_SP5-SOCKET6096_13568-001,SMLF,IO,DGA^6000030   I159 @T6G_MB_LIB.T6G(SCH_1):PAGE48
   J37  137 DQS3_B_T SCONN288_DDR506112002KQ-SCONN288_DDR506112002KQ,SMA   I235 @T6G_MB_LIB.T6G(SCH_1):PAGE108

M_L_CPU1_SB_DQS_DP<4> @T6G_MB_LIB.T6G(SCH_1):M_L_CPU1_SB_DQS_DP(4)
   U26 BY11 MLB_DQS_H4 GENOA_SP5-SOCKET6096_13568-001,SMLF,IO,DGA^6000030   I159 @T6G_MB_LIB.T6G(SCH_1):PAGE48
   J37  239 DQS4_B_T SCONN288_DDR506112002KQ-SCONN288_DDR506112002KQ,SMA   I235 @T6G_MB_LIB.T6G(SCH_1):PAGE108

M_L_CPU1_SB_DQS_DP<5> @T6G_MB_LIB.T6G(SCH_1):M_L_CPU1_SB_DQS_DP(5)
   U26 CF11 MLB_DQS_H5 GENOA_SP5-SOCKET6096_13568-001,SMLF,IO,DGA^6000030   I159 @T6G_MB_LIB.T6G(SCH_1):PAGE48
   J37  250 DQS5_B_T||TDQS5_B_T SCONN288_DDR506112002KQ-SCONN288_DDR506112002KQ,SMA   I235 @T6G_MB_LIB.T6G(SCH_1):PAGE108

M_L_CPU1_SB_DQS_DP<6> @T6G_MB_LIB.T6G(SCH_1):M_L_CPU1_SB_DQS_DP(6)
   U26 CM11 MLB_DQS_H6 GENOA_SP5-SOCKET6096_13568-001,SMLF,IO,DGA^6000030   I159 @T6G_MB_LIB.T6G(SCH_1):PAGE48
   J37  261 DQS6_B_T||TDQS6_B_T SCONN288_DDR506112002KQ-SCONN288_DDR506112002KQ,SMA   I235 @T6G_MB_LIB.T6G(SCH_1):PAGE108

M_L_CPU1_SB_DQS_DP<7> @T6G_MB_LIB.T6G(SCH_1):M_L_CPU1_SB_DQS_DP(7)
   U26 CV11 MLB_DQS_H7 GENOA_SP5-SOCKET6096_13568-001,SMLF,IO,DGA^6000030   I159 @T6G_MB_LIB.T6G(SCH_1):PAGE48
   J37  272 DQS7_B_T||TDQS7_B_T SCONN288_DDR506112002KQ-SCONN288_DDR506112002KQ,SMA   I235 @T6G_MB_LIB.T6G(SCH_1):PAGE108

M_L_CPU1_SB_DQS_DP<8> @T6G_MB_LIB.T6G(SCH_1):M_L_CPU1_SB_DQS_DP(8)
   U26 DD11 MLB_DQS_H8 GENOA_SP5-SOCKET6096_13568-001,SMLF,IO,DGA^6000030   I159 @T6G_MB_LIB.T6G(SCH_1):PAGE48
   J37  283 DQS8_B_T||TDQS8_B_T SCONN288_DDR506112002KQ-SCONN288_DDR506112002KQ,SMA   I235 @T6G_MB_LIB.T6G(SCH_1):PAGE108

M_L_CPU1_SB_DQS_DP<9> @T6G_MB_LIB.T6G(SCH_1):M_L_CPU1_SB_DQS_DP(9)
   U26  BV9 MLB_DQS_H9 GENOA_SP5-SOCKET6096_13568-001,SMLF,IO,DGA^6000030   I159 @T6G_MB_LIB.T6G(SCH_1):PAGE48
   J37   93 DQS9_B_T||TDQS9_B_T||DBI4_B_N SCONN288_DDR506112002KQ-SCONN288_DDR506112002KQ,SMA   I235 @T6G_MB_LIB.T6G(SCH_1):PAGE108

M_L_CPU1_SB_PAR @T6G_MB_LIB.T6G(SCH_1):M_L_CPU1_SB_PAR
   U26 BL10 MLB_PAR GENOA_SP5-SOCKET6096_13568-001,SMLF,IO,DGA^6000030   I159 @T6G_MB_LIB.T6G(SCH_1):PAGE48
   J37  227  PAR_B SCONN288_DDR506112002KQ-SCONN288_DDR506112002KQ,SMA    I22 @T6G_MB_LIB.T6G(SCH_1):PAGE108

M_L_CPU1_SB_RSP<0> @T6G_MB_LIB.T6G(SCH_1):M_L_CPU1_SB_RSP(0)
   U26  BP9 MLB0_RSP_L GENOA_SP5-SOCKET6096_13568-001,SMLF,IO,DGA^6000030   I159 @T6G_MB_LIB.T6G(SCH_1):PAGE48
   J37   87 LBS||RSP_B_N SCONN288_DDR506112002KQ-SCONN288_DDR506112002KQ,SMA    I22 @T6G_MB_LIB.T6G(SCH_1):PAGE108

NC         NC
   U25 BF74 MA1_CLK_H GENOA_SP5-SOCKET6096_13568-001,SMLF,IO,DGA^6000030   I200 @T6G_MB_LIB.T6G(SCH_1):PAGE10
   U25 BG74 MA1_CLK_L GENOA_SP5-SOCKET6096_13568-001,SMLF,IO,DGA^6000030   I200 @T6G_MB_LIB.T6G(SCH_1):PAGE10
   U25 AU74 MAA1_CS_L0 GENOA_SP5-SOCKET6096_13568-001,SMLF,IO,DGA^6000030   I200 @T6G_MB_LIB.T6G(SCH_1):PAGE10
   U25 AV72 MAA1_CS_L1 GENOA_SP5-SOCKET6096_13568-001,SMLF,IO,DGA^6000030   I200 @T6G_MB_LIB.T6G(SCH_1):PAGE10
   U25 BP72 MAA1_RSP_L GENOA_SP5-SOCKET6096_13568-001,SMLF,IO,DGA^6000030   I200 @T6G_MB_LIB.T6G(SCH_1):PAGE10
   U25 BL73 MAB1_CS_L0 GENOA_SP5-SOCKET6096_13568-001,SMLF,IO,DGA^6000030   I200 @T6G_MB_LIB.T6G(SCH_1):PAGE10
   U25 BM74 MAB1_CS_L1 GENOA_SP5-SOCKET6096_13568-001,SMLF,IO,DGA^6000030   I200 @T6G_MB_LIB.T6G(SCH_1):PAGE10
   U25 BR74 MAB1_RSP_L GENOA_SP5-SOCKET6096_13568-001,SMLF,IO,DGA^6000030   I200 @T6G_MB_LIB.T6G(SCH_1):PAGE10
   U25 BF63 MB1_CLK_H GENOA_SP5-SOCKET6096_13568-001,SMLF,IO,DGA^6000030   I171 @T6G_MB_LIB.T6G(SCH_1):PAGE11
   U25 BG64 MB1_CLK_L GENOA_SP5-SOCKET6096_13568-001,SMLF,IO,DGA^6000030   I171 @T6G_MB_LIB.T6G(SCH_1):PAGE11
   U25 AU64 MBA1_CS_L0 GENOA_SP5-SOCKET6096_13568-001,SMLF,IO,DGA^6000030   I171 @T6G_MB_LIB.T6G(SCH_1):PAGE11
   U25 AV62 MBA1_CS_L1 GENOA_SP5-SOCKET6096_13568-001,SMLF,IO,DGA^6000030   I171 @T6G_MB_LIB.T6G(SCH_1):PAGE11
   U25 BP62 MBA1_RSP_L GENOA_SP5-SOCKET6096_13568-001,SMLF,IO,DGA^6000030   I171 @T6G_MB_LIB.T6G(SCH_1):PAGE11
   U25 BL62 MBB1_CS_L0 GENOA_SP5-SOCKET6096_13568-001,SMLF,IO,DGA^6000030   I171 @T6G_MB_LIB.T6G(SCH_1):PAGE11
   U25 BM63 MBB1_CS_L1 GENOA_SP5-SOCKET6096_13568-001,SMLF,IO,DGA^6000030   I171 @T6G_MB_LIB.T6G(SCH_1):PAGE11
   U25 BR64 MBB1_RSP_L GENOA_SP5-SOCKET6096_13568-001,SMLF,IO,DGA^6000030   I171 @T6G_MB_LIB.T6G(SCH_1):PAGE11
   U25 BF56 MC1_CLK_H GENOA_SP5-SOCKET6096_13568-001,SMLF,IO,DGA^6000030   I159 @T6G_MB_LIB.T6G(SCH_1):PAGE12
   U25 BG57 MC1_CLK_L GENOA_SP5-SOCKET6096_13568-001,SMLF,IO,DGA^6000030   I159 @T6G_MB_LIB.T6G(SCH_1):PAGE12
   U25 AU57 MCA1_CS_L0 GENOA_SP5-SOCKET6096_13568-001,SMLF,IO,DGA^6000030   I159 @T6G_MB_LIB.T6G(SCH_1):PAGE12
   U25 AV55 MCA1_CS_L1 GENOA_SP5-SOCKET6096_13568-001,SMLF,IO,DGA^6000030   I159 @T6G_MB_LIB.T6G(SCH_1):PAGE12
   U25 BP55 MCA1_RSP_L GENOA_SP5-SOCKET6096_13568-001,SMLF,IO,DGA^6000030   I159 @T6G_MB_LIB.T6G(SCH_1):PAGE12
   U25 BL55 MCB1_CS_L0 GENOA_SP5-SOCKET6096_13568-001,SMLF,IO,DGA^6000030   I159 @T6G_MB_LIB.T6G(SCH_1):PAGE12
   U25 BM56 MCB1_CS_L1 GENOA_SP5-SOCKET6096_13568-001,SMLF,IO,DGA^6000030   I159 @T6G_MB_LIB.T6G(SCH_1):PAGE12
   U25 BR57 MCB1_RSP_L GENOA_SP5-SOCKET6096_13568-001,SMLF,IO,DGA^6000030   I159 @T6G_MB_LIB.T6G(SCH_1):PAGE12
   U25 BF60 MD1_CLK_H GENOA_SP5-SOCKET6096_13568-001,SMLF,IO,DGA^6000030   I159 @T6G_MB_LIB.T6G(SCH_1):PAGE13
   U25 BG60 MD1_CLK_L GENOA_SP5-SOCKET6096_13568-001,SMLF,IO,DGA^6000030   I159 @T6G_MB_LIB.T6G(SCH_1):PAGE13
   U25 AU60 MDA1_CS_L0 GENOA_SP5-SOCKET6096_13568-001,SMLF,IO,DGA^6000030   I159 @T6G_MB_LIB.T6G(SCH_1):PAGE13
   U25 AV58 MDA1_CS_L1 GENOA_SP5-SOCKET6096_13568-001,SMLF,IO,DGA^6000030   I159 @T6G_MB_LIB.T6G(SCH_1):PAGE13
   U25 BP58 MDA1_RSP_L GENOA_SP5-SOCKET6096_13568-001,SMLF,IO,DGA^6000030   I159 @T6G_MB_LIB.T6G(SCH_1):PAGE13
   U25 BL59 MDB1_CS_L0 GENOA_SP5-SOCKET6096_13568-001,SMLF,IO,DGA^6000030   I159 @T6G_MB_LIB.T6G(SCH_1):PAGE13
   U25 BM60 MDB1_CS_L1 GENOA_SP5-SOCKET6096_13568-001,SMLF,IO,DGA^6000030   I159 @T6G_MB_LIB.T6G(SCH_1):PAGE13
   U25 BR60 MDB1_RSP_L GENOA_SP5-SOCKET6096_13568-001,SMLF,IO,DGA^6000030   I159 @T6G_MB_LIB.T6G(SCH_1):PAGE13
   U25 BF70 ME1_CLK_H GENOA_SP5-SOCKET6096_13568-001,SMLF,IO,DGA^6000030   I159 @T6G_MB_LIB.T6G(SCH_1):PAGE14
   U25 BG71 ME1_CLK_L GENOA_SP5-SOCKET6096_13568-001,SMLF,IO,DGA^6000030   I159 @T6G_MB_LIB.T6G(SCH_1):PAGE14
   U25 AU71 MEA1_CS_L0 GENOA_SP5-SOCKET6096_13568-001,SMLF,IO,DGA^6000030   I159 @T6G_MB_LIB.T6G(SCH_1):PAGE14
   U25 AV69 MEA1_CS_L1 GENOA_SP5-SOCKET6096_13568-001,SMLF,IO,DGA^6000030   I159 @T6G_MB_LIB.T6G(SCH_1):PAGE14
   U25 BP69 MEA1_RSP_L GENOA_SP5-SOCKET6096_13568-001,SMLF,IO,DGA^6000030   I159 @T6G_MB_LIB.T6G(SCH_1):PAGE14
   U25 BL69 MEB1_CS_L0 GENOA_SP5-SOCKET6096_13568-001,SMLF,IO,DGA^6000030   I159 @T6G_MB_LIB.T6G(SCH_1):PAGE14
   U25 BM70 MEB1_CS_L1 GENOA_SP5-SOCKET6096_13568-001,SMLF,IO,DGA^6000030   I159 @T6G_MB_LIB.T6G(SCH_1):PAGE14
   U25 BR71 MEB1_RSP_L GENOA_SP5-SOCKET6096_13568-001,SMLF,IO,DGA^6000030   I159 @T6G_MB_LIB.T6G(SCH_1):PAGE14
   U25 BF67 MF1_CLK_H GENOA_SP5-SOCKET6096_13568-001,SMLF,IO,DGA^6000030   I159 @T6G_MB_LIB.T6G(SCH_1):PAGE15
   U25 BG67 MF1_CLK_L GENOA_SP5-SOCKET6096_13568-001,SMLF,IO,DGA^6000030   I159 @T6G_MB_LIB.T6G(SCH_1):PAGE15
   U25 AU67 MFA1_CS_L0 GENOA_SP5-SOCKET6096_13568-001,SMLF,IO,DGA^6000030   I159 @T6G_MB_LIB.T6G(SCH_1):PAGE15
   U25 AV65 MFA1_CS_L1 GENOA_SP5-SOCKET6096_13568-001,SMLF,IO,DGA^6000030   I159 @T6G_MB_LIB.T6G(SCH_1):PAGE15
   U25 BP65 MFA1_RSP_L GENOA_SP5-SOCKET6096_13568-001,SMLF,IO,DGA^6000030   I159 @T6G_MB_LIB.T6G(SCH_1):PAGE15
   U25 BL66 MFB1_CS_L0 GENOA_SP5-SOCKET6096_13568-001,SMLF,IO,DGA^6000030   I159 @T6G_MB_LIB.T6G(SCH_1):PAGE15
   U25 BM67 MFB1_CS_L1 GENOA_SP5-SOCKET6096_13568-001,SMLF,IO,DGA^6000030   I159 @T6G_MB_LIB.T6G(SCH_1):PAGE15
   U25 BR67 MFB1_RSP_L GENOA_SP5-SOCKET6096_13568-001,SMLF,IO,DGA^6000030   I159 @T6G_MB_LIB.T6G(SCH_1):PAGE15
   U25  BF2 MG1_CLK_H GENOA_SP5-SOCKET6096_13568-001,SMLF,IO,DGA^6000030   I167 @T6G_MB_LIB.T6G(SCH_1):PAGE16
   U25  BG2 MG1_CLK_L GENOA_SP5-SOCKET6096_13568-001,SMLF,IO,DGA^6000030   I167 @T6G_MB_LIB.T6G(SCH_1):PAGE16
   U25  AV2 MGA1_CS_L0 GENOA_SP5-SOCKET6096_13568-001,SMLF,IO,DGA^6000030   I167 @T6G_MB_LIB.T6G(SCH_1):PAGE16
   U25  AW3 MGA1_CS_L1 GENOA_SP5-SOCKET6096_13568-001,SMLF,IO,DGA^6000030   I167 @T6G_MB_LIB.T6G(SCH_1):PAGE16
   U25  BP4 MGA1_RSP_L GENOA_SP5-SOCKET6096_13568-001,SMLF,IO,DGA^6000030   I167 @T6G_MB_LIB.T6G(SCH_1):PAGE16
   U25  BL2 MGB1_CS_L0 GENOA_SP5-SOCKET6096_13568-001,SMLF,IO,DGA^6000030   I167 @T6G_MB_LIB.T6G(SCH_1):PAGE16
   U25  BM2 MGB1_CS_L1 GENOA_SP5-SOCKET6096_13568-001,SMLF,IO,DGA^6000030   I167 @T6G_MB_LIB.T6G(SCH_1):PAGE16
   U25  BR2 MGB1_RSP_L GENOA_SP5-SOCKET6096_13568-001,SMLF,IO,DGA^6000030   I167 @T6G_MB_LIB.T6G(SCH_1):PAGE16
   U25 BF13 MH1_CLK_H GENOA_SP5-SOCKET6096_13568-001,SMLF,IO,DGA^6000030   I159 @T6G_MB_LIB.T6G(SCH_1):PAGE17
   U25 BG12 MH1_CLK_L GENOA_SP5-SOCKET6096_13568-001,SMLF,IO,DGA^6000030   I159 @T6G_MB_LIB.T6G(SCH_1):PAGE17
   U25 AV13 MHA1_CS_L0 GENOA_SP5-SOCKET6096_13568-001,SMLF,IO,DGA^6000030   I159 @T6G_MB_LIB.T6G(SCH_1):PAGE17
   U25 AW14 MHA1_CS_L1 GENOA_SP5-SOCKET6096_13568-001,SMLF,IO,DGA^6000030   I159 @T6G_MB_LIB.T6G(SCH_1):PAGE17
   U25 BP14 MHA1_RSP_L GENOA_SP5-SOCKET6096_13568-001,SMLF,IO,DGA^6000030   I159 @T6G_MB_LIB.T6G(SCH_1):PAGE17
   U25 BL12 MHB1_CS_L0 GENOA_SP5-SOCKET6096_13568-001,SMLF,IO,DGA^6000030   I159 @T6G_MB_LIB.T6G(SCH_1):PAGE17
   U25 BM13 MHB1_CS_L1 GENOA_SP5-SOCKET6096_13568-001,SMLF,IO,DGA^6000030   I159 @T6G_MB_LIB.T6G(SCH_1):PAGE17
   U25 BR12 MHB1_RSP_L GENOA_SP5-SOCKET6096_13568-001,SMLF,IO,DGA^6000030   I159 @T6G_MB_LIB.T6G(SCH_1):PAGE17
   U25 BF20 MI1_CLK_H GENOA_SP5-SOCKET6096_13568-001,SMLF,IO,DGA^6000030   I159 @T6G_MB_LIB.T6G(SCH_1):PAGE18
   U25 BG19 MI1_CLK_L GENOA_SP5-SOCKET6096_13568-001,SMLF,IO,DGA^6000030   I159 @T6G_MB_LIB.T6G(SCH_1):PAGE18
   U25 AV20 MIA1_CS_L0 GENOA_SP5-SOCKET6096_13568-001,SMLF,IO,DGA^6000030   I159 @T6G_MB_LIB.T6G(SCH_1):PAGE18
   U25 AW21 MIA1_CS_L1 GENOA_SP5-SOCKET6096_13568-001,SMLF,IO,DGA^6000030   I159 @T6G_MB_LIB.T6G(SCH_1):PAGE18
   U25 BP21 MIA1_RSP_L GENOA_SP5-SOCKET6096_13568-001,SMLF,IO,DGA^6000030   I159 @T6G_MB_LIB.T6G(SCH_1):PAGE18
   U25 BL19 MIB1_CS_L0 GENOA_SP5-SOCKET6096_13568-001,SMLF,IO,DGA^6000030   I159 @T6G_MB_LIB.T6G(SCH_1):PAGE18
   U25 BM20 MIB1_CS_L1 GENOA_SP5-SOCKET6096_13568-001,SMLF,IO,DGA^6000030   I159 @T6G_MB_LIB.T6G(SCH_1):PAGE18
   U25 BR19 MIB1_RSP_L GENOA_SP5-SOCKET6096_13568-001,SMLF,IO,DGA^6000030   I159 @T6G_MB_LIB.T6G(SCH_1):PAGE18
   U25 BF16 MJ1_CLK_H GENOA_SP5-SOCKET6096_13568-001,SMLF,IO,DGA^6000030   I159 @T6G_MB_LIB.T6G(SCH_1):PAGE19
   U25 BG16 MJ1_CLK_L GENOA_SP5-SOCKET6096_13568-001,SMLF,IO,DGA^6000030   I159 @T6G_MB_LIB.T6G(SCH_1):PAGE19
   U25 AV16 MJA1_CS_L0 GENOA_SP5-SOCKET6096_13568-001,SMLF,IO,DGA^6000030   I159 @T6G_MB_LIB.T6G(SCH_1):PAGE19
   U25 AW17 MJA1_CS_L1 GENOA_SP5-SOCKET6096_13568-001,SMLF,IO,DGA^6000030   I159 @T6G_MB_LIB.T6G(SCH_1):PAGE19
   U25 BP18 MJA1_RSP_L GENOA_SP5-SOCKET6096_13568-001,SMLF,IO,DGA^6000030   I159 @T6G_MB_LIB.T6G(SCH_1):PAGE19
   U25 BL16 MJB1_CS_L0 GENOA_SP5-SOCKET6096_13568-001,SMLF,IO,DGA^6000030   I159 @T6G_MB_LIB.T6G(SCH_1):PAGE19
   U25 BM16 MJB1_CS_L1 GENOA_SP5-SOCKET6096_13568-001,SMLF,IO,DGA^6000030   I159 @T6G_MB_LIB.T6G(SCH_1):PAGE19
   U25 BR16 MJB1_RSP_L GENOA_SP5-SOCKET6096_13568-001,SMLF,IO,DGA^6000030   I159 @T6G_MB_LIB.T6G(SCH_1):PAGE19
   U25  BF6 MK1_CLK_H GENOA_SP5-SOCKET6096_13568-001,SMLF,IO,DGA^6000030   I159 @T6G_MB_LIB.T6G(SCH_1):PAGE20
   U25  BG5 MK1_CLK_L GENOA_SP5-SOCKET6096_13568-001,SMLF,IO,DGA^6000030   I159 @T6G_MB_LIB.T6G(SCH_1):PAGE20
   U25  AV6 MKA1_CS_L0 GENOA_SP5-SOCKET6096_13568-001,SMLF,IO,DGA^6000030   I159 @T6G_MB_LIB.T6G(SCH_1):PAGE20
   U25  AW7 MKA1_CS_L1 GENOA_SP5-SOCKET6096_13568-001,SMLF,IO,DGA^6000030   I159 @T6G_MB_LIB.T6G(SCH_1):PAGE20
   U25  BP7 MKA1_RSP_L GENOA_SP5-SOCKET6096_13568-001,SMLF,IO,DGA^6000030   I159 @T6G_MB_LIB.T6G(SCH_1):PAGE20
   U25  BL5 MKB1_CS_L0 GENOA_SP5-SOCKET6096_13568-001,SMLF,IO,DGA^6000030   I159 @T6G_MB_LIB.T6G(SCH_1):PAGE20
   U25  BM6 MKB1_CS_L1 GENOA_SP5-SOCKET6096_13568-001,SMLF,IO,DGA^6000030   I159 @T6G_MB_LIB.T6G(SCH_1):PAGE20
   U25  BR5 MKB1_RSP_L GENOA_SP5-SOCKET6096_13568-001,SMLF,IO,DGA^6000030   I159 @T6G_MB_LIB.T6G(SCH_1):PAGE20
   U25  BF9 ML1_CLK_H GENOA_SP5-SOCKET6096_13568-001,SMLF,IO,DGA^6000030   I159 @T6G_MB_LIB.T6G(SCH_1):PAGE21
   U25  BG9 ML1_CLK_L GENOA_SP5-SOCKET6096_13568-001,SMLF,IO,DGA^6000030   I159 @T6G_MB_LIB.T6G(SCH_1):PAGE21
   U25  AV9 MLA1_CS_L0 GENOA_SP5-SOCKET6096_13568-001,SMLF,IO,DGA^6000030   I159 @T6G_MB_LIB.T6G(SCH_1):PAGE21
   U25 AW10 MLA1_CS_L1 GENOA_SP5-SOCKET6096_13568-001,SMLF,IO,DGA^6000030   I159 @T6G_MB_LIB.T6G(SCH_1):PAGE21
   U25 BP11 MLA1_RSP_L GENOA_SP5-SOCKET6096_13568-001,SMLF,IO,DGA^6000030   I159 @T6G_MB_LIB.T6G(SCH_1):PAGE21
   U25  BL9 MLB1_CS_L0 GENOA_SP5-SOCKET6096_13568-001,SMLF,IO,DGA^6000030   I159 @T6G_MB_LIB.T6G(SCH_1):PAGE21
   U25  BM9 MLB1_CS_L1 GENOA_SP5-SOCKET6096_13568-001,SMLF,IO,DGA^6000030   I159 @T6G_MB_LIB.T6G(SCH_1):PAGE21
   U25  BR9 MLB1_RSP_L GENOA_SP5-SOCKET6096_13568-001,SMLF,IO,DGA^6000030   I159 @T6G_MB_LIB.T6G(SCH_1):PAGE21
   U25  E41 P5_RXN3 GENOA_SP5-SOCKET6096_13568-001,SMLF,IO,DGA^6000030    I59 @T6G_MB_LIB.T6G(SCH_1):PAGE26
   U25  E40 P5_RXP3 GENOA_SP5-SOCKET6096_13568-001,SMLF,IO,DGA^6000030    I59 @T6G_MB_LIB.T6G(SCH_1):PAGE26
   U25  C42 P5_TXN3 GENOA_SP5-SOCKET6096_13568-001,SMLF,IO,DGA^6000030    I59 @T6G_MB_LIB.T6G(SCH_1):PAGE26
   U25  C41 P5_TXP3 GENOA_SP5-SOCKET6096_13568-001,SMLF,IO,DGA^6000030    I59 @T6G_MB_LIB.T6G(SCH_1):PAGE26
   U25  E47 WAFL_RXN1||P5_RXN1 GENOA_SP5-SOCKET6096_13568-001,SMLF,IO,DGA^6000030    I59 @T6G_MB_LIB.T6G(SCH_1):PAGE26
   U25  E46 WAFL_RXP1||P5_RXP1 GENOA_SP5-SOCKET6096_13568-001,SMLF,IO,DGA^6000030    I59 @T6G_MB_LIB.T6G(SCH_1):PAGE26
   U25  C48 WAFL_TXN1||P5_TXN1 GENOA_SP5-SOCKET6096_13568-001,SMLF,IO,DGA^6000030    I59 @T6G_MB_LIB.T6G(SCH_1):PAGE26
   U25  C47 WAFL_TXP1||P5_TXP1 GENOA_SP5-SOCKET6096_13568-001,SMLF,IO,DGA^6000030    I59 @T6G_MB_LIB.T6G(SCH_1):PAGE26
   U25  E24 USB01_OC_L||AGPIO265 GENOA_SP5-SOCKET6096_13568-001,SMLF,IO,DGA^6000030   I287 @T6G_MB_LIB.T6G(SCH_1):PAGE29
   U25  C28 USB01_RXN GENOA_SP5-SOCKET6096_13568-001,SMLF,IO,DGA^6000030   I287 @T6G_MB_LIB.T6G(SCH_1):PAGE29
   U25  C29 USB01_RXP GENOA_SP5-SOCKET6096_13568-001,SMLF,IO,DGA^6000030   I287 @T6G_MB_LIB.T6G(SCH_1):PAGE29
   U25  E29 USB01_TXN GENOA_SP5-SOCKET6096_13568-001,SMLF,IO,DGA^6000030   I287 @T6G_MB_LIB.T6G(SCH_1):PAGE29
   U25  E30 USB01_TXP GENOA_SP5-SOCKET6096_13568-001,SMLF,IO,DGA^6000030   I287 @T6G_MB_LIB.T6G(SCH_1):PAGE29
   U25 DG40 USB10_OC_L||AGPIO16 GENOA_SP5-SOCKET6096_13568-001,SMLF,IO,DGA^6000030   I287 @T6G_MB_LIB.T6G(SCH_1):PAGE29
   U25 DH65 USB10_RXN GENOA_SP5-SOCKET6096_13568-001,SMLF,IO,DGA^6000030   I287 @T6G_MB_LIB.T6G(SCH_1):PAGE29
   U25 DJ65 USB10_RXP GENOA_SP5-SOCKET6096_13568-001,SMLF,IO,DGA^6000030   I287 @T6G_MB_LIB.T6G(SCH_1):PAGE29
   U25 DJ69 USB10_TXN GENOA_SP5-SOCKET6096_13568-001,SMLF,IO,DGA^6000030   I287 @T6G_MB_LIB.T6G(SCH_1):PAGE29
   U25 DH69 USB10_TXP GENOA_SP5-SOCKET6096_13568-001,SMLF,IO,DGA^6000030   I287 @T6G_MB_LIB.T6G(SCH_1):PAGE29
   U25 DH40 USB11_OC_L||AGPIO17 GENOA_SP5-SOCKET6096_13568-001,SMLF,IO,DGA^6000030   I287 @T6G_MB_LIB.T6G(SCH_1):PAGE29
   U25 DH62 USB11_RXN GENOA_SP5-SOCKET6096_13568-001,SMLF,IO,DGA^6000030   I287 @T6G_MB_LIB.T6G(SCH_1):PAGE29
   U25 DJ62 USB11_RXP GENOA_SP5-SOCKET6096_13568-001,SMLF,IO,DGA^6000030   I287 @T6G_MB_LIB.T6G(SCH_1):PAGE29
   U25 DH58 USB11_TXN GENOA_SP5-SOCKET6096_13568-001,SMLF,IO,DGA^6000030   I287 @T6G_MB_LIB.T6G(SCH_1):PAGE29
   U25 DG58 USB11_TXP GENOA_SP5-SOCKET6096_13568-001,SMLF,IO,DGA^6000030   I287 @T6G_MB_LIB.T6G(SCH_1):PAGE29
    U3    1     NC SN74LVC1G07DBVR_SMLF-SN74LVC1G07DBVR,IC,AL1G0007024   I373 @T6G_MB_LIB.T6G(SCH_1):PAGE29
   U25  A31 RSVD_A31 GENOA_SP5-SOCKET6096_13568-001,SMLF,IO,DGA^6000030    I29 @T6G_MB_LIB.T6G(SCH_1):PAGE30
   U25  A35 RSVD_A35 GENOA_SP5-SOCKET6096_13568-001,SMLF,IO,DGA^6000030    I29 @T6G_MB_LIB.T6G(SCH_1):PAGE30
   U25  A41 RSVD_A41 GENOA_SP5-SOCKET6096_13568-001,SMLF,IO,DGA^6000030    I29 @T6G_MB_LIB.T6G(SCH_1):PAGE30
   U25  A42 RSVD_A42 GENOA_SP5-SOCKET6096_13568-001,SMLF,IO,DGA^6000030    I29 @T6G_MB_LIB.T6G(SCH_1):PAGE30
   U25  A45 RSVD_A45 GENOA_SP5-SOCKET6096_13568-001,SMLF,IO,DGA^6000030    I29 @T6G_MB_LIB.T6G(SCH_1):PAGE30
   U25  A48 RSVD_A48 GENOA_SP5-SOCKET6096_13568-001,SMLF,IO,DGA^6000030    I29 @T6G_MB_LIB.T6G(SCH_1):PAGE30
   U25  A50 RSVD_A50 GENOA_SP5-SOCKET6096_13568-001,SMLF,IO,DGA^6000030    I29 @T6G_MB_LIB.T6G(SCH_1):PAGE30
   U25  A51 RSVD_A51 GENOA_SP5-SOCKET6096_13568-001,SMLF,IO,DGA^6000030    I29 @T6G_MB_LIB.T6G(SCH_1):PAGE30
   U25  A54 RSVD_A54 GENOA_SP5-SOCKET6096_13568-001,SMLF,IO,DGA^6000030    I29 @T6G_MB_LIB.T6G(SCH_1):PAGE30
   U25  A55 RSVD_A55 GENOA_SP5-SOCKET6096_13568-001,SMLF,IO,DGA^6000030    I29 @T6G_MB_LIB.T6G(SCH_1):PAGE30
   U25  A56 RSVD_A56 GENOA_SP5-SOCKET6096_13568-001,SMLF,IO,DGA^6000030    I29 @T6G_MB_LIB.T6G(SCH_1):PAGE30
   U25  A57 RSVD_A57 GENOA_SP5-SOCKET6096_13568-001,SMLF,IO,DGA^6000030    I29 @T6G_MB_LIB.T6G(SCH_1):PAGE30
   U25  A59 RSVD_A59 GENOA_SP5-SOCKET6096_13568-001,SMLF,IO,DGA^6000030    I29 @T6G_MB_LIB.T6G(SCH_1):PAGE30
   U25  A60 RSVD_A60 GENOA_SP5-SOCKET6096_13568-001,SMLF,IO,DGA^6000030    I29 @T6G_MB_LIB.T6G(SCH_1):PAGE30
   U25  B40 RSVD_B40 GENOA_SP5-SOCKET6096_13568-001,SMLF,IO,DGA^6000030    I29 @T6G_MB_LIB.T6G(SCH_1):PAGE30
   U25  BD4 RSVD_BD4 GENOA_SP5-SOCKET6096_13568-001,SMLF,IO,DGA^6000030    I29 @T6G_MB_LIB.T6G(SCH_1):PAGE30
   U25  BD7 RSVD_BD7 GENOA_SP5-SOCKET6096_13568-001,SMLF,IO,DGA^6000030    I29 @T6G_MB_LIB.T6G(SCH_1):PAGE30
   U25 BD11 RSVD_BD11 GENOA_SP5-SOCKET6096_13568-001,SMLF,IO,DGA^6000030    I29 @T6G_MB_LIB.T6G(SCH_1):PAGE30
   U25 BD14 RSVD_BD14 GENOA_SP5-SOCKET6096_13568-001,SMLF,IO,DGA^6000030    I29 @T6G_MB_LIB.T6G(SCH_1):PAGE30
   U25 BD18 RSVD_BD18 GENOA_SP5-SOCKET6096_13568-001,SMLF,IO,DGA^6000030    I29 @T6G_MB_LIB.T6G(SCH_1):PAGE30
   U25 BD21 RSVD_BD21 GENOA_SP5-SOCKET6096_13568-001,SMLF,IO,DGA^6000030    I29 @T6G_MB_LIB.T6G(SCH_1):PAGE30
   U25 BD55 RSVD_BD55 GENOA_SP5-SOCKET6096_13568-001,SMLF,IO,DGA^6000030    I29 @T6G_MB_LIB.T6G(SCH_1):PAGE30
   U25 BD58 RSVD_BD58 GENOA_SP5-SOCKET6096_13568-001,SMLF,IO,DGA^6000030    I29 @T6G_MB_LIB.T6G(SCH_1):PAGE30
   U25 BD62 RSVD_BD62 GENOA_SP5-SOCKET6096_13568-001,SMLF,IO,DGA^6000030    I29 @T6G_MB_LIB.T6G(SCH_1):PAGE30
   U25 BD65 RSVD_BD65 GENOA_SP5-SOCKET6096_13568-001,SMLF,IO,DGA^6000030    I29 @T6G_MB_LIB.T6G(SCH_1):PAGE30
   U25 BD69 RSVD_BD69 GENOA_SP5-SOCKET6096_13568-001,SMLF,IO,DGA^6000030    I29 @T6G_MB_LIB.T6G(SCH_1):PAGE30
   U25 BD72 RSVD_BD72 GENOA_SP5-SOCKET6096_13568-001,SMLF,IO,DGA^6000030    I29 @T6G_MB_LIB.T6G(SCH_1):PAGE30
   U25  C31 RSVD_C31 GENOA_SP5-SOCKET6096_13568-001,SMLF,IO,DGA^6000030    I29 @T6G_MB_LIB.T6G(SCH_1):PAGE30
   U25  C34 RSVD_C34 GENOA_SP5-SOCKET6096_13568-001,SMLF,IO,DGA^6000030    I29 @T6G_MB_LIB.T6G(SCH_1):PAGE30
   U25  C35 RSVD_C35 GENOA_SP5-SOCKET6096_13568-001,SMLF,IO,DGA^6000030    I29 @T6G_MB_LIB.T6G(SCH_1):PAGE30
   U25  C53 RSVD_C53 GENOA_SP5-SOCKET6096_13568-001,SMLF,IO,DGA^6000030    I29 @T6G_MB_LIB.T6G(SCH_1):PAGE30
   U25  C54 RSVD_C54 GENOA_SP5-SOCKET6096_13568-001,SMLF,IO,DGA^6000030    I29 @T6G_MB_LIB.T6G(SCH_1):PAGE30
   U25   D4 RSVD_D4 GENOA_SP5-SOCKET6096_13568-001,SMLF,IO,DGA^6000030    I29 @T6G_MB_LIB.T6G(SCH_1):PAGE30
   U25   D8 RSVD_D8 GENOA_SP5-SOCKET6096_13568-001,SMLF,IO,DGA^6000030    I29 @T6G_MB_LIB.T6G(SCH_1):PAGE30
   U25  D11 RSVD_D11 GENOA_SP5-SOCKET6096_13568-001,SMLF,IO,DGA^6000030    I29 @T6G_MB_LIB.T6G(SCH_1):PAGE30
   U25  D22 RSVD_D22 GENOA_SP5-SOCKET6096_13568-001,SMLF,IO,DGA^6000030    I29 @T6G_MB_LIB.T6G(SCH_1):PAGE30
   U25  D34 RSVD_D34 GENOA_SP5-SOCKET6096_13568-001,SMLF,IO,DGA^6000030    I29 @T6G_MB_LIB.T6G(SCH_1):PAGE30
   U25  D36 RSVD_D36 GENOA_SP5-SOCKET6096_13568-001,SMLF,IO,DGA^6000030    I29 @T6G_MB_LIB.T6G(SCH_1):PAGE30
   U25  D58 RSVD_D58 GENOA_SP5-SOCKET6096_13568-001,SMLF,IO,DGA^6000030    I29 @T6G_MB_LIB.T6G(SCH_1):PAGE30
   U25  D62 RSVD_D62 GENOA_SP5-SOCKET6096_13568-001,SMLF,IO,DGA^6000030    I29 @T6G_MB_LIB.T6G(SCH_1):PAGE30
   U25  D65 RSVD_D65 GENOA_SP5-SOCKET6096_13568-001,SMLF,IO,DGA^6000030    I29 @T6G_MB_LIB.T6G(SCH_1):PAGE30
   U25  D72 RSVD_D72 GENOA_SP5-SOCKET6096_13568-001,SMLF,IO,DGA^6000030    I29 @T6G_MB_LIB.T6G(SCH_1):PAGE30
   U25 DG17 RSVD_DG17 GENOA_SP5-SOCKET6096_13568-001,SMLF,IO,DGA^6000030    I29 @T6G_MB_LIB.T6G(SCH_1):PAGE30
   U25 DH17 RSVD_DH17 GENOA_SP5-SOCKET6096_13568-001,SMLF,IO,DGA^6000030    I29 @T6G_MB_LIB.T6G(SCH_1):PAGE30
   U25 DH21 RSVD_DH21 GENOA_SP5-SOCKET6096_13568-001,SMLF,IO,DGA^6000030    I29 @T6G_MB_LIB.T6G(SCH_1):PAGE30
   U25  DJ4 RSVD_DJ4 GENOA_SP5-SOCKET6096_13568-001,SMLF,IO,DGA^6000030    I29 @T6G_MB_LIB.T6G(SCH_1):PAGE30
   U25  E33 RSVD_E33 GENOA_SP5-SOCKET6096_13568-001,SMLF,IO,DGA^6000030    I29 @T6G_MB_LIB.T6G(SCH_1):PAGE30
   U25  E36 RSVD_E36 GENOA_SP5-SOCKET6096_13568-001,SMLF,IO,DGA^6000030    I29 @T6G_MB_LIB.T6G(SCH_1):PAGE30
   U25  C58 TEST4_CCD12 GENOA_SP5-SOCKET6096_13568-001,SMLF,IO,DGA^6000030    I29 @T6G_MB_LIB.T6G(SCH_1):PAGE30
   U25 DH13 TEST4_CCD13 GENOA_SP5-SOCKET6096_13568-001,SMLF,IO,DGA^6000030    I29 @T6G_MB_LIB.T6G(SCH_1):PAGE30
   U25 DF41 TEST4_CCD14 GENOA_SP5-SOCKET6096_13568-001,SMLF,IO,DGA^6000030    I29 @T6G_MB_LIB.T6G(SCH_1):PAGE30
   U25  C23 TEST4_CCD15 GENOA_SP5-SOCKET6096_13568-001,SMLF,IO,DGA^6000030    I29 @T6G_MB_LIB.T6G(SCH_1):PAGE30
   U25  C59 TEST5_CCD12 GENOA_SP5-SOCKET6096_13568-001,SMLF,IO,DGA^6000030    I29 @T6G_MB_LIB.T6G(SCH_1):PAGE30
   U25 DH14 TEST5_CCD13 GENOA_SP5-SOCKET6096_13568-001,SMLF,IO,DGA^6000030    I29 @T6G_MB_LIB.T6G(SCH_1):PAGE30
   U25 DG42 TEST5_CCD14 GENOA_SP5-SOCKET6096_13568-001,SMLF,IO,DGA^6000030    I29 @T6G_MB_LIB.T6G(SCH_1):PAGE30
   U25  D23 TEST5_CCD15 GENOA_SP5-SOCKET6096_13568-001,SMLF,IO,DGA^6000030    I29 @T6G_MB_LIB.T6G(SCH_1):PAGE30
   U25  B36 TEST6_X3D6 GENOA_SP5-SOCKET6096_13568-001,SMLF,IO,DGA^6000030    I29 @T6G_MB_LIB.T6G(SCH_1):PAGE30
   U25 DJ57 TEST6_X3D7 GENOA_SP5-SOCKET6096_13568-001,SMLF,IO,DGA^6000030    I29 @T6G_MB_LIB.T6G(SCH_1):PAGE30
  U101    1     NC SN74LVC1G07DBVR_SMLF-SN74LVC1G07DBVR,IC,AL1G0007024    I55 @T6G_MB_LIB.T6G(SCH_1):PAGE34
   U26 BF74 MA1_CLK_H GENOA_SP5-SOCKET6096_13568-001,SMLF,IO,DGA^6000030   I167 @T6G_MB_LIB.T6G(SCH_1):PAGE37
   U26 BG74 MA1_CLK_L GENOA_SP5-SOCKET6096_13568-001,SMLF,IO,DGA^6000030   I167 @T6G_MB_LIB.T6G(SCH_1):PAGE37
   U26 AU74 MAA1_CS_L0 GENOA_SP5-SOCKET6096_13568-001,SMLF,IO,DGA^6000030   I167 @T6G_MB_LIB.T6G(SCH_1):PAGE37
   U26 AV72 MAA1_CS_L1 GENOA_SP5-SOCKET6096_13568-001,SMLF,IO,DGA^6000030   I167 @T6G_MB_LIB.T6G(SCH_1):PAGE37
   U26 BP72 MAA1_RSP_L GENOA_SP5-SOCKET6096_13568-001,SMLF,IO,DGA^6000030   I167 @T6G_MB_LIB.T6G(SCH_1):PAGE37
   U26 BL73 MAB1_CS_L0 GENOA_SP5-SOCKET6096_13568-001,SMLF,IO,DGA^6000030   I167 @T6G_MB_LIB.T6G(SCH_1):PAGE37
   U26 BM74 MAB1_CS_L1 GENOA_SP5-SOCKET6096_13568-001,SMLF,IO,DGA^6000030   I167 @T6G_MB_LIB.T6G(SCH_1):PAGE37
   U26 BR74 MAB1_RSP_L GENOA_SP5-SOCKET6096_13568-001,SMLF,IO,DGA^6000030   I167 @T6G_MB_LIB.T6G(SCH_1):PAGE37
   U26 BF63 MB1_CLK_H GENOA_SP5-SOCKET6096_13568-001,SMLF,IO,DGA^6000030   I159 @T6G_MB_LIB.T6G(SCH_1):PAGE38
   U26 BG64 MB1_CLK_L GENOA_SP5-SOCKET6096_13568-001,SMLF,IO,DGA^6000030   I159 @T6G_MB_LIB.T6G(SCH_1):PAGE38
   U26 AU64 MBA1_CS_L0 GENOA_SP5-SOCKET6096_13568-001,SMLF,IO,DGA^6000030   I159 @T6G_MB_LIB.T6G(SCH_1):PAGE38
   U26 AV62 MBA1_CS_L1 GENOA_SP5-SOCKET6096_13568-001,SMLF,IO,DGA^6000030   I159 @T6G_MB_LIB.T6G(SCH_1):PAGE38
   U26 BP62 MBA1_RSP_L GENOA_SP5-SOCKET6096_13568-001,SMLF,IO,DGA^6000030   I159 @T6G_MB_LIB.T6G(SCH_1):PAGE38
   U26 BL62 MBB1_CS_L0 GENOA_SP5-SOCKET6096_13568-001,SMLF,IO,DGA^6000030   I159 @T6G_MB_LIB.T6G(SCH_1):PAGE38
   U26 BM63 MBB1_CS_L1 GENOA_SP5-SOCKET6096_13568-001,SMLF,IO,DGA^6000030   I159 @T6G_MB_LIB.T6G(SCH_1):PAGE38
   U26 BR64 MBB1_RSP_L GENOA_SP5-SOCKET6096_13568-001,SMLF,IO,DGA^6000030   I159 @T6G_MB_LIB.T6G(SCH_1):PAGE38
   U26 BF56 MC1_CLK_H GENOA_SP5-SOCKET6096_13568-001,SMLF,IO,DGA^6000030   I159 @T6G_MB_LIB.T6G(SCH_1):PAGE39
   U26 BG57 MC1_CLK_L GENOA_SP5-SOCKET6096_13568-001,SMLF,IO,DGA^6000030   I159 @T6G_MB_LIB.T6G(SCH_1):PAGE39
   U26 AU57 MCA1_CS_L0 GENOA_SP5-SOCKET6096_13568-001,SMLF,IO,DGA^6000030   I159 @T6G_MB_LIB.T6G(SCH_1):PAGE39
   U26 AV55 MCA1_CS_L1 GENOA_SP5-SOCKET6096_13568-001,SMLF,IO,DGA^6000030   I159 @T6G_MB_LIB.T6G(SCH_1):PAGE39
   U26 BP55 MCA1_RSP_L GENOA_SP5-SOCKET6096_13568-001,SMLF,IO,DGA^6000030   I159 @T6G_MB_LIB.T6G(SCH_1):PAGE39
   U26 BL55 MCB1_CS_L0 GENOA_SP5-SOCKET6096_13568-001,SMLF,IO,DGA^6000030   I159 @T6G_MB_LIB.T6G(SCH_1):PAGE39
   U26 BM56 MCB1_CS_L1 GENOA_SP5-SOCKET6096_13568-001,SMLF,IO,DGA^6000030   I159 @T6G_MB_LIB.T6G(SCH_1):PAGE39
   U26 BR57 MCB1_RSP_L GENOA_SP5-SOCKET6096_13568-001,SMLF,IO,DGA^6000030   I159 @T6G_MB_LIB.T6G(SCH_1):PAGE39
   U26 BF60 MD1_CLK_H GENOA_SP5-SOCKET6096_13568-001,SMLF,IO,DGA^6000030   I159 @T6G_MB_LIB.T6G(SCH_1):PAGE40
   U26 BG60 MD1_CLK_L GENOA_SP5-SOCKET6096_13568-001,SMLF,IO,DGA^6000030   I159 @T6G_MB_LIB.T6G(SCH_1):PAGE40
   U26 AU60 MDA1_CS_L0 GENOA_SP5-SOCKET6096_13568-001,SMLF,IO,DGA^6000030   I159 @T6G_MB_LIB.T6G(SCH_1):PAGE40
   U26 AV58 MDA1_CS_L1 GENOA_SP5-SOCKET6096_13568-001,SMLF,IO,DGA^6000030   I159 @T6G_MB_LIB.T6G(SCH_1):PAGE40
   U26 BP58 MDA1_RSP_L GENOA_SP5-SOCKET6096_13568-001,SMLF,IO,DGA^6000030   I159 @T6G_MB_LIB.T6G(SCH_1):PAGE40
   U26 BL59 MDB1_CS_L0 GENOA_SP5-SOCKET6096_13568-001,SMLF,IO,DGA^6000030   I159 @T6G_MB_LIB.T6G(SCH_1):PAGE40
   U26 BM60 MDB1_CS_L1 GENOA_SP5-SOCKET6096_13568-001,SMLF,IO,DGA^6000030   I159 @T6G_MB_LIB.T6G(SCH_1):PAGE40
   U26 BR60 MDB1_RSP_L GENOA_SP5-SOCKET6096_13568-001,SMLF,IO,DGA^6000030   I159 @T6G_MB_LIB.T6G(SCH_1):PAGE40
   U26 BF70 ME1_CLK_H GENOA_SP5-SOCKET6096_13568-001,SMLF,IO,DGA^6000030   I159 @T6G_MB_LIB.T6G(SCH_1):PAGE41
   U26 BG71 ME1_CLK_L GENOA_SP5-SOCKET6096_13568-001,SMLF,IO,DGA^6000030   I159 @T6G_MB_LIB.T6G(SCH_1):PAGE41
   U26 AU71 MEA1_CS_L0 GENOA_SP5-SOCKET6096_13568-001,SMLF,IO,DGA^6000030   I159 @T6G_MB_LIB.T6G(SCH_1):PAGE41
   U26 AV69 MEA1_CS_L1 GENOA_SP5-SOCKET6096_13568-001,SMLF,IO,DGA^6000030   I159 @T6G_MB_LIB.T6G(SCH_1):PAGE41
   U26 BP69 MEA1_RSP_L GENOA_SP5-SOCKET6096_13568-001,SMLF,IO,DGA^6000030   I159 @T6G_MB_LIB.T6G(SCH_1):PAGE41
   U26 BL69 MEB1_CS_L0 GENOA_SP5-SOCKET6096_13568-001,SMLF,IO,DGA^6000030   I159 @T6G_MB_LIB.T6G(SCH_1):PAGE41
   U26 BM70 MEB1_CS_L1 GENOA_SP5-SOCKET6096_13568-001,SMLF,IO,DGA^6000030   I159 @T6G_MB_LIB.T6G(SCH_1):PAGE41
   U26 BR71 MEB1_RSP_L GENOA_SP5-SOCKET6096_13568-001,SMLF,IO,DGA^6000030   I159 @T6G_MB_LIB.T6G(SCH_1):PAGE41
   U26 BF67 MF1_CLK_H GENOA_SP5-SOCKET6096_13568-001,SMLF,IO,DGA^6000030   I159 @T6G_MB_LIB.T6G(SCH_1):PAGE42
   U26 BG67 MF1_CLK_L GENOA_SP5-SOCKET6096_13568-001,SMLF,IO,DGA^6000030   I159 @T6G_MB_LIB.T6G(SCH_1):PAGE42
   U26 AU67 MFA1_CS_L0 GENOA_SP5-SOCKET6096_13568-001,SMLF,IO,DGA^6000030   I159 @T6G_MB_LIB.T6G(SCH_1):PAGE42
   U26 AV65 MFA1_CS_L1 GENOA_SP5-SOCKET6096_13568-001,SMLF,IO,DGA^6000030   I159 @T6G_MB_LIB.T6G(SCH_1):PAGE42
   U26 BP65 MFA1_RSP_L GENOA_SP5-SOCKET6096_13568-001,SMLF,IO,DGA^6000030   I159 @T6G_MB_LIB.T6G(SCH_1):PAGE42
   U26 BL66 MFB1_CS_L0 GENOA_SP5-SOCKET6096_13568-001,SMLF,IO,DGA^6000030   I159 @T6G_MB_LIB.T6G(SCH_1):PAGE42
   U26 BM67 MFB1_CS_L1 GENOA_SP5-SOCKET6096_13568-001,SMLF,IO,DGA^6000030   I159 @T6G_MB_LIB.T6G(SCH_1):PAGE42
   U26 BR67 MFB1_RSP_L GENOA_SP5-SOCKET6096_13568-001,SMLF,IO,DGA^6000030   I159 @T6G_MB_LIB.T6G(SCH_1):PAGE42
   U26  BF2 MG1_CLK_H GENOA_SP5-SOCKET6096_13568-001,SMLF,IO,DGA^6000030   I167 @T6G_MB_LIB.T6G(SCH_1):PAGE43
   U26  BG2 MG1_CLK_L GENOA_SP5-SOCKET6096_13568-001,SMLF,IO,DGA^6000030   I167 @T6G_MB_LIB.T6G(SCH_1):PAGE43
   U26  AV2 MGA1_CS_L0 GENOA_SP5-SOCKET6096_13568-001,SMLF,IO,DGA^6000030   I167 @T6G_MB_LIB.T6G(SCH_1):PAGE43
   U26  AW3 MGA1_CS_L1 GENOA_SP5-SOCKET6096_13568-001,SMLF,IO,DGA^6000030   I167 @T6G_MB_LIB.T6G(SCH_1):PAGE43
   U26  BP4 MGA1_RSP_L GENOA_SP5-SOCKET6096_13568-001,SMLF,IO,DGA^6000030   I167 @T6G_MB_LIB.T6G(SCH_1):PAGE43
   U26  BL2 MGB1_CS_L0 GENOA_SP5-SOCKET6096_13568-001,SMLF,IO,DGA^6000030   I167 @T6G_MB_LIB.T6G(SCH_1):PAGE43
   U26  BM2 MGB1_CS_L1 GENOA_SP5-SOCKET6096_13568-001,SMLF,IO,DGA^6000030   I167 @T6G_MB_LIB.T6G(SCH_1):PAGE43
   U26  BR2 MGB1_RSP_L GENOA_SP5-SOCKET6096_13568-001,SMLF,IO,DGA^6000030   I167 @T6G_MB_LIB.T6G(SCH_1):PAGE43
   U26 BF13 MH1_CLK_H GENOA_SP5-SOCKET6096_13568-001,SMLF,IO,DGA^6000030   I159 @T6G_MB_LIB.T6G(SCH_1):PAGE44
   U26 BG12 MH1_CLK_L GENOA_SP5-SOCKET6096_13568-001,SMLF,IO,DGA^6000030   I159 @T6G_MB_LIB.T6G(SCH_1):PAGE44
   U26 AV13 MHA1_CS_L0 GENOA_SP5-SOCKET6096_13568-001,SMLF,IO,DGA^6000030   I159 @T6G_MB_LIB.T6G(SCH_1):PAGE44
   U26 AW14 MHA1_CS_L1 GENOA_SP5-SOCKET6096_13568-001,SMLF,IO,DGA^6000030   I159 @T6G_MB_LIB.T6G(SCH_1):PAGE44
   U26 BP14 MHA1_RSP_L GENOA_SP5-SOCKET6096_13568-001,SMLF,IO,DGA^6000030   I159 @T6G_MB_LIB.T6G(SCH_1):PAGE44
   U26 BL12 MHB1_CS_L0 GENOA_SP5-SOCKET6096_13568-001,SMLF,IO,DGA^6000030   I159 @T6G_MB_LIB.T6G(SCH_1):PAGE44
   U26 BM13 MHB1_CS_L1 GENOA_SP5-SOCKET6096_13568-001,SMLF,IO,DGA^6000030   I159 @T6G_MB_LIB.T6G(SCH_1):PAGE44
   U26 BR12 MHB1_RSP_L GENOA_SP5-SOCKET6096_13568-001,SMLF,IO,DGA^6000030   I159 @T6G_MB_LIB.T6G(SCH_1):PAGE44
   U26 BF20 MI1_CLK_H GENOA_SP5-SOCKET6096_13568-001,SMLF,IO,DGA^6000030   I159 @T6G_MB_LIB.T6G(SCH_1):PAGE45
   U26 BG19 MI1_CLK_L GENOA_SP5-SOCKET6096_13568-001,SMLF,IO,DGA^6000030   I159 @T6G_MB_LIB.T6G(SCH_1):PAGE45
   U26 AV20 MIA1_CS_L0 GENOA_SP5-SOCKET6096_13568-001,SMLF,IO,DGA^6000030   I159 @T6G_MB_LIB.T6G(SCH_1):PAGE45
   U26 AW21 MIA1_CS_L1 GENOA_SP5-SOCKET6096_13568-001,SMLF,IO,DGA^6000030   I159 @T6G_MB_LIB.T6G(SCH_1):PAGE45
   U26 BP21 MIA1_RSP_L GENOA_SP5-SOCKET6096_13568-001,SMLF,IO,DGA^6000030   I159 @T6G_MB_LIB.T6G(SCH_1):PAGE45
   U26 BL19 MIB1_CS_L0 GENOA_SP5-SOCKET6096_13568-001,SMLF,IO,DGA^6000030   I159 @T6G_MB_LIB.T6G(SCH_1):PAGE45
   U26 BM20 MIB1_CS_L1 GENOA_SP5-SOCKET6096_13568-001,SMLF,IO,DGA^6000030   I159 @T6G_MB_LIB.T6G(SCH_1):PAGE45
   U26 BR19 MIB1_RSP_L GENOA_SP5-SOCKET6096_13568-001,SMLF,IO,DGA^6000030   I159 @T6G_MB_LIB.T6G(SCH_1):PAGE45
   U26 BF16 MJ1_CLK_H GENOA_SP5-SOCKET6096_13568-001,SMLF,IO,DGA^6000030   I159 @T6G_MB_LIB.T6G(SCH_1):PAGE46
   U26 BG16 MJ1_CLK_L GENOA_SP5-SOCKET6096_13568-001,SMLF,IO,DGA^6000030   I159 @T6G_MB_LIB.T6G(SCH_1):PAGE46
   U26 AV16 MJA1_CS_L0 GENOA_SP5-SOCKET6096_13568-001,SMLF,IO,DGA^6000030   I159 @T6G_MB_LIB.T6G(SCH_1):PAGE46
   U26 AW17 MJA1_CS_L1 GENOA_SP5-SOCKET6096_13568-001,SMLF,IO,DGA^6000030   I159 @T6G_MB_LIB.T6G(SCH_1):PAGE46
   U26 BP18 MJA1_RSP_L GENOA_SP5-SOCKET6096_13568-001,SMLF,IO,DGA^6000030   I159 @T6G_MB_LIB.T6G(SCH_1):PAGE46
   U26 BL16 MJB1_CS_L0 GENOA_SP5-SOCKET6096_13568-001,SMLF,IO,DGA^6000030   I159 @T6G_MB_LIB.T6G(SCH_1):PAGE46
   U26 BM16 MJB1_CS_L1 GENOA_SP5-SOCKET6096_13568-001,SMLF,IO,DGA^6000030   I159 @T6G_MB_LIB.T6G(SCH_1):PAGE46
   U26 BR16 MJB1_RSP_L GENOA_SP5-SOCKET6096_13568-001,SMLF,IO,DGA^6000030   I159 @T6G_MB_LIB.T6G(SCH_1):PAGE46
   U26  BF6 MK1_CLK_H GENOA_SP5-SOCKET6096_13568-001,SMLF,IO,DGA^6000030   I159 @T6G_MB_LIB.T6G(SCH_1):PAGE47
   U26  BG5 MK1_CLK_L GENOA_SP5-SOCKET6096_13568-001,SMLF,IO,DGA^6000030   I159 @T6G_MB_LIB.T6G(SCH_1):PAGE47
   U26  AV6 MKA1_CS_L0 GENOA_SP5-SOCKET6096_13568-001,SMLF,IO,DGA^6000030   I159 @T6G_MB_LIB.T6G(SCH_1):PAGE47
   U26  AW7 MKA1_CS_L1 GENOA_SP5-SOCKET6096_13568-001,SMLF,IO,DGA^6000030   I159 @T6G_MB_LIB.T6G(SCH_1):PAGE47
   U26  BP7 MKA1_RSP_L GENOA_SP5-SOCKET6096_13568-001,SMLF,IO,DGA^6000030   I159 @T6G_MB_LIB.T6G(SCH_1):PAGE47
   U26  BL5 MKB1_CS_L0 GENOA_SP5-SOCKET6096_13568-001,SMLF,IO,DGA^6000030   I159 @T6G_MB_LIB.T6G(SCH_1):PAGE47
   U26  BM6 MKB1_CS_L1 GENOA_SP5-SOCKET6096_13568-001,SMLF,IO,DGA^6000030   I159 @T6G_MB_LIB.T6G(SCH_1):PAGE47
   U26  BR5 MKB1_RSP_L GENOA_SP5-SOCKET6096_13568-001,SMLF,IO,DGA^6000030   I159 @T6G_MB_LIB.T6G(SCH_1):PAGE47
   U26  BF9 ML1_CLK_H GENOA_SP5-SOCKET6096_13568-001,SMLF,IO,DGA^6000030   I159 @T6G_MB_LIB.T6G(SCH_1):PAGE48
   U26  BG9 ML1_CLK_L GENOA_SP5-SOCKET6096_13568-001,SMLF,IO,DGA^6000030   I159 @T6G_MB_LIB.T6G(SCH_1):PAGE48
   U26  AV9 MLA1_CS_L0 GENOA_SP5-SOCKET6096_13568-001,SMLF,IO,DGA^6000030   I159 @T6G_MB_LIB.T6G(SCH_1):PAGE48
   U26 AW10 MLA1_CS_L1 GENOA_SP5-SOCKET6096_13568-001,SMLF,IO,DGA^6000030   I159 @T6G_MB_LIB.T6G(SCH_1):PAGE48
   U26 BP11 MLA1_RSP_L GENOA_SP5-SOCKET6096_13568-001,SMLF,IO,DGA^6000030   I159 @T6G_MB_LIB.T6G(SCH_1):PAGE48
   U26  BL9 MLB1_CS_L0 GENOA_SP5-SOCKET6096_13568-001,SMLF,IO,DGA^6000030   I159 @T6G_MB_LIB.T6G(SCH_1):PAGE48
   U26  BM9 MLB1_CS_L1 GENOA_SP5-SOCKET6096_13568-001,SMLF,IO,DGA^6000030   I159 @T6G_MB_LIB.T6G(SCH_1):PAGE48
   U26  BR9 MLB1_RSP_L GENOA_SP5-SOCKET6096_13568-001,SMLF,IO,DGA^6000030   I159 @T6G_MB_LIB.T6G(SCH_1):PAGE48
   U26 DJ32 UART1_TXD||AGPIO142 GENOA_SP5-SOCKET6096_13568-001,SMLF,IO,DGA^6000030   I190 @T6G_MB_LIB.T6G(SCH_1):PAGE54
   U26 DF36 AGPIO4||SATA_ACT_L GENOA_SP5-SOCKET6096_13568-001,SMLF,IO,DGA^6000030   I182 @T6G_MB_LIB.T6G(SCH_1):PAGE55
   U26  DH4 AGPIO7 GENOA_SP5-SOCKET6096_13568-001,SMLF,IO,DGA^6000030   I182 @T6G_MB_LIB.T6G(SCH_1):PAGE55
   U26 DG11 AGPIO87 GENOA_SP5-SOCKET6096_13568-001,SMLF,IO,DGA^6000030   I182 @T6G_MB_LIB.T6G(SCH_1):PAGE55
   U26 DJ29 AGPIO88 GENOA_SP5-SOCKET6096_13568-001,SMLF,IO,DGA^6000030   I182 @T6G_MB_LIB.T6G(SCH_1):PAGE55
   U26 DH30 AGPIO104 GENOA_SP5-SOCKET6096_13568-001,SMLF,IO,DGA^6000030   I182 @T6G_MB_LIB.T6G(SCH_1):PAGE55
   U26 DE30 AGPIO105 GENOA_SP5-SOCKET6096_13568-001,SMLF,IO,DGA^6000030   I182 @T6G_MB_LIB.T6G(SCH_1):PAGE55
   U26 DF31 AGPIO106 GENOA_SP5-SOCKET6096_13568-001,SMLF,IO,DGA^6000030   I182 @T6G_MB_LIB.T6G(SCH_1):PAGE55
   U26 DG31 AGPIO107 GENOA_SP5-SOCKET6096_13568-001,SMLF,IO,DGA^6000030   I182 @T6G_MB_LIB.T6G(SCH_1):PAGE55
   U26 DG32 AGPIO109 GENOA_SP5-SOCKET6096_13568-001,SMLF,IO,DGA^6000030   I182 @T6G_MB_LIB.T6G(SCH_1):PAGE55
   U26  A14 AGPIO256||SGPIO0_CLK GENOA_SP5-SOCKET6096_13568-001,SMLF,IO,DGA^6000030   I182 @T6G_MB_LIB.T6G(SCH_1):PAGE55
   U26  C14 AGPIO257||SGPIO1_CLK||CLK_REQ01_L GENOA_SP5-SOCKET6096_13568-001,SMLF,IO,DGA^6000030   I182 @T6G_MB_LIB.T6G(SCH_1):PAGE55
   U26  A13 AGPIO258||SGPIO2_CLK||CLK_REQ02_L GENOA_SP5-SOCKET6096_13568-001,SMLF,IO,DGA^6000030   I182 @T6G_MB_LIB.T6G(SCH_1):PAGE55
   U26  B16 AGPIO259||SGPIO3_CLK GENOA_SP5-SOCKET6096_13568-001,SMLF,IO,DGA^6000030   I182 @T6G_MB_LIB.T6G(SCH_1):PAGE55
   U26 DJ47 GPP_CLK14N GENOA_SP5-SOCKET6096_13568-001,SMLF,IO,DGA^6000030   I182 @T6G_MB_LIB.T6G(SCH_1):PAGE55
   U26 DJ48 GPP_CLK14P GENOA_SP5-SOCKET6096_13568-001,SMLF,IO,DGA^6000030   I182 @T6G_MB_LIB.T6G(SCH_1):PAGE55
   U26 DJ50 GPP_CLK15N GENOA_SP5-SOCKET6096_13568-001,SMLF,IO,DGA^6000030   I182 @T6G_MB_LIB.T6G(SCH_1):PAGE55
   U26 DJ51 GPP_CLK15P GENOA_SP5-SOCKET6096_13568-001,SMLF,IO,DGA^6000030   I182 @T6G_MB_LIB.T6G(SCH_1):PAGE55
   U26 DG12 I2C4_SCL||HP_SCL||UBM_SCL||AGPIO13 GENOA_SP5-SOCKET6096_13568-001,SMLF,IO,DGA^6000030   I182 @T6G_MB_LIB.T6G(SCH_1):PAGE55
   U26 DH12 I2C4_SDA||HP_SDA||UBM_SDA||AGPIO14 GENOA_SP5-SOCKET6096_13568-001,SMLF,IO,DGA^6000030   I182 @T6G_MB_LIB.T6G(SCH_1):PAGE55
   U26 DJ21 I2C5_SCL||BMC_SCL||SMBUS1_SCL||AGPIO19 GENOA_SP5-SOCKET6096_13568-001,SMLF,IO,DGA^6000030   I182 @T6G_MB_LIB.T6G(SCH_1):PAGE55
   U26 DJ20 I2C5_SDA||BMC_SDA||SMBUS1_SDA||AGPIO20 GENOA_SP5-SOCKET6096_13568-001,SMLF,IO,DGA^6000030   I182 @T6G_MB_LIB.T6G(SCH_1):PAGE55
   U26  C72 I3C2_SCL||I2C2_SCL||SPD2_SCL||AGPIO149 GENOA_SP5-SOCKET6096_13568-001,SMLF,IO,DGA^6000030   I182 @T6G_MB_LIB.T6G(SCH_1):PAGE55
   U26  B72 I3C2_SDA||I2C2_SDA||SPD2_SDA||AGPIO150 GENOA_SP5-SOCKET6096_13568-001,SMLF,IO,DGA^6000030   I182 @T6G_MB_LIB.T6G(SCH_1):PAGE55
   U26   A4 I3C3_SCL||I2C3_SCL||SPD3_SCL||AGPIO151 GENOA_SP5-SOCKET6096_13568-001,SMLF,IO,DGA^6000030   I182 @T6G_MB_LIB.T6G(SCH_1):PAGE55
   U26   B4 I3C3_SDA||I2C3_SDA||SPD3_SDA||AGPIO152 GENOA_SP5-SOCKET6096_13568-001,SMLF,IO,DGA^6000030   I182 @T6G_MB_LIB.T6G(SCH_1):PAGE55
   U26  D15 SGPIO_DATAOUT||AGPIO260 GENOA_SP5-SOCKET6096_13568-001,SMLF,IO,DGA^6000030   I182 @T6G_MB_LIB.T6G(SCH_1):PAGE55
   U26  B15 SGPIO_LOAD||AGPIO261 GENOA_SP5-SOCKET6096_13568-001,SMLF,IO,DGA^6000030   I182 @T6G_MB_LIB.T6G(SCH_1):PAGE55
   U26 DJ25 AGPIO76||SPI_TPM_CS_L GENOA_SP5-SOCKET6096_13568-001,SMLF,IO,DGA^6000030     I8 @T6G_MB_LIB.T6G(SCH_1):PAGE56
   U26 DJ22 ESPI0_ALERT_L||AGPIO108 GENOA_SP5-SOCKET6096_13568-001,SMLF,IO,DGA^6000030     I8 @T6G_MB_LIB.T6G(SCH_1):PAGE56
   U26 DF28 ESPI0_DAT0||SPI0_DAT0||AGPIO120 GENOA_SP5-SOCKET6096_13568-001,SMLF,IO,DGA^6000030     I8 @T6G_MB_LIB.T6G(SCH_1):PAGE56
   U26 DG22 ESPI0_DAT1||SPI0_DAT1||AGPIO121 GENOA_SP5-SOCKET6096_13568-001,SMLF,IO,DGA^6000030     I8 @T6G_MB_LIB.T6G(SCH_1):PAGE56
   U26 DJ28 ESPI0_DAT2||SPI0_DAT2||AGPIO122 GENOA_SP5-SOCKET6096_13568-001,SMLF,IO,DGA^6000030     I8 @T6G_MB_LIB.T6G(SCH_1):PAGE56
   U26 DG29 ESPI0_DAT3||SPI0_DAT3||AGPIO123 GENOA_SP5-SOCKET6096_13568-001,SMLF,IO,DGA^6000030     I8 @T6G_MB_LIB.T6G(SCH_1):PAGE56
   U26 DF24 ESPI1_ALERT_L||AGPIO110 GENOA_SP5-SOCKET6096_13568-001,SMLF,IO,DGA^6000030     I8 @T6G_MB_LIB.T6G(SCH_1):PAGE56
   U26 DH24 ESPI1_DAT0||SPI1_DAT0||AGPIO131 GENOA_SP5-SOCKET6096_13568-001,SMLF,IO,DGA^6000030     I8 @T6G_MB_LIB.T6G(SCH_1):PAGE56
   U26 DE24 ESPI1_DAT1||SPI1_DAT1||AGPIO132 GENOA_SP5-SOCKET6096_13568-001,SMLF,IO,DGA^6000030     I8 @T6G_MB_LIB.T6G(SCH_1):PAGE56
   U26 DF25 ESPI1_DAT2||SPI1_DAT2||AGPIO133 GENOA_SP5-SOCKET6096_13568-001,SMLF,IO,DGA^6000030     I8 @T6G_MB_LIB.T6G(SCH_1):PAGE56
   U26 DG25 ESPI1_DAT3||SPI1_DAT3||AGPIO134 GENOA_SP5-SOCKET6096_13568-001,SMLF,IO,DGA^6000030     I8 @T6G_MB_LIB.T6G(SCH_1):PAGE56
   U26 DG23 ESPI_CLK1||SPI_CLK1||AGPIO75 GENOA_SP5-SOCKET6096_13568-001,SMLF,IO,DGA^6000030     I8 @T6G_MB_LIB.T6G(SCH_1):PAGE56
   U26 DG28 ESPI_CS0_L||AGPIO124 GENOA_SP5-SOCKET6096_13568-001,SMLF,IO,DGA^6000030     I8 @T6G_MB_LIB.T6G(SCH_1):PAGE56
   U26 DJ23 ESPI_CS1_L||AGPIO125 GENOA_SP5-SOCKET6096_13568-001,SMLF,IO,DGA^6000030     I8 @T6G_MB_LIB.T6G(SCH_1):PAGE56
   U26 DJ26 ESPI_RSTIN_L||KBRST_L||AGPIO129 GENOA_SP5-SOCKET6096_13568-001,SMLF,IO,DGA^6000030     I8 @T6G_MB_LIB.T6G(SCH_1):PAGE56
   U26 DE27 ESPI_RSTOUT_L||AGPIO23 GENOA_SP5-SOCKET6096_13568-001,SMLF,IO,DGA^6000030     I8 @T6G_MB_LIB.T6G(SCH_1):PAGE56
   U26 DF30 SPI_CS0_L||AGPIO118 GENOA_SP5-SOCKET6096_13568-001,SMLF,IO,DGA^6000030     I8 @T6G_MB_LIB.T6G(SCH_1):PAGE56
   U26 DG26 SPI_CS1_L||AGPIO119 GENOA_SP5-SOCKET6096_13568-001,SMLF,IO,DGA^6000030     I8 @T6G_MB_LIB.T6G(SCH_1):PAGE56
   U26 DH27 SPI_CS2_L||AGPIO126 GENOA_SP5-SOCKET6096_13568-001,SMLF,IO,DGA^6000030     I8 @T6G_MB_LIB.T6G(SCH_1):PAGE56
   U26  A31 RSVD_A31 GENOA_SP5-SOCKET6096_13568-001,SMLF,IO,DGA^6000030    I46 @T6G_MB_LIB.T6G(SCH_1):PAGE57
   U26  A35 RSVD_A35 GENOA_SP5-SOCKET6096_13568-001,SMLF,IO,DGA^6000030    I46 @T6G_MB_LIB.T6G(SCH_1):PAGE57
   U26  A41 RSVD_A41 GENOA_SP5-SOCKET6096_13568-001,SMLF,IO,DGA^6000030    I46 @T6G_MB_LIB.T6G(SCH_1):PAGE57
   U26  A42 RSVD_A42 GENOA_SP5-SOCKET6096_13568-001,SMLF,IO,DGA^6000030    I46 @T6G_MB_LIB.T6G(SCH_1):PAGE57
   U26  A45 RSVD_A45 GENOA_SP5-SOCKET6096_13568-001,SMLF,IO,DGA^6000030    I46 @T6G_MB_LIB.T6G(SCH_1):PAGE57
   U26  A48 RSVD_A48 GENOA_SP5-SOCKET6096_13568-001,SMLF,IO,DGA^6000030    I46 @T6G_MB_LIB.T6G(SCH_1):PAGE57
   U26  A50 RSVD_A50 GENOA_SP5-SOCKET6096_13568-001,SMLF,IO,DGA^6000030    I46 @T6G_MB_LIB.T6G(SCH_1):PAGE57
   U26  A51 RSVD_A51 GENOA_SP5-SOCKET6096_13568-001,SMLF,IO,DGA^6000030    I46 @T6G_MB_LIB.T6G(SCH_1):PAGE57
   U26  A54 RSVD_A54 GENOA_SP5-SOCKET6096_13568-001,SMLF,IO,DGA^6000030    I46 @T6G_MB_LIB.T6G(SCH_1):PAGE57
   U26  A55 RSVD_A55 GENOA_SP5-SOCKET6096_13568-001,SMLF,IO,DGA^6000030    I46 @T6G_MB_LIB.T6G(SCH_1):PAGE57
   U26  A56 RSVD_A56 GENOA_SP5-SOCKET6096_13568-001,SMLF,IO,DGA^6000030    I46 @T6G_MB_LIB.T6G(SCH_1):PAGE57
   U26  A57 RSVD_A57 GENOA_SP5-SOCKET6096_13568-001,SMLF,IO,DGA^6000030    I46 @T6G_MB_LIB.T6G(SCH_1):PAGE57
   U26  A59 RSVD_A59 GENOA_SP5-SOCKET6096_13568-001,SMLF,IO,DGA^6000030    I46 @T6G_MB_LIB.T6G(SCH_1):PAGE57
   U26  A60 RSVD_A60 GENOA_SP5-SOCKET6096_13568-001,SMLF,IO,DGA^6000030    I46 @T6G_MB_LIB.T6G(SCH_1):PAGE57
   U26  B40 RSVD_B40 GENOA_SP5-SOCKET6096_13568-001,SMLF,IO,DGA^6000030    I46 @T6G_MB_LIB.T6G(SCH_1):PAGE57
   U26  BD4 RSVD_BD4 GENOA_SP5-SOCKET6096_13568-001,SMLF,IO,DGA^6000030    I46 @T6G_MB_LIB.T6G(SCH_1):PAGE57
   U26  BD7 RSVD_BD7 GENOA_SP5-SOCKET6096_13568-001,SMLF,IO,DGA^6000030    I46 @T6G_MB_LIB.T6G(SCH_1):PAGE57
   U26 BD11 RSVD_BD11 GENOA_SP5-SOCKET6096_13568-001,SMLF,IO,DGA^6000030    I46 @T6G_MB_LIB.T6G(SCH_1):PAGE57
   U26 BD14 RSVD_BD14 GENOA_SP5-SOCKET6096_13568-001,SMLF,IO,DGA^6000030    I46 @T6G_MB_LIB.T6G(SCH_1):PAGE57
   U26 BD18 RSVD_BD18 GENOA_SP5-SOCKET6096_13568-001,SMLF,IO,DGA^6000030    I46 @T6G_MB_LIB.T6G(SCH_1):PAGE57
   U26 BD21 RSVD_BD21 GENOA_SP5-SOCKET6096_13568-001,SMLF,IO,DGA^6000030    I46 @T6G_MB_LIB.T6G(SCH_1):PAGE57
   U26 BD55 RSVD_BD55 GENOA_SP5-SOCKET6096_13568-001,SMLF,IO,DGA^6000030    I46 @T6G_MB_LIB.T6G(SCH_1):PAGE57
   U26 BD58 RSVD_BD58 GENOA_SP5-SOCKET6096_13568-001,SMLF,IO,DGA^6000030    I46 @T6G_MB_LIB.T6G(SCH_1):PAGE57
   U26 BD62 RSVD_BD62 GENOA_SP5-SOCKET6096_13568-001,SMLF,IO,DGA^6000030    I46 @T6G_MB_LIB.T6G(SCH_1):PAGE57
   U26 BD65 RSVD_BD65 GENOA_SP5-SOCKET6096_13568-001,SMLF,IO,DGA^6000030    I46 @T6G_MB_LIB.T6G(SCH_1):PAGE57
   U26 BD69 RSVD_BD69 GENOA_SP5-SOCKET6096_13568-001,SMLF,IO,DGA^6000030    I46 @T6G_MB_LIB.T6G(SCH_1):PAGE57
   U26 BD72 RSVD_BD72 GENOA_SP5-SOCKET6096_13568-001,SMLF,IO,DGA^6000030    I46 @T6G_MB_LIB.T6G(SCH_1):PAGE57
   U26  C31 RSVD_C31 GENOA_SP5-SOCKET6096_13568-001,SMLF,IO,DGA^6000030    I46 @T6G_MB_LIB.T6G(SCH_1):PAGE57
   U26  C34 RSVD_C34 GENOA_SP5-SOCKET6096_13568-001,SMLF,IO,DGA^6000030    I46 @T6G_MB_LIB.T6G(SCH_1):PAGE57
   U26  C35 RSVD_C35 GENOA_SP5-SOCKET6096_13568-001,SMLF,IO,DGA^6000030    I46 @T6G_MB_LIB.T6G(SCH_1):PAGE57
   U26  C53 RSVD_C53 GENOA_SP5-SOCKET6096_13568-001,SMLF,IO,DGA^6000030    I46 @T6G_MB_LIB.T6G(SCH_1):PAGE57
   U26  C54 RSVD_C54 GENOA_SP5-SOCKET6096_13568-001,SMLF,IO,DGA^6000030    I46 @T6G_MB_LIB.T6G(SCH_1):PAGE57
   U26   D4 RSVD_D4 GENOA_SP5-SOCKET6096_13568-001,SMLF,IO,DGA^6000030    I46 @T6G_MB_LIB.T6G(SCH_1):PAGE57
   U26   D8 RSVD_D8 GENOA_SP5-SOCKET6096_13568-001,SMLF,IO,DGA^6000030    I46 @T6G_MB_LIB.T6G(SCH_1):PAGE57
   U26  D11 RSVD_D11 GENOA_SP5-SOCKET6096_13568-001,SMLF,IO,DGA^6000030    I46 @T6G_MB_LIB.T6G(SCH_1):PAGE57
   U26  D22 RSVD_D22 GENOA_SP5-SOCKET6096_13568-001,SMLF,IO,DGA^6000030    I46 @T6G_MB_LIB.T6G(SCH_1):PAGE57
   U26  D34 RSVD_D34 GENOA_SP5-SOCKET6096_13568-001,SMLF,IO,DGA^6000030    I46 @T6G_MB_LIB.T6G(SCH_1):PAGE57
   U26  D36 RSVD_D36 GENOA_SP5-SOCKET6096_13568-001,SMLF,IO,DGA^6000030    I46 @T6G_MB_LIB.T6G(SCH_1):PAGE57
   U26  D58 RSVD_D58 GENOA_SP5-SOCKET6096_13568-001,SMLF,IO,DGA^6000030    I46 @T6G_MB_LIB.T6G(SCH_1):PAGE57
   U26  D62 RSVD_D62 GENOA_SP5-SOCKET6096_13568-001,SMLF,IO,DGA^6000030    I46 @T6G_MB_LIB.T6G(SCH_1):PAGE57
   U26  D65 RSVD_D65 GENOA_SP5-SOCKET6096_13568-001,SMLF,IO,DGA^6000030    I46 @T6G_MB_LIB.T6G(SCH_1):PAGE57
   U26  D72 RSVD_D72 GENOA_SP5-SOCKET6096_13568-001,SMLF,IO,DGA^6000030    I46 @T6G_MB_LIB.T6G(SCH_1):PAGE57
   U26 DG17 RSVD_DG17 GENOA_SP5-SOCKET6096_13568-001,SMLF,IO,DGA^6000030    I46 @T6G_MB_LIB.T6G(SCH_1):PAGE57
   U26 DH17 RSVD_DH17 GENOA_SP5-SOCKET6096_13568-001,SMLF,IO,DGA^6000030    I46 @T6G_MB_LIB.T6G(SCH_1):PAGE57
   U26 DH21 RSVD_DH21 GENOA_SP5-SOCKET6096_13568-001,SMLF,IO,DGA^6000030    I46 @T6G_MB_LIB.T6G(SCH_1):PAGE57
   U26  DJ4 RSVD_DJ4 GENOA_SP5-SOCKET6096_13568-001,SMLF,IO,DGA^6000030    I46 @T6G_MB_LIB.T6G(SCH_1):PAGE57
   U26  E33 RSVD_E33 GENOA_SP5-SOCKET6096_13568-001,SMLF,IO,DGA^6000030    I46 @T6G_MB_LIB.T6G(SCH_1):PAGE57
   U26  E36 RSVD_E36 GENOA_SP5-SOCKET6096_13568-001,SMLF,IO,DGA^6000030    I46 @T6G_MB_LIB.T6G(SCH_1):PAGE57
   U26  C58 TEST4_CCD12 GENOA_SP5-SOCKET6096_13568-001,SMLF,IO,DGA^6000030    I46 @T6G_MB_LIB.T6G(SCH_1):PAGE57
   U26 DH13 TEST4_CCD13 GENOA_SP5-SOCKET6096_13568-001,SMLF,IO,DGA^6000030    I46 @T6G_MB_LIB.T6G(SCH_1):PAGE57
   U26 DF41 TEST4_CCD14 GENOA_SP5-SOCKET6096_13568-001,SMLF,IO,DGA^6000030    I46 @T6G_MB_LIB.T6G(SCH_1):PAGE57
   U26  C23 TEST4_CCD15 GENOA_SP5-SOCKET6096_13568-001,SMLF,IO,DGA^6000030    I46 @T6G_MB_LIB.T6G(SCH_1):PAGE57
   U26  C59 TEST5_CCD12 GENOA_SP5-SOCKET6096_13568-001,SMLF,IO,DGA^6000030    I46 @T6G_MB_LIB.T6G(SCH_1):PAGE57
   U26 DH14 TEST5_CCD13 GENOA_SP5-SOCKET6096_13568-001,SMLF,IO,DGA^6000030    I46 @T6G_MB_LIB.T6G(SCH_1):PAGE57
   U26 DG42 TEST5_CCD14 GENOA_SP5-SOCKET6096_13568-001,SMLF,IO,DGA^6000030    I46 @T6G_MB_LIB.T6G(SCH_1):PAGE57
   U26  D23 TEST5_CCD15 GENOA_SP5-SOCKET6096_13568-001,SMLF,IO,DGA^6000030    I46 @T6G_MB_LIB.T6G(SCH_1):PAGE57
   U26  B36 TEST6_X3D6 GENOA_SP5-SOCKET6096_13568-001,SMLF,IO,DGA^6000030    I46 @T6G_MB_LIB.T6G(SCH_1):PAGE57
   U26 DJ57 TEST6_X3D7 GENOA_SP5-SOCKET6096_13568-001,SMLF,IO,DGA^6000030    I46 @T6G_MB_LIB.T6G(SCH_1):PAGE57
   J15    2   RFU0 SCONN288_DDR506112002KQ-SCONN288_DDR506112002KQ,SMA   I350 @T6G_MB_LIB.T6G(SCH_1):PAGE86
   J15  144   RFU1 SCONN288_DDR506112002KQ-SCONN288_DDR506112002KQ,SMA   I350 @T6G_MB_LIB.T6G(SCH_1):PAGE86
   J15  149   RFU2 SCONN288_DDR506112002KQ-SCONN288_DDR506112002KQ,SMA   I350 @T6G_MB_LIB.T6G(SCH_1):PAGE86
   J15  150   RFU3 SCONN288_DDR506112002KQ-SCONN288_DDR506112002KQ,SMA   I350 @T6G_MB_LIB.T6G(SCH_1):PAGE86
   J15  220   RFU4 SCONN288_DDR506112002KQ-SCONN288_DDR506112002KQ,SMA   I350 @T6G_MB_LIB.T6G(SCH_1):PAGE86
   J15  231   RFU5 SCONN288_DDR506112002KQ-SCONN288_DDR506112002KQ,SMA   I350 @T6G_MB_LIB.T6G(SCH_1):PAGE86
   J15  232   RFU6 SCONN288_DDR506112002KQ-SCONN288_DDR506112002KQ,SMA   I350 @T6G_MB_LIB.T6G(SCH_1):PAGE86
   J17    2   RFU0 SCONN288_DDR506112002KQ-SCONN288_DDR506112002KQ,SMA   I350 @T6G_MB_LIB.T6G(SCH_1):PAGE87
   J17  144   RFU1 SCONN288_DDR506112002KQ-SCONN288_DDR506112002KQ,SMA   I350 @T6G_MB_LIB.T6G(SCH_1):PAGE87
   J17  149   RFU2 SCONN288_DDR506112002KQ-SCONN288_DDR506112002KQ,SMA   I350 @T6G_MB_LIB.T6G(SCH_1):PAGE87
   J17  150   RFU3 SCONN288_DDR506112002KQ-SCONN288_DDR506112002KQ,SMA   I350 @T6G_MB_LIB.T6G(SCH_1):PAGE87
   J17  220   RFU4 SCONN288_DDR506112002KQ-SCONN288_DDR506112002KQ,SMA   I350 @T6G_MB_LIB.T6G(SCH_1):PAGE87
   J17  231   RFU5 SCONN288_DDR506112002KQ-SCONN288_DDR506112002KQ,SMA   I350 @T6G_MB_LIB.T6G(SCH_1):PAGE87
   J17  232   RFU6 SCONN288_DDR506112002KQ-SCONN288_DDR506112002KQ,SMA   I350 @T6G_MB_LIB.T6G(SCH_1):PAGE87
   J19    2   RFU0 SCONN288_DDR506112002KQ-SCONN288_DDR506112002KQ,SMA   I350 @T6G_MB_LIB.T6G(SCH_1):PAGE88
   J19  144   RFU1 SCONN288_DDR506112002KQ-SCONN288_DDR506112002KQ,SMA   I350 @T6G_MB_LIB.T6G(SCH_1):PAGE88
   J19  149   RFU2 SCONN288_DDR506112002KQ-SCONN288_DDR506112002KQ,SMA   I350 @T6G_MB_LIB.T6G(SCH_1):PAGE88
   J19  150   RFU3 SCONN288_DDR506112002KQ-SCONN288_DDR506112002KQ,SMA   I350 @T6G_MB_LIB.T6G(SCH_1):PAGE88
   J19  220   RFU4 SCONN288_DDR506112002KQ-SCONN288_DDR506112002KQ,SMA   I350 @T6G_MB_LIB.T6G(SCH_1):PAGE88
   J19  231   RFU5 SCONN288_DDR506112002KQ-SCONN288_DDR506112002KQ,SMA   I350 @T6G_MB_LIB.T6G(SCH_1):PAGE88
   J19  232   RFU6 SCONN288_DDR506112002KQ-SCONN288_DDR506112002KQ,SMA   I350 @T6G_MB_LIB.T6G(SCH_1):PAGE88
   J21    2   RFU0 SCONN288_DDR506112002KQ-SCONN288_DDR506112002KQ,SMA   I348 @T6G_MB_LIB.T6G(SCH_1):PAGE89
   J21  144   RFU1 SCONN288_DDR506112002KQ-SCONN288_DDR506112002KQ,SMA   I348 @T6G_MB_LIB.T6G(SCH_1):PAGE89
   J21  149   RFU2 SCONN288_DDR506112002KQ-SCONN288_DDR506112002KQ,SMA   I348 @T6G_MB_LIB.T6G(SCH_1):PAGE89
   J21  150   RFU3 SCONN288_DDR506112002KQ-SCONN288_DDR506112002KQ,SMA   I348 @T6G_MB_LIB.T6G(SCH_1):PAGE89
   J21  220   RFU4 SCONN288_DDR506112002KQ-SCONN288_DDR506112002KQ,SMA   I348 @T6G_MB_LIB.T6G(SCH_1):PAGE89
   J21  231   RFU5 SCONN288_DDR506112002KQ-SCONN288_DDR506112002KQ,SMA   I348 @T6G_MB_LIB.T6G(SCH_1):PAGE89
   J21  232   RFU6 SCONN288_DDR506112002KQ-SCONN288_DDR506112002KQ,SMA   I348 @T6G_MB_LIB.T6G(SCH_1):PAGE89
   J23    2   RFU0 SCONN288_DDR506112002KQ-SCONN288_DDR506112002KQ,SMA   I350 @T6G_MB_LIB.T6G(SCH_1):PAGE90
   J23  144   RFU1 SCONN288_DDR506112002KQ-SCONN288_DDR506112002KQ,SMA   I350 @T6G_MB_LIB.T6G(SCH_1):PAGE90
   J23  149   RFU2 SCONN288_DDR506112002KQ-SCONN288_DDR506112002KQ,SMA   I350 @T6G_MB_LIB.T6G(SCH_1):PAGE90
   J23  150   RFU3 SCONN288_DDR506112002KQ-SCONN288_DDR506112002KQ,SMA   I350 @T6G_MB_LIB.T6G(SCH_1):PAGE90
   J23  220   RFU4 SCONN288_DDR506112002KQ-SCONN288_DDR506112002KQ,SMA   I350 @T6G_MB_LIB.T6G(SCH_1):PAGE90
   J23  231   RFU5 SCONN288_DDR506112002KQ-SCONN288_DDR506112002KQ,SMA   I350 @T6G_MB_LIB.T6G(SCH_1):PAGE90
   J23  232   RFU6 SCONN288_DDR506112002KQ-SCONN288_DDR506112002KQ,SMA   I350 @T6G_MB_LIB.T6G(SCH_1):PAGE90
   J16    2   RFU0 SCONN288_DDR506112002KQ-SCONN288_DDR506112002KQ,SMA    I22 @T6G_MB_LIB.T6G(SCH_1):PAGE91
   J16  144   RFU1 SCONN288_DDR506112002KQ-SCONN288_DDR506112002KQ,SMA    I22 @T6G_MB_LIB.T6G(SCH_1):PAGE91
   J16  149   RFU2 SCONN288_DDR506112002KQ-SCONN288_DDR506112002KQ,SMA    I22 @T6G_MB_LIB.T6G(SCH_1):PAGE91
   J16  150   RFU3 SCONN288_DDR506112002KQ-SCONN288_DDR506112002KQ,SMA    I22 @T6G_MB_LIB.T6G(SCH_1):PAGE91
   J16  220   RFU4 SCONN288_DDR506112002KQ-SCONN288_DDR506112002KQ,SMA    I22 @T6G_MB_LIB.T6G(SCH_1):PAGE91
   J16  231   RFU5 SCONN288_DDR506112002KQ-SCONN288_DDR506112002KQ,SMA    I22 @T6G_MB_LIB.T6G(SCH_1):PAGE91
   J16  232   RFU6 SCONN288_DDR506112002KQ-SCONN288_DDR506112002KQ,SMA    I22 @T6G_MB_LIB.T6G(SCH_1):PAGE91
   J69    2   RFU0 SCONN288_DDR506112002KQ-SCONN288_DDR506112002KQ,SMA    I22 @T6G_MB_LIB.T6G(SCH_1):PAGE92
   J69  144   RFU1 SCONN288_DDR506112002KQ-SCONN288_DDR506112002KQ,SMA    I22 @T6G_MB_LIB.T6G(SCH_1):PAGE92
   J69  149   RFU2 SCONN288_DDR506112002KQ-SCONN288_DDR506112002KQ,SMA    I22 @T6G_MB_LIB.T6G(SCH_1):PAGE92
   J69  150   RFU3 SCONN288_DDR506112002KQ-SCONN288_DDR506112002KQ,SMA    I22 @T6G_MB_LIB.T6G(SCH_1):PAGE92
   J69  220   RFU4 SCONN288_DDR506112002KQ-SCONN288_DDR506112002KQ,SMA    I22 @T6G_MB_LIB.T6G(SCH_1):PAGE92
   J69  231   RFU5 SCONN288_DDR506112002KQ-SCONN288_DDR506112002KQ,SMA    I22 @T6G_MB_LIB.T6G(SCH_1):PAGE92
   J69  232   RFU6 SCONN288_DDR506112002KQ-SCONN288_DDR506112002KQ,SMA    I22 @T6G_MB_LIB.T6G(SCH_1):PAGE92
   J18    2   RFU0 SCONN288_DDR506112002KQ-SCONN288_DDR506112002KQ,SMA    I22 @T6G_MB_LIB.T6G(SCH_1):PAGE93
   J18  144   RFU1 SCONN288_DDR506112002KQ-SCONN288_DDR506112002KQ,SMA    I22 @T6G_MB_LIB.T6G(SCH_1):PAGE93
   J18  149   RFU2 SCONN288_DDR506112002KQ-SCONN288_DDR506112002KQ,SMA    I22 @T6G_MB_LIB.T6G(SCH_1):PAGE93
   J18  150   RFU3 SCONN288_DDR506112002KQ-SCONN288_DDR506112002KQ,SMA    I22 @T6G_MB_LIB.T6G(SCH_1):PAGE93
   J18  220   RFU4 SCONN288_DDR506112002KQ-SCONN288_DDR506112002KQ,SMA    I22 @T6G_MB_LIB.T6G(SCH_1):PAGE93
   J18  231   RFU5 SCONN288_DDR506112002KQ-SCONN288_DDR506112002KQ,SMA    I22 @T6G_MB_LIB.T6G(SCH_1):PAGE93
   J18  232   RFU6 SCONN288_DDR506112002KQ-SCONN288_DDR506112002KQ,SMA    I22 @T6G_MB_LIB.T6G(SCH_1):PAGE93
   J68    2   RFU0 SCONN288_DDR506112002KQ-SCONN288_DDR506112002KQ,SMA    I22 @T6G_MB_LIB.T6G(SCH_1):PAGE94
   J68  144   RFU1 SCONN288_DDR506112002KQ-SCONN288_DDR506112002KQ,SMA    I22 @T6G_MB_LIB.T6G(SCH_1):PAGE94
   J68  149   RFU2 SCONN288_DDR506112002KQ-SCONN288_DDR506112002KQ,SMA    I22 @T6G_MB_LIB.T6G(SCH_1):PAGE94
   J68  150   RFU3 SCONN288_DDR506112002KQ-SCONN288_DDR506112002KQ,SMA    I22 @T6G_MB_LIB.T6G(SCH_1):PAGE94
   J68  220   RFU4 SCONN288_DDR506112002KQ-SCONN288_DDR506112002KQ,SMA    I22 @T6G_MB_LIB.T6G(SCH_1):PAGE94
   J68  231   RFU5 SCONN288_DDR506112002KQ-SCONN288_DDR506112002KQ,SMA    I22 @T6G_MB_LIB.T6G(SCH_1):PAGE94
   J68  232   RFU6 SCONN288_DDR506112002KQ-SCONN288_DDR506112002KQ,SMA    I22 @T6G_MB_LIB.T6G(SCH_1):PAGE94
   J20    2   RFU0 SCONN288_DDR506112002KQ-SCONN288_DDR506112002KQ,SMA    I22 @T6G_MB_LIB.T6G(SCH_1):PAGE95
   J20  144   RFU1 SCONN288_DDR506112002KQ-SCONN288_DDR506112002KQ,SMA    I22 @T6G_MB_LIB.T6G(SCH_1):PAGE95
   J20  149   RFU2 SCONN288_DDR506112002KQ-SCONN288_DDR506112002KQ,SMA    I22 @T6G_MB_LIB.T6G(SCH_1):PAGE95
   J20  150   RFU3 SCONN288_DDR506112002KQ-SCONN288_DDR506112002KQ,SMA    I22 @T6G_MB_LIB.T6G(SCH_1):PAGE95
   J20  220   RFU4 SCONN288_DDR506112002KQ-SCONN288_DDR506112002KQ,SMA    I22 @T6G_MB_LIB.T6G(SCH_1):PAGE95
   J20  231   RFU5 SCONN288_DDR506112002KQ-SCONN288_DDR506112002KQ,SMA    I22 @T6G_MB_LIB.T6G(SCH_1):PAGE95
   J20  232   RFU6 SCONN288_DDR506112002KQ-SCONN288_DDR506112002KQ,SMA    I22 @T6G_MB_LIB.T6G(SCH_1):PAGE95
   J67    2   RFU0 SCONN288_DDR506112002KQ-SCONN288_DDR506112002KQ,SMA    I22 @T6G_MB_LIB.T6G(SCH_1):PAGE96
   J67  144   RFU1 SCONN288_DDR506112002KQ-SCONN288_DDR506112002KQ,SMA    I22 @T6G_MB_LIB.T6G(SCH_1):PAGE96
   J67  149   RFU2 SCONN288_DDR506112002KQ-SCONN288_DDR506112002KQ,SMA    I22 @T6G_MB_LIB.T6G(SCH_1):PAGE96
   J67  150   RFU3 SCONN288_DDR506112002KQ-SCONN288_DDR506112002KQ,SMA    I22 @T6G_MB_LIB.T6G(SCH_1):PAGE96
   J67  220   RFU4 SCONN288_DDR506112002KQ-SCONN288_DDR506112002KQ,SMA    I22 @T6G_MB_LIB.T6G(SCH_1):PAGE96
   J67  231   RFU5 SCONN288_DDR506112002KQ-SCONN288_DDR506112002KQ,SMA    I22 @T6G_MB_LIB.T6G(SCH_1):PAGE96
   J67  232   RFU6 SCONN288_DDR506112002KQ-SCONN288_DDR506112002KQ,SMA    I22 @T6G_MB_LIB.T6G(SCH_1):PAGE96
   J24    2   RFU0 SCONN288_DDR506112002KQ-SCONN288_DDR506112002KQ,SMA    I22 @T6G_MB_LIB.T6G(SCH_1):PAGE97
   J24  144   RFU1 SCONN288_DDR506112002KQ-SCONN288_DDR506112002KQ,SMA    I22 @T6G_MB_LIB.T6G(SCH_1):PAGE97
   J24  149   RFU2 SCONN288_DDR506112002KQ-SCONN288_DDR506112002KQ,SMA    I22 @T6G_MB_LIB.T6G(SCH_1):PAGE97
   J24  150   RFU3 SCONN288_DDR506112002KQ-SCONN288_DDR506112002KQ,SMA    I22 @T6G_MB_LIB.T6G(SCH_1):PAGE97
   J24  220   RFU4 SCONN288_DDR506112002KQ-SCONN288_DDR506112002KQ,SMA    I22 @T6G_MB_LIB.T6G(SCH_1):PAGE97
   J24  231   RFU5 SCONN288_DDR506112002KQ-SCONN288_DDR506112002KQ,SMA    I22 @T6G_MB_LIB.T6G(SCH_1):PAGE97
   J24  232   RFU6 SCONN288_DDR506112002KQ-SCONN288_DDR506112002KQ,SMA    I22 @T6G_MB_LIB.T6G(SCH_1):PAGE97
   J26    2   RFU0 SCONN288_DDR506112002KQ-SCONN288_DDR506112002KQ,SMA    I22 @T6G_MB_LIB.T6G(SCH_1):PAGE98
   J26  144   RFU1 SCONN288_DDR506112002KQ-SCONN288_DDR506112002KQ,SMA    I22 @T6G_MB_LIB.T6G(SCH_1):PAGE98
   J26  149   RFU2 SCONN288_DDR506112002KQ-SCONN288_DDR506112002KQ,SMA    I22 @T6G_MB_LIB.T6G(SCH_1):PAGE98
   J26  150   RFU3 SCONN288_DDR506112002KQ-SCONN288_DDR506112002KQ,SMA    I22 @T6G_MB_LIB.T6G(SCH_1):PAGE98
   J26  220   RFU4 SCONN288_DDR506112002KQ-SCONN288_DDR506112002KQ,SMA    I22 @T6G_MB_LIB.T6G(SCH_1):PAGE98
   J26  231   RFU5 SCONN288_DDR506112002KQ-SCONN288_DDR506112002KQ,SMA    I22 @T6G_MB_LIB.T6G(SCH_1):PAGE98
   J26  232   RFU6 SCONN288_DDR506112002KQ-SCONN288_DDR506112002KQ,SMA    I22 @T6G_MB_LIB.T6G(SCH_1):PAGE98
   J28    2   RFU0 SCONN288_DDR506112002KQ-SCONN288_DDR506112002KQ,SMA    I22 @T6G_MB_LIB.T6G(SCH_1):PAGE99
   J28  144   RFU1 SCONN288_DDR506112002KQ-SCONN288_DDR506112002KQ,SMA    I22 @T6G_MB_LIB.T6G(SCH_1):PAGE99
   J28  149   RFU2 SCONN288_DDR506112002KQ-SCONN288_DDR506112002KQ,SMA    I22 @T6G_MB_LIB.T6G(SCH_1):PAGE99
   J28  150   RFU3 SCONN288_DDR506112002KQ-SCONN288_DDR506112002KQ,SMA    I22 @T6G_MB_LIB.T6G(SCH_1):PAGE99
   J28  220   RFU4 SCONN288_DDR506112002KQ-SCONN288_DDR506112002KQ,SMA    I22 @T6G_MB_LIB.T6G(SCH_1):PAGE99
   J28  231   RFU5 SCONN288_DDR506112002KQ-SCONN288_DDR506112002KQ,SMA    I22 @T6G_MB_LIB.T6G(SCH_1):PAGE99
   J28  232   RFU6 SCONN288_DDR506112002KQ-SCONN288_DDR506112002KQ,SMA    I22 @T6G_MB_LIB.T6G(SCH_1):PAGE99
   J30    2   RFU0 SCONN288_DDR506112002KQ-SCONN288_DDR506112002KQ,SMA    I52 @T6G_MB_LIB.T6G(SCH_1):PAGE100
   J30  144   RFU1 SCONN288_DDR506112002KQ-SCONN288_DDR506112002KQ,SMA    I52 @T6G_MB_LIB.T6G(SCH_1):PAGE100
   J30  149   RFU2 SCONN288_DDR506112002KQ-SCONN288_DDR506112002KQ,SMA    I52 @T6G_MB_LIB.T6G(SCH_1):PAGE100
   J30  150   RFU3 SCONN288_DDR506112002KQ-SCONN288_DDR506112002KQ,SMA    I52 @T6G_MB_LIB.T6G(SCH_1):PAGE100
   J30  220   RFU4 SCONN288_DDR506112002KQ-SCONN288_DDR506112002KQ,SMA    I52 @T6G_MB_LIB.T6G(SCH_1):PAGE100
   J30  231   RFU5 SCONN288_DDR506112002KQ-SCONN288_DDR506112002KQ,SMA    I52 @T6G_MB_LIB.T6G(SCH_1):PAGE100
   J30  232   RFU6 SCONN288_DDR506112002KQ-SCONN288_DDR506112002KQ,SMA    I52 @T6G_MB_LIB.T6G(SCH_1):PAGE100
   J32    2   RFU0 SCONN288_DDR506112002KQ-SCONN288_DDR506112002KQ,SMA    I52 @T6G_MB_LIB.T6G(SCH_1):PAGE101
   J32  144   RFU1 SCONN288_DDR506112002KQ-SCONN288_DDR506112002KQ,SMA    I52 @T6G_MB_LIB.T6G(SCH_1):PAGE101
   J32  149   RFU2 SCONN288_DDR506112002KQ-SCONN288_DDR506112002KQ,SMA    I52 @T6G_MB_LIB.T6G(SCH_1):PAGE101
   J32  150   RFU3 SCONN288_DDR506112002KQ-SCONN288_DDR506112002KQ,SMA    I52 @T6G_MB_LIB.T6G(SCH_1):PAGE101
   J32  220   RFU4 SCONN288_DDR506112002KQ-SCONN288_DDR506112002KQ,SMA    I52 @T6G_MB_LIB.T6G(SCH_1):PAGE101
   J32  231   RFU5 SCONN288_DDR506112002KQ-SCONN288_DDR506112002KQ,SMA    I52 @T6G_MB_LIB.T6G(SCH_1):PAGE101
   J32  232   RFU6 SCONN288_DDR506112002KQ-SCONN288_DDR506112002KQ,SMA    I52 @T6G_MB_LIB.T6G(SCH_1):PAGE101
   J33    2   RFU0 SCONN288_DDR506112002KQ-SCONN288_DDR506112002KQ,SMA    I22 @T6G_MB_LIB.T6G(SCH_1):PAGE102
   J33  144   RFU1 SCONN288_DDR506112002KQ-SCONN288_DDR506112002KQ,SMA    I22 @T6G_MB_LIB.T6G(SCH_1):PAGE102
   J33  149   RFU2 SCONN288_DDR506112002KQ-SCONN288_DDR506112002KQ,SMA    I22 @T6G_MB_LIB.T6G(SCH_1):PAGE102
   J33  150   RFU3 SCONN288_DDR506112002KQ-SCONN288_DDR506112002KQ,SMA    I22 @T6G_MB_LIB.T6G(SCH_1):PAGE102
   J33  220   RFU4 SCONN288_DDR506112002KQ-SCONN288_DDR506112002KQ,SMA    I22 @T6G_MB_LIB.T6G(SCH_1):PAGE102
   J33  231   RFU5 SCONN288_DDR506112002KQ-SCONN288_DDR506112002KQ,SMA    I22 @T6G_MB_LIB.T6G(SCH_1):PAGE102
   J33  232   RFU6 SCONN288_DDR506112002KQ-SCONN288_DDR506112002KQ,SMA    I22 @T6G_MB_LIB.T6G(SCH_1):PAGE102
  J102    2   RFU0 SCONN288_DDR506112002KQ-SCONN288_DDR506112002KQ,SMA    I22 @T6G_MB_LIB.T6G(SCH_1):PAGE103
  J102  144   RFU1 SCONN288_DDR506112002KQ-SCONN288_DDR506112002KQ,SMA    I22 @T6G_MB_LIB.T6G(SCH_1):PAGE103
  J102  149   RFU2 SCONN288_DDR506112002KQ-SCONN288_DDR506112002KQ,SMA    I22 @T6G_MB_LIB.T6G(SCH_1):PAGE103
  J102  150   RFU3 SCONN288_DDR506112002KQ-SCONN288_DDR506112002KQ,SMA    I22 @T6G_MB_LIB.T6G(SCH_1):PAGE103
  J102  220   RFU4 SCONN288_DDR506112002KQ-SCONN288_DDR506112002KQ,SMA    I22 @T6G_MB_LIB.T6G(SCH_1):PAGE103
  J102  231   RFU5 SCONN288_DDR506112002KQ-SCONN288_DDR506112002KQ,SMA    I22 @T6G_MB_LIB.T6G(SCH_1):PAGE103
  J102  232   RFU6 SCONN288_DDR506112002KQ-SCONN288_DDR506112002KQ,SMA    I22 @T6G_MB_LIB.T6G(SCH_1):PAGE103
   J27    2   RFU0 SCONN288_DDR506112002KQ-SCONN288_DDR506112002KQ,SMA    I22 @T6G_MB_LIB.T6G(SCH_1):PAGE104
   J27  144   RFU1 SCONN288_DDR506112002KQ-SCONN288_DDR506112002KQ,SMA    I22 @T6G_MB_LIB.T6G(SCH_1):PAGE104
   J27  149   RFU2 SCONN288_DDR506112002KQ-SCONN288_DDR506112002KQ,SMA    I22 @T6G_MB_LIB.T6G(SCH_1):PAGE104
   J27  150   RFU3 SCONN288_DDR506112002KQ-SCONN288_DDR506112002KQ,SMA    I22 @T6G_MB_LIB.T6G(SCH_1):PAGE104
   J27  220   RFU4 SCONN288_DDR506112002KQ-SCONN288_DDR506112002KQ,SMA    I22 @T6G_MB_LIB.T6G(SCH_1):PAGE104
   J27  231   RFU5 SCONN288_DDR506112002KQ-SCONN288_DDR506112002KQ,SMA    I22 @T6G_MB_LIB.T6G(SCH_1):PAGE104
   J27  232   RFU6 SCONN288_DDR506112002KQ-SCONN288_DDR506112002KQ,SMA    I22 @T6G_MB_LIB.T6G(SCH_1):PAGE104
  J100    2   RFU0 SCONN288_DDR506112002KQ-SCONN288_DDR506112002KQ,SMA    I22 @T6G_MB_LIB.T6G(SCH_1):PAGE105
  J100  144   RFU1 SCONN288_DDR506112002KQ-SCONN288_DDR506112002KQ,SMA    I22 @T6G_MB_LIB.T6G(SCH_1):PAGE105
  J100  149   RFU2 SCONN288_DDR506112002KQ-SCONN288_DDR506112002KQ,SMA    I22 @T6G_MB_LIB.T6G(SCH_1):PAGE105
  J100  150   RFU3 SCONN288_DDR506112002KQ-SCONN288_DDR506112002KQ,SMA    I22 @T6G_MB_LIB.T6G(SCH_1):PAGE105
  J100  220   RFU4 SCONN288_DDR506112002KQ-SCONN288_DDR506112002KQ,SMA    I22 @T6G_MB_LIB.T6G(SCH_1):PAGE105
  J100  231   RFU5 SCONN288_DDR506112002KQ-SCONN288_DDR506112002KQ,SMA    I22 @T6G_MB_LIB.T6G(SCH_1):PAGE105
  J100  232   RFU6 SCONN288_DDR506112002KQ-SCONN288_DDR506112002KQ,SMA    I22 @T6G_MB_LIB.T6G(SCH_1):PAGE105
   J29    2   RFU0 SCONN288_DDR506112002KQ-SCONN288_DDR506112002KQ,SMA    I22 @T6G_MB_LIB.T6G(SCH_1):PAGE106
   J29  144   RFU1 SCONN288_DDR506112002KQ-SCONN288_DDR506112002KQ,SMA    I22 @T6G_MB_LIB.T6G(SCH_1):PAGE106
   J29  149   RFU2 SCONN288_DDR506112002KQ-SCONN288_DDR506112002KQ,SMA    I22 @T6G_MB_LIB.T6G(SCH_1):PAGE106
   J29  150   RFU3 SCONN288_DDR506112002KQ-SCONN288_DDR506112002KQ,SMA    I22 @T6G_MB_LIB.T6G(SCH_1):PAGE106
   J29  220   RFU4 SCONN288_DDR506112002KQ-SCONN288_DDR506112002KQ,SMA    I22 @T6G_MB_LIB.T6G(SCH_1):PAGE106
   J29  231   RFU5 SCONN288_DDR506112002KQ-SCONN288_DDR506112002KQ,SMA    I22 @T6G_MB_LIB.T6G(SCH_1):PAGE106
   J29  232   RFU6 SCONN288_DDR506112002KQ-SCONN288_DDR506112002KQ,SMA    I22 @T6G_MB_LIB.T6G(SCH_1):PAGE106
   J99    2   RFU0 SCONN288_DDR506112002KQ-SCONN288_DDR506112002KQ,SMA    I22 @T6G_MB_LIB.T6G(SCH_1):PAGE107
   J99  144   RFU1 SCONN288_DDR506112002KQ-SCONN288_DDR506112002KQ,SMA    I22 @T6G_MB_LIB.T6G(SCH_1):PAGE107
   J99  149   RFU2 SCONN288_DDR506112002KQ-SCONN288_DDR506112002KQ,SMA    I22 @T6G_MB_LIB.T6G(SCH_1):PAGE107
   J99  150   RFU3 SCONN288_DDR506112002KQ-SCONN288_DDR506112002KQ,SMA    I22 @T6G_MB_LIB.T6G(SCH_1):PAGE107
   J99  220   RFU4 SCONN288_DDR506112002KQ-SCONN288_DDR506112002KQ,SMA    I22 @T6G_MB_LIB.T6G(SCH_1):PAGE107
   J99  231   RFU5 SCONN288_DDR506112002KQ-SCONN288_DDR506112002KQ,SMA    I22 @T6G_MB_LIB.T6G(SCH_1):PAGE107
   J99  232   RFU6 SCONN288_DDR506112002KQ-SCONN288_DDR506112002KQ,SMA    I22 @T6G_MB_LIB.T6G(SCH_1):PAGE107
   J37    2   RFU0 SCONN288_DDR506112002KQ-SCONN288_DDR506112002KQ,SMA    I22 @T6G_MB_LIB.T6G(SCH_1):PAGE108
   J37  144   RFU1 SCONN288_DDR506112002KQ-SCONN288_DDR506112002KQ,SMA    I22 @T6G_MB_LIB.T6G(SCH_1):PAGE108
   J37  149   RFU2 SCONN288_DDR506112002KQ-SCONN288_DDR506112002KQ,SMA    I22 @T6G_MB_LIB.T6G(SCH_1):PAGE108
   J37  150   RFU3 SCONN288_DDR506112002KQ-SCONN288_DDR506112002KQ,SMA    I22 @T6G_MB_LIB.T6G(SCH_1):PAGE108
   J37  220   RFU4 SCONN288_DDR506112002KQ-SCONN288_DDR506112002KQ,SMA    I22 @T6G_MB_LIB.T6G(SCH_1):PAGE108
   J37  231   RFU5 SCONN288_DDR506112002KQ-SCONN288_DDR506112002KQ,SMA    I22 @T6G_MB_LIB.T6G(SCH_1):PAGE108
   J37  232   RFU6 SCONN288_DDR506112002KQ-SCONN288_DDR506112002KQ,SMA    I22 @T6G_MB_LIB.T6G(SCH_1):PAGE108
   U82    1     NC SN74LVC1G07DBVR_SMLF-SN74LVC1G07DBVR,IC,AL1G0007024    I26 @T6G_MB_LIB.T6G(SCH_1):PAGE143
   U86    1     NC SN74LVC1G07DBVR_SMLF-SN74LVC1G07DBVR,IC,AL1G0007024    I31 @T6G_MB_LIB.T6G(SCH_1):PAGE143
  U124    1     NC SN74LVC1G07DBVR_SMLF-SN74LVC1G07DBVR,IC,AL1G0007024    I38 @T6G_MB_LIB.T6G(SCH_1):PAGE144
   U99    1     NC SN74LVC1G07DBVR_SMLF-SN74LVC1G07DBVR,EMPTY,AL1G000A   I340 @T6G_MB_LIB.T6G(SCH_1):PAGE148
   J54   14     14 SCONN20_HSU2101L00007H-SCONN20_HSU2101-L0000-7H,SMA   I142 @T6G_MB_LIB.T6G(SCH_1):PAGE149
   J54   20     20 SCONN20_HSU2101L00007H-SCONN20_HSU2101-L0000-7H,SMA   I142 @T6G_MB_LIB.T6G(SCH_1):PAGE149
    J1    2   RFU0 SCONN288_DDR506112002KQ-SCONN288_DDR506112002KQ,SMA   I536 @T6G_MB_LIB.T6G(SCH_1):PAGE85
    J1  144   RFU1 SCONN288_DDR506112002KQ-SCONN288_DDR506112002KQ,SMA   I536 @T6G_MB_LIB.T6G(SCH_1):PAGE85
    J1  149   RFU2 SCONN288_DDR506112002KQ-SCONN288_DDR506112002KQ,SMA   I536 @T6G_MB_LIB.T6G(SCH_1):PAGE85
    J1  150   RFU3 SCONN288_DDR506112002KQ-SCONN288_DDR506112002KQ,SMA   I536 @T6G_MB_LIB.T6G(SCH_1):PAGE85
    J1  220   RFU4 SCONN288_DDR506112002KQ-SCONN288_DDR506112002KQ,SMA   I536 @T6G_MB_LIB.T6G(SCH_1):PAGE85
    J1  231   RFU5 SCONN288_DDR506112002KQ-SCONN288_DDR506112002KQ,SMA   I536 @T6G_MB_LIB.T6G(SCH_1):PAGE85
    J1  232   RFU6 SCONN288_DDR506112002KQ-SCONN288_DDR506112002KQ,SMA   I536 @T6G_MB_LIB.T6G(SCH_1):PAGE85
  U192    5  READY LTC4307CMS8-LTC4307CMS8,SMLF,IC,AL004307000   I398 @T6G_MB_LIB.T6G(SCH_1):PAGE363
  U308    3     2A 74LVC2G07DW7-74LVC2G07DW-7,SMLF,IC,AL002G07003    I37 @T6G_MB_LIB.T6G(SCH_1):PAGE364
  U308    4     2Y 74LVC2G07DW7-74LVC2G07DW-7,SMLF,IC,AL002G07003    I37 @T6G_MB_LIB.T6G(SCH_1):PAGE364
  U200    5  READY LTC4307CMS8-LTC4307CMS8,SMLF,IC,AL004307000    I15 @T6G_MB_LIB.T6G(SCH_1):PAGE249
  U176    5  READY LTC4307CMS8-LTC4307CMS8,SMLF,EMPTY,AL004307000    I30 @T6G_MB_LIB.T6G(SCH_1):PAGE249
  U194    5  READY LTC4307CMS8-LTC4307CMS8,SMLF,IC,AL004307000    I42 @T6G_MB_LIB.T6G(SCH_1):PAGE249
  U175    5  READY LTC4307CMS8-LTC4307CMS8,SMLF,IC,AL004307000    I49 @T6G_MB_LIB.T6G(SCH_1):PAGE249
   U39   20    SC7 TCA9548APWR-TCA9548APWR,SMLF,IC,AL009548K02    I74 @T6G_MB_LIB.T6G(SCH_1):PAGE251
   U39   19    SD7 TCA9548APWR-TCA9548APWR,SMLF,IC,AL009548K02    I74 @T6G_MB_LIB.T6G(SCH_1):PAGE251
   U36   20    SC7 TCA9548APWR-TCA9548APWR,SMLF,IC,AL009548K02    I33 @T6G_MB_LIB.T6G(SCH_1):PAGE252
   U36   19    SD7 TCA9548APWR-TCA9548APWR,SMLF,IC,AL009548K02    I33 @T6G_MB_LIB.T6G(SCH_1):PAGE252
   U26  E50 WAFL_RXN0||P5_RXN0 GENOA_SP5-SOCKET6096_13568-001,SMLF,IO,DGA^6000030   I145 @T6G_MB_LIB.T6G(SCH_1):PAGE53
   U26  E49 WAFL_RXP0||P5_RXP0 GENOA_SP5-SOCKET6096_13568-001,SMLF,IO,DGA^6000030   I145 @T6G_MB_LIB.T6G(SCH_1):PAGE53
   U26  C51 WAFL_TXN0||P5_TXN0 GENOA_SP5-SOCKET6096_13568-001,SMLF,IO,DGA^6000030   I145 @T6G_MB_LIB.T6G(SCH_1):PAGE53
   U26  C50 WAFL_TXP0||P5_TXP0 GENOA_SP5-SOCKET6096_13568-001,SMLF,IO,DGA^6000030   I145 @T6G_MB_LIB.T6G(SCH_1):PAGE53
   U44    1     NC 74LVC1G17GW-74LVC1G17GW,SMLF,IC,AL1G0017K01    I97 @T6G_MB_LIB.T6G(SCH_1):PAGE297
   U92    1     NC SN74LVC1G07DBVR_SMLF-SN74LVC1G07DBVR,IC,AL1G0007024    I26 @T6G_MB_LIB.T6G(SCH_1):PAGE83
   J57    4      4 CONN8_HBB1081L200D8H-CONN8_HBB1081-L200D-8H,THLF,IA    I41 @T6G_MB_LIB.T6G(SCH_1):PAGE84
   J57    5      5 CONN8_HBB1081L200D8H-CONN8_HBB1081-L200D-8H,THLF,IA    I41 @T6G_MB_LIB.T6G(SCH_1):PAGE84
   U18  U12  PB27C LCMXO3LF9400C5BG484C-LCMXO3LF-9400C-5BG484C,SMLF,IA   I216 @T6G_MB_LIB.T6G(SCH_1):PAGE80
    J6    5      5 CONN6_HBC1031L200D8H-CONN6_HBC1031-L200D-8H,THLF,IA    I28 @T6G_MB_LIB.T6G(SCH_1):PAGE28
   U25 DG11 AGPIO87 GENOA_SP5-SOCKET6096_13568-001,SMLF,IO,DGA^6000030   I188 @T6G_MB_LIB.T6G(SCH_1):PAGE28
   U25  B16 AGPIO259||SGPIO3_CLK GENOA_SP5-SOCKET6096_13568-001,SMLF,IO,DGA^6000030   I188 @T6G_MB_LIB.T6G(SCH_1):PAGE28
   U25 DJ47 GPP_CLK14N GENOA_SP5-SOCKET6096_13568-001,SMLF,IO,DGA^6000030   I188 @T6G_MB_LIB.T6G(SCH_1):PAGE28
   U25 DJ48 GPP_CLK14P GENOA_SP5-SOCKET6096_13568-001,SMLF,IO,DGA^6000030   I188 @T6G_MB_LIB.T6G(SCH_1):PAGE28
   U25 DJ50 GPP_CLK15N GENOA_SP5-SOCKET6096_13568-001,SMLF,IO,DGA^6000030   I188 @T6G_MB_LIB.T6G(SCH_1):PAGE28
   U25 DJ51 GPP_CLK15P GENOA_SP5-SOCKET6096_13568-001,SMLF,IO,DGA^6000030   I188 @T6G_MB_LIB.T6G(SCH_1):PAGE28
   U25  D15 SGPIO_DATAOUT||AGPIO260 GENOA_SP5-SOCKET6096_13568-001,SMLF,IO,DGA^6000030   I188 @T6G_MB_LIB.T6G(SCH_1):PAGE28
   U25  B15 SGPIO_LOAD||AGPIO261 GENOA_SP5-SOCKET6096_13568-001,SMLF,IO,DGA^6000030   I188 @T6G_MB_LIB.T6G(SCH_1):PAGE28
   H27    1      1 HOLE_TH-EMPTY,DUMMY50    I41 @T6G_MB_LIB.T6G(SCH_1):PAGE212
   H28    1      1 HOLE_TH-EMPTY,DUMMY50    I50 @T6G_MB_LIB.T6G(SCH_1):PAGE212
   H29    1      1 HOLE_TH-EMPTY,DUMMY50    I51 @T6G_MB_LIB.T6G(SCH_1):PAGE212
   H30    1      1 HOLE_TH-EMPTY,DUMMY50    I56 @T6G_MB_LIB.T6G(SCH_1):PAGE212
  H124    1      1 HOLE_TH-EMPTY,TMP-C_T2I_ALEX_1121_1    I84 @T6G_MB_LIB.T6G(SCH_1):PAGE212
  H125    1      1 HOLE_TH-EMPTY,TMP-C_T2I_ALEX_1121_1    I85 @T6G_MB_LIB.T6G(SCH_1):PAGE212
   H74    1      1 HOLE_TH-EMPTY,HOLE1247    I88 @T6G_MB_LIB.T6G(SCH_1):PAGE212
   H75    1      1 HOLE_TH-EMPTY,HOLE1247    I89 @T6G_MB_LIB.T6G(SCH_1):PAGE212
  H127    1      1 HOLE_TH-EMPTY,TMP-C_T2I_ALEX_1121_1    I94 @T6G_MB_LIB.T6G(SCH_1):PAGE212
  J122 SCR_H1    NC1 CONN1_10165288101LF-CONN1_10165288-101LF,THLF,IO,DA   I101 @T6G_MB_LIB.T6G(SCH_1):PAGE212
  J123 SCR_H1    NC1 CONN1_10165288101LF-CONN1_10165288-101LF,THLF,IO,DA   I106 @T6G_MB_LIB.T6G(SCH_1):PAGE212
  H126    1      1 HOLE_TH-EMPTY,TMP-C_T2I_ALEX_1121_1   I111 @T6G_MB_LIB.T6G(SCH_1):PAGE212
   U75    1     NC 74LVC1G17GW-74LVC1G17GW,SMLF,IC,AL1G0017K01    I64 @T6G_MB_LIB.T6G(SCH_1):PAGE337
  U207    1     NC 74LVC1G17GW-74LVC1G17GW,SMLF,IC,AL1G0017K01    I58 @T6G_MB_LIB.T6G(SCH_1):PAGE342
JP4003    1      1 CONN3_210HP1030BR1-CONN3_210-HP1-030BR1,THLF,IO,DFA    I18 @T6G_MB_LIB.T6G(SCH_1):PAGE372
 U6001   63 DS2_DM CYUSB330468LTXI-CYUSB3304-68LTXI,SMLF,IC,AJ0330400A     I1 @T6G_MB_LIB.T6G(SCH_1):PAGE153
 U6001   62 DS2_DP CYUSB330468LTXI-CYUSB3304-68LTXI,SMLF,IC,AJ0330400A     I1 @T6G_MB_LIB.T6G(SCH_1):PAGE153
 U6001   44 DS2_RXM CYUSB330468LTXI-CYUSB3304-68LTXI,SMLF,IC,AJ0330400A     I1 @T6G_MB_LIB.T6G(SCH_1):PAGE153
 U6001   45 DS2_RXP CYUSB330468LTXI-CYUSB3304-68LTXI,SMLF,IC,AJ0330400A     I1 @T6G_MB_LIB.T6G(SCH_1):PAGE153
 U6001   42 DS2_TXM CYUSB330468LTXI-CYUSB3304-68LTXI,SMLF,IC,AJ0330400A     I1 @T6G_MB_LIB.T6G(SCH_1):PAGE153
 U6001   41 DS2_TXP CYUSB330468LTXI-CYUSB3304-68LTXI,SMLF,IC,AJ0330400A     I1 @T6G_MB_LIB.T6G(SCH_1):PAGE153
 U6001   64 DS3_DM CYUSB330468LTXI-CYUSB3304-68LTXI,SMLF,IC,AJ0330400A     I1 @T6G_MB_LIB.T6G(SCH_1):PAGE153
 U6001   65 DS3_DP CYUSB330468LTXI-CYUSB3304-68LTXI,SMLF,IC,AJ0330400A     I1 @T6G_MB_LIB.T6G(SCH_1):PAGE153
 U6001   36 DS3_RXM CYUSB330468LTXI-CYUSB3304-68LTXI,SMLF,IC,AJ0330400A     I1 @T6G_MB_LIB.T6G(SCH_1):PAGE153
 U6001   35 DS3_RXP CYUSB330468LTXI-CYUSB3304-68LTXI,SMLF,IC,AJ0330400A     I1 @T6G_MB_LIB.T6G(SCH_1):PAGE153
 U6001   39 DS3_TXM CYUSB330468LTXI-CYUSB3304-68LTXI,SMLF,IC,AJ0330400A     I1 @T6G_MB_LIB.T6G(SCH_1):PAGE153
 U6001   38 DS3_TXP CYUSB330468LTXI-CYUSB3304-68LTXI,SMLF,IC,AJ0330400A     I1 @T6G_MB_LIB.T6G(SCH_1):PAGE153
 U6001   68 DS4_DM CYUSB330468LTXI-CYUSB3304-68LTXI,SMLF,IC,AJ0330400A     I1 @T6G_MB_LIB.T6G(SCH_1):PAGE153
 U6001   67 DS4_DP CYUSB330468LTXI-CYUSB3304-68LTXI,SMLF,IC,AJ0330400A     I1 @T6G_MB_LIB.T6G(SCH_1):PAGE153
 U6001   14 DS4_RXM CYUSB330468LTXI-CYUSB3304-68LTXI,SMLF,IC,AJ0330400A     I1 @T6G_MB_LIB.T6G(SCH_1):PAGE153
 U6001   15 DS4_RXP CYUSB330468LTXI-CYUSB3304-68LTXI,SMLF,IC,AJ0330400A     I1 @T6G_MB_LIB.T6G(SCH_1):PAGE153
 U6001   12 DS4_TXM CYUSB330468LTXI-CYUSB3304-68LTXI,SMLF,IC,AJ0330400A     I1 @T6G_MB_LIB.T6G(SCH_1):PAGE153
 U6001   11 DS4_TXP CYUSB330468LTXI-CYUSB3304-68LTXI,SMLF,IC,AJ0330400A     I1 @T6G_MB_LIB.T6G(SCH_1):PAGE153
 U6001   25  NC_25 CYUSB330468LTXI-CYUSB3304-68LTXI,SMLF,IC,AJ0330400A     I1 @T6G_MB_LIB.T6G(SCH_1):PAGE153
  J212    9      9 CONN10_HBC1051L300D8H-CONN10_HBC1051-L300D-8H,THLFA   I423 @T6G_MB_LIB.T6G(SCH_1):PAGE27
  J212   10     10 CONN10_HBC1051L300D8H-CONN10_HBC1051-L300D-8H,THLFA   I423 @T6G_MB_LIB.T6G(SCH_1):PAGE27
 U6002   36 PWRCTL1||BATEN1 TUSB8042AIRGCR-TUSB8042AIRGCR,SMLF,IC,AL008042000   I101 @T6G_MB_LIB.T6G(SCH_1):PAGE155
 U6002   32 PWRCTL4||BATEN4 TUSB8042AIRGCR-TUSB8042AIRGCR,SMLF,IC,AL008042000   I101 @T6G_MB_LIB.T6G(SCH_1):PAGE155
 U6002    2 USB_DM_DN1 TUSB8042AIRGCR-TUSB8042AIRGCR,SMLF,IC,AL008042000   I101 @T6G_MB_LIB.T6G(SCH_1):PAGE155
 U6002   25 USB_DM_DN4 TUSB8042AIRGCR-TUSB8042AIRGCR,SMLF,IC,AL008042000   I101 @T6G_MB_LIB.T6G(SCH_1):PAGE155
 U6002   24 USB_DP_DN4 TUSB8042AIRGCR-TUSB8042AIRGCR,SMLF,IC,AL008042000   I101 @T6G_MB_LIB.T6G(SCH_1):PAGE155
 U6002    7 USB_SSRXM_DN1 TUSB8042AIRGCR-TUSB8042AIRGCR,SMLF,IC,AL008042000   I101 @T6G_MB_LIB.T6G(SCH_1):PAGE155
 U6002   22 USB_SSRXP_DN3 TUSB8042AIRGCR-TUSB8042AIRGCR,SMLF,IC,AL008042000   I101 @T6G_MB_LIB.T6G(SCH_1):PAGE155
 U6002   29 USB_SSRXP_DN4 TUSB8042AIRGCR-TUSB8042AIRGCR,SMLF,IC,AL008042000   I101 @T6G_MB_LIB.T6G(SCH_1):PAGE155
 U6002    4 USB_SSTXM_DN1 TUSB8042AIRGCR-TUSB8042AIRGCR,SMLF,IC,AL008042000   I101 @T6G_MB_LIB.T6G(SCH_1):PAGE155
 U6002   20 USB_SSTXM_DN3 TUSB8042AIRGCR-TUSB8042AIRGCR,SMLF,IC,AL008042000   I101 @T6G_MB_LIB.T6G(SCH_1):PAGE155
 U6002   27 USB_SSTXM_DN4 TUSB8042AIRGCR-TUSB8042AIRGCR,SMLF,IC,AL008042000   I101 @T6G_MB_LIB.T6G(SCH_1):PAGE155
 U6002    3 USB_SSTXP_DN1 TUSB8042AIRGCR-TUSB8042AIRGCR,SMLF,IC,AL008042000   I101 @T6G_MB_LIB.T6G(SCH_1):PAGE155
 U6002   19 USB_SSTXP_DN3 TUSB8042AIRGCR-TUSB8042AIRGCR,SMLF,IC,AL008042000   I101 @T6G_MB_LIB.T6G(SCH_1):PAGE155
 U6002   26 USB_SSTXP_DN4 TUSB8042AIRGCR-TUSB8042AIRGCR,SMLF,IC,AL008042000   I101 @T6G_MB_LIB.T6G(SCH_1):PAGE155
   H90    1      1 HOLE_TH-EMPTY,HOLE372   I167 @T6G_MB_LIB.T6G(SCH_1):PAGE212
 U8005    3      3 LM4040AIM3X25NOPB-LM4040AIM3X-2.5/NOPB,SMLF,EMPTY,A   I101 @T6G_MB_LIB.T6G(SCH_1):PAGE371
 U8007    3      3 LM4040AIM3X25NOPB-LM4040AIM3X-2.5/NOPB,SMLF,IC,AL4A    I51 @T6G_MB_LIB.T6G(SCH_1):PAGE372
 U8009    3      3 LM4040AIM3X25NOPB-LM4040AIM3X-2.5/NOPB,SMLF,IC,AL4A    I93 @T6G_MB_LIB.T6G(SCH_1):PAGE372
 U6014  FJ6  GPIO0 PT5161LRS-PT5161LRS,SMLF,IC,AJ051610U03     I1 @T6G_MB_LIB.T6G(SCH_1):PAGE401
 U6014 FJ23  GPIO1 PT5161LRS-PT5161LRS,SMLF,IC,AJ051610U03     I1 @T6G_MB_LIB.T6G(SCH_1):PAGE401
 U6014 FJ31  INT_N PT5161LRS-PT5161LRS,SMLF,IC,AJ051610U03     I1 @T6G_MB_LIB.T6G(SCH_1):PAGE401
 U6014  E18 REFCLK_OUTN PT5161LRS-PT5161LRS,SMLF,IC,AJ051610U03     I1 @T6G_MB_LIB.T6G(SCH_1):PAGE401
 U6014  B16 REFCLK_OUTP PT5161LRS-PT5161LRS,SMLF,IC,AJ051610U03     I1 @T6G_MB_LIB.T6G(SCH_1):PAGE401
   U11    1    DU1 M24M02DRMN6TP-M24M02-DRMN6TP,SMLF,IC,AKE33Z00600     I3 @T6G_MB_LIB.T6G(SCH_1):PAGE387
   U11    2    DU2 M24M02DRMN6TP-M24M02-DRMN6TP,SMLF,IC,AKE33Z00600     I3 @T6G_MB_LIB.T6G(SCH_1):PAGE387
   U15    1    DU1 M24M02DRMN6TP-M24M02-DRMN6TP,SMLF,IC,AKE33Z00600     I5 @T6G_MB_LIB.T6G(SCH_1):PAGE410
   U15    2    DU2 M24M02DRMN6TP-M24M02-DRMN6TP,SMLF,IC,AKE33Z00600     I5 @T6G_MB_LIB.T6G(SCH_1):PAGE410
   U16    1    DU1 M24M02DRMN6TP-M24M02-DRMN6TP,SMLF,IC,AKE33Z00600     I5 @T6G_MB_LIB.T6G(SCH_1):PAGE421
   U16    2    DU2 M24M02DRMN6TP-M24M02-DRMN6TP,SMLF,IC,AKE33Z00600     I5 @T6G_MB_LIB.T6G(SCH_1):PAGE421
   U17    1    DU1 M24M02DRMN6TP-M24M02-DRMN6TP,SMLF,IC,AKE33Z00600     I5 @T6G_MB_LIB.T6G(SCH_1):PAGE432
   U17    2    DU2 M24M02DRMN6TP-M24M02-DRMN6TP,SMLF,IC,AKE33Z00600     I5 @T6G_MB_LIB.T6G(SCH_1):PAGE432
   U12    1    DU1 M24M02DRMN6TP-M24M02-DRMN6TP,SMLF,IC,AKE33Z00600     I5 @T6G_MB_LIB.T6G(SCH_1):PAGE399
   U12    2    DU2 M24M02DRMN6TP-M24M02-DRMN6TP,SMLF,IC,AKE33Z00600     I5 @T6G_MB_LIB.T6G(SCH_1):PAGE399
   U19    1    DU1 M24M02DRMN6TP-M24M02-DRMN6TP,SMLF,IC,AKE33Z00600     I5 @T6G_MB_LIB.T6G(SCH_1):PAGE442
   U19    2    DU2 M24M02DRMN6TP-M24M02-DRMN6TP,SMLF,IC,AKE33Z00600     I5 @T6G_MB_LIB.T6G(SCH_1):PAGE442
   U20    1    DU1 M24M02DRMN6TP-M24M02-DRMN6TP,SMLF,IC,AKE33Z00600     I5 @T6G_MB_LIB.T6G(SCH_1):PAGE453
   U20    2    DU2 M24M02DRMN6TP-M24M02-DRMN6TP,SMLF,IC,AKE33Z00600     I5 @T6G_MB_LIB.T6G(SCH_1):PAGE453
   U21    1    DU1 M24M02DRMN6TP-M24M02-DRMN6TP,SMLF,IC,AKE33Z00600     I5 @T6G_MB_LIB.T6G(SCH_1):PAGE464
   U21    2    DU2 M24M02DRMN6TP-M24M02-DRMN6TP,SMLF,IC,AKE33Z00600     I5 @T6G_MB_LIB.T6G(SCH_1):PAGE464
 U6015  FJ6  GPIO0 PT5161LRS-PT5161LRS,SMLF,IC,AJ051610U03    I47 @T6G_MB_LIB.T6G(SCH_1):PAGE392
 U6015 FJ23  GPIO1 PT5161LRS-PT5161LRS,SMLF,IC,AJ051610U03    I47 @T6G_MB_LIB.T6G(SCH_1):PAGE392
 U6015 FJ31  INT_N PT5161LRS-PT5161LRS,SMLF,IC,AJ051610U03    I47 @T6G_MB_LIB.T6G(SCH_1):PAGE392
 U6015  E18 REFCLK_OUTN PT5161LRS-PT5161LRS,SMLF,IC,AJ051610U03    I47 @T6G_MB_LIB.T6G(SCH_1):PAGE392
 U6015  B16 REFCLK_OUTP PT5161LRS-PT5161LRS,SMLF,IC,AJ051610U03    I47 @T6G_MB_LIB.T6G(SCH_1):PAGE392
 U6016  FJ6  GPIO0 PT5161LRS-PT5161LRS,SMLF,IC,AJ051610U03    I97 @T6G_MB_LIB.T6G(SCH_1):PAGE451
 U6016 FJ23  GPIO1 PT5161LRS-PT5161LRS,SMLF,IC,AJ051610U03    I97 @T6G_MB_LIB.T6G(SCH_1):PAGE451
 U6016 FJ31  INT_N PT5161LRS-PT5161LRS,SMLF,IC,AJ051610U03    I97 @T6G_MB_LIB.T6G(SCH_1):PAGE451
 U6016  E18 REFCLK_OUTN PT5161LRS-PT5161LRS,SMLF,IC,AJ051610U03    I97 @T6G_MB_LIB.T6G(SCH_1):PAGE451
 U6016  B16 REFCLK_OUTP PT5161LRS-PT5161LRS,SMLF,IC,AJ051610U03    I97 @T6G_MB_LIB.T6G(SCH_1):PAGE451
 U6017  FJ6  GPIO0 PT5161LRS-PT5161LRS,SMLF,IC,AJ051610U03    I97 @T6G_MB_LIB.T6G(SCH_1):PAGE462
 U6017 FJ23  GPIO1 PT5161LRS-PT5161LRS,SMLF,IC,AJ051610U03    I97 @T6G_MB_LIB.T6G(SCH_1):PAGE462
 U6017 FJ31  INT_N PT5161LRS-PT5161LRS,SMLF,IC,AJ051610U03    I97 @T6G_MB_LIB.T6G(SCH_1):PAGE462
 U6017  E18 REFCLK_OUTN PT5161LRS-PT5161LRS,SMLF,IC,AJ051610U03    I97 @T6G_MB_LIB.T6G(SCH_1):PAGE462
 U6017  B16 REFCLK_OUTP PT5161LRS-PT5161LRS,SMLF,IC,AJ051610U03    I97 @T6G_MB_LIB.T6G(SCH_1):PAGE462
 U6010  FJ6  GPIO0 PT5161LRS-PT5161LRS,SMLF,IC,AJ051610U03    I53 @T6G_MB_LIB.T6G(SCH_1):PAGE385
 U6010 FJ23  GPIO1 PT5161LRS-PT5161LRS,SMLF,IC,AJ051610U03    I53 @T6G_MB_LIB.T6G(SCH_1):PAGE385
 U6010 FJ31  INT_N PT5161LRS-PT5161LRS,SMLF,IC,AJ051610U03    I53 @T6G_MB_LIB.T6G(SCH_1):PAGE385
 U6010  E18 REFCLK_OUTN PT5161LRS-PT5161LRS,SMLF,IC,AJ051610U03    I53 @T6G_MB_LIB.T6G(SCH_1):PAGE385
 U6010  B16 REFCLK_OUTP PT5161LRS-PT5161LRS,SMLF,IC,AJ051610U03    I53 @T6G_MB_LIB.T6G(SCH_1):PAGE385
 U6011  FJ6  GPIO0 PT5161LRS-PT5161LRS,SMLF,IC,AJ051610U03    I83 @T6G_MB_LIB.T6G(SCH_1):PAGE408
 U6011 FJ23  GPIO1 PT5161LRS-PT5161LRS,SMLF,IC,AJ051610U03    I83 @T6G_MB_LIB.T6G(SCH_1):PAGE408
 U6011 FJ31  INT_N PT5161LRS-PT5161LRS,SMLF,IC,AJ051610U03    I83 @T6G_MB_LIB.T6G(SCH_1):PAGE408
 U6011  E18 REFCLK_OUTN PT5161LRS-PT5161LRS,SMLF,IC,AJ051610U03    I83 @T6G_MB_LIB.T6G(SCH_1):PAGE408
 U6011  B16 REFCLK_OUTP PT5161LRS-PT5161LRS,SMLF,IC,AJ051610U03    I83 @T6G_MB_LIB.T6G(SCH_1):PAGE408
 U6012  FJ6  GPIO0 PT5161LRS-PT5161LRS,SMLF,IC,AJ051610U03    I83 @T6G_MB_LIB.T6G(SCH_1):PAGE419
 U6012 FJ23  GPIO1 PT5161LRS-PT5161LRS,SMLF,IC,AJ051610U03    I83 @T6G_MB_LIB.T6G(SCH_1):PAGE419
 U6012 FJ31  INT_N PT5161LRS-PT5161LRS,SMLF,IC,AJ051610U03    I83 @T6G_MB_LIB.T6G(SCH_1):PAGE419
 U6012  E18 REFCLK_OUTN PT5161LRS-PT5161LRS,SMLF,IC,AJ051610U03    I83 @T6G_MB_LIB.T6G(SCH_1):PAGE419
 U6012  B16 REFCLK_OUTP PT5161LRS-PT5161LRS,SMLF,IC,AJ051610U03    I83 @T6G_MB_LIB.T6G(SCH_1):PAGE419
 U6013  FJ6  GPIO0 PT5161LRS-PT5161LRS,SMLF,IC,AJ051610U03    I83 @T6G_MB_LIB.T6G(SCH_1):PAGE430
 U6013 FJ23  GPIO1 PT5161LRS-PT5161LRS,SMLF,IC,AJ051610U03    I83 @T6G_MB_LIB.T6G(SCH_1):PAGE430
 U6013 FJ31  INT_N PT5161LRS-PT5161LRS,SMLF,IC,AJ051610U03    I83 @T6G_MB_LIB.T6G(SCH_1):PAGE430
 U6013  E18 REFCLK_OUTN PT5161LRS-PT5161LRS,SMLF,IC,AJ051610U03    I83 @T6G_MB_LIB.T6G(SCH_1):PAGE430
 U6013  B16 REFCLK_OUTP PT5161LRS-PT5161LRS,SMLF,IC,AJ051610U03    I83 @T6G_MB_LIB.T6G(SCH_1):PAGE430
   U28    1     NC SN74LVC1G07DBVR_SMLF-SN74LVC1G07DBVR,IC,AL1G0007024    I51 @T6G_MB_LIB.T6G(SCH_1):PAGE340
   U30    1     NC SN74LVC1G07DBVR_SMLF-SN74LVC1G07DBVR,IC,AL1G0007024    I66 @T6G_MB_LIB.T6G(SCH_1):PAGE340
   U34    1     NC SN74LVC1G07DBVR_SMLF-SN74LVC1G07DBVR,IC,AL1G0007024    I45 @T6G_MB_LIB.T6G(SCH_1):PAGE257
   U33    1     NC SN74LVC1G07DBVR_SMLF-SN74LVC1G07DBVR,IC,AL1G0007024    I64 @T6G_MB_LIB.T6G(SCH_1):PAGE257
   U57    2      A SCHOTTKY_DUAL_12A_3C-BAT54CW,SMLF,EMPTY,BCBAT54CZ13     I5 @T6G_MB_LIB.T6G(SCH_1):PAGE146
   U60    2      A SCHOTTKY_DUAL_12A_3C-BAT54CW,SMLF,EMPTY,BCBAT54CZ13    I25 @T6G_MB_LIB.T6G(SCH_1):PAGE146

NCF_A1_CPU0_P0_GND @T6G_MB_LIB.T6G(SCH_1):NCF_A1_CPU0_P0_GND
 R6820    1      A Q_RES_0201LF-0,5%,1/20W,CHIP,CS00001JE10    I15 @T6G_MB_LIB.T6G(SCH_1):PAGE386
 U6010   A1 NCF_GND1 PT5161LRS-PT5161LRS,SMLF,IC,AJ051610U03    I17 @T6G_MB_LIB.T6G(SCH_1):PAGE386

NCF_A1_CPU0_P1_GND @T6G_MB_LIB.T6G(SCH_1):NCF_A1_CPU0_P1_GND
 R1043    1      A Q_RES_0201LF-0,5%,1/20W,CHIP,CS00001JE10    I15 @T6G_MB_LIB.T6G(SCH_1):PAGE409
 U6011   A1 NCF_GND1 PT5161LRS-PT5161LRS,SMLF,IC,AJ051610U03    I17 @T6G_MB_LIB.T6G(SCH_1):PAGE409

NCF_A1_CPU0_P2_GND @T6G_MB_LIB.T6G(SCH_1):NCF_A1_CPU0_P2_GND
 R1084    1      A Q_RES_0201LF-0,5%,1/20W,CHIP,CS00001JE10    I14 @T6G_MB_LIB.T6G(SCH_1):PAGE420
 U6012   A1 NCF_GND1 PT5161LRS-PT5161LRS,SMLF,IC,AJ051610U03    I17 @T6G_MB_LIB.T6G(SCH_1):PAGE420

NCF_A1_CPU0_P3_GND @T6G_MB_LIB.T6G(SCH_1):NCF_A1_CPU0_P3_GND
 R1126    1      A Q_RES_0201LF-0,5%,1/20W,CHIP,CS00001JE10    I14 @T6G_MB_LIB.T6G(SCH_1):PAGE431
 U6013   A1 NCF_GND1 PT5161LRS-PT5161LRS,SMLF,IC,AJ051610U03    I17 @T6G_MB_LIB.T6G(SCH_1):PAGE431

NCF_A1_CPU1_P0_GND @T6G_MB_LIB.T6G(SCH_1):NCF_A1_CPU1_P0_GND
 U6014   A1 NCF_GND1 PT5161LRS-PT5161LRS,SMLF,IC,AJ051610U03     I2 @T6G_MB_LIB.T6G(SCH_1):PAGE400
  R711    1      A Q_RES_0201LF-0,5%,1/20W,CHIP,CS00001JE10   I102 @T6G_MB_LIB.T6G(SCH_1):PAGE400

NCF_A1_CPU1_P1_GND @T6G_MB_LIB.T6G(SCH_1):NCF_A1_CPU1_P1_GND
 R6732    1      A Q_RES_0201LF-0,5%,1/20W,CHIP,CS00001JE10    I16 @T6G_MB_LIB.T6G(SCH_1):PAGE391
 U6015   A1 NCF_GND1 PT5161LRS-PT5161LRS,SMLF,IC,AJ051610U03    I19 @T6G_MB_LIB.T6G(SCH_1):PAGE391

NCF_A1_CPU1_P2_GND @T6G_MB_LIB.T6G(SCH_1):NCF_A1_CPU1_P2_GND
 R6796    1      A Q_RES_0201LF-0,5%,1/20W,CHIP,CS00001JE10    I18 @T6G_MB_LIB.T6G(SCH_1):PAGE452
 U6016   A1 NCF_GND1 PT5161LRS-PT5161LRS,SMLF,IC,AJ051610U03    I19 @T6G_MB_LIB.T6G(SCH_1):PAGE452

NCF_A1_CPU1_P3_GND @T6G_MB_LIB.T6G(SCH_1):NCF_A1_CPU1_P3_GND
 R6902    1      A Q_RES_0201LF-0,5%,1/20W,CHIP,CS00001JE10    I15 @T6G_MB_LIB.T6G(SCH_1):PAGE463
 U6017   A1 NCF_GND1 PT5161LRS-PT5161LRS,SMLF,IC,AJ051610U03    I17 @T6G_MB_LIB.T6G(SCH_1):PAGE463

NCF_CPU0_P0_GND @T6G_MB_LIB.T6G(SCH_1):NCF_CPU0_P0_GND
 R6821    1      A Q_RES_0201LF-0,5%,1/20W,CHIP,CS00001JE10    I13 @T6G_MB_LIB.T6G(SCH_1):PAGE386
 U6010  A35 NCF_GND2 PT5161LRS-PT5161LRS,SMLF,IC,AJ051610U03    I17 @T6G_MB_LIB.T6G(SCH_1):PAGE386
 U6010   C2 NCF_GND3 PT5161LRS-PT5161LRS,SMLF,IC,AJ051610U03    I17 @T6G_MB_LIB.T6G(SCH_1):PAGE386
 U6010  C34 NCF_GND4 PT5161LRS-PT5161LRS,SMLF,IC,AJ051610U03    I17 @T6G_MB_LIB.T6G(SCH_1):PAGE386
 U6010   D1 NCF_GND5 PT5161LRS-PT5161LRS,SMLF,IC,AJ051610U03    I17 @T6G_MB_LIB.T6G(SCH_1):PAGE386
 U6010  D35 NCF_GND6 PT5161LRS-PT5161LRS,SMLF,IC,AJ051610U03    I17 @T6G_MB_LIB.T6G(SCH_1):PAGE386
 U6010  FE2 NCF_GND7 PT5161LRS-PT5161LRS,SMLF,IC,AJ051610U03    I17 @T6G_MB_LIB.T6G(SCH_1):PAGE386
 U6010 FE34 NCF_GND8 PT5161LRS-PT5161LRS,SMLF,IC,AJ051610U03    I17 @T6G_MB_LIB.T6G(SCH_1):PAGE386
 U6010  FG1 NCF_GND9 PT5161LRS-PT5161LRS,SMLF,IC,AJ051610U03    I17 @T6G_MB_LIB.T6G(SCH_1):PAGE386
 U6010 FG35 NCF_GND10 PT5161LRS-PT5161LRS,SMLF,IC,AJ051610U03    I17 @T6G_MB_LIB.T6G(SCH_1):PAGE386
 U6010  FH2 NCF_GND11 PT5161LRS-PT5161LRS,SMLF,IC,AJ051610U03    I17 @T6G_MB_LIB.T6G(SCH_1):PAGE386
 U6010 FH34 NCF_GND12 PT5161LRS-PT5161LRS,SMLF,IC,AJ051610U03    I17 @T6G_MB_LIB.T6G(SCH_1):PAGE386

NCF_CPU0_P1_GND @T6G_MB_LIB.T6G(SCH_1):NCF_CPU0_P1_GND
 R1042    1      A Q_RES_0201LF-0,5%,1/20W,CHIP,CS00001JE10    I13 @T6G_MB_LIB.T6G(SCH_1):PAGE409
 U6011  A35 NCF_GND2 PT5161LRS-PT5161LRS,SMLF,IC,AJ051610U03    I17 @T6G_MB_LIB.T6G(SCH_1):PAGE409
 U6011   C2 NCF_GND3 PT5161LRS-PT5161LRS,SMLF,IC,AJ051610U03    I17 @T6G_MB_LIB.T6G(SCH_1):PAGE409
 U6011  C34 NCF_GND4 PT5161LRS-PT5161LRS,SMLF,IC,AJ051610U03    I17 @T6G_MB_LIB.T6G(SCH_1):PAGE409
 U6011   D1 NCF_GND5 PT5161LRS-PT5161LRS,SMLF,IC,AJ051610U03    I17 @T6G_MB_LIB.T6G(SCH_1):PAGE409
 U6011  D35 NCF_GND6 PT5161LRS-PT5161LRS,SMLF,IC,AJ051610U03    I17 @T6G_MB_LIB.T6G(SCH_1):PAGE409
 U6011  FE2 NCF_GND7 PT5161LRS-PT5161LRS,SMLF,IC,AJ051610U03    I17 @T6G_MB_LIB.T6G(SCH_1):PAGE409
 U6011 FE34 NCF_GND8 PT5161LRS-PT5161LRS,SMLF,IC,AJ051610U03    I17 @T6G_MB_LIB.T6G(SCH_1):PAGE409
 U6011  FG1 NCF_GND9 PT5161LRS-PT5161LRS,SMLF,IC,AJ051610U03    I17 @T6G_MB_LIB.T6G(SCH_1):PAGE409
 U6011 FG35 NCF_GND10 PT5161LRS-PT5161LRS,SMLF,IC,AJ051610U03    I17 @T6G_MB_LIB.T6G(SCH_1):PAGE409
 U6011  FH2 NCF_GND11 PT5161LRS-PT5161LRS,SMLF,IC,AJ051610U03    I17 @T6G_MB_LIB.T6G(SCH_1):PAGE409
 U6011 FH34 NCF_GND12 PT5161LRS-PT5161LRS,SMLF,IC,AJ051610U03    I17 @T6G_MB_LIB.T6G(SCH_1):PAGE409

NCF_CPU0_P2_GND @T6G_MB_LIB.T6G(SCH_1):NCF_CPU0_P2_GND
 R1083    1      A Q_RES_0201LF-0,5%,1/20W,CHIP,CS00001JE10    I13 @T6G_MB_LIB.T6G(SCH_1):PAGE420
 U6012  A35 NCF_GND2 PT5161LRS-PT5161LRS,SMLF,IC,AJ051610U03    I17 @T6G_MB_LIB.T6G(SCH_1):PAGE420
 U6012   C2 NCF_GND3 PT5161LRS-PT5161LRS,SMLF,IC,AJ051610U03    I17 @T6G_MB_LIB.T6G(SCH_1):PAGE420
 U6012  C34 NCF_GND4 PT5161LRS-PT5161LRS,SMLF,IC,AJ051610U03    I17 @T6G_MB_LIB.T6G(SCH_1):PAGE420
 U6012   D1 NCF_GND5 PT5161LRS-PT5161LRS,SMLF,IC,AJ051610U03    I17 @T6G_MB_LIB.T6G(SCH_1):PAGE420
 U6012  D35 NCF_GND6 PT5161LRS-PT5161LRS,SMLF,IC,AJ051610U03    I17 @T6G_MB_LIB.T6G(SCH_1):PAGE420
 U6012  FE2 NCF_GND7 PT5161LRS-PT5161LRS,SMLF,IC,AJ051610U03    I17 @T6G_MB_LIB.T6G(SCH_1):PAGE420
 U6012 FE34 NCF_GND8 PT5161LRS-PT5161LRS,SMLF,IC,AJ051610U03    I17 @T6G_MB_LIB.T6G(SCH_1):PAGE420
 U6012  FG1 NCF_GND9 PT5161LRS-PT5161LRS,SMLF,IC,AJ051610U03    I17 @T6G_MB_LIB.T6G(SCH_1):PAGE420
 U6012 FG35 NCF_GND10 PT5161LRS-PT5161LRS,SMLF,IC,AJ051610U03    I17 @T6G_MB_LIB.T6G(SCH_1):PAGE420
 U6012  FH2 NCF_GND11 PT5161LRS-PT5161LRS,SMLF,IC,AJ051610U03    I17 @T6G_MB_LIB.T6G(SCH_1):PAGE420
 U6012 FH34 NCF_GND12 PT5161LRS-PT5161LRS,SMLF,IC,AJ051610U03    I17 @T6G_MB_LIB.T6G(SCH_1):PAGE420

NCF_CPU0_P3_GND @T6G_MB_LIB.T6G(SCH_1):NCF_CPU0_P3_GND
 R1125    1      A Q_RES_0201LF-0,5%,1/20W,CHIP,CS00001JE10    I13 @T6G_MB_LIB.T6G(SCH_1):PAGE431
 U6013  A35 NCF_GND2 PT5161LRS-PT5161LRS,SMLF,IC,AJ051610U03    I17 @T6G_MB_LIB.T6G(SCH_1):PAGE431
 U6013   C2 NCF_GND3 PT5161LRS-PT5161LRS,SMLF,IC,AJ051610U03    I17 @T6G_MB_LIB.T6G(SCH_1):PAGE431
 U6013  C34 NCF_GND4 PT5161LRS-PT5161LRS,SMLF,IC,AJ051610U03    I17 @T6G_MB_LIB.T6G(SCH_1):PAGE431
 U6013   D1 NCF_GND5 PT5161LRS-PT5161LRS,SMLF,IC,AJ051610U03    I17 @T6G_MB_LIB.T6G(SCH_1):PAGE431
 U6013  D35 NCF_GND6 PT5161LRS-PT5161LRS,SMLF,IC,AJ051610U03    I17 @T6G_MB_LIB.T6G(SCH_1):PAGE431
 U6013  FE2 NCF_GND7 PT5161LRS-PT5161LRS,SMLF,IC,AJ051610U03    I17 @T6G_MB_LIB.T6G(SCH_1):PAGE431
 U6013 FE34 NCF_GND8 PT5161LRS-PT5161LRS,SMLF,IC,AJ051610U03    I17 @T6G_MB_LIB.T6G(SCH_1):PAGE431
 U6013  FG1 NCF_GND9 PT5161LRS-PT5161LRS,SMLF,IC,AJ051610U03    I17 @T6G_MB_LIB.T6G(SCH_1):PAGE431
 U6013 FG35 NCF_GND10 PT5161LRS-PT5161LRS,SMLF,IC,AJ051610U03    I17 @T6G_MB_LIB.T6G(SCH_1):PAGE431
 U6013  FH2 NCF_GND11 PT5161LRS-PT5161LRS,SMLF,IC,AJ051610U03    I17 @T6G_MB_LIB.T6G(SCH_1):PAGE431
 U6013 FH34 NCF_GND12 PT5161LRS-PT5161LRS,SMLF,IC,AJ051610U03    I17 @T6G_MB_LIB.T6G(SCH_1):PAGE431

NCF_CPU1_P0_GND @T6G_MB_LIB.T6G(SCH_1):NCF_CPU1_P0_GND
 U6014  A35 NCF_GND2 PT5161LRS-PT5161LRS,SMLF,IC,AJ051610U03     I2 @T6G_MB_LIB.T6G(SCH_1):PAGE400
 U6014   C2 NCF_GND3 PT5161LRS-PT5161LRS,SMLF,IC,AJ051610U03     I2 @T6G_MB_LIB.T6G(SCH_1):PAGE400
 U6014  C34 NCF_GND4 PT5161LRS-PT5161LRS,SMLF,IC,AJ051610U03     I2 @T6G_MB_LIB.T6G(SCH_1):PAGE400
 U6014   D1 NCF_GND5 PT5161LRS-PT5161LRS,SMLF,IC,AJ051610U03     I2 @T6G_MB_LIB.T6G(SCH_1):PAGE400
 U6014  D35 NCF_GND6 PT5161LRS-PT5161LRS,SMLF,IC,AJ051610U03     I2 @T6G_MB_LIB.T6G(SCH_1):PAGE400
 U6014  FE2 NCF_GND7 PT5161LRS-PT5161LRS,SMLF,IC,AJ051610U03     I2 @T6G_MB_LIB.T6G(SCH_1):PAGE400
 U6014 FE34 NCF_GND8 PT5161LRS-PT5161LRS,SMLF,IC,AJ051610U03     I2 @T6G_MB_LIB.T6G(SCH_1):PAGE400
 U6014  FG1 NCF_GND9 PT5161LRS-PT5161LRS,SMLF,IC,AJ051610U03     I2 @T6G_MB_LIB.T6G(SCH_1):PAGE400
 U6014 FG35 NCF_GND10 PT5161LRS-PT5161LRS,SMLF,IC,AJ051610U03     I2 @T6G_MB_LIB.T6G(SCH_1):PAGE400
 U6014  FH2 NCF_GND11 PT5161LRS-PT5161LRS,SMLF,IC,AJ051610U03     I2 @T6G_MB_LIB.T6G(SCH_1):PAGE400
 U6014 FH34 NCF_GND12 PT5161LRS-PT5161LRS,SMLF,IC,AJ051610U03     I2 @T6G_MB_LIB.T6G(SCH_1):PAGE400
  R709    1      A Q_RES_0201LF-0,5%,1/20W,CHIP,CS00001JE10   I103 @T6G_MB_LIB.T6G(SCH_1):PAGE400

NCF_CPU1_P1_GND @T6G_MB_LIB.T6G(SCH_1):NCF_CPU1_P1_GND
 R6733    1      A Q_RES_0201LF-0,5%,1/20W,CHIP,CS00001JE10    I15 @T6G_MB_LIB.T6G(SCH_1):PAGE391
 U6015  A35 NCF_GND2 PT5161LRS-PT5161LRS,SMLF,IC,AJ051610U03    I19 @T6G_MB_LIB.T6G(SCH_1):PAGE391
 U6015   C2 NCF_GND3 PT5161LRS-PT5161LRS,SMLF,IC,AJ051610U03    I19 @T6G_MB_LIB.T6G(SCH_1):PAGE391
 U6015  C34 NCF_GND4 PT5161LRS-PT5161LRS,SMLF,IC,AJ051610U03    I19 @T6G_MB_LIB.T6G(SCH_1):PAGE391
 U6015   D1 NCF_GND5 PT5161LRS-PT5161LRS,SMLF,IC,AJ051610U03    I19 @T6G_MB_LIB.T6G(SCH_1):PAGE391
 U6015  D35 NCF_GND6 PT5161LRS-PT5161LRS,SMLF,IC,AJ051610U03    I19 @T6G_MB_LIB.T6G(SCH_1):PAGE391
 U6015  FE2 NCF_GND7 PT5161LRS-PT5161LRS,SMLF,IC,AJ051610U03    I19 @T6G_MB_LIB.T6G(SCH_1):PAGE391
 U6015 FE34 NCF_GND8 PT5161LRS-PT5161LRS,SMLF,IC,AJ051610U03    I19 @T6G_MB_LIB.T6G(SCH_1):PAGE391
 U6015  FG1 NCF_GND9 PT5161LRS-PT5161LRS,SMLF,IC,AJ051610U03    I19 @T6G_MB_LIB.T6G(SCH_1):PAGE391
 U6015 FG35 NCF_GND10 PT5161LRS-PT5161LRS,SMLF,IC,AJ051610U03    I19 @T6G_MB_LIB.T6G(SCH_1):PAGE391
 U6015  FH2 NCF_GND11 PT5161LRS-PT5161LRS,SMLF,IC,AJ051610U03    I19 @T6G_MB_LIB.T6G(SCH_1):PAGE391
 U6015 FH34 NCF_GND12 PT5161LRS-PT5161LRS,SMLF,IC,AJ051610U03    I19 @T6G_MB_LIB.T6G(SCH_1):PAGE391

NCF_CPU1_P2_GND @T6G_MB_LIB.T6G(SCH_1):NCF_CPU1_P2_GND
 R6797    1      A Q_RES_0201LF-0,5%,1/20W,CHIP,CS00001JE10    I15 @T6G_MB_LIB.T6G(SCH_1):PAGE452
 U6016  A35 NCF_GND2 PT5161LRS-PT5161LRS,SMLF,IC,AJ051610U03    I19 @T6G_MB_LIB.T6G(SCH_1):PAGE452
 U6016   C2 NCF_GND3 PT5161LRS-PT5161LRS,SMLF,IC,AJ051610U03    I19 @T6G_MB_LIB.T6G(SCH_1):PAGE452
 U6016  C34 NCF_GND4 PT5161LRS-PT5161LRS,SMLF,IC,AJ051610U03    I19 @T6G_MB_LIB.T6G(SCH_1):PAGE452
 U6016   D1 NCF_GND5 PT5161LRS-PT5161LRS,SMLF,IC,AJ051610U03    I19 @T6G_MB_LIB.T6G(SCH_1):PAGE452
 U6016  D35 NCF_GND6 PT5161LRS-PT5161LRS,SMLF,IC,AJ051610U03    I19 @T6G_MB_LIB.T6G(SCH_1):PAGE452
 U6016  FE2 NCF_GND7 PT5161LRS-PT5161LRS,SMLF,IC,AJ051610U03    I19 @T6G_MB_LIB.T6G(SCH_1):PAGE452
 U6016 FE34 NCF_GND8 PT5161LRS-PT5161LRS,SMLF,IC,AJ051610U03    I19 @T6G_MB_LIB.T6G(SCH_1):PAGE452
 U6016  FG1 NCF_GND9 PT5161LRS-PT5161LRS,SMLF,IC,AJ051610U03    I19 @T6G_MB_LIB.T6G(SCH_1):PAGE452
 U6016 FG35 NCF_GND10 PT5161LRS-PT5161LRS,SMLF,IC,AJ051610U03    I19 @T6G_MB_LIB.T6G(SCH_1):PAGE452
 U6016  FH2 NCF_GND11 PT5161LRS-PT5161LRS,SMLF,IC,AJ051610U03    I19 @T6G_MB_LIB.T6G(SCH_1):PAGE452
 U6016 FH34 NCF_GND12 PT5161LRS-PT5161LRS,SMLF,IC,AJ051610U03    I19 @T6G_MB_LIB.T6G(SCH_1):PAGE452

NCF_CPU1_P3_GND @T6G_MB_LIB.T6G(SCH_1):NCF_CPU1_P3_GND
 R6903    1      A Q_RES_0201LF-0,5%,1/20W,CHIP,CS00001JE10    I13 @T6G_MB_LIB.T6G(SCH_1):PAGE463
 U6017  A35 NCF_GND2 PT5161LRS-PT5161LRS,SMLF,IC,AJ051610U03    I17 @T6G_MB_LIB.T6G(SCH_1):PAGE463
 U6017   C2 NCF_GND3 PT5161LRS-PT5161LRS,SMLF,IC,AJ051610U03    I17 @T6G_MB_LIB.T6G(SCH_1):PAGE463
 U6017  C34 NCF_GND4 PT5161LRS-PT5161LRS,SMLF,IC,AJ051610U03    I17 @T6G_MB_LIB.T6G(SCH_1):PAGE463
 U6017   D1 NCF_GND5 PT5161LRS-PT5161LRS,SMLF,IC,AJ051610U03    I17 @T6G_MB_LIB.T6G(SCH_1):PAGE463
 U6017  D35 NCF_GND6 PT5161LRS-PT5161LRS,SMLF,IC,AJ051610U03    I17 @T6G_MB_LIB.T6G(SCH_1):PAGE463
 U6017  FE2 NCF_GND7 PT5161LRS-PT5161LRS,SMLF,IC,AJ051610U03    I17 @T6G_MB_LIB.T6G(SCH_1):PAGE463
 U6017 FE34 NCF_GND8 PT5161LRS-PT5161LRS,SMLF,IC,AJ051610U03    I17 @T6G_MB_LIB.T6G(SCH_1):PAGE463
 U6017  FG1 NCF_GND9 PT5161LRS-PT5161LRS,SMLF,IC,AJ051610U03    I17 @T6G_MB_LIB.T6G(SCH_1):PAGE463
 U6017 FG35 NCF_GND10 PT5161LRS-PT5161LRS,SMLF,IC,AJ051610U03    I17 @T6G_MB_LIB.T6G(SCH_1):PAGE463
 U6017  FH2 NCF_GND11 PT5161LRS-PT5161LRS,SMLF,IC,AJ051610U03    I17 @T6G_MB_LIB.T6G(SCH_1):PAGE463
 U6017 FH34 NCF_GND12 PT5161LRS-PT5161LRS,SMLF,IC,AJ051610U03    I17 @T6G_MB_LIB.T6G(SCH_1):PAGE463

NCSI_BMC_CRS_DV_R @T6G_MB_LIB.T6G(SCH_1):NCSI_BMC_CRS_DV_R
   U67    9     3A 74CBTLV3126PW-74CBTLV3126PW,SMLF,IC,AL003126K08     I1 @T6G_MB_LIB.T6G(SCH_1):PAGE336
   R59    1      A Q_RES_0402LF-22,1%,1/16W,CHIP,CS02202FB02    I99 @T6G_MB_LIB.T6G(SCH_1):PAGE336

NCSI_BMC_CRS_DV_R1 @T6G_MB_LIB.T6G(SCH_1):NCSI_BMC_CRS_DV_R1
  U222    9     3A 74CBTLV3126PW-74CBTLV3126PW,SMLF,IC,AL003126K08    I32 @T6G_MB_LIB.T6G(SCH_1):PAGE307
 R3210    1      A Q_RES_0402LF-22,1%,1/16W,EMPTY,CS02202FB02    I65 @T6G_MB_LIB.T6G(SCH_1):PAGE307

NCSI_BMC_RXD0_R @T6G_MB_LIB.T6G(SCH_1):NCSI_BMC_RXD0_R
   U67    5     2A 74CBTLV3126PW-74CBTLV3126PW,SMLF,IC,AL003126K08     I1 @T6G_MB_LIB.T6G(SCH_1):PAGE336
   R72    1      A Q_RES_0402LF-22,1%,1/16W,CHIP,CS02202FB02   I100 @T6G_MB_LIB.T6G(SCH_1):PAGE336

NCSI_BMC_RXD0_R1 @T6G_MB_LIB.T6G(SCH_1):NCSI_BMC_RXD0_R1
  U222    5     2A 74CBTLV3126PW-74CBTLV3126PW,SMLF,IC,AL003126K08    I32 @T6G_MB_LIB.T6G(SCH_1):PAGE307
 R3211    1      A Q_RES_0402LF-22,1%,1/16W,EMPTY,CS02202FB02    I63 @T6G_MB_LIB.T6G(SCH_1):PAGE307

NCSI_BMC_RXD1_R @T6G_MB_LIB.T6G(SCH_1):NCSI_BMC_RXD1_R
   U67    2     1A 74CBTLV3126PW-74CBTLV3126PW,SMLF,IC,AL003126K08     I1 @T6G_MB_LIB.T6G(SCH_1):PAGE336
   R73    1      A Q_RES_0402LF-22,1%,1/16W,CHIP,CS02202FB02   I101 @T6G_MB_LIB.T6G(SCH_1):PAGE336

NCSI_BMC_RXD1_R1 @T6G_MB_LIB.T6G(SCH_1):NCSI_BMC_RXD1_R1
  U222    2     1A 74CBTLV3126PW-74CBTLV3126PW,SMLF,IC,AL003126K08    I32 @T6G_MB_LIB.T6G(SCH_1):PAGE307
 R3212    1      A Q_RES_0402LF-22,1%,1/16W,EMPTY,CS02202FB02    I62 @T6G_MB_LIB.T6G(SCH_1):PAGE307

NCSI_BMC_TXD0_R @T6G_MB_LIB.T6G(SCH_1):NCSI_BMC_TXD0_R
    U7    5     2A 74CBTLV3126PW-74CBTLV3126PW,SMLF,IC,AL003126K08     I2 @T6G_MB_LIB.T6G(SCH_1):PAGE336
   R75    1      A Q_RES_0402LF-0,5%,1/16W,CHIP,CS00002JB13   I103 @T6G_MB_LIB.T6G(SCH_1):PAGE336

NCSI_BMC_TXD0_R1 @T6G_MB_LIB.T6G(SCH_1):NCSI_BMC_TXD0_R1
 R3214    1      A Q_RES_0402LF-0,5%,1/16W,EMPTY,CS00002JB13    I60 @T6G_MB_LIB.T6G(SCH_1):PAGE307
  U223    5     2A 74CBTLV3126PW-74CBTLV3126PW,SMLF,IC,AL003126K08    I78 @T6G_MB_LIB.T6G(SCH_1):PAGE307

NCSI_BMC_TXD1_R @T6G_MB_LIB.T6G(SCH_1):NCSI_BMC_TXD1_R
    U7    2     1A 74CBTLV3126PW-74CBTLV3126PW,SMLF,IC,AL003126K08     I2 @T6G_MB_LIB.T6G(SCH_1):PAGE336
   R76    1      A Q_RES_0402LF-0,5%,1/16W,CHIP,CS00002JB13   I104 @T6G_MB_LIB.T6G(SCH_1):PAGE336

NCSI_BMC_TXD1_R1 @T6G_MB_LIB.T6G(SCH_1):NCSI_BMC_TXD1_R1
 R3215    1      A Q_RES_0402LF-0,5%,1/16W,EMPTY,CS00002JB13    I56 @T6G_MB_LIB.T6G(SCH_1):PAGE307
  U223    2     1A 74CBTLV3126PW-74CBTLV3126PW,SMLF,IC,AL003126K08    I78 @T6G_MB_LIB.T6G(SCH_1):PAGE307

NCSI_BMC_TX_EN_R @T6G_MB_LIB.T6G(SCH_1):NCSI_BMC_TX_EN_R
    U7    9     3A 74CBTLV3126PW-74CBTLV3126PW,SMLF,IC,AL003126K08     I2 @T6G_MB_LIB.T6G(SCH_1):PAGE336
   R74    1      A Q_RES_0402LF-0,5%,1/16W,CHIP,CS00002JB13   I102 @T6G_MB_LIB.T6G(SCH_1):PAGE336

NCSI_BMC_TX_EN_R1 @T6G_MB_LIB.T6G(SCH_1):NCSI_BMC_TX_EN_R1
 R3213    1      A Q_RES_0402LF-0,5%,1/16W,EMPTY,CS00002JB13    I61 @T6G_MB_LIB.T6G(SCH_1):PAGE307
  U223    9     3A 74CBTLV3126PW-74CBTLV3126PW,SMLF,IC,AL003126K08    I78 @T6G_MB_LIB.T6G(SCH_1):PAGE307

NCSI_OCP_SFF_CRS_DV @T6G_MB_LIB.T6G(SCH_1):NCSI_OCP_SFF_CRS_DV
   J38 OB14 RBT_CRS_DV SCONN168_ME1016810202011-SCONN168_ME1016810202011,A   I168 @T6G_MB_LIB.T6G(SCH_1):PAGE335
   U67    8     3B 74CBTLV3126PW-74CBTLV3126PW,SMLF,IC,AL003126K08     I1 @T6G_MB_LIB.T6G(SCH_1):PAGE336

NCSI_OCP_SFF_RXD0 @T6G_MB_LIB.T6G(SCH_1):NCSI_OCP_SFF_RXD0
   J38  OB9 RBT_RXD0 SCONN168_ME1016810202011-SCONN168_ME1016810202011,A   I168 @T6G_MB_LIB.T6G(SCH_1):PAGE335
   U67    6     2B 74CBTLV3126PW-74CBTLV3126PW,SMLF,IC,AL003126K08     I1 @T6G_MB_LIB.T6G(SCH_1):PAGE336

NCSI_OCP_SFF_RXD1 @T6G_MB_LIB.T6G(SCH_1):NCSI_OCP_SFF_RXD1
   J38  OB8 RBT_RXD1 SCONN168_ME1016810202011-SCONN168_ME1016810202011,A   I168 @T6G_MB_LIB.T6G(SCH_1):PAGE335
   U67    3     1B 74CBTLV3126PW-74CBTLV3126PW,SMLF,IC,AL003126K08     I1 @T6G_MB_LIB.T6G(SCH_1):PAGE336

NCSI_OCP_SFF_TXD0 @T6G_MB_LIB.T6G(SCH_1):NCSI_OCP_SFF_TXD0
   J38  OA9 RBT_TXD0 SCONN168_ME1016810202011-SCONN168_ME1016810202011,A   I168 @T6G_MB_LIB.T6G(SCH_1):PAGE335
    U7    6     2B 74CBTLV3126PW-74CBTLV3126PW,SMLF,IC,AL003126K08     I2 @T6G_MB_LIB.T6G(SCH_1):PAGE336

NCSI_OCP_SFF_TXD1 @T6G_MB_LIB.T6G(SCH_1):NCSI_OCP_SFF_TXD1
   J38  OA8 RBT_TXD1 SCONN168_ME1016810202011-SCONN168_ME1016810202011,A   I168 @T6G_MB_LIB.T6G(SCH_1):PAGE335
    U7    3     1B 74CBTLV3126PW-74CBTLV3126PW,SMLF,IC,AL003126K08     I2 @T6G_MB_LIB.T6G(SCH_1):PAGE336

NCSI_OCP_SFF_TX_EN @T6G_MB_LIB.T6G(SCH_1):NCSI_OCP_SFF_TX_EN
   J38  OA7 RBT_TX_EN SCONN168_ME1016810202011-SCONN168_ME1016810202011,A   I168 @T6G_MB_LIB.T6G(SCH_1):PAGE335
    U7    8     3B 74CBTLV3126PW-74CBTLV3126PW,SMLF,IC,AL003126K08     I2 @T6G_MB_LIB.T6G(SCH_1):PAGE336

NCSI_OCP_V3_2_CRS_DV @T6G_MB_LIB.T6G(SCH_1):NCSI_OCP_V3_2_CRS_DV
  U222    8     3B 74CBTLV3126PW-74CBTLV3126PW,SMLF,IC,AL003126K08    I32 @T6G_MB_LIB.T6G(SCH_1):PAGE307
   J35 OB14 RBT_CRS_DV SCONN168_ME1016810202011-SCONN168_ME1016810202011,A   I168 @T6G_MB_LIB.T6G(SCH_1):PAGE341

NCSI_OCP_V3_2_RXD0 @T6G_MB_LIB.T6G(SCH_1):NCSI_OCP_V3_2_RXD0
  U222    6     2B 74CBTLV3126PW-74CBTLV3126PW,SMLF,IC,AL003126K08    I32 @T6G_MB_LIB.T6G(SCH_1):PAGE307
   J35  OB9 RBT_RXD0 SCONN168_ME1016810202011-SCONN168_ME1016810202011,A   I168 @T6G_MB_LIB.T6G(SCH_1):PAGE341

NCSI_OCP_V3_2_RXD1 @T6G_MB_LIB.T6G(SCH_1):NCSI_OCP_V3_2_RXD1
  U222    3     1B 74CBTLV3126PW-74CBTLV3126PW,SMLF,IC,AL003126K08    I32 @T6G_MB_LIB.T6G(SCH_1):PAGE307
   J35  OB8 RBT_RXD1 SCONN168_ME1016810202011-SCONN168_ME1016810202011,A   I168 @T6G_MB_LIB.T6G(SCH_1):PAGE341

NCSI_OCP_V3_2_TXD0 @T6G_MB_LIB.T6G(SCH_1):NCSI_OCP_V3_2_TXD0
  U223    6     2B 74CBTLV3126PW-74CBTLV3126PW,SMLF,IC,AL003126K08    I78 @T6G_MB_LIB.T6G(SCH_1):PAGE307
   J35  OA9 RBT_TXD0 SCONN168_ME1016810202011-SCONN168_ME1016810202011,A   I168 @T6G_MB_LIB.T6G(SCH_1):PAGE341

NCSI_OCP_V3_2_TXD1 @T6G_MB_LIB.T6G(SCH_1):NCSI_OCP_V3_2_TXD1
  U223    3     1B 74CBTLV3126PW-74CBTLV3126PW,SMLF,IC,AL003126K08    I78 @T6G_MB_LIB.T6G(SCH_1):PAGE307
   J35  OA8 RBT_TXD1 SCONN168_ME1016810202011-SCONN168_ME1016810202011,A   I168 @T6G_MB_LIB.T6G(SCH_1):PAGE341

NCSI_OCP_V3_2_TX_EN @T6G_MB_LIB.T6G(SCH_1):NCSI_OCP_V3_2_TX_EN
  U223    8     3B 74CBTLV3126PW-74CBTLV3126PW,SMLF,IC,AL003126K08    I78 @T6G_MB_LIB.T6G(SCH_1):PAGE307
   J35  OA7 RBT_TX_EN SCONN168_ME1016810202011-SCONN168_ME1016810202011,A   I168 @T6G_MB_LIB.T6G(SCH_1):PAGE341

NC_CPU0_AZ_BITCLK @T6G_MB_LIB.T6G(SCH_1):NC_CPU0_AZ_BITCLK
   U25  C32 AZ_BITCLK GENOA_SP5-SOCKET6096_13568-001,SMLF,IO,DGA^6000030   I227 @T6G_MB_LIB.T6G(SCH_1):PAGE27

NC_CPU0_AZ_RST_N @T6G_MB_LIB.T6G(SCH_1):NC_CPU0_AZ_RST_N
   U25  A34 AZ_RST_L||SW_MDATA1 GENOA_SP5-SOCKET6096_13568-001,SMLF,IO,DGA^6000030   I227 @T6G_MB_LIB.T6G(SCH_1):PAGE27

NC_CPU0_AZ_SDIN0 @T6G_MB_LIB.T6G(SCH_1):NC_CPU0_AZ_SDIN0
   U25  C33 AZ_SDIN0||SW_MDATA3 GENOA_SP5-SOCKET6096_13568-001,SMLF,IO,DGA^6000030   I227 @T6G_MB_LIB.T6G(SCH_1):PAGE27

NC_CPU0_AZ_SDIN1 @T6G_MB_LIB.T6G(SCH_1):NC_CPU0_AZ_SDIN1
   U25  D33 AZ_SDIN1||SW_MCLK GENOA_SP5-SOCKET6096_13568-001,SMLF,IO,DGA^6000030   I227 @T6G_MB_LIB.T6G(SCH_1):PAGE27

NC_CPU0_AZ_SDIN2 @T6G_MB_LIB.T6G(SCH_1):NC_CPU0_AZ_SDIN2
   U25  A33 AZ_SDIN2||SW_MDATA0 GENOA_SP5-SOCKET6096_13568-001,SMLF,IO,DGA^6000030   I227 @T6G_MB_LIB.T6G(SCH_1):PAGE27

NC_CPU0_AZ_SDOUT @T6G_MB_LIB.T6G(SCH_1):NC_CPU0_AZ_SDOUT
   U25  A32 AZ_SDOUT||SW_MDATA2 GENOA_SP5-SOCKET6096_13568-001,SMLF,IO,DGA^6000030   I227 @T6G_MB_LIB.T6G(SCH_1):PAGE27

NC_CPU0_AZ_SYNC @T6G_MB_LIB.T6G(SCH_1):NC_CPU0_AZ_SYNC
   U25  D32 AZ_SYNC GENOA_SP5-SOCKET6096_13568-001,SMLF,IO,DGA^6000030   I227 @T6G_MB_LIB.T6G(SCH_1):PAGE27

NC_CPU0_SPI_CS2_N @T6G_MB_LIB.T6G(SCH_1):NC_CPU0_SPI_CS2_N
   U25 DH27 SPI_CS2_L||AGPIO126 GENOA_SP5-SOCKET6096_13568-001,SMLF,IO,DGA^6000030   I287 @T6G_MB_LIB.T6G(SCH_1):PAGE29

NC_CPU1_AZ_BITCLK @T6G_MB_LIB.T6G(SCH_1):NC_CPU1_AZ_BITCLK
   U26  C32 AZ_BITCLK GENOA_SP5-SOCKET6096_13568-001,SMLF,IO,DGA^6000030   I190 @T6G_MB_LIB.T6G(SCH_1):PAGE54

NC_CPU1_AZ_RST_N @T6G_MB_LIB.T6G(SCH_1):NC_CPU1_AZ_RST_N
   U26  A34 AZ_RST_L||SW_MDATA1 GENOA_SP5-SOCKET6096_13568-001,SMLF,IO,DGA^6000030   I190 @T6G_MB_LIB.T6G(SCH_1):PAGE54

NC_CPU1_AZ_SDIN0 @T6G_MB_LIB.T6G(SCH_1):NC_CPU1_AZ_SDIN0
   U26  C33 AZ_SDIN0||SW_MDATA3 GENOA_SP5-SOCKET6096_13568-001,SMLF,IO,DGA^6000030   I190 @T6G_MB_LIB.T6G(SCH_1):PAGE54

NC_CPU1_AZ_SDIN1 @T6G_MB_LIB.T6G(SCH_1):NC_CPU1_AZ_SDIN1
   U26  D33 AZ_SDIN1||SW_MCLK GENOA_SP5-SOCKET6096_13568-001,SMLF,IO,DGA^6000030   I190 @T6G_MB_LIB.T6G(SCH_1):PAGE54

NC_CPU1_AZ_SDIN2 @T6G_MB_LIB.T6G(SCH_1):NC_CPU1_AZ_SDIN2
   U26  A33 AZ_SDIN2||SW_MDATA0 GENOA_SP5-SOCKET6096_13568-001,SMLF,IO,DGA^6000030   I190 @T6G_MB_LIB.T6G(SCH_1):PAGE54

NC_CPU1_AZ_SDOUT @T6G_MB_LIB.T6G(SCH_1):NC_CPU1_AZ_SDOUT
   U26  A32 AZ_SDOUT||SW_MDATA2 GENOA_SP5-SOCKET6096_13568-001,SMLF,IO,DGA^6000030   I190 @T6G_MB_LIB.T6G(SCH_1):PAGE54

NC_CPU1_AZ_SYNC @T6G_MB_LIB.T6G(SCH_1):NC_CPU1_AZ_SYNC
   U26  D32 AZ_SYNC GENOA_SP5-SOCKET6096_13568-001,SMLF,IO,DGA^6000030   I190 @T6G_MB_LIB.T6G(SCH_1):PAGE54

NC_CPU1_PWR_BTN_N @T6G_MB_LIB.T6G(SCH_1):NC_CPU1_PWR_BTN_N
   U26  DH7 PWR_BTN_L||AGPIO0 GENOA_SP5-SOCKET6096_13568-001,SMLF,IO,DGA^6000030   I182 @T6G_MB_LIB.T6G(SCH_1):PAGE55

NC_CPU1_USB00_OC_N @T6G_MB_LIB.T6G(SCH_1):NC_CPU1_USB00_OC_N
   U26  E23 USB00_OC_L||AGPIO264 GENOA_SP5-SOCKET6096_13568-001,SMLF,IO,DGA^6000030     I8 @T6G_MB_LIB.T6G(SCH_1):PAGE56

NC_CPU1_USB01_OC_N @T6G_MB_LIB.T6G(SCH_1):NC_CPU1_USB01_OC_N
   U26  E24 USB01_OC_L||AGPIO265 GENOA_SP5-SOCKET6096_13568-001,SMLF,IO,DGA^6000030     I8 @T6G_MB_LIB.T6G(SCH_1):PAGE56

NC_CPU1_USB10_OC_N @T6G_MB_LIB.T6G(SCH_1):NC_CPU1_USB10_OC_N
   U26 DG40 USB10_OC_L||AGPIO16 GENOA_SP5-SOCKET6096_13568-001,SMLF,IO,DGA^6000030     I8 @T6G_MB_LIB.T6G(SCH_1):PAGE56

NC_CPU1_USB11_OC_N @T6G_MB_LIB.T6G(SCH_1):NC_CPU1_USB11_OC_N
   U26 DH40 USB11_OC_L||AGPIO17 GENOA_SP5-SOCKET6096_13568-001,SMLF,IO,DGA^6000030     I8 @T6G_MB_LIB.T6G(SCH_1):PAGE56

NC_CPU1_USB2_USB00_DN @T6G_MB_LIB.T6G(SCH_1):NC_CPU1_USB2_USB00_DN
   U26  A25 USB00_DN GENOA_SP5-SOCKET6096_13568-001,SMLF,IO,DGA^6000030     I8 @T6G_MB_LIB.T6G(SCH_1):PAGE56

NC_CPU1_USB2_USB00_DP @T6G_MB_LIB.T6G(SCH_1):NC_CPU1_USB2_USB00_DP
   U26  A26 USB00_DP GENOA_SP5-SOCKET6096_13568-001,SMLF,IO,DGA^6000030     I8 @T6G_MB_LIB.T6G(SCH_1):PAGE56

NC_CPU1_USB2_USB01_DN @T6G_MB_LIB.T6G(SCH_1):NC_CPU1_USB2_USB01_DN
   U26  A29 USB01_DN GENOA_SP5-SOCKET6096_13568-001,SMLF,IO,DGA^6000030     I8 @T6G_MB_LIB.T6G(SCH_1):PAGE56

NC_CPU1_USB2_USB01_DP @T6G_MB_LIB.T6G(SCH_1):NC_CPU1_USB2_USB01_DP
   U26  A28 USB01_DP GENOA_SP5-SOCKET6096_13568-001,SMLF,IO,DGA^6000030     I8 @T6G_MB_LIB.T6G(SCH_1):PAGE56

NC_CPU1_USB2_USB10_DN @T6G_MB_LIB.T6G(SCH_1):NC_CPU1_USB2_USB10_DN
   U26 DH67 USB10_DN GENOA_SP5-SOCKET6096_13568-001,SMLF,IO,DGA^6000030     I8 @T6G_MB_LIB.T6G(SCH_1):PAGE56

NC_CPU1_USB2_USB10_DP @T6G_MB_LIB.T6G(SCH_1):NC_CPU1_USB2_USB10_DP
   U26 DJ67 USB10_DP GENOA_SP5-SOCKET6096_13568-001,SMLF,IO,DGA^6000030     I8 @T6G_MB_LIB.T6G(SCH_1):PAGE56

NC_CPU1_USB2_USB11_DN @T6G_MB_LIB.T6G(SCH_1):NC_CPU1_USB2_USB11_DN
   U26 DJ60 USB11_DN GENOA_SP5-SOCKET6096_13568-001,SMLF,IO,DGA^6000030     I8 @T6G_MB_LIB.T6G(SCH_1):PAGE56

NC_CPU1_USB2_USB11_DP @T6G_MB_LIB.T6G(SCH_1):NC_CPU1_USB2_USB11_DP
   U26 DH60 USB11_DP GENOA_SP5-SOCKET6096_13568-001,SMLF,IO,DGA^6000030     I8 @T6G_MB_LIB.T6G(SCH_1):PAGE56

NC_CPU1_USB3_USB00_RXN @T6G_MB_LIB.T6G(SCH_1):NC_CPU1_USB3_USB00_RXN
   U26  E26 USB00_RXN GENOA_SP5-SOCKET6096_13568-001,SMLF,IO,DGA^6000030     I8 @T6G_MB_LIB.T6G(SCH_1):PAGE56

NC_CPU1_USB3_USB00_RXP @T6G_MB_LIB.T6G(SCH_1):NC_CPU1_USB3_USB00_RXP
   U26  E27 USB00_RXP GENOA_SP5-SOCKET6096_13568-001,SMLF,IO,DGA^6000030     I8 @T6G_MB_LIB.T6G(SCH_1):PAGE56

NC_CPU1_USB3_USB00_TXN @T6G_MB_LIB.T6G(SCH_1):NC_CPU1_USB3_USB00_TXN
   U26  C25 USB00_TXP GENOA_SP5-SOCKET6096_13568-001,SMLF,IO,DGA^6000030     I8 @T6G_MB_LIB.T6G(SCH_1):PAGE56

NC_CPU1_USB3_USB00_TXP @T6G_MB_LIB.T6G(SCH_1):NC_CPU1_USB3_USB00_TXP
   U26  C26 USB00_TXN GENOA_SP5-SOCKET6096_13568-001,SMLF,IO,DGA^6000030     I8 @T6G_MB_LIB.T6G(SCH_1):PAGE56

NC_CPU1_USB3_USB01_RXN @T6G_MB_LIB.T6G(SCH_1):NC_CPU1_USB3_USB01_RXN
   U26  C28 USB01_RXN GENOA_SP5-SOCKET6096_13568-001,SMLF,IO,DGA^6000030     I8 @T6G_MB_LIB.T6G(SCH_1):PAGE56

NC_CPU1_USB3_USB01_RXP @T6G_MB_LIB.T6G(SCH_1):NC_CPU1_USB3_USB01_RXP
   U26  C29 USB01_RXP GENOA_SP5-SOCKET6096_13568-001,SMLF,IO,DGA^6000030     I8 @T6G_MB_LIB.T6G(SCH_1):PAGE56

NC_CPU1_USB3_USB01_TXN @T6G_MB_LIB.T6G(SCH_1):NC_CPU1_USB3_USB01_TXN
   U26  E29 USB01_TXN GENOA_SP5-SOCKET6096_13568-001,SMLF,IO,DGA^6000030     I8 @T6G_MB_LIB.T6G(SCH_1):PAGE56

NC_CPU1_USB3_USB01_TXP @T6G_MB_LIB.T6G(SCH_1):NC_CPU1_USB3_USB01_TXP
   U26  E30 USB01_TXP GENOA_SP5-SOCKET6096_13568-001,SMLF,IO,DGA^6000030     I8 @T6G_MB_LIB.T6G(SCH_1):PAGE56

NC_CPU1_USB3_USB10_RXN @T6G_MB_LIB.T6G(SCH_1):NC_CPU1_USB3_USB10_RXN
   U26 DH65 USB10_RXN GENOA_SP5-SOCKET6096_13568-001,SMLF,IO,DGA^6000030     I8 @T6G_MB_LIB.T6G(SCH_1):PAGE56

NC_CPU1_USB3_USB10_RXP @T6G_MB_LIB.T6G(SCH_1):NC_CPU1_USB3_USB10_RXP
   U26 DJ65 USB10_RXP GENOA_SP5-SOCKET6096_13568-001,SMLF,IO,DGA^6000030     I8 @T6G_MB_LIB.T6G(SCH_1):PAGE56

NC_CPU1_USB3_USB10_TXN @T6G_MB_LIB.T6G(SCH_1):NC_CPU1_USB3_USB10_TXN
   U26 DJ69 USB10_TXN GENOA_SP5-SOCKET6096_13568-001,SMLF,IO,DGA^6000030     I8 @T6G_MB_LIB.T6G(SCH_1):PAGE56

NC_CPU1_USB3_USB10_TXP @T6G_MB_LIB.T6G(SCH_1):NC_CPU1_USB3_USB10_TXP
   U26 DH69 USB10_TXP GENOA_SP5-SOCKET6096_13568-001,SMLF,IO,DGA^6000030     I8 @T6G_MB_LIB.T6G(SCH_1):PAGE56

NC_CPU1_USB3_USB11_RXN @T6G_MB_LIB.T6G(SCH_1):NC_CPU1_USB3_USB11_RXN
   U26 DH62 USB11_RXN GENOA_SP5-SOCKET6096_13568-001,SMLF,IO,DGA^6000030     I8 @T6G_MB_LIB.T6G(SCH_1):PAGE56

NC_CPU1_USB3_USB11_RXP @T6G_MB_LIB.T6G(SCH_1):NC_CPU1_USB3_USB11_RXP
   U26 DJ62 USB11_RXP GENOA_SP5-SOCKET6096_13568-001,SMLF,IO,DGA^6000030     I8 @T6G_MB_LIB.T6G(SCH_1):PAGE56

NC_CPU1_USB3_USB11_TXN @T6G_MB_LIB.T6G(SCH_1):NC_CPU1_USB3_USB11_TXN
   U26 DH58 USB11_TXN GENOA_SP5-SOCKET6096_13568-001,SMLF,IO,DGA^6000030     I8 @T6G_MB_LIB.T6G(SCH_1):PAGE56

NC_CPU1_USB3_USB11_TXP @T6G_MB_LIB.T6G(SCH_1):NC_CPU1_USB3_USB11_TXP
   U26 DG58 USB11_TXP GENOA_SP5-SOCKET6096_13568-001,SMLF,IO,DGA^6000030     I8 @T6G_MB_LIB.T6G(SCH_1):PAGE56

NC_HICCUP @T6G_MB_LIB.T6G(SCH_1):NC_HICCUP
   PU9   35 HICCUP# NCP3284AMNTXG-NCP3284AMNTXG,SMLF,IC,AL003284002    I21 @T6G_MB_LIB.T6G(SCH_1):PAGE245

NC_HSC_TYPE_NC0 @T6G_MB_LIB.T6G(SCH_1):NC_HSC_TYPE_NC0
 U6005    6    NC0 ISL28022FRZT-ISL28022FRZ-T,SMLF,IC,AL028022003    I28 @T6G_MB_LIB.T6G(SCH_1):PAGE271

NC_HSC_TYPE_NC1 @T6G_MB_LIB.T6G(SCH_1):NC_HSC_TYPE_NC1
 U6005    7    NC1 ISL28022FRZT-ISL28022FRZ-T,SMLF,IC,AL028022003    I28 @T6G_MB_LIB.T6G(SCH_1):PAGE271

NC_HSC_TYPE_NC2 @T6G_MB_LIB.T6G(SCH_1):NC_HSC_TYPE_NC2
 U6005    8    NC2 ISL28022FRZT-ISL28022FRZ-T,SMLF,IC,AL028022003    I28 @T6G_MB_LIB.T6G(SCH_1):PAGE271

NC_HSC_TYPE_NC3 @T6G_MB_LIB.T6G(SCH_1):NC_HSC_TYPE_NC3
 U6005   14    NC3 ISL28022FRZT-ISL28022FRZ-T,SMLF,IC,AL028022003    I28 @T6G_MB_LIB.T6G(SCH_1):PAGE271

NC_HSC_TYPE_NC4 @T6G_MB_LIB.T6G(SCH_1):NC_HSC_TYPE_NC4
 U6005   15    NC4 ISL28022FRZT-ISL28022FRZ-T,SMLF,IC,AL028022003    I28 @T6G_MB_LIB.T6G(SCH_1):PAGE271

NC_HSC_TYPE_NC5 @T6G_MB_LIB.T6G(SCH_1):NC_HSC_TYPE_NC5
 U6005   16    NC5 ISL28022FRZT-ISL28022FRZ-T,SMLF,IC,AL028022003    I28 @T6G_MB_LIB.T6G(SCH_1):PAGE271

NC_HSC_TYPE_VINM @T6G_MB_LIB.T6G(SCH_1):NC_HSC_TYPE_VINM
 U6005   12   VINM ISL28022FRZT-ISL28022FRZ-T,SMLF,IC,AL028022003    I28 @T6G_MB_LIB.T6G(SCH_1):PAGE271

NC_HSC_TYPE_VINP @T6G_MB_LIB.T6G(SCH_1):NC_HSC_TYPE_VINP
 U6005   13   VINP ISL28022FRZT-ISL28022FRZ-T,SMLF,IC,AL028022003    I28 @T6G_MB_LIB.T6G(SCH_1):PAGE271

NC_INA230_1_NC0 @T6G_MB_LIB.T6G(SCH_1):NC_INA230_1_NC0
  U266    6    NC0 ISL28022FRZT-ISL28022FRZ-T,SMLF,IC,AL028022003    I30 @T6G_MB_LIB.T6G(SCH_1):PAGE295

NC_INA230_1_NC1 @T6G_MB_LIB.T6G(SCH_1):NC_INA230_1_NC1
  U266    7    NC1 ISL28022FRZT-ISL28022FRZ-T,SMLF,IC,AL028022003    I30 @T6G_MB_LIB.T6G(SCH_1):PAGE295

NC_INA230_1_NC2 @T6G_MB_LIB.T6G(SCH_1):NC_INA230_1_NC2
  U266    8    NC2 ISL28022FRZT-ISL28022FRZ-T,SMLF,IC,AL028022003    I30 @T6G_MB_LIB.T6G(SCH_1):PAGE295

NC_INA230_1_NC3 @T6G_MB_LIB.T6G(SCH_1):NC_INA230_1_NC3
  U266   14    NC3 ISL28022FRZT-ISL28022FRZ-T,SMLF,IC,AL028022003    I30 @T6G_MB_LIB.T6G(SCH_1):PAGE295

NC_INA230_1_NC4 @T6G_MB_LIB.T6G(SCH_1):NC_INA230_1_NC4
  U266   15    NC4 ISL28022FRZT-ISL28022FRZ-T,SMLF,IC,AL028022003    I30 @T6G_MB_LIB.T6G(SCH_1):PAGE295

NC_INA230_1_NC5 @T6G_MB_LIB.T6G(SCH_1):NC_INA230_1_NC5
  U266   16    NC5 ISL28022FRZT-ISL28022FRZ-T,SMLF,IC,AL028022003    I30 @T6G_MB_LIB.T6G(SCH_1):PAGE295

NC_INA230_2_NC0 @T6G_MB_LIB.T6G(SCH_1):NC_INA230_2_NC0
  U276    6    NC0 ISL28022FRZT-ISL28022FRZ-T,SMLF,IC,AL028022003   I129 @T6G_MB_LIB.T6G(SCH_1):PAGE295

NC_INA230_2_NC1 @T6G_MB_LIB.T6G(SCH_1):NC_INA230_2_NC1
  U276    7    NC1 ISL28022FRZT-ISL28022FRZ-T,SMLF,IC,AL028022003   I129 @T6G_MB_LIB.T6G(SCH_1):PAGE295

NC_INA230_2_NC2 @T6G_MB_LIB.T6G(SCH_1):NC_INA230_2_NC2
  U276    8    NC2 ISL28022FRZT-ISL28022FRZ-T,SMLF,IC,AL028022003   I129 @T6G_MB_LIB.T6G(SCH_1):PAGE295

NC_INA230_2_NC3 @T6G_MB_LIB.T6G(SCH_1):NC_INA230_2_NC3
  U276   14    NC3 ISL28022FRZT-ISL28022FRZ-T,SMLF,IC,AL028022003   I129 @T6G_MB_LIB.T6G(SCH_1):PAGE295

NC_INA230_2_NC4 @T6G_MB_LIB.T6G(SCH_1):NC_INA230_2_NC4
  U276   15    NC4 ISL28022FRZT-ISL28022FRZ-T,SMLF,IC,AL028022003   I129 @T6G_MB_LIB.T6G(SCH_1):PAGE295

NC_INA230_2_NC5 @T6G_MB_LIB.T6G(SCH_1):NC_INA230_2_NC5
  U276   16    NC5 ISL28022FRZT-ISL28022FRZ-T,SMLF,IC,AL028022003   I129 @T6G_MB_LIB.T6G(SCH_1):PAGE295

NC_INA230_3_NC0 @T6G_MB_LIB.T6G(SCH_1):NC_INA230_3_NC0
  U263    6    NC0 ISL28022FRZT-ISL28022FRZ-T,SMLF,IC,AL028022003    I94 @T6G_MB_LIB.T6G(SCH_1):PAGE360

NC_INA230_3_NC1 @T6G_MB_LIB.T6G(SCH_1):NC_INA230_3_NC1
  U263    7    NC1 ISL28022FRZT-ISL28022FRZ-T,SMLF,IC,AL028022003    I94 @T6G_MB_LIB.T6G(SCH_1):PAGE360

NC_INA230_3_NC2 @T6G_MB_LIB.T6G(SCH_1):NC_INA230_3_NC2
  U263    8    NC2 ISL28022FRZT-ISL28022FRZ-T,SMLF,IC,AL028022003    I94 @T6G_MB_LIB.T6G(SCH_1):PAGE360

NC_INA230_3_NC3 @T6G_MB_LIB.T6G(SCH_1):NC_INA230_3_NC3
  U263   14    NC3 ISL28022FRZT-ISL28022FRZ-T,SMLF,IC,AL028022003    I94 @T6G_MB_LIB.T6G(SCH_1):PAGE360

NC_INA230_3_NC4 @T6G_MB_LIB.T6G(SCH_1):NC_INA230_3_NC4
  U263   15    NC4 ISL28022FRZT-ISL28022FRZ-T,SMLF,IC,AL028022003    I94 @T6G_MB_LIB.T6G(SCH_1):PAGE360

NC_INA230_3_NC5 @T6G_MB_LIB.T6G(SCH_1):NC_INA230_3_NC5
  U263   16    NC5 ISL28022FRZT-ISL28022FRZ-T,SMLF,IC,AL028022003    I94 @T6G_MB_LIB.T6G(SCH_1):PAGE360

NC_INA230_4_NC0 @T6G_MB_LIB.T6G(SCH_1):NC_INA230_4_NC0
  U264    6    NC0 ISL28022FRZT-ISL28022FRZ-T,SMLF,IC,AL028022003    I46 @T6G_MB_LIB.T6G(SCH_1):PAGE360

NC_INA230_4_NC1 @T6G_MB_LIB.T6G(SCH_1):NC_INA230_4_NC1
  U264    7    NC1 ISL28022FRZT-ISL28022FRZ-T,SMLF,IC,AL028022003    I46 @T6G_MB_LIB.T6G(SCH_1):PAGE360

NC_INA230_4_NC2 @T6G_MB_LIB.T6G(SCH_1):NC_INA230_4_NC2
  U264    8    NC2 ISL28022FRZT-ISL28022FRZ-T,SMLF,IC,AL028022003    I46 @T6G_MB_LIB.T6G(SCH_1):PAGE360

NC_INA230_4_NC3 @T6G_MB_LIB.T6G(SCH_1):NC_INA230_4_NC3
  U264   14    NC3 ISL28022FRZT-ISL28022FRZ-T,SMLF,IC,AL028022003    I46 @T6G_MB_LIB.T6G(SCH_1):PAGE360

NC_INA230_4_NC4 @T6G_MB_LIB.T6G(SCH_1):NC_INA230_4_NC4
  U264   15    NC4 ISL28022FRZT-ISL28022FRZ-T,SMLF,IC,AL028022003    I46 @T6G_MB_LIB.T6G(SCH_1):PAGE360

NC_INA230_4_NC5 @T6G_MB_LIB.T6G(SCH_1):NC_INA230_4_NC5
  U264   16    NC5 ISL28022FRZT-ISL28022FRZ-T,SMLF,IC,AL028022003    I46 @T6G_MB_LIB.T6G(SCH_1):PAGE360

NC_INA230_5_NC0 @T6G_MB_LIB.T6G(SCH_1):NC_INA230_5_NC0
  U265    6    NC0 ISL28022FRZT-ISL28022FRZ-T,SMLF,IC,AL028022003    I69 @T6G_MB_LIB.T6G(SCH_1):PAGE360

NC_INA230_5_NC1 @T6G_MB_LIB.T6G(SCH_1):NC_INA230_5_NC1
  U265    7    NC1 ISL28022FRZT-ISL28022FRZ-T,SMLF,IC,AL028022003    I69 @T6G_MB_LIB.T6G(SCH_1):PAGE360

NC_INA230_5_NC2 @T6G_MB_LIB.T6G(SCH_1):NC_INA230_5_NC2
  U265    8    NC2 ISL28022FRZT-ISL28022FRZ-T,SMLF,IC,AL028022003    I69 @T6G_MB_LIB.T6G(SCH_1):PAGE360

NC_INA230_5_NC3 @T6G_MB_LIB.T6G(SCH_1):NC_INA230_5_NC3
  U265   14    NC3 ISL28022FRZT-ISL28022FRZ-T,SMLF,IC,AL028022003    I69 @T6G_MB_LIB.T6G(SCH_1):PAGE360

NC_INA230_5_NC4 @T6G_MB_LIB.T6G(SCH_1):NC_INA230_5_NC4
  U265   15    NC4 ISL28022FRZT-ISL28022FRZ-T,SMLF,IC,AL028022003    I69 @T6G_MB_LIB.T6G(SCH_1):PAGE360

NC_INA230_5_NC5 @T6G_MB_LIB.T6G(SCH_1):NC_INA230_5_NC5
  U265   16    NC5 ISL28022FRZT-ISL28022FRZ-T,SMLF,IC,AL028022003    I69 @T6G_MB_LIB.T6G(SCH_1):PAGE360

NC_INA230_6_NC0 @T6G_MB_LIB.T6G(SCH_1):NC_INA230_6_NC0
   U55    6    NC0 ISL28022FRZT-ISL28022FRZ-T,SMLF,IC,AL028022003    I28 @T6G_MB_LIB.T6G(SCH_1):PAGE466

NC_INA230_6_NC1 @T6G_MB_LIB.T6G(SCH_1):NC_INA230_6_NC1
   U55    7    NC1 ISL28022FRZT-ISL28022FRZ-T,SMLF,IC,AL028022003    I28 @T6G_MB_LIB.T6G(SCH_1):PAGE466

NC_INA230_6_NC2 @T6G_MB_LIB.T6G(SCH_1):NC_INA230_6_NC2
   U55    8    NC2 ISL28022FRZT-ISL28022FRZ-T,SMLF,IC,AL028022003    I28 @T6G_MB_LIB.T6G(SCH_1):PAGE466

NC_INA230_6_NC3 @T6G_MB_LIB.T6G(SCH_1):NC_INA230_6_NC3
   U55   14    NC3 ISL28022FRZT-ISL28022FRZ-T,SMLF,IC,AL028022003    I28 @T6G_MB_LIB.T6G(SCH_1):PAGE466

NC_INA230_6_NC4 @T6G_MB_LIB.T6G(SCH_1):NC_INA230_6_NC4
   U55   15    NC4 ISL28022FRZT-ISL28022FRZ-T,SMLF,IC,AL028022003    I28 @T6G_MB_LIB.T6G(SCH_1):PAGE466

NC_INA230_6_NC5 @T6G_MB_LIB.T6G(SCH_1):NC_INA230_6_NC5
   U55   16    NC5 ISL28022FRZT-ISL28022FRZ-T,SMLF,IC,AL028022003    I28 @T6G_MB_LIB.T6G(SCH_1):PAGE466

NC_INA230_7_NC0 @T6G_MB_LIB.T6G(SCH_1):NC_INA230_7_NC0
   U56    6    NC0 ISL28022FRZT-ISL28022FRZ-T,SMLF,IC,AL028022003    I29 @T6G_MB_LIB.T6G(SCH_1):PAGE466

NC_INA230_7_NC1 @T6G_MB_LIB.T6G(SCH_1):NC_INA230_7_NC1
   U56    7    NC1 ISL28022FRZT-ISL28022FRZ-T,SMLF,IC,AL028022003    I29 @T6G_MB_LIB.T6G(SCH_1):PAGE466

NC_INA230_7_NC2 @T6G_MB_LIB.T6G(SCH_1):NC_INA230_7_NC2
   U56    8    NC2 ISL28022FRZT-ISL28022FRZ-T,SMLF,IC,AL028022003    I29 @T6G_MB_LIB.T6G(SCH_1):PAGE466

NC_INA230_7_NC3 @T6G_MB_LIB.T6G(SCH_1):NC_INA230_7_NC3
   U56   14    NC3 ISL28022FRZT-ISL28022FRZ-T,SMLF,IC,AL028022003    I29 @T6G_MB_LIB.T6G(SCH_1):PAGE466

NC_INA230_7_NC4 @T6G_MB_LIB.T6G(SCH_1):NC_INA230_7_NC4
   U56   15    NC4 ISL28022FRZT-ISL28022FRZ-T,SMLF,IC,AL028022003    I29 @T6G_MB_LIB.T6G(SCH_1):PAGE466

NC_INA230_7_NC5 @T6G_MB_LIB.T6G(SCH_1):NC_INA230_7_NC5
   U56   16    NC5 ISL28022FRZT-ISL28022FRZ-T,SMLF,IC,AL028022003    I29 @T6G_MB_LIB.T6G(SCH_1):PAGE466

NC_INA230_8_NC0 @T6G_MB_LIB.T6G(SCH_1):NC_INA230_8_NC0
   U52    6    NC0 ISL28022FRZT-ISL28022FRZ-T,SMLF,IC,AL028022003    I57 @T6G_MB_LIB.T6G(SCH_1):PAGE466

NC_INA230_8_NC1 @T6G_MB_LIB.T6G(SCH_1):NC_INA230_8_NC1
   U52    7    NC1 ISL28022FRZT-ISL28022FRZ-T,SMLF,IC,AL028022003    I57 @T6G_MB_LIB.T6G(SCH_1):PAGE466

NC_INA230_8_NC2 @T6G_MB_LIB.T6G(SCH_1):NC_INA230_8_NC2
   U52    8    NC2 ISL28022FRZT-ISL28022FRZ-T,SMLF,IC,AL028022003    I57 @T6G_MB_LIB.T6G(SCH_1):PAGE466

NC_INA230_8_NC3 @T6G_MB_LIB.T6G(SCH_1):NC_INA230_8_NC3
   U52   14    NC3 ISL28022FRZT-ISL28022FRZ-T,SMLF,IC,AL028022003    I57 @T6G_MB_LIB.T6G(SCH_1):PAGE466

NC_INA230_8_NC4 @T6G_MB_LIB.T6G(SCH_1):NC_INA230_8_NC4
   U52   15    NC4 ISL28022FRZT-ISL28022FRZ-T,SMLF,IC,AL028022003    I57 @T6G_MB_LIB.T6G(SCH_1):PAGE466

NC_INA230_8_NC5 @T6G_MB_LIB.T6G(SCH_1):NC_INA230_8_NC5
   U52   16    NC5 ISL28022FRZT-ISL28022FRZ-T,SMLF,IC,AL028022003    I57 @T6G_MB_LIB.T6G(SCH_1):PAGE466

NC_J106_A5 @T6G_MB_LIB.T6G(SCH_1):NC_J106_A5
  J106   A5     A5 CONN112_10137002101LF-CONN112_10137002-101LF,THLF,A    I19 @T6G_MB_LIB.T6G(SCH_1):PAGE327

NC_J107_A1 @T6G_MB_LIB.T6G(SCH_1):NC_J107_A1
  J107   A1     A1 CONN112_10137002101LF-CONN112_10137002-101LF,THLF,A    I49 @T6G_MB_LIB.T6G(SCH_1):PAGE317

NC_J107_A3 @T6G_MB_LIB.T6G(SCH_1):NC_J107_A3
  J107   A3     A3 CONN112_10137002101LF-CONN112_10137002-101LF,THLF,A    I49 @T6G_MB_LIB.T6G(SCH_1):PAGE317

NC_J107_A5 @T6G_MB_LIB.T6G(SCH_1):NC_J107_A5
  J107   A5     A5 CONN112_10137002101LF-CONN112_10137002-101LF,THLF,A    I70 @T6G_MB_LIB.T6G(SCH_1):PAGE317

NC_J107_N4 @T6G_MB_LIB.T6G(SCH_1):NC_J107_N4
  J107   N4     N4 CONN112_10137002101LF-CONN112_10137002-101LF,THLF,A    I49 @T6G_MB_LIB.T6G(SCH_1):PAGE317

NC_J107_N6 @T6G_MB_LIB.T6G(SCH_1):NC_J107_N6
  J107   N6     N6 CONN112_10137002101LF-CONN112_10137002-101LF,THLF,A    I70 @T6G_MB_LIB.T6G(SCH_1):PAGE317

NC_J108_N2 @T6G_MB_LIB.T6G(SCH_1):NC_J108_N2
  J108   N2     N2 CONN112_10137002101LF-CONN112_10137002-101LF,THLF,A    I72 @T6G_MB_LIB.T6G(SCH_1):PAGE320

NC_J108_N4 @T6G_MB_LIB.T6G(SCH_1):NC_J108_N4
  J108   N4     N4 CONN112_10137002101LF-CONN112_10137002-101LF,THLF,A    I72 @T6G_MB_LIB.T6G(SCH_1):PAGE320

NC_J108_N6 @T6G_MB_LIB.T6G(SCH_1):NC_J108_N6
  J108   N6     N6 CONN112_10137002101LF-CONN112_10137002-101LF,THLF,A    I15 @T6G_MB_LIB.T6G(SCH_1):PAGE320

NC_J112_N2 @T6G_MB_LIB.T6G(SCH_1):NC_J112_N2
  J112   N2     N2 CONN160_10131762101LF-CONN160_10131762-101LF,THLF,A   I102 @T6G_MB_LIB.T6G(SCH_1):PAGE329

NC_J112_O2 @T6G_MB_LIB.T6G(SCH_1):NC_J112_O2
  J112   O2     O2 CONN160_10131762101LF-CONN160_10131762-101LF,THLF,A   I102 @T6G_MB_LIB.T6G(SCH_1):PAGE329

NC_J112_O5 @T6G_MB_LIB.T6G(SCH_1):NC_J112_O5
  J112   O5     O5 CONN160_10131762101LF-CONN160_10131762-101LF,THLF,A     I7 @T6G_MB_LIB.T6G(SCH_1):PAGE329

NC_J112_P5 @T6G_MB_LIB.T6G(SCH_1):NC_J112_P5
  J112   P5     P5 CONN160_10131762101LF-CONN160_10131762-101LF,THLF,A     I7 @T6G_MB_LIB.T6G(SCH_1):PAGE329

NC_J112_R5 @T6G_MB_LIB.T6G(SCH_1):NC_J112_R5
  J112   R5     R5 CONN160_10131762101LF-CONN160_10131762-101LF,THLF,A     I7 @T6G_MB_LIB.T6G(SCH_1):PAGE329

NC_J112_S5 @T6G_MB_LIB.T6G(SCH_1):NC_J112_S5
  J112   S5     S5 CONN160_10131762101LF-CONN160_10131762-101LF,THLF,A     I7 @T6G_MB_LIB.T6G(SCH_1):PAGE329

NC_M2_0_NC1 @T6G_MB_LIB.T6G(SCH_1):NC_M2_0_NC1
   J59    6    NC1 SCONN75K_APCI0155P004A-SCONN75K_APCI0155-P004A,SMLA    I88 @T6G_MB_LIB.T6G(SCH_1):PAGE345

NC_M2_0_NC10 @T6G_MB_LIB.T6G(SCH_1):NC_M2_0_NC10
   J59   34   NC10 SCONN75K_APCI0155P004A-SCONN75K_APCI0155-P004A,SMLA    I88 @T6G_MB_LIB.T6G(SCH_1):PAGE345

NC_M2_0_NC11 @T6G_MB_LIB.T6G(SCH_1):NC_M2_0_NC11
   J59   36   NC11 SCONN75K_APCI0155P004A-SCONN75K_APCI0155-P004A,SMLA    I88 @T6G_MB_LIB.T6G(SCH_1):PAGE345

NC_M2_0_NC14 @T6G_MB_LIB.T6G(SCH_1):NC_M2_0_NC14
   J59   44   NC14 SCONN75K_APCI0155P004A-SCONN75K_APCI0155-P004A,SMLA    I88 @T6G_MB_LIB.T6G(SCH_1):PAGE345

NC_M2_0_NC15 @T6G_MB_LIB.T6G(SCH_1):NC_M2_0_NC15
   J59   46   NC15 SCONN75K_APCI0155P004A-SCONN75K_APCI0155-P004A,SMLA    I88 @T6G_MB_LIB.T6G(SCH_1):PAGE345

NC_M2_0_NC16 @T6G_MB_LIB.T6G(SCH_1):NC_M2_0_NC16
   J59   48   NC16 SCONN75K_APCI0155P004A-SCONN75K_APCI0155-P004A,SMLA    I88 @T6G_MB_LIB.T6G(SCH_1):PAGE345

NC_M2_0_NC17 @T6G_MB_LIB.T6G(SCH_1):NC_M2_0_NC17
   J59   56   NC17 SCONN75K_APCI0155P004A-SCONN75K_APCI0155-P004A,SMLA    I88 @T6G_MB_LIB.T6G(SCH_1):PAGE345

NC_M2_0_NC18 @T6G_MB_LIB.T6G(SCH_1):NC_M2_0_NC18
   J59   58   NC18 SCONN75K_APCI0155P004A-SCONN75K_APCI0155-P004A,SMLA    I88 @T6G_MB_LIB.T6G(SCH_1):PAGE345

NC_M2_0_NC19 @T6G_MB_LIB.T6G(SCH_1):NC_M2_0_NC19
   J59   67   NC19 SCONN75K_APCI0155P004A-SCONN75K_APCI0155-P004A,SMLA    I88 @T6G_MB_LIB.T6G(SCH_1):PAGE345

NC_M2_0_NC2 @T6G_MB_LIB.T6G(SCH_1):NC_M2_0_NC2
   J59    8    NC2 SCONN75K_APCI0155P004A-SCONN75K_APCI0155-P004A,SMLA    I88 @T6G_MB_LIB.T6G(SCH_1):PAGE345

NC_M2_0_NC3 @T6G_MB_LIB.T6G(SCH_1):NC_M2_0_NC3
   J59   20    NC3 SCONN75K_APCI0155P004A-SCONN75K_APCI0155-P004A,SMLA    I88 @T6G_MB_LIB.T6G(SCH_1):PAGE345

NC_M2_0_NC4 @T6G_MB_LIB.T6G(SCH_1):NC_M2_0_NC4
   J59   22    NC4 SCONN75K_APCI0155P004A-SCONN75K_APCI0155-P004A,SMLA    I88 @T6G_MB_LIB.T6G(SCH_1):PAGE345

NC_M2_0_NC5 @T6G_MB_LIB.T6G(SCH_1):NC_M2_0_NC5
   J59   24    NC5 SCONN75K_APCI0155P004A-SCONN75K_APCI0155-P004A,SMLA    I88 @T6G_MB_LIB.T6G(SCH_1):PAGE345

NC_M2_0_NC6 @T6G_MB_LIB.T6G(SCH_1):NC_M2_0_NC6
   J59   26    NC6 SCONN75K_APCI0155P004A-SCONN75K_APCI0155-P004A,SMLA    I88 @T6G_MB_LIB.T6G(SCH_1):PAGE345

NC_M2_0_NC7 @T6G_MB_LIB.T6G(SCH_1):NC_M2_0_NC7
   J59   28    NC7 SCONN75K_APCI0155P004A-SCONN75K_APCI0155-P004A,SMLA    I88 @T6G_MB_LIB.T6G(SCH_1):PAGE345

NC_M2_0_NC8 @T6G_MB_LIB.T6G(SCH_1):NC_M2_0_NC8
   J59   30    NC8 SCONN75K_APCI0155P004A-SCONN75K_APCI0155-P004A,SMLA    I88 @T6G_MB_LIB.T6G(SCH_1):PAGE345

NC_M2_0_NC9 @T6G_MB_LIB.T6G(SCH_1):NC_M2_0_NC9
   J59   32    NC9 SCONN75K_APCI0155P004A-SCONN75K_APCI0155-P004A,SMLA    I88 @T6G_MB_LIB.T6G(SCH_1):PAGE345

NC_M2_0_SUSCLK @T6G_MB_LIB.T6G(SCH_1):NC_M2_0_SUSCLK
   J59   68 SUSCLK SCONN75K_APCI0155P004A-SCONN75K_APCI0155-P004A,SMLA    I88 @T6G_MB_LIB.T6G(SCH_1):PAGE345

NC_P0V9_RETIMER_CPU0_IMON3 @T6G_MB_LIB.T6G(SCH_1):NC_P0V9_RETIMER_CPU0_IMON3
PU6502   25    CS5 ISL69260IRAZT-ISL69260IRAZ-T,SMLF,IC,AL069260000    I42 @T6G_MB_LIB.T6G(SCH_1):PAGE475
PR6609    1      A Q_RES_0402LF-0,5%,1/16W,CHIP,CS00002JB13   I188 @T6G_MB_LIB.T6G(SCH_1):PAGE475

NC_P0V9_RETIMER_CPU0_IMON4 @T6G_MB_LIB.T6G(SCH_1):NC_P0V9_RETIMER_CPU0_IMON4
PU6502   26    CS4 ISL69260IRAZT-ISL69260IRAZ-T,SMLF,IC,AL069260000    I42 @T6G_MB_LIB.T6G(SCH_1):PAGE475
PR6610    1      A Q_RES_0402LF-0,5%,1/16W,CHIP,CS00002JB13   I190 @T6G_MB_LIB.T6G(SCH_1):PAGE475

NC_P0V9_RETIMER_CPU0_IMON5 @T6G_MB_LIB.T6G(SCH_1):NC_P0V9_RETIMER_CPU0_IMON5
PU6502   27    CS3 ISL69260IRAZT-ISL69260IRAZ-T,SMLF,IC,AL069260000    I42 @T6G_MB_LIB.T6G(SCH_1):PAGE475
PR6611    1      A Q_RES_0402LF-0,5%,1/16W,CHIP,CS00002JB13   I191 @T6G_MB_LIB.T6G(SCH_1):PAGE475

NC_P0V9_RETIMER_CPU0_IMON6 @T6G_MB_LIB.T6G(SCH_1):NC_P0V9_RETIMER_CPU0_IMON6
PU6502   28    CS2 ISL69260IRAZT-ISL69260IRAZ-T,SMLF,IC,AL069260000    I42 @T6G_MB_LIB.T6G(SCH_1):PAGE475
PR6612    1      A Q_RES_0402LF-0,5%,1/16W,CHIP,CS00002JB13   I192 @T6G_MB_LIB.T6G(SCH_1):PAGE475

NC_P0V9_RETIMER_CPU0_IMON7 @T6G_MB_LIB.T6G(SCH_1):NC_P0V9_RETIMER_CPU0_IMON7
PU6502   29    CS1 ISL69260IRAZT-ISL69260IRAZ-T,SMLF,IC,AL069260000    I42 @T6G_MB_LIB.T6G(SCH_1):PAGE475
PR6613    1      A Q_RES_0402LF-0,5%,1/16W,CHIP,CS00002JB13   I193 @T6G_MB_LIB.T6G(SCH_1):PAGE475

NC_P0V9_RETIMER_CPU0_IMON8 @T6G_MB_LIB.T6G(SCH_1):NC_P0V9_RETIMER_CPU0_IMON8
PU6502   30    CS0 ISL69260IRAZT-ISL69260IRAZ-T,SMLF,IC,AL069260000    I42 @T6G_MB_LIB.T6G(SCH_1):PAGE475
PR6614    1      A Q_RES_0402LF-0,5%,1/16W,CHIP,CS00002JB13   I198 @T6G_MB_LIB.T6G(SCH_1):PAGE475

NC_P0V9_RETIMER_CPU0_PG1 @T6G_MB_LIB.T6G(SCH_1):NC_P0V9_RETIMER_CPU0_PG1
PU6502   16    PG1 ISL69260IRAZT-ISL69260IRAZ-T,SMLF,IC,AL069260000    I42 @T6G_MB_LIB.T6G(SCH_1):PAGE475

NC_P0V9_RETIMER_CPU0_PWM3 @T6G_MB_LIB.T6G(SCH_1):NC_P0V9_RETIMER_CPU0_PWM3
PU6502    6   PWM5 ISL69260IRAZT-ISL69260IRAZ-T,SMLF,IC,AL069260000    I42 @T6G_MB_LIB.T6G(SCH_1):PAGE475

NC_P0V9_RETIMER_CPU0_PWM4 @T6G_MB_LIB.T6G(SCH_1):NC_P0V9_RETIMER_CPU0_PWM4
PU6502    5   PWM4 ISL69260IRAZT-ISL69260IRAZ-T,SMLF,IC,AL069260000    I42 @T6G_MB_LIB.T6G(SCH_1):PAGE475

NC_P0V9_RETIMER_CPU0_PWM5 @T6G_MB_LIB.T6G(SCH_1):NC_P0V9_RETIMER_CPU0_PWM5
PU6502    4   PWM3 ISL69260IRAZT-ISL69260IRAZ-T,SMLF,IC,AL069260000    I42 @T6G_MB_LIB.T6G(SCH_1):PAGE475

NC_P0V9_RETIMER_CPU0_PWM6 @T6G_MB_LIB.T6G(SCH_1):NC_P0V9_RETIMER_CPU0_PWM6
PU6502    3   PWM2 ISL69260IRAZT-ISL69260IRAZ-T,SMLF,IC,AL069260000    I42 @T6G_MB_LIB.T6G(SCH_1):PAGE475

NC_P0V9_RETIMER_CPU0_PWM7 @T6G_MB_LIB.T6G(SCH_1):NC_P0V9_RETIMER_CPU0_PWM7
PU6502    2   PWM1 ISL69260IRAZT-ISL69260IRAZ-T,SMLF,IC,AL069260000    I42 @T6G_MB_LIB.T6G(SCH_1):PAGE475

NC_P0V9_RETIMER_CPU0_PWM8 @T6G_MB_LIB.T6G(SCH_1):NC_P0V9_RETIMER_CPU0_PWM8
PU6502    1   PWM0 ISL69260IRAZT-ISL69260IRAZ-T,SMLF,IC,AL069260000    I42 @T6G_MB_LIB.T6G(SCH_1):PAGE475

NC_P0V9_RETIMER_CPU1_IMON3 @T6G_MB_LIB.T6G(SCH_1):NC_P0V9_RETIMER_CPU1_IMON3
PR6539    1      A Q_RES_0402LF-0,5%,1/16W,CHIP,CS00002JB13    I69 @T6G_MB_LIB.T6G(SCH_1):PAGE477
PU6510   25    CS5 ISL69260IRAZT-ISL69260IRAZ-T,SMLF,IC,AL069260000    I88 @T6G_MB_LIB.T6G(SCH_1):PAGE477

NC_P0V9_RETIMER_CPU1_IMON4 @T6G_MB_LIB.T6G(SCH_1):NC_P0V9_RETIMER_CPU1_IMON4
PR6540    1      A Q_RES_0402LF-0,5%,1/16W,CHIP,CS00002JB13    I68 @T6G_MB_LIB.T6G(SCH_1):PAGE477
PU6510   26    CS4 ISL69260IRAZT-ISL69260IRAZ-T,SMLF,IC,AL069260000    I88 @T6G_MB_LIB.T6G(SCH_1):PAGE477

NC_P0V9_RETIMER_CPU1_IMON5 @T6G_MB_LIB.T6G(SCH_1):NC_P0V9_RETIMER_CPU1_IMON5
PR6541    1      A Q_RES_0402LF-0,5%,1/16W,CHIP,CS00002JB13    I65 @T6G_MB_LIB.T6G(SCH_1):PAGE477
PU6510   27    CS3 ISL69260IRAZT-ISL69260IRAZ-T,SMLF,IC,AL069260000    I88 @T6G_MB_LIB.T6G(SCH_1):PAGE477

NC_P0V9_RETIMER_CPU1_IMON6 @T6G_MB_LIB.T6G(SCH_1):NC_P0V9_RETIMER_CPU1_IMON6
PR6542    1      A Q_RES_0402LF-0,5%,1/16W,CHIP,CS00002JB13    I64 @T6G_MB_LIB.T6G(SCH_1):PAGE477
PU6510   28    CS2 ISL69260IRAZT-ISL69260IRAZ-T,SMLF,IC,AL069260000    I88 @T6G_MB_LIB.T6G(SCH_1):PAGE477

NC_P0V9_RETIMER_CPU1_IMON7 @T6G_MB_LIB.T6G(SCH_1):NC_P0V9_RETIMER_CPU1_IMON7
PR6543    1      A Q_RES_0402LF-0,5%,1/16W,CHIP,CS00002JB13    I58 @T6G_MB_LIB.T6G(SCH_1):PAGE477
PU6510   29    CS1 ISL69260IRAZT-ISL69260IRAZ-T,SMLF,IC,AL069260000    I88 @T6G_MB_LIB.T6G(SCH_1):PAGE477

NC_P0V9_RETIMER_CPU1_IMON8 @T6G_MB_LIB.T6G(SCH_1):NC_P0V9_RETIMER_CPU1_IMON8
PR6544    1      A Q_RES_0402LF-0,5%,1/16W,CHIP,CS00002JB13    I57 @T6G_MB_LIB.T6G(SCH_1):PAGE477
PU6510   30    CS0 ISL69260IRAZT-ISL69260IRAZ-T,SMLF,IC,AL069260000    I88 @T6G_MB_LIB.T6G(SCH_1):PAGE477

NC_P0V9_RETIMER_CPU1_PG1 @T6G_MB_LIB.T6G(SCH_1):NC_P0V9_RETIMER_CPU1_PG1
PU6510   16    PG1 ISL69260IRAZT-ISL69260IRAZ-T,SMLF,IC,AL069260000    I88 @T6G_MB_LIB.T6G(SCH_1):PAGE477

NC_P0V9_RETIMER_CPU1_PWM3 @T6G_MB_LIB.T6G(SCH_1):NC_P0V9_RETIMER_CPU1_PWM3
PU6510    6   PWM5 ISL69260IRAZT-ISL69260IRAZ-T,SMLF,IC,AL069260000    I88 @T6G_MB_LIB.T6G(SCH_1):PAGE477

NC_P0V9_RETIMER_CPU1_PWM4 @T6G_MB_LIB.T6G(SCH_1):NC_P0V9_RETIMER_CPU1_PWM4
PU6510    5   PWM4 ISL69260IRAZT-ISL69260IRAZ-T,SMLF,IC,AL069260000    I88 @T6G_MB_LIB.T6G(SCH_1):PAGE477

NC_P0V9_RETIMER_CPU1_PWM5 @T6G_MB_LIB.T6G(SCH_1):NC_P0V9_RETIMER_CPU1_PWM5
PU6510    4   PWM3 ISL69260IRAZT-ISL69260IRAZ-T,SMLF,IC,AL069260000    I88 @T6G_MB_LIB.T6G(SCH_1):PAGE477

NC_P0V9_RETIMER_CPU1_PWM6 @T6G_MB_LIB.T6G(SCH_1):NC_P0V9_RETIMER_CPU1_PWM6
PU6510    3   PWM2 ISL69260IRAZT-ISL69260IRAZ-T,SMLF,IC,AL069260000    I88 @T6G_MB_LIB.T6G(SCH_1):PAGE477

NC_P0V9_RETIMER_CPU1_PWM7 @T6G_MB_LIB.T6G(SCH_1):NC_P0V9_RETIMER_CPU1_PWM7
PU6510    2   PWM1 ISL69260IRAZT-ISL69260IRAZ-T,SMLF,IC,AL069260000    I88 @T6G_MB_LIB.T6G(SCH_1):PAGE477

NC_P0V9_RETIMER_CPU1_PWM8 @T6G_MB_LIB.T6G(SCH_1):NC_P0V9_RETIMER_CPU1_PWM8
PU6510    1   PWM0 ISL69260IRAZT-ISL69260IRAZ-T,SMLF,IC,AL069260000    I88 @T6G_MB_LIB.T6G(SCH_1):PAGE477

NC_PU9_1 @T6G_MB_LIB.T6G(SCH_1):NC_PU9_1
   PU9   33    NC1 NCP3284AMNTXG-NCP3284AMNTXG,SMLF,IC,AL003284002    I21 @T6G_MB_LIB.T6G(SCH_1):PAGE245

NC_PU9_2 @T6G_MB_LIB.T6G(SCH_1):NC_PU9_2
   PU9   34    NC2 NCP3284AMNTXG-NCP3284AMNTXG,SMLF,IC,AL003284002    I21 @T6G_MB_LIB.T6G(SCH_1):PAGE245

NC_PU9_3 @T6G_MB_LIB.T6G(SCH_1):NC_PU9_3
   PU9    6    GL1 NCP3284AMNTXG-NCP3284AMNTXG,SMLF,IC,AL003284002    I21 @T6G_MB_LIB.T6G(SCH_1):PAGE245

NC_PU9_4 @T6G_MB_LIB.T6G(SCH_1):NC_PU9_4
   PU9   37    GL2 NCP3284AMNTXG-NCP3284AMNTXG,SMLF,IC,AL003284002    I21 @T6G_MB_LIB.T6G(SCH_1):PAGE245

NC_PV09_RETIMER_CPU0_DNC1 @T6G_MB_LIB.T6G(SCH_1):NC_PV09_RETIMER_CPU0_DNC1
PU6503   31    DNC ISL99390FRZTR5935-ISL99390FRZ-TR5935,SMLF,IC,AL099A    I53 @T6G_MB_LIB.T6G(SCH_1):PAGE476

NC_PV09_RETIMER_CPU0_DNC2 @T6G_MB_LIB.T6G(SCH_1):NC_PV09_RETIMER_CPU0_DNC2
PU6504   31    DNC ISL99390FRZTR5935-ISL99390FRZ-TR5935,SMLF,IC,AL099A   I270 @T6G_MB_LIB.T6G(SCH_1):PAGE476

NC_PV09_RETIMER_CPU0_GL1_1 @T6G_MB_LIB.T6G(SCH_1):NC_PV09_RETIMER_CPU0_GL1_1
PU6503    6    GL1 ISL99390FRZTR5935-ISL99390FRZ-TR5935,SMLF,IC,AL099A    I53 @T6G_MB_LIB.T6G(SCH_1):PAGE476

NC_PV09_RETIMER_CPU0_GL1_2 @T6G_MB_LIB.T6G(SCH_1):NC_PV09_RETIMER_CPU0_GL1_2
PU6504    6    GL1 ISL99390FRZTR5935-ISL99390FRZ-TR5935,SMLF,IC,AL099A   I270 @T6G_MB_LIB.T6G(SCH_1):PAGE476

NC_PV09_RETIMER_CPU0_GL2_1 @T6G_MB_LIB.T6G(SCH_1):NC_PV09_RETIMER_CPU0_GL2_1
PU6503   41    GL2 ISL99390FRZTR5935-ISL99390FRZ-TR5935,SMLF,IC,AL099A    I53 @T6G_MB_LIB.T6G(SCH_1):PAGE476

NC_PV09_RETIMER_CPU0_GL2_2 @T6G_MB_LIB.T6G(SCH_1):NC_PV09_RETIMER_CPU0_GL2_2
PU6504   41    GL2 ISL99390FRZTR5935-ISL99390FRZ-TR5935,SMLF,IC,AL099A   I270 @T6G_MB_LIB.T6G(SCH_1):PAGE476

NC_PV09_RETIMER_CPU1_DNC1 @T6G_MB_LIB.T6G(SCH_1):NC_PV09_RETIMER_CPU1_DNC1
PU6511   31    DNC ISL99390FRZTR5935-ISL99390FRZ-TR5935,SMLF,IC,AL099A    I51 @T6G_MB_LIB.T6G(SCH_1):PAGE478

NC_PV09_RETIMER_CPU1_DNC2 @T6G_MB_LIB.T6G(SCH_1):NC_PV09_RETIMER_CPU1_DNC2
PU6512   31    DNC ISL99390FRZTR5935-ISL99390FRZ-TR5935,SMLF,IC,AL099A    I12 @T6G_MB_LIB.T6G(SCH_1):PAGE478

NC_PV09_RETIMER_CPU1_GL1_1 @T6G_MB_LIB.T6G(SCH_1):NC_PV09_RETIMER_CPU1_GL1_1
PU6511    6    GL1 ISL99390FRZTR5935-ISL99390FRZ-TR5935,SMLF,IC,AL099A    I51 @T6G_MB_LIB.T6G(SCH_1):PAGE478

NC_PV09_RETIMER_CPU1_GL1_2 @T6G_MB_LIB.T6G(SCH_1):NC_PV09_RETIMER_CPU1_GL1_2
PU6512    6    GL1 ISL99390FRZTR5935-ISL99390FRZ-TR5935,SMLF,IC,AL099A    I12 @T6G_MB_LIB.T6G(SCH_1):PAGE478

NC_PV09_RETIMER_CPU1_GL2_1 @T6G_MB_LIB.T6G(SCH_1):NC_PV09_RETIMER_CPU1_GL2_1
PU6511   41    GL2 ISL99390FRZTR5935-ISL99390FRZ-TR5935,SMLF,IC,AL099A    I51 @T6G_MB_LIB.T6G(SCH_1):PAGE478

NC_PV09_RETIMER_CPU1_GL2_2 @T6G_MB_LIB.T6G(SCH_1):NC_PV09_RETIMER_CPU1_GL2_2
PU6512   41    GL2 ISL99390FRZTR5935-ISL99390FRZ-TR5935,SMLF,IC,AL099A    I12 @T6G_MB_LIB.T6G(SCH_1):PAGE478

NC_PVDD11_S3_P0_DNC1 @T6G_MB_LIB.T6G(SCH_1):NC_PVDD11_S3_P0_DNC1
  PU22   31    DNC ISL99390FRZTR5935-ISL99390FRZ-TR5935,SMLF,IC,AL099A    I92 @T6G_MB_LIB.T6G(SCH_1):PAGE183

NC_PVDD11_S3_P0_DNC2 @T6G_MB_LIB.T6G(SCH_1):NC_PVDD11_S3_P0_DNC2
  PU23   31    DNC ISL99390FRZTR5935-ISL99390FRZ-TR5935,SMLF,IC,AL099A    I13 @T6G_MB_LIB.T6G(SCH_1):PAGE183

NC_PVDD11_S3_P0_GL1_1 @T6G_MB_LIB.T6G(SCH_1):NC_PVDD11_S3_P0_GL1_1
  PU22    6    GL1 ISL99390FRZTR5935-ISL99390FRZ-TR5935,SMLF,IC,AL099A    I92 @T6G_MB_LIB.T6G(SCH_1):PAGE183

NC_PVDD11_S3_P0_GL1_2 @T6G_MB_LIB.T6G(SCH_1):NC_PVDD11_S3_P0_GL1_2
  PU23    6    GL1 ISL99390FRZTR5935-ISL99390FRZ-TR5935,SMLF,IC,AL099A    I13 @T6G_MB_LIB.T6G(SCH_1):PAGE183

NC_PVDD11_S3_P0_GL2_1 @T6G_MB_LIB.T6G(SCH_1):NC_PVDD11_S3_P0_GL2_1
  PU22   41    GL2 ISL99390FRZTR5935-ISL99390FRZ-TR5935,SMLF,IC,AL099A    I92 @T6G_MB_LIB.T6G(SCH_1):PAGE183

NC_PVDD11_S3_P0_GL2_2 @T6G_MB_LIB.T6G(SCH_1):NC_PVDD11_S3_P0_GL2_2
  PU23   41    GL2 ISL99390FRZTR5935-ISL99390FRZ-TR5935,SMLF,IC,AL099A    I13 @T6G_MB_LIB.T6G(SCH_1):PAGE183

NC_PVDD11_S3_P0_IMON3 @T6G_MB_LIB.T6G(SCH_1):NC_PVDD11_S3_P0_IMON3
  PU21   25    CS5 RAA229621GNPHA0-RAA229621GNP#HA0,SMLF,IC,ARF0TGP40A    I24 @T6G_MB_LIB.T6G(SCH_1):PAGE182
  PR37    1      A Q_RES_0402LF-0,5%,1/16W,CHIP,CS00002JB13    I71 @T6G_MB_LIB.T6G(SCH_1):PAGE182

NC_PVDD11_S3_P0_IMON4 @T6G_MB_LIB.T6G(SCH_1):NC_PVDD11_S3_P0_IMON4
  PU21   26    CS4 RAA229621GNPHA0-RAA229621GNP#HA0,SMLF,IC,ARF0TGP40A    I24 @T6G_MB_LIB.T6G(SCH_1):PAGE182
  PR33    1      A Q_RES_0402LF-0,5%,1/16W,CHIP,CS00002JB13    I61 @T6G_MB_LIB.T6G(SCH_1):PAGE182

NC_PVDD11_S3_P0_IMON5 @T6G_MB_LIB.T6G(SCH_1):NC_PVDD11_S3_P0_IMON5
  PU21   27    CS3 RAA229621GNPHA0-RAA229621GNP#HA0,SMLF,IC,ARF0TGP40A    I24 @T6G_MB_LIB.T6G(SCH_1):PAGE182
  PR34    1      A Q_RES_0402LF-0,5%,1/16W,CHIP,CS00002JB13    I60 @T6G_MB_LIB.T6G(SCH_1):PAGE182

NC_PVDD11_S3_P0_IMON6 @T6G_MB_LIB.T6G(SCH_1):NC_PVDD11_S3_P0_IMON6
  PU21   28    CS2 RAA229621GNPHA0-RAA229621GNP#HA0,SMLF,IC,ARF0TGP40A    I24 @T6G_MB_LIB.T6G(SCH_1):PAGE182
  PR35    1      A Q_RES_0402LF-0,5%,1/16W,CHIP,CS00002JB13    I59 @T6G_MB_LIB.T6G(SCH_1):PAGE182

NC_PVDD11_S3_P0_IMON7 @T6G_MB_LIB.T6G(SCH_1):NC_PVDD11_S3_P0_IMON7
  PU21   29    CS1 RAA229621GNPHA0-RAA229621GNP#HA0,SMLF,IC,ARF0TGP40A    I24 @T6G_MB_LIB.T6G(SCH_1):PAGE182
 PR419    1      A Q_RES_0402LF-0,5%,1/16W,CHIP,CS00002JB13    I58 @T6G_MB_LIB.T6G(SCH_1):PAGE182

NC_PVDD11_S3_P0_IMON8 @T6G_MB_LIB.T6G(SCH_1):NC_PVDD11_S3_P0_IMON8
  PU21   30    CS0 RAA229621GNPHA0-RAA229621GNP#HA0,SMLF,IC,ARF0TGP40A    I24 @T6G_MB_LIB.T6G(SCH_1):PAGE182
  PR36    1      A Q_RES_0402LF-0,5%,1/16W,CHIP,CS00002JB13    I53 @T6G_MB_LIB.T6G(SCH_1):PAGE182

NC_PVDD11_S3_P0_PG1 @T6G_MB_LIB.T6G(SCH_1):NC_PVDD11_S3_P0_PG1
  PU21   16    PG1 RAA229621GNPHA0-RAA229621GNP#HA0,SMLF,IC,ARF0TGP40A    I24 @T6G_MB_LIB.T6G(SCH_1):PAGE182

NC_PVDD11_S3_P0_PWM3 @T6G_MB_LIB.T6G(SCH_1):NC_PVDD11_S3_P0_PWM3
  PU21    6   PWM5 RAA229621GNPHA0-RAA229621GNP#HA0,SMLF,IC,ARF0TGP40A    I24 @T6G_MB_LIB.T6G(SCH_1):PAGE182

NC_PVDD11_S3_P0_PWM4 @T6G_MB_LIB.T6G(SCH_1):NC_PVDD11_S3_P0_PWM4
  PU21    5   PWM4 RAA229621GNPHA0-RAA229621GNP#HA0,SMLF,IC,ARF0TGP40A    I24 @T6G_MB_LIB.T6G(SCH_1):PAGE182

NC_PVDD11_S3_P0_PWM5 @T6G_MB_LIB.T6G(SCH_1):NC_PVDD11_S3_P0_PWM5
  PU21    4   PWM3 RAA229621GNPHA0-RAA229621GNP#HA0,SMLF,IC,ARF0TGP40A    I24 @T6G_MB_LIB.T6G(SCH_1):PAGE182

NC_PVDD11_S3_P0_PWM6 @T6G_MB_LIB.T6G(SCH_1):NC_PVDD11_S3_P0_PWM6
  PU21    3   PWM2 RAA229621GNPHA0-RAA229621GNP#HA0,SMLF,IC,ARF0TGP40A    I24 @T6G_MB_LIB.T6G(SCH_1):PAGE182

NC_PVDD11_S3_P0_PWM7 @T6G_MB_LIB.T6G(SCH_1):NC_PVDD11_S3_P0_PWM7
  PU21    2   PWM1 RAA229621GNPHA0-RAA229621GNP#HA0,SMLF,IC,ARF0TGP40A    I24 @T6G_MB_LIB.T6G(SCH_1):PAGE182

NC_PVDD11_S3_P0_PWM8 @T6G_MB_LIB.T6G(SCH_1):NC_PVDD11_S3_P0_PWM8
  PU21    1   PWM0 RAA229621GNPHA0-RAA229621GNP#HA0,SMLF,IC,ARF0TGP40A    I24 @T6G_MB_LIB.T6G(SCH_1):PAGE182

NC_PVDD11_S3_P0_SVTO @T6G_MB_LIB.T6G(SCH_1):NC_PVDD11_S3_P0_SVTO
  PU21   19   SVTO RAA229621GNPHA0-RAA229621GNP#HA0,SMLF,IC,ARF0TGP40A    I24 @T6G_MB_LIB.T6G(SCH_1):PAGE182

NC_PVDD11_S3_P1_DNC1 @T6G_MB_LIB.T6G(SCH_1):NC_PVDD11_S3_P1_DNC1
  PU44   31    DNC ISL99390FRZTR5935-ISL99390FRZ-TR5935,SMLF,IC,AL099A    I22 @T6G_MB_LIB.T6G(SCH_1):PAGE200

NC_PVDD11_S3_P1_DNC2 @T6G_MB_LIB.T6G(SCH_1):NC_PVDD11_S3_P1_DNC2
  PU45   31    DNC ISL99390FRZTR5935-ISL99390FRZ-TR5935,SMLF,IC,AL099A    I92 @T6G_MB_LIB.T6G(SCH_1):PAGE200

NC_PVDD11_S3_P1_GL1_1 @T6G_MB_LIB.T6G(SCH_1):NC_PVDD11_S3_P1_GL1_1
  PU44    6    GL1 ISL99390FRZTR5935-ISL99390FRZ-TR5935,SMLF,IC,AL099A    I22 @T6G_MB_LIB.T6G(SCH_1):PAGE200

NC_PVDD11_S3_P1_GL1_2 @T6G_MB_LIB.T6G(SCH_1):NC_PVDD11_S3_P1_GL1_2
  PU45    6    GL1 ISL99390FRZTR5935-ISL99390FRZ-TR5935,SMLF,IC,AL099A    I92 @T6G_MB_LIB.T6G(SCH_1):PAGE200

NC_PVDD11_S3_P1_GL2_1 @T6G_MB_LIB.T6G(SCH_1):NC_PVDD11_S3_P1_GL2_1
  PU44   41    GL2 ISL99390FRZTR5935-ISL99390FRZ-TR5935,SMLF,IC,AL099A    I22 @T6G_MB_LIB.T6G(SCH_1):PAGE200

NC_PVDD11_S3_P1_GL2_2 @T6G_MB_LIB.T6G(SCH_1):NC_PVDD11_S3_P1_GL2_2
  PU45   41    GL2 ISL99390FRZTR5935-ISL99390FRZ-TR5935,SMLF,IC,AL099A    I92 @T6G_MB_LIB.T6G(SCH_1):PAGE200

NC_PVDD11_S3_P1_IMON3 @T6G_MB_LIB.T6G(SCH_1):NC_PVDD11_S3_P1_IMON3
 PR406    1      A Q_RES_0402LF-0,5%,1/16W,CHIP,CS00002JB13    I70 @T6G_MB_LIB.T6G(SCH_1):PAGE199
  PU54   25    CS5 RAA229621GNPHA0-RAA229621GNP#HA0,SMLF,IC,ARF0TGP40A    I86 @T6G_MB_LIB.T6G(SCH_1):PAGE199

NC_PVDD11_S3_P1_IMON4 @T6G_MB_LIB.T6G(SCH_1):NC_PVDD11_S3_P1_IMON4
 PR407    1      A Q_RES_0402LF-0,5%,1/16W,CHIP,CS00002JB13    I60 @T6G_MB_LIB.T6G(SCH_1):PAGE199
  PU54   26    CS4 RAA229621GNPHA0-RAA229621GNP#HA0,SMLF,IC,ARF0TGP40A    I86 @T6G_MB_LIB.T6G(SCH_1):PAGE199

NC_PVDD11_S3_P1_IMON5 @T6G_MB_LIB.T6G(SCH_1):NC_PVDD11_S3_P1_IMON5
  PR13    1      A Q_RES_0402LF-0,5%,1/16W,CHIP,CS00002JB13    I59 @T6G_MB_LIB.T6G(SCH_1):PAGE199
  PU54   27    CS3 RAA229621GNPHA0-RAA229621GNP#HA0,SMLF,IC,ARF0TGP40A    I86 @T6G_MB_LIB.T6G(SCH_1):PAGE199

NC_PVDD11_S3_P1_IMON6 @T6G_MB_LIB.T6G(SCH_1):NC_PVDD11_S3_P1_IMON6
  PR14    1      A Q_RES_0402LF-0,5%,1/16W,CHIP,CS00002JB13    I58 @T6G_MB_LIB.T6G(SCH_1):PAGE199
  PU54   28    CS2 RAA229621GNPHA0-RAA229621GNP#HA0,SMLF,IC,ARF0TGP40A    I86 @T6G_MB_LIB.T6G(SCH_1):PAGE199

NC_PVDD11_S3_P1_IMON7 @T6G_MB_LIB.T6G(SCH_1):NC_PVDD11_S3_P1_IMON7
 PR408    1      A Q_RES_0402LF-0,5%,1/16W,CHIP,CS00002JB13    I57 @T6G_MB_LIB.T6G(SCH_1):PAGE199
  PU54   29    CS1 RAA229621GNPHA0-RAA229621GNP#HA0,SMLF,IC,ARF0TGP40A    I86 @T6G_MB_LIB.T6G(SCH_1):PAGE199

NC_PVDD11_S3_P1_IMON8 @T6G_MB_LIB.T6G(SCH_1):NC_PVDD11_S3_P1_IMON8
 PR409    1      A Q_RES_0402LF-0,5%,1/16W,CHIP,CS00002JB13    I52 @T6G_MB_LIB.T6G(SCH_1):PAGE199
  PU54   30    CS0 RAA229621GNPHA0-RAA229621GNP#HA0,SMLF,IC,ARF0TGP40A    I86 @T6G_MB_LIB.T6G(SCH_1):PAGE199

NC_PVDD11_S3_P1_PG1 @T6G_MB_LIB.T6G(SCH_1):NC_PVDD11_S3_P1_PG1
  PU54   16    PG1 RAA229621GNPHA0-RAA229621GNP#HA0,SMLF,IC,ARF0TGP40A    I86 @T6G_MB_LIB.T6G(SCH_1):PAGE199

NC_PVDD11_S3_P1_PWM3 @T6G_MB_LIB.T6G(SCH_1):NC_PVDD11_S3_P1_PWM3
  PU54    6   PWM5 RAA229621GNPHA0-RAA229621GNP#HA0,SMLF,IC,ARF0TGP40A    I86 @T6G_MB_LIB.T6G(SCH_1):PAGE199

NC_PVDD11_S3_P1_PWM4 @T6G_MB_LIB.T6G(SCH_1):NC_PVDD11_S3_P1_PWM4
  PU54    5   PWM4 RAA229621GNPHA0-RAA229621GNP#HA0,SMLF,IC,ARF0TGP40A    I86 @T6G_MB_LIB.T6G(SCH_1):PAGE199

NC_PVDD11_S3_P1_PWM5 @T6G_MB_LIB.T6G(SCH_1):NC_PVDD11_S3_P1_PWM5
  PU54    4   PWM3 RAA229621GNPHA0-RAA229621GNP#HA0,SMLF,IC,ARF0TGP40A    I86 @T6G_MB_LIB.T6G(SCH_1):PAGE199

NC_PVDD11_S3_P1_PWM6 @T6G_MB_LIB.T6G(SCH_1):NC_PVDD11_S3_P1_PWM6
  PU54    3   PWM2 RAA229621GNPHA0-RAA229621GNP#HA0,SMLF,IC,ARF0TGP40A    I86 @T6G_MB_LIB.T6G(SCH_1):PAGE199

NC_PVDD11_S3_P1_PWM7 @T6G_MB_LIB.T6G(SCH_1):NC_PVDD11_S3_P1_PWM7
  PU54    2   PWM1 RAA229621GNPHA0-RAA229621GNP#HA0,SMLF,IC,ARF0TGP40A    I86 @T6G_MB_LIB.T6G(SCH_1):PAGE199

NC_PVDD11_S3_P1_PWM8 @T6G_MB_LIB.T6G(SCH_1):NC_PVDD11_S3_P1_PWM8
  PU54    1   PWM0 RAA229621GNPHA0-RAA229621GNP#HA0,SMLF,IC,ARF0TGP40A    I86 @T6G_MB_LIB.T6G(SCH_1):PAGE199

NC_PVDD11_S3_P1_SVTO @T6G_MB_LIB.T6G(SCH_1):NC_PVDD11_S3_P1_SVTO
  PU54   19   SVTO RAA229621GNPHA0-RAA229621GNP#HA0,SMLF,IC,ARF0TGP40A    I86 @T6G_MB_LIB.T6G(SCH_1):PAGE199

NC_PVDDCR_CPU0_P0_DNC1 @T6G_MB_LIB.T6G(SCH_1):NC_PVDDCR_CPU0_P0_DNC1
   PU6   31    DNC ISL99390FRZTR5935-ISL99390FRZ-TR5935,SMLF,IC,AL099A    I26 @T6G_MB_LIB.T6G(SCH_1):PAGE169

NC_PVDDCR_CPU0_P0_DNC2 @T6G_MB_LIB.T6G(SCH_1):NC_PVDDCR_CPU0_P0_DNC2
  PU43   31    DNC ISL99390FRZTR5935-ISL99390FRZ-TR5935,SMLF,IC,AL099A    I16 @T6G_MB_LIB.T6G(SCH_1):PAGE169

NC_PVDDCR_CPU0_P0_DNC3 @T6G_MB_LIB.T6G(SCH_1):NC_PVDDCR_CPU0_P0_DNC3
  PU46   31    DNC ISL99390FRZTR5935-ISL99390FRZ-TR5935,SMLF,IC,AL099A    I38 @T6G_MB_LIB.T6G(SCH_1):PAGE170

NC_PVDDCR_CPU0_P0_DNC4 @T6G_MB_LIB.T6G(SCH_1):NC_PVDDCR_CPU0_P0_DNC4
  PU47   31    DNC ISL99390FRZTR5935-ISL99390FRZ-TR5935,SMLF,IC,AL099A     I9 @T6G_MB_LIB.T6G(SCH_1):PAGE170

NC_PVDDCR_CPU0_P0_DNC5 @T6G_MB_LIB.T6G(SCH_1):NC_PVDDCR_CPU0_P0_DNC5
  PU48   31    DNC ISL99390FRZTR5935-ISL99390FRZ-TR5935,SMLF,IC,AL099A    I18 @T6G_MB_LIB.T6G(SCH_1):PAGE171

NC_PVDDCR_CPU0_P0_DNC6 @T6G_MB_LIB.T6G(SCH_1):NC_PVDDCR_CPU0_P0_DNC6
  PU10   31    DNC ISL99390FRZTR5935-ISL99390FRZ-TR5935,SMLF,IC,AL099A    I73 @T6G_MB_LIB.T6G(SCH_1):PAGE171

NC_PVDDCR_CPU0_P0_GL1_1 @T6G_MB_LIB.T6G(SCH_1):NC_PVDDCR_CPU0_P0_GL1_1
   PU6    6    GL1 ISL99390FRZTR5935-ISL99390FRZ-TR5935,SMLF,IC,AL099A    I26 @T6G_MB_LIB.T6G(SCH_1):PAGE169

NC_PVDDCR_CPU0_P0_GL1_2 @T6G_MB_LIB.T6G(SCH_1):NC_PVDDCR_CPU0_P0_GL1_2
  PU43    6    GL1 ISL99390FRZTR5935-ISL99390FRZ-TR5935,SMLF,IC,AL099A    I16 @T6G_MB_LIB.T6G(SCH_1):PAGE169

NC_PVDDCR_CPU0_P0_GL1_3 @T6G_MB_LIB.T6G(SCH_1):NC_PVDDCR_CPU0_P0_GL1_3
  PU46    6    GL1 ISL99390FRZTR5935-ISL99390FRZ-TR5935,SMLF,IC,AL099A    I38 @T6G_MB_LIB.T6G(SCH_1):PAGE170

NC_PVDDCR_CPU0_P0_GL1_4 @T6G_MB_LIB.T6G(SCH_1):NC_PVDDCR_CPU0_P0_GL1_4
  PU47    6    GL1 ISL99390FRZTR5935-ISL99390FRZ-TR5935,SMLF,IC,AL099A     I9 @T6G_MB_LIB.T6G(SCH_1):PAGE170

NC_PVDDCR_CPU0_P0_GL1_5 @T6G_MB_LIB.T6G(SCH_1):NC_PVDDCR_CPU0_P0_GL1_5
  PU48    6    GL1 ISL99390FRZTR5935-ISL99390FRZ-TR5935,SMLF,IC,AL099A    I18 @T6G_MB_LIB.T6G(SCH_1):PAGE171

NC_PVDDCR_CPU0_P0_GL1_6 @T6G_MB_LIB.T6G(SCH_1):NC_PVDDCR_CPU0_P0_GL1_6
  PU10    6    GL1 ISL99390FRZTR5935-ISL99390FRZ-TR5935,SMLF,IC,AL099A    I73 @T6G_MB_LIB.T6G(SCH_1):PAGE171

NC_PVDDCR_CPU0_P0_GL2_1 @T6G_MB_LIB.T6G(SCH_1):NC_PVDDCR_CPU0_P0_GL2_1
   PU6   41    GL2 ISL99390FRZTR5935-ISL99390FRZ-TR5935,SMLF,IC,AL099A    I26 @T6G_MB_LIB.T6G(SCH_1):PAGE169

NC_PVDDCR_CPU0_P0_GL2_2 @T6G_MB_LIB.T6G(SCH_1):NC_PVDDCR_CPU0_P0_GL2_2
  PU43   41    GL2 ISL99390FRZTR5935-ISL99390FRZ-TR5935,SMLF,IC,AL099A    I16 @T6G_MB_LIB.T6G(SCH_1):PAGE169

NC_PVDDCR_CPU0_P0_GL2_3 @T6G_MB_LIB.T6G(SCH_1):NC_PVDDCR_CPU0_P0_GL2_3
  PU46   41    GL2 ISL99390FRZTR5935-ISL99390FRZ-TR5935,SMLF,IC,AL099A    I38 @T6G_MB_LIB.T6G(SCH_1):PAGE170

NC_PVDDCR_CPU0_P0_GL2_4 @T6G_MB_LIB.T6G(SCH_1):NC_PVDDCR_CPU0_P0_GL2_4
  PU47   41    GL2 ISL99390FRZTR5935-ISL99390FRZ-TR5935,SMLF,IC,AL099A     I9 @T6G_MB_LIB.T6G(SCH_1):PAGE170

NC_PVDDCR_CPU0_P0_GL2_5 @T6G_MB_LIB.T6G(SCH_1):NC_PVDDCR_CPU0_P0_GL2_5
  PU48   41    GL2 ISL99390FRZTR5935-ISL99390FRZ-TR5935,SMLF,IC,AL099A    I18 @T6G_MB_LIB.T6G(SCH_1):PAGE171

NC_PVDDCR_CPU0_P0_GL2_6 @T6G_MB_LIB.T6G(SCH_1):NC_PVDDCR_CPU0_P0_GL2_6
  PU10   41    GL2 ISL99390FRZTR5935-ISL99390FRZ-TR5935,SMLF,IC,AL099A    I73 @T6G_MB_LIB.T6G(SCH_1):PAGE171

NC_PVDDCR_CPU0_P0_IMON7 @T6G_MB_LIB.T6G(SCH_1):NC_PVDDCR_CPU0_P0_IMON7
 PR531    1      A Q_RES_0402LF-0,5%,1/16W,CHIP,CS00002JB13   I111 @T6G_MB_LIB.T6G(SCH_1):PAGE168
  PU42   33    CS5 RAA229620GNPHA0-RAA229620GNP#HA0,SMLF,IC,ARF0TGP40A   I135 @T6G_MB_LIB.T6G(SCH_1):PAGE168

NC_PVDDCR_CPU0_P0_IMON8 @T6G_MB_LIB.T6G(SCH_1):NC_PVDDCR_CPU0_P0_IMON8
 PR440    1      A Q_RES_0402LF-0,5%,1/16W,CHIP,CS00002JB13   I108 @T6G_MB_LIB.T6G(SCH_1):PAGE168
  PU42   34    CS4 RAA229620GNPHA0-RAA229620GNP#HA0,SMLF,IC,ARF0TGP40A   I135 @T6G_MB_LIB.T6G(SCH_1):PAGE168

NC_PVDDCR_CPU0_P0_IMON9 @T6G_MB_LIB.T6G(SCH_1):NC_PVDDCR_CPU0_P0_IMON9
 PR441    1      A Q_RES_0402LF-0,5%,1/16W,CHIP,CS00002JB13   I107 @T6G_MB_LIB.T6G(SCH_1):PAGE168
  PU42   35    CS3 RAA229620GNPHA0-RAA229620GNP#HA0,SMLF,IC,ARF0TGP40A   I135 @T6G_MB_LIB.T6G(SCH_1):PAGE168

NC_PVDDCR_CPU0_P0_PWM7 @T6G_MB_LIB.T6G(SCH_1):NC_PVDDCR_CPU0_P0_PWM7
  PU42    6   PWM5 RAA229620GNPHA0-RAA229620GNP#HA0,SMLF,IC,ARF0TGP40A   I135 @T6G_MB_LIB.T6G(SCH_1):PAGE168

NC_PVDDCR_CPU0_P0_PWM8 @T6G_MB_LIB.T6G(SCH_1):NC_PVDDCR_CPU0_P0_PWM8
  PU42    5   PWM4 RAA229620GNPHA0-RAA229620GNP#HA0,SMLF,IC,ARF0TGP40A   I135 @T6G_MB_LIB.T6G(SCH_1):PAGE168

NC_PVDDCR_CPU0_P0_PWM9 @T6G_MB_LIB.T6G(SCH_1):NC_PVDDCR_CPU0_P0_PWM9
  PU42    4   PWM3 RAA229620GNPHA0-RAA229620GNP#HA0,SMLF,IC,ARF0TGP40A   I135 @T6G_MB_LIB.T6G(SCH_1):PAGE168

NC_PVDDCR_CPU0_P1_DNC1 @T6G_MB_LIB.T6G(SCH_1):NC_PVDDCR_CPU0_P1_DNC1
   PU4   31    DNC ISL99390FRZTR5935-ISL99390FRZ-TR5935,SMLF,IC,AL099A    I88 @T6G_MB_LIB.T6G(SCH_1):PAGE186

NC_PVDDCR_CPU0_P1_DNC2 @T6G_MB_LIB.T6G(SCH_1):NC_PVDDCR_CPU0_P1_DNC2
  PU26   31    DNC ISL99390FRZTR5935-ISL99390FRZ-TR5935,SMLF,IC,AL099A    I91 @T6G_MB_LIB.T6G(SCH_1):PAGE186

NC_PVDDCR_CPU0_P1_DNC3 @T6G_MB_LIB.T6G(SCH_1):NC_PVDDCR_CPU0_P1_DNC3
  PU27   31    DNC ISL99390FRZTR5935-ISL99390FRZ-TR5935,SMLF,IC,AL099A    I39 @T6G_MB_LIB.T6G(SCH_1):PAGE187

NC_PVDDCR_CPU0_P1_DNC4 @T6G_MB_LIB.T6G(SCH_1):NC_PVDDCR_CPU0_P1_DNC4
  PU28   31    DNC ISL99390FRZTR5935-ISL99390FRZ-TR5935,SMLF,IC,AL099A     I9 @T6G_MB_LIB.T6G(SCH_1):PAGE187

NC_PVDDCR_CPU0_P1_DNC5 @T6G_MB_LIB.T6G(SCH_1):NC_PVDDCR_CPU0_P1_DNC5
  PU29   31    DNC ISL99390FRZTR5935-ISL99390FRZ-TR5935,SMLF,IC,AL099A    I18 @T6G_MB_LIB.T6G(SCH_1):PAGE188

NC_PVDDCR_CPU0_P1_DNC6 @T6G_MB_LIB.T6G(SCH_1):NC_PVDDCR_CPU0_P1_DNC6
  PU24   31    DNC ISL99390FRZTR5935-ISL99390FRZ-TR5935,SMLF,IC,AL099A    I73 @T6G_MB_LIB.T6G(SCH_1):PAGE188

NC_PVDDCR_CPU0_P1_GL1_1 @T6G_MB_LIB.T6G(SCH_1):NC_PVDDCR_CPU0_P1_GL1_1
   PU4    6    GL1 ISL99390FRZTR5935-ISL99390FRZ-TR5935,SMLF,IC,AL099A    I88 @T6G_MB_LIB.T6G(SCH_1):PAGE186

NC_PVDDCR_CPU0_P1_GL1_2 @T6G_MB_LIB.T6G(SCH_1):NC_PVDDCR_CPU0_P1_GL1_2
  PU26    6    GL1 ISL99390FRZTR5935-ISL99390FRZ-TR5935,SMLF,IC,AL099A    I91 @T6G_MB_LIB.T6G(SCH_1):PAGE186

NC_PVDDCR_CPU0_P1_GL1_3 @T6G_MB_LIB.T6G(SCH_1):NC_PVDDCR_CPU0_P1_GL1_3
  PU27    6    GL1 ISL99390FRZTR5935-ISL99390FRZ-TR5935,SMLF,IC,AL099A    I39 @T6G_MB_LIB.T6G(SCH_1):PAGE187

NC_PVDDCR_CPU0_P1_GL1_4 @T6G_MB_LIB.T6G(SCH_1):NC_PVDDCR_CPU0_P1_GL1_4
  PU28    6    GL1 ISL99390FRZTR5935-ISL99390FRZ-TR5935,SMLF,IC,AL099A     I9 @T6G_MB_LIB.T6G(SCH_1):PAGE187

NC_PVDDCR_CPU0_P1_GL1_5 @T6G_MB_LIB.T6G(SCH_1):NC_PVDDCR_CPU0_P1_GL1_5
  PU29    6    GL1 ISL99390FRZTR5935-ISL99390FRZ-TR5935,SMLF,IC,AL099A    I18 @T6G_MB_LIB.T6G(SCH_1):PAGE188

NC_PVDDCR_CPU0_P1_GL1_6 @T6G_MB_LIB.T6G(SCH_1):NC_PVDDCR_CPU0_P1_GL1_6
  PU24    6    GL1 ISL99390FRZTR5935-ISL99390FRZ-TR5935,SMLF,IC,AL099A    I73 @T6G_MB_LIB.T6G(SCH_1):PAGE188

NC_PVDDCR_CPU0_P1_GL2_1 @T6G_MB_LIB.T6G(SCH_1):NC_PVDDCR_CPU0_P1_GL2_1
   PU4   41    GL2 ISL99390FRZTR5935-ISL99390FRZ-TR5935,SMLF,IC,AL099A    I88 @T6G_MB_LIB.T6G(SCH_1):PAGE186

NC_PVDDCR_CPU0_P1_GL2_2 @T6G_MB_LIB.T6G(SCH_1):NC_PVDDCR_CPU0_P1_GL2_2
  PU26   41    GL2 ISL99390FRZTR5935-ISL99390FRZ-TR5935,SMLF,IC,AL099A    I91 @T6G_MB_LIB.T6G(SCH_1):PAGE186

NC_PVDDCR_CPU0_P1_GL2_3 @T6G_MB_LIB.T6G(SCH_1):NC_PVDDCR_CPU0_P1_GL2_3
  PU27   41    GL2 ISL99390FRZTR5935-ISL99390FRZ-TR5935,SMLF,IC,AL099A    I39 @T6G_MB_LIB.T6G(SCH_1):PAGE187

NC_PVDDCR_CPU0_P1_GL2_4 @T6G_MB_LIB.T6G(SCH_1):NC_PVDDCR_CPU0_P1_GL2_4
  PU28   41    GL2 ISL99390FRZTR5935-ISL99390FRZ-TR5935,SMLF,IC,AL099A     I9 @T6G_MB_LIB.T6G(SCH_1):PAGE187

NC_PVDDCR_CPU0_P1_GL2_5 @T6G_MB_LIB.T6G(SCH_1):NC_PVDDCR_CPU0_P1_GL2_5
  PU29   41    GL2 ISL99390FRZTR5935-ISL99390FRZ-TR5935,SMLF,IC,AL099A    I18 @T6G_MB_LIB.T6G(SCH_1):PAGE188

NC_PVDDCR_CPU0_P1_GL2_6 @T6G_MB_LIB.T6G(SCH_1):NC_PVDDCR_CPU0_P1_GL2_6
  PU24   41    GL2 ISL99390FRZTR5935-ISL99390FRZ-TR5935,SMLF,IC,AL099A    I73 @T6G_MB_LIB.T6G(SCH_1):PAGE188

NC_PVDDCR_CPU0_P1_IMON7 @T6G_MB_LIB.T6G(SCH_1):NC_PVDDCR_CPU0_P1_IMON7
 PR530    1      A Q_RES_0402LF-0,5%,1/16W,CHIP,CS00002JB13   I107 @T6G_MB_LIB.T6G(SCH_1):PAGE185
  PU25   33    CS5 RAA229620GNPHA0-RAA229620GNP#HA0,SMLF,IC,ARF0TGP40A   I133 @T6G_MB_LIB.T6G(SCH_1):PAGE185

NC_PVDDCR_CPU0_P1_IMON8 @T6G_MB_LIB.T6G(SCH_1):NC_PVDDCR_CPU0_P1_IMON8
 PR436    1      A Q_RES_0402LF-0,5%,1/16W,CHIP,CS00002JB13   I103 @T6G_MB_LIB.T6G(SCH_1):PAGE185
  PU25   34    CS4 RAA229620GNPHA0-RAA229620GNP#HA0,SMLF,IC,ARF0TGP40A   I133 @T6G_MB_LIB.T6G(SCH_1):PAGE185

NC_PVDDCR_CPU0_P1_IMON9 @T6G_MB_LIB.T6G(SCH_1):NC_PVDDCR_CPU0_P1_IMON9
 PR437    1      A Q_RES_0402LF-0,5%,1/16W,CHIP,CS00002JB13   I102 @T6G_MB_LIB.T6G(SCH_1):PAGE185
  PU25   35    CS3 RAA229620GNPHA0-RAA229620GNP#HA0,SMLF,IC,ARF0TGP40A   I133 @T6G_MB_LIB.T6G(SCH_1):PAGE185

NC_PVDDCR_CPU0_P1_PWM7 @T6G_MB_LIB.T6G(SCH_1):NC_PVDDCR_CPU0_P1_PWM7
  PU25    6   PWM5 RAA229620GNPHA0-RAA229620GNP#HA0,SMLF,IC,ARF0TGP40A   I133 @T6G_MB_LIB.T6G(SCH_1):PAGE185

NC_PVDDCR_CPU0_P1_PWM8 @T6G_MB_LIB.T6G(SCH_1):NC_PVDDCR_CPU0_P1_PWM8
  PU25    5   PWM4 RAA229620GNPHA0-RAA229620GNP#HA0,SMLF,IC,ARF0TGP40A   I133 @T6G_MB_LIB.T6G(SCH_1):PAGE185

NC_PVDDCR_CPU0_P1_PWM9 @T6G_MB_LIB.T6G(SCH_1):NC_PVDDCR_CPU0_P1_PWM9
  PU25    4   PWM3 RAA229620GNPHA0-RAA229620GNP#HA0,SMLF,IC,ARF0TGP40A   I133 @T6G_MB_LIB.T6G(SCH_1):PAGE185

NC_PVDDCR_CPU1_P0_DNC1 @T6G_MB_LIB.T6G(SCH_1):NC_PVDDCR_CPU1_P0_DNC1
  PU13   31    DNC ISL99390FRZTR5935-ISL99390FRZ-TR5935,SMLF,IC,AL099A    I35 @T6G_MB_LIB.T6G(SCH_1):PAGE176

NC_PVDDCR_CPU1_P0_DNC2 @T6G_MB_LIB.T6G(SCH_1):NC_PVDDCR_CPU1_P0_DNC2
   PU2   31    DNC ISL99390FRZTR5935-ISL99390FRZ-TR5935,SMLF,IC,AL099A    I33 @T6G_MB_LIB.T6G(SCH_1):PAGE176

NC_PVDDCR_CPU1_P0_DNC3 @T6G_MB_LIB.T6G(SCH_1):NC_PVDDCR_CPU1_P0_DNC3
  PU15   31    DNC ISL99390FRZTR5935-ISL99390FRZ-TR5935,SMLF,IC,AL099A    I23 @T6G_MB_LIB.T6G(SCH_1):PAGE177

NC_PVDDCR_CPU1_P0_DNC4 @T6G_MB_LIB.T6G(SCH_1):NC_PVDDCR_CPU1_P0_DNC4
  PU14   31    DNC ISL99390FRZTR5935-ISL99390FRZ-TR5935,SMLF,IC,AL099A    I21 @T6G_MB_LIB.T6G(SCH_1):PAGE177

NC_PVDDCR_CPU1_P0_DNC5 @T6G_MB_LIB.T6G(SCH_1):NC_PVDDCR_CPU1_P0_DNC5
  PU16   31    DNC ISL99390FRZTR5935-ISL99390FRZ-TR5935,SMLF,IC,AL099A    I22 @T6G_MB_LIB.T6G(SCH_1):PAGE178

NC_PVDDCR_CPU1_P0_DNC6 @T6G_MB_LIB.T6G(SCH_1):NC_PVDDCR_CPU1_P0_DNC6
  PU11   31    DNC ISL99390FRZTR5935-ISL99390FRZ-TR5935,SMLF,IC,AL099A    I73 @T6G_MB_LIB.T6G(SCH_1):PAGE178

NC_PVDDCR_CPU1_P0_GL1_1 @T6G_MB_LIB.T6G(SCH_1):NC_PVDDCR_CPU1_P0_GL1_1
  PU13    6    GL1 ISL99390FRZTR5935-ISL99390FRZ-TR5935,SMLF,IC,AL099A    I35 @T6G_MB_LIB.T6G(SCH_1):PAGE176

NC_PVDDCR_CPU1_P0_GL1_2 @T6G_MB_LIB.T6G(SCH_1):NC_PVDDCR_CPU1_P0_GL1_2
   PU2    6    GL1 ISL99390FRZTR5935-ISL99390FRZ-TR5935,SMLF,IC,AL099A    I33 @T6G_MB_LIB.T6G(SCH_1):PAGE176

NC_PVDDCR_CPU1_P0_GL1_3 @T6G_MB_LIB.T6G(SCH_1):NC_PVDDCR_CPU1_P0_GL1_3
  PU15    6    GL1 ISL99390FRZTR5935-ISL99390FRZ-TR5935,SMLF,IC,AL099A    I23 @T6G_MB_LIB.T6G(SCH_1):PAGE177

NC_PVDDCR_CPU1_P0_GL1_4 @T6G_MB_LIB.T6G(SCH_1):NC_PVDDCR_CPU1_P0_GL1_4
  PU14    6    GL1 ISL99390FRZTR5935-ISL99390FRZ-TR5935,SMLF,IC,AL099A    I21 @T6G_MB_LIB.T6G(SCH_1):PAGE177

NC_PVDDCR_CPU1_P0_GL1_5 @T6G_MB_LIB.T6G(SCH_1):NC_PVDDCR_CPU1_P0_GL1_5
  PU16    6    GL1 ISL99390FRZTR5935-ISL99390FRZ-TR5935,SMLF,IC,AL099A    I22 @T6G_MB_LIB.T6G(SCH_1):PAGE178

NC_PVDDCR_CPU1_P0_GL1_6 @T6G_MB_LIB.T6G(SCH_1):NC_PVDDCR_CPU1_P0_GL1_6
  PU11    6    GL1 ISL99390FRZTR5935-ISL99390FRZ-TR5935,SMLF,IC,AL099A    I73 @T6G_MB_LIB.T6G(SCH_1):PAGE178

NC_PVDDCR_CPU1_P0_GL2_1 @T6G_MB_LIB.T6G(SCH_1):NC_PVDDCR_CPU1_P0_GL2_1
  PU13   41    GL2 ISL99390FRZTR5935-ISL99390FRZ-TR5935,SMLF,IC,AL099A    I35 @T6G_MB_LIB.T6G(SCH_1):PAGE176

NC_PVDDCR_CPU1_P0_GL2_2 @T6G_MB_LIB.T6G(SCH_1):NC_PVDDCR_CPU1_P0_GL2_2
   PU2   41    GL2 ISL99390FRZTR5935-ISL99390FRZ-TR5935,SMLF,IC,AL099A    I33 @T6G_MB_LIB.T6G(SCH_1):PAGE176

NC_PVDDCR_CPU1_P0_GL2_3 @T6G_MB_LIB.T6G(SCH_1):NC_PVDDCR_CPU1_P0_GL2_3
  PU15   41    GL2 ISL99390FRZTR5935-ISL99390FRZ-TR5935,SMLF,IC,AL099A    I23 @T6G_MB_LIB.T6G(SCH_1):PAGE177

NC_PVDDCR_CPU1_P0_GL2_4 @T6G_MB_LIB.T6G(SCH_1):NC_PVDDCR_CPU1_P0_GL2_4
  PU14   41    GL2 ISL99390FRZTR5935-ISL99390FRZ-TR5935,SMLF,IC,AL099A    I21 @T6G_MB_LIB.T6G(SCH_1):PAGE177

NC_PVDDCR_CPU1_P0_GL2_5 @T6G_MB_LIB.T6G(SCH_1):NC_PVDDCR_CPU1_P0_GL2_5
  PU16   41    GL2 ISL99390FRZTR5935-ISL99390FRZ-TR5935,SMLF,IC,AL099A    I22 @T6G_MB_LIB.T6G(SCH_1):PAGE178

NC_PVDDCR_CPU1_P0_GL2_6 @T6G_MB_LIB.T6G(SCH_1):NC_PVDDCR_CPU1_P0_GL2_6
  PU11   41    GL2 ISL99390FRZTR5935-ISL99390FRZ-TR5935,SMLF,IC,AL099A    I73 @T6G_MB_LIB.T6G(SCH_1):PAGE178

NC_PVDDCR_CPU1_P0_IMON7 @T6G_MB_LIB.T6G(SCH_1):NC_PVDDCR_CPU1_P0_IMON7
 PR532    1      A Q_RES_0402LF-0,5%,1/16W,CHIP,CS00002JB13    I76 @T6G_MB_LIB.T6G(SCH_1):PAGE175
  PU12   33    CS5 RAA229620GNPHA0-RAA229620GNP#HA0,SMLF,IC,ARF0TGP40A   I128 @T6G_MB_LIB.T6G(SCH_1):PAGE175

NC_PVDDCR_CPU1_P0_IMON8 @T6G_MB_LIB.T6G(SCH_1):NC_PVDDCR_CPU1_P0_IMON8
  PR32    1      A Q_RES_0402LF-0,5%,1/16W,CHIP,CS00002JB13    I77 @T6G_MB_LIB.T6G(SCH_1):PAGE175
  PU12   34    CS4 RAA229620GNPHA0-RAA229620GNP#HA0,SMLF,IC,ARF0TGP40A   I128 @T6G_MB_LIB.T6G(SCH_1):PAGE175

NC_PVDDCR_CPU1_P0_PWM7 @T6G_MB_LIB.T6G(SCH_1):NC_PVDDCR_CPU1_P0_PWM7
  PU12    6   PWM5 RAA229620GNPHA0-RAA229620GNP#HA0,SMLF,IC,ARF0TGP40A   I128 @T6G_MB_LIB.T6G(SCH_1):PAGE175

NC_PVDDCR_CPU1_P0_PWM8 @T6G_MB_LIB.T6G(SCH_1):NC_PVDDCR_CPU1_P0_PWM8
  PU12    5   PWM4 RAA229620GNPHA0-RAA229620GNP#HA0,SMLF,IC,ARF0TGP40A   I128 @T6G_MB_LIB.T6G(SCH_1):PAGE175

NC_PVDDCR_CPU1_P1_DNC1 @T6G_MB_LIB.T6G(SCH_1):NC_PVDDCR_CPU1_P1_DNC1
  PU35   31    DNC ISL99390FRZTR5935-ISL99390FRZ-TR5935,SMLF,IC,AL099A    I91 @T6G_MB_LIB.T6G(SCH_1):PAGE193

NC_PVDDCR_CPU1_P1_DNC2 @T6G_MB_LIB.T6G(SCH_1):NC_PVDDCR_CPU1_P1_DNC2
   PU5   31    DNC ISL99390FRZTR5935-ISL99390FRZ-TR5935,SMLF,IC,AL099A    I31 @T6G_MB_LIB.T6G(SCH_1):PAGE193

NC_PVDDCR_CPU1_P1_DNC3 @T6G_MB_LIB.T6G(SCH_1):NC_PVDDCR_CPU1_P1_DNC3
  PU37   31    DNC ISL99390FRZTR5935-ISL99390FRZ-TR5935,SMLF,IC,AL099A    I72 @T6G_MB_LIB.T6G(SCH_1):PAGE194

NC_PVDDCR_CPU1_P1_DNC4 @T6G_MB_LIB.T6G(SCH_1):NC_PVDDCR_CPU1_P1_DNC4
  PU36   31    DNC ISL99390FRZTR5935-ISL99390FRZ-TR5935,SMLF,IC,AL099A    I21 @T6G_MB_LIB.T6G(SCH_1):PAGE194

NC_PVDDCR_CPU1_P1_DNC5 @T6G_MB_LIB.T6G(SCH_1):NC_PVDDCR_CPU1_P1_DNC5
  PU38   31    DNC ISL99390FRZTR5935-ISL99390FRZ-TR5935,SMLF,IC,AL099A    I73 @T6G_MB_LIB.T6G(SCH_1):PAGE195

NC_PVDDCR_CPU1_P1_DNC6 @T6G_MB_LIB.T6G(SCH_1):NC_PVDDCR_CPU1_P1_DNC6
  PU33   31    DNC ISL99390FRZTR5935-ISL99390FRZ-TR5935,SMLF,IC,AL099A    I19 @T6G_MB_LIB.T6G(SCH_1):PAGE195

NC_PVDDCR_CPU1_P1_GL1_1 @T6G_MB_LIB.T6G(SCH_1):NC_PVDDCR_CPU1_P1_GL1_1
  PU35    6    GL1 ISL99390FRZTR5935-ISL99390FRZ-TR5935,SMLF,IC,AL099A    I91 @T6G_MB_LIB.T6G(SCH_1):PAGE193

NC_PVDDCR_CPU1_P1_GL1_2 @T6G_MB_LIB.T6G(SCH_1):NC_PVDDCR_CPU1_P1_GL1_2
   PU5    6    GL1 ISL99390FRZTR5935-ISL99390FRZ-TR5935,SMLF,IC,AL099A    I31 @T6G_MB_LIB.T6G(SCH_1):PAGE193

NC_PVDDCR_CPU1_P1_GL1_3 @T6G_MB_LIB.T6G(SCH_1):NC_PVDDCR_CPU1_P1_GL1_3
  PU37    6    GL1 ISL99390FRZTR5935-ISL99390FRZ-TR5935,SMLF,IC,AL099A    I72 @T6G_MB_LIB.T6G(SCH_1):PAGE194

NC_PVDDCR_CPU1_P1_GL1_4 @T6G_MB_LIB.T6G(SCH_1):NC_PVDDCR_CPU1_P1_GL1_4
  PU36    6    GL1 ISL99390FRZTR5935-ISL99390FRZ-TR5935,SMLF,IC,AL099A    I21 @T6G_MB_LIB.T6G(SCH_1):PAGE194

NC_PVDDCR_CPU1_P1_GL1_5 @T6G_MB_LIB.T6G(SCH_1):NC_PVDDCR_CPU1_P1_GL1_5
  PU38    6    GL1 ISL99390FRZTR5935-ISL99390FRZ-TR5935,SMLF,IC,AL099A    I73 @T6G_MB_LIB.T6G(SCH_1):PAGE195

NC_PVDDCR_CPU1_P1_GL1_6 @T6G_MB_LIB.T6G(SCH_1):NC_PVDDCR_CPU1_P1_GL1_6
  PU33    6    GL1 ISL99390FRZTR5935-ISL99390FRZ-TR5935,SMLF,IC,AL099A    I19 @T6G_MB_LIB.T6G(SCH_1):PAGE195

NC_PVDDCR_CPU1_P1_GL2_1 @T6G_MB_LIB.T6G(SCH_1):NC_PVDDCR_CPU1_P1_GL2_1
  PU35   41    GL2 ISL99390FRZTR5935-ISL99390FRZ-TR5935,SMLF,IC,AL099A    I91 @T6G_MB_LIB.T6G(SCH_1):PAGE193

NC_PVDDCR_CPU1_P1_GL2_2 @T6G_MB_LIB.T6G(SCH_1):NC_PVDDCR_CPU1_P1_GL2_2
   PU5   41    GL2 ISL99390FRZTR5935-ISL99390FRZ-TR5935,SMLF,IC,AL099A    I31 @T6G_MB_LIB.T6G(SCH_1):PAGE193

NC_PVDDCR_CPU1_P1_GL2_3 @T6G_MB_LIB.T6G(SCH_1):NC_PVDDCR_CPU1_P1_GL2_3
  PU37   41    GL2 ISL99390FRZTR5935-ISL99390FRZ-TR5935,SMLF,IC,AL099A    I72 @T6G_MB_LIB.T6G(SCH_1):PAGE194

NC_PVDDCR_CPU1_P1_GL2_4 @T6G_MB_LIB.T6G(SCH_1):NC_PVDDCR_CPU1_P1_GL2_4
  PU36   41    GL2 ISL99390FRZTR5935-ISL99390FRZ-TR5935,SMLF,IC,AL099A    I21 @T6G_MB_LIB.T6G(SCH_1):PAGE194

NC_PVDDCR_CPU1_P1_GL2_5 @T6G_MB_LIB.T6G(SCH_1):NC_PVDDCR_CPU1_P1_GL2_5
  PU38   41    GL2 ISL99390FRZTR5935-ISL99390FRZ-TR5935,SMLF,IC,AL099A    I73 @T6G_MB_LIB.T6G(SCH_1):PAGE195

NC_PVDDCR_CPU1_P1_GL2_6 @T6G_MB_LIB.T6G(SCH_1):NC_PVDDCR_CPU1_P1_GL2_6
  PU33   41    GL2 ISL99390FRZTR5935-ISL99390FRZ-TR5935,SMLF,IC,AL099A    I19 @T6G_MB_LIB.T6G(SCH_1):PAGE195

NC_PVDDCR_CPU1_P1_IMON7 @T6G_MB_LIB.T6G(SCH_1):NC_PVDDCR_CPU1_P1_IMON7
 PR533    1      A Q_RES_0402LF-0,5%,1/16W,CHIP,CS00002JB13    I76 @T6G_MB_LIB.T6G(SCH_1):PAGE192
  PU34   33    CS5 RAA229620GNPHA0-RAA229620GNP#HA0,SMLF,IC,ARF0TGP40A   I128 @T6G_MB_LIB.T6G(SCH_1):PAGE192

NC_PVDDCR_CPU1_P1_IMON8 @T6G_MB_LIB.T6G(SCH_1):NC_PVDDCR_CPU1_P1_IMON8
  PR12    1      A Q_RES_0402LF-0,5%,1/16W,CHIP,CS00002JB13   I127 @T6G_MB_LIB.T6G(SCH_1):PAGE192
  PU34   34    CS4 RAA229620GNPHA0-RAA229620GNP#HA0,SMLF,IC,ARF0TGP40A   I128 @T6G_MB_LIB.T6G(SCH_1):PAGE192

NC_PVDDCR_CPU1_P1_PWM7 @T6G_MB_LIB.T6G(SCH_1):NC_PVDDCR_CPU1_P1_PWM7
  PU34    6   PWM5 RAA229620GNPHA0-RAA229620GNP#HA0,SMLF,IC,ARF0TGP40A   I128 @T6G_MB_LIB.T6G(SCH_1):PAGE192

NC_PVDDCR_CPU1_P1_PWM8 @T6G_MB_LIB.T6G(SCH_1):NC_PVDDCR_CPU1_P1_PWM8
  PU34    5   PWM4 RAA229620GNPHA0-RAA229620GNP#HA0,SMLF,IC,ARF0TGP40A   I128 @T6G_MB_LIB.T6G(SCH_1):PAGE192

NC_PVDDCR_SOC_P0_DNC1 @T6G_MB_LIB.T6G(SCH_1):NC_PVDDCR_SOC_P0_DNC1
  PU49   31    DNC ISL99390FRZTR5935-ISL99390FRZ-TR5935,SMLF,IC,AL099A    I41 @T6G_MB_LIB.T6G(SCH_1):PAGE173

NC_PVDDCR_SOC_P0_DNC2 @T6G_MB_LIB.T6G(SCH_1):NC_PVDDCR_SOC_P0_DNC2
  PU50   31    DNC ISL99390FRZTR5935-ISL99390FRZ-TR5935,SMLF,IC,AL099A    I86 @T6G_MB_LIB.T6G(SCH_1):PAGE173

NC_PVDDCR_SOC_P0_DNC3 @T6G_MB_LIB.T6G(SCH_1):NC_PVDDCR_SOC_P0_DNC3
  PU51   31    DNC ISL99390FRZTR5935-ISL99390FRZ-TR5935,SMLF,IC,AL099A    I38 @T6G_MB_LIB.T6G(SCH_1):PAGE174

NC_PVDDCR_SOC_P0_GL1_1 @T6G_MB_LIB.T6G(SCH_1):NC_PVDDCR_SOC_P0_GL1_1
  PU49    6    GL1 ISL99390FRZTR5935-ISL99390FRZ-TR5935,SMLF,IC,AL099A    I41 @T6G_MB_LIB.T6G(SCH_1):PAGE173

NC_PVDDCR_SOC_P0_GL1_2 @T6G_MB_LIB.T6G(SCH_1):NC_PVDDCR_SOC_P0_GL1_2
  PU50    6    GL1 ISL99390FRZTR5935-ISL99390FRZ-TR5935,SMLF,IC,AL099A    I86 @T6G_MB_LIB.T6G(SCH_1):PAGE173

NC_PVDDCR_SOC_P0_GL1_3 @T6G_MB_LIB.T6G(SCH_1):NC_PVDDCR_SOC_P0_GL1_3
  PU51    6    GL1 ISL99390FRZTR5935-ISL99390FRZ-TR5935,SMLF,IC,AL099A    I38 @T6G_MB_LIB.T6G(SCH_1):PAGE174

NC_PVDDCR_SOC_P0_GL2_1 @T6G_MB_LIB.T6G(SCH_1):NC_PVDDCR_SOC_P0_GL2_1
  PU49   41    GL2 ISL99390FRZTR5935-ISL99390FRZ-TR5935,SMLF,IC,AL099A    I41 @T6G_MB_LIB.T6G(SCH_1):PAGE173

NC_PVDDCR_SOC_P0_GL2_2 @T6G_MB_LIB.T6G(SCH_1):NC_PVDDCR_SOC_P0_GL2_2
  PU50   41    GL2 ISL99390FRZTR5935-ISL99390FRZ-TR5935,SMLF,IC,AL099A    I86 @T6G_MB_LIB.T6G(SCH_1):PAGE173

NC_PVDDCR_SOC_P0_GL2_3 @T6G_MB_LIB.T6G(SCH_1):NC_PVDDCR_SOC_P0_GL2_3
  PU51   41    GL2 ISL99390FRZTR5935-ISL99390FRZ-TR5935,SMLF,IC,AL099A    I38 @T6G_MB_LIB.T6G(SCH_1):PAGE174

NC_PVDDCR_SOC_P1_DNC1 @T6G_MB_LIB.T6G(SCH_1):NC_PVDDCR_SOC_P1_DNC1
  PU30   31    DNC ISL99390FRZTR5935-ISL99390FRZ-TR5935,SMLF,IC,AL099A    I17 @T6G_MB_LIB.T6G(SCH_1):PAGE190

NC_PVDDCR_SOC_P1_DNC2 @T6G_MB_LIB.T6G(SCH_1):NC_PVDDCR_SOC_P1_DNC2
  PU31   31    DNC ISL99390FRZTR5935-ISL99390FRZ-TR5935,SMLF,IC,AL099A    I86 @T6G_MB_LIB.T6G(SCH_1):PAGE190

NC_PVDDCR_SOC_P1_DNC3 @T6G_MB_LIB.T6G(SCH_1):NC_PVDDCR_SOC_P1_DNC3
  PU32   31    DNC ISL99390FRZTR5935-ISL99390FRZ-TR5935,SMLF,IC,AL099A    I38 @T6G_MB_LIB.T6G(SCH_1):PAGE191

NC_PVDDCR_SOC_P1_GL1_1 @T6G_MB_LIB.T6G(SCH_1):NC_PVDDCR_SOC_P1_GL1_1
  PU30    6    GL1 ISL99390FRZTR5935-ISL99390FRZ-TR5935,SMLF,IC,AL099A    I17 @T6G_MB_LIB.T6G(SCH_1):PAGE190

NC_PVDDCR_SOC_P1_GL1_2 @T6G_MB_LIB.T6G(SCH_1):NC_PVDDCR_SOC_P1_GL1_2
  PU31    6    GL1 ISL99390FRZTR5935-ISL99390FRZ-TR5935,SMLF,IC,AL099A    I86 @T6G_MB_LIB.T6G(SCH_1):PAGE190

NC_PVDDCR_SOC_P1_GL1_3 @T6G_MB_LIB.T6G(SCH_1):NC_PVDDCR_SOC_P1_GL1_3
  PU32    6    GL1 ISL99390FRZTR5935-ISL99390FRZ-TR5935,SMLF,IC,AL099A    I38 @T6G_MB_LIB.T6G(SCH_1):PAGE191

NC_PVDDCR_SOC_P1_GL2_1 @T6G_MB_LIB.T6G(SCH_1):NC_PVDDCR_SOC_P1_GL2_1
  PU30   41    GL2 ISL99390FRZTR5935-ISL99390FRZ-TR5935,SMLF,IC,AL099A    I17 @T6G_MB_LIB.T6G(SCH_1):PAGE190

NC_PVDDCR_SOC_P1_GL2_2 @T6G_MB_LIB.T6G(SCH_1):NC_PVDDCR_SOC_P1_GL2_2
  PU31   41    GL2 ISL99390FRZTR5935-ISL99390FRZ-TR5935,SMLF,IC,AL099A    I86 @T6G_MB_LIB.T6G(SCH_1):PAGE190

NC_PVDDCR_SOC_P1_GL2_3 @T6G_MB_LIB.T6G(SCH_1):NC_PVDDCR_SOC_P1_GL2_3
  PU32   41    GL2 ISL99390FRZTR5935-ISL99390FRZ-TR5935,SMLF,IC,AL099A    I38 @T6G_MB_LIB.T6G(SCH_1):PAGE191

NC_PVDDIO_P0_DNC1 @T6G_MB_LIB.T6G(SCH_1):NC_PVDDIO_P0_DNC1
  PU17   31    DNC ISL99390FRZTR5935-ISL99390FRZ-TR5935,SMLF,IC,AL099A    I84 @T6G_MB_LIB.T6G(SCH_1):PAGE180

NC_PVDDIO_P0_DNC2 @T6G_MB_LIB.T6G(SCH_1):NC_PVDDIO_P0_DNC2
  PU18   31    DNC ISL99390FRZTR5935-ISL99390FRZ-TR5935,SMLF,IC,AL099A    I15 @T6G_MB_LIB.T6G(SCH_1):PAGE180

NC_PVDDIO_P0_DNC3 @T6G_MB_LIB.T6G(SCH_1):NC_PVDDIO_P0_DNC3
  PU19   31    DNC ISL99390FRZTR5935-ISL99390FRZ-TR5935,SMLF,IC,AL099A    I32 @T6G_MB_LIB.T6G(SCH_1):PAGE181

NC_PVDDIO_P0_DNC4 @T6G_MB_LIB.T6G(SCH_1):NC_PVDDIO_P0_DNC4
  PU20   31    DNC ISL99390FRZTR5935-ISL99390FRZ-TR5935,SMLF,IC,AL099A    I73 @T6G_MB_LIB.T6G(SCH_1):PAGE181

NC_PVDDIO_P0_GL1_1 @T6G_MB_LIB.T6G(SCH_1):NC_PVDDIO_P0_GL1_1
  PU17    6    GL1 ISL99390FRZTR5935-ISL99390FRZ-TR5935,SMLF,IC,AL099A    I84 @T6G_MB_LIB.T6G(SCH_1):PAGE180

NC_PVDDIO_P0_GL1_2 @T6G_MB_LIB.T6G(SCH_1):NC_PVDDIO_P0_GL1_2
  PU18    6    GL1 ISL99390FRZTR5935-ISL99390FRZ-TR5935,SMLF,IC,AL099A    I15 @T6G_MB_LIB.T6G(SCH_1):PAGE180

NC_PVDDIO_P0_GL1_3 @T6G_MB_LIB.T6G(SCH_1):NC_PVDDIO_P0_GL1_3
  PU19    6    GL1 ISL99390FRZTR5935-ISL99390FRZ-TR5935,SMLF,IC,AL099A    I32 @T6G_MB_LIB.T6G(SCH_1):PAGE181

NC_PVDDIO_P0_GL1_4 @T6G_MB_LIB.T6G(SCH_1):NC_PVDDIO_P0_GL1_4
  PU20    6    GL1 ISL99390FRZTR5935-ISL99390FRZ-TR5935,SMLF,IC,AL099A    I73 @T6G_MB_LIB.T6G(SCH_1):PAGE181

NC_PVDDIO_P0_GL2_1 @T6G_MB_LIB.T6G(SCH_1):NC_PVDDIO_P0_GL2_1
  PU17   41    GL2 ISL99390FRZTR5935-ISL99390FRZ-TR5935,SMLF,IC,AL099A    I84 @T6G_MB_LIB.T6G(SCH_1):PAGE180

NC_PVDDIO_P0_GL2_2 @T6G_MB_LIB.T6G(SCH_1):NC_PVDDIO_P0_GL2_2
  PU18   41    GL2 ISL99390FRZTR5935-ISL99390FRZ-TR5935,SMLF,IC,AL099A    I15 @T6G_MB_LIB.T6G(SCH_1):PAGE180

NC_PVDDIO_P0_GL2_3 @T6G_MB_LIB.T6G(SCH_1):NC_PVDDIO_P0_GL2_3
  PU19   41    GL2 ISL99390FRZTR5935-ISL99390FRZ-TR5935,SMLF,IC,AL099A    I32 @T6G_MB_LIB.T6G(SCH_1):PAGE181

NC_PVDDIO_P0_GL2_4 @T6G_MB_LIB.T6G(SCH_1):NC_PVDDIO_P0_GL2_4
  PU20   41    GL2 ISL99390FRZTR5935-ISL99390FRZ-TR5935,SMLF,IC,AL099A    I73 @T6G_MB_LIB.T6G(SCH_1):PAGE181

NC_PVDDIO_P1_DNC1 @T6G_MB_LIB.T6G(SCH_1):NC_PVDDIO_P1_DNC1
  PU39   31    DNC ISL99390FRZTR5935-ISL99390FRZ-TR5935,SMLF,IC,AL099A    I39 @T6G_MB_LIB.T6G(SCH_1):PAGE197

NC_PVDDIO_P1_DNC2 @T6G_MB_LIB.T6G(SCH_1):NC_PVDDIO_P1_DNC2
  PU40   31    DNC ISL99390FRZTR5935-ISL99390FRZ-TR5935,SMLF,IC,AL099A    I84 @T6G_MB_LIB.T6G(SCH_1):PAGE197

NC_PVDDIO_P1_DNC3 @T6G_MB_LIB.T6G(SCH_1):NC_PVDDIO_P1_DNC3
  PU52   31    DNC ISL99390FRZTR5935-ISL99390FRZ-TR5935,SMLF,IC,AL099A    I73 @T6G_MB_LIB.T6G(SCH_1):PAGE198

NC_PVDDIO_P1_DNC4 @T6G_MB_LIB.T6G(SCH_1):NC_PVDDIO_P1_DNC4
  PU53   31    DNC ISL99390FRZTR5935-ISL99390FRZ-TR5935,SMLF,IC,AL099A    I15 @T6G_MB_LIB.T6G(SCH_1):PAGE198

NC_PVDDIO_P1_GL1_1 @T6G_MB_LIB.T6G(SCH_1):NC_PVDDIO_P1_GL1_1
  PU39    6    GL1 ISL99390FRZTR5935-ISL99390FRZ-TR5935,SMLF,IC,AL099A    I39 @T6G_MB_LIB.T6G(SCH_1):PAGE197

NC_PVDDIO_P1_GL1_2 @T6G_MB_LIB.T6G(SCH_1):NC_PVDDIO_P1_GL1_2
  PU40    6    GL1 ISL99390FRZTR5935-ISL99390FRZ-TR5935,SMLF,IC,AL099A    I84 @T6G_MB_LIB.T6G(SCH_1):PAGE197

NC_PVDDIO_P1_GL1_3 @T6G_MB_LIB.T6G(SCH_1):NC_PVDDIO_P1_GL1_3
  PU52    6    GL1 ISL99390FRZTR5935-ISL99390FRZ-TR5935,SMLF,IC,AL099A    I73 @T6G_MB_LIB.T6G(SCH_1):PAGE198

NC_PVDDIO_P1_GL1_4 @T6G_MB_LIB.T6G(SCH_1):NC_PVDDIO_P1_GL1_4
  PU53    6    GL1 ISL99390FRZTR5935-ISL99390FRZ-TR5935,SMLF,IC,AL099A    I15 @T6G_MB_LIB.T6G(SCH_1):PAGE198

NC_PVDDIO_P1_GL2_1 @T6G_MB_LIB.T6G(SCH_1):NC_PVDDIO_P1_GL2_1
  PU39   41    GL2 ISL99390FRZTR5935-ISL99390FRZ-TR5935,SMLF,IC,AL099A    I39 @T6G_MB_LIB.T6G(SCH_1):PAGE197

NC_PVDDIO_P1_GL2_2 @T6G_MB_LIB.T6G(SCH_1):NC_PVDDIO_P1_GL2_2
  PU40   41    GL2 ISL99390FRZTR5935-ISL99390FRZ-TR5935,SMLF,IC,AL099A    I84 @T6G_MB_LIB.T6G(SCH_1):PAGE197

NC_PVDDIO_P1_GL2_3 @T6G_MB_LIB.T6G(SCH_1):NC_PVDDIO_P1_GL2_3
  PU52   41    GL2 ISL99390FRZTR5935-ISL99390FRZ-TR5935,SMLF,IC,AL099A    I73 @T6G_MB_LIB.T6G(SCH_1):PAGE198

NC_PVDDIO_P1_GL2_4 @T6G_MB_LIB.T6G(SCH_1):NC_PVDDIO_P1_GL2_4
  PU53   41    GL2 ISL99390FRZTR5935-ISL99390FRZ-TR5935,SMLF,IC,AL099A    I15 @T6G_MB_LIB.T6G(SCH_1):PAGE198

NC_Q83_D2 @T6G_MB_LIB.T6G(SCH_1):NC_Q83_D2
   Q83    3     D2 MOSFET_NCH_DUAL-PJT138K,SMLF,IC,BAM138K0003    I43 @T6G_MB_LIB.T6G(SCH_1):PAGE374

NC_Q83_G2 @T6G_MB_LIB.T6G(SCH_1):NC_Q83_G2
   Q83    5     G2 MOSFET_NCH_DUAL-PJT138K,SMLF,IC,BAM138K0003    I43 @T6G_MB_LIB.T6G(SCH_1):PAGE374

NC_Q83_S2 @T6G_MB_LIB.T6G(SCH_1):NC_Q83_S2
   Q83    4     S2 MOSFET_NCH_DUAL-PJT138K,SMLF,IC,BAM138K0003    I43 @T6G_MB_LIB.T6G(SCH_1):PAGE374

NC_Q95_D2 @T6G_MB_LIB.T6G(SCH_1):NC_Q95_D2
   Q95    3     D2 MOSFET_NCH_DUAL-PJT138K,SMLF,IC,BAM138K0003    I89 @T6G_MB_LIB.T6G(SCH_1):PAGE345

NC_Q95_G2 @T6G_MB_LIB.T6G(SCH_1):NC_Q95_G2
   Q95    5     G2 MOSFET_NCH_DUAL-PJT138K,SMLF,IC,BAM138K0003    I89 @T6G_MB_LIB.T6G(SCH_1):PAGE345

NC_Q95_S2 @T6G_MB_LIB.T6G(SCH_1):NC_Q95_S2
   Q95    4     S2 MOSFET_NCH_DUAL-PJT138K,SMLF,IC,BAM138K0003    I89 @T6G_MB_LIB.T6G(SCH_1):PAGE345

NC_RES @T6G_MB_LIB.T6G(SCH_1):NC_RES
 U6000   13    RES DS125BR111RTWR-DS125BR111RTWR,SMLF,IC,AL000125003     I1 @T6G_MB_LIB.T6G(SCH_1):PAGE111

NC_U104_NC1 @T6G_MB_LIB.T6G(SCH_1):NC_U104_NC1
  U104    1    NC1 74LVC1G07GV-74LVC1G07GV,SMLF,IC,AL1G0007001    I38 @T6G_MB_LIB.T6G(SCH_1):PAGE337

NC_U10_FBOUT @T6G_MB_LIB.T6G(SCH_1):NC_U10_FBOUT
   U10    9 FBOUT_NC 9ZXL0451EKILFT-9ZXL0451EKILFT,SMLF,IC,AL000451003    I63 @T6G_MB_LIB.T6G(SCH_1):PAGE379

NC_U10_FBOUT_N @T6G_MB_LIB.T6G(SCH_1):NC_U10_FBOUT_N
   U10    8 FBOUT_NC# 9ZXL0451EKILFT-9ZXL0451EKILFT,SMLF,IC,AL000451003    I63 @T6G_MB_LIB.T6G(SCH_1):PAGE379

NC_U10_NC0 @T6G_MB_LIB.T6G(SCH_1):NC_U10_NC0
   U10   10    NC0 9ZXL0451EKILFT-9ZXL0451EKILFT,SMLF,IC,AL000451003    I63 @T6G_MB_LIB.T6G(SCH_1):PAGE379

NC_U10_NC1 @T6G_MB_LIB.T6G(SCH_1):NC_U10_NC1
   U10   11    NC1 9ZXL0451EKILFT-9ZXL0451EKILFT,SMLF,IC,AL000451003    I63 @T6G_MB_LIB.T6G(SCH_1):PAGE379

NC_U10_NC2 @T6G_MB_LIB.T6G(SCH_1):NC_U10_NC2
   U10   17    NC2 9ZXL0451EKILFT-9ZXL0451EKILFT,SMLF,IC,AL000451003    I63 @T6G_MB_LIB.T6G(SCH_1):PAGE379

NC_U10_NC3 @T6G_MB_LIB.T6G(SCH_1):NC_U10_NC3
   U10   30    NC3 9ZXL0451EKILFT-9ZXL0451EKILFT,SMLF,IC,AL000451003    I63 @T6G_MB_LIB.T6G(SCH_1):PAGE379

NC_U157_NC1 @T6G_MB_LIB.T6G(SCH_1):NC_U157_NC1
  U157    1    NC1 74LVC1G07GV-74LVC1G07GV,SMLF,IC,AL1G0007001    I25 @T6G_MB_LIB.T6G(SCH_1):PAGE337

NC_U218_NC1 @T6G_MB_LIB.T6G(SCH_1):NC_U218_NC1
  U218    1    NC1 74LVC1G07GV-74LVC1G07GV,SMLF,IC,AL1G0007001    I22 @T6G_MB_LIB.T6G(SCH_1):PAGE342

NC_U219_NC1 @T6G_MB_LIB.T6G(SCH_1):NC_U219_NC1
  U219    1    NC1 74LVC1G07GV-74LVC1G07GV,SMLF,IC,AL1G0007001    I32 @T6G_MB_LIB.T6G(SCH_1):PAGE342

NC_U257_2Y @T6G_MB_LIB.T6G(SCH_1):NC_U257_2Y
  U257    4     2Y 74LVC2G07DW7-74LVC2G07DW-7,SMLF,IC,AL002G07003    I50 @T6G_MB_LIB.T6G(SCH_1):PAGE255

NC_U314_FBOUT @T6G_MB_LIB.T6G(SCH_1):NC_U314_FBOUT
  U314    9 FBOUT_NC 9ZXL0451EKILFT-9ZXL0451EKILFT,SMLF,IC,AL000451003    I63 @T6G_MB_LIB.T6G(SCH_1):PAGE160

NC_U314_FBOUT_N @T6G_MB_LIB.T6G(SCH_1):NC_U314_FBOUT_N
  U314    8 FBOUT_NC# 9ZXL0451EKILFT-9ZXL0451EKILFT,SMLF,IC,AL000451003    I63 @T6G_MB_LIB.T6G(SCH_1):PAGE160

NC_U314_NC0 @T6G_MB_LIB.T6G(SCH_1):NC_U314_NC0
  U314   10    NC0 9ZXL0451EKILFT-9ZXL0451EKILFT,SMLF,IC,AL000451003    I63 @T6G_MB_LIB.T6G(SCH_1):PAGE160

NC_U314_NC1 @T6G_MB_LIB.T6G(SCH_1):NC_U314_NC1
  U314   11    NC1 9ZXL0451EKILFT-9ZXL0451EKILFT,SMLF,IC,AL000451003    I63 @T6G_MB_LIB.T6G(SCH_1):PAGE160

NC_U314_NC2 @T6G_MB_LIB.T6G(SCH_1):NC_U314_NC2
  U314   17    NC2 9ZXL0451EKILFT-9ZXL0451EKILFT,SMLF,IC,AL000451003    I63 @T6G_MB_LIB.T6G(SCH_1):PAGE160

NC_U314_NC3 @T6G_MB_LIB.T6G(SCH_1):NC_U314_NC3
  U314   30    NC3 9ZXL0451EKILFT-9ZXL0451EKILFT,SMLF,IC,AL000451003    I63 @T6G_MB_LIB.T6G(SCH_1):PAGE160

NC_U316_2Y @T6G_MB_LIB.T6G(SCH_1):NC_U316_2Y
  U316    4     B1 74LVC2G17GW-74LVC2G17GW,SMLF,IC,AL2G0017005    I86 @T6G_MB_LIB.T6G(SCH_1):PAGE331

NC_U8004_2Y @T6G_MB_LIB.T6G(SCH_1):NC_U8004_2Y
 U8004    4     2Y 74LVC2G07DW7-74LVC2G07DW-7,SMLF,EMPTY,AL002G07003    I16 @T6G_MB_LIB.T6G(SCH_1):PAGE365

NC_USB_HUB_DM2 @T6G_MB_LIB.T6G(SCH_1):NC_USB_HUB_DM2
  U268    6    DM2 GL852GOHY60-GL852G-OHY60,SMLF,IC,AL000852001   I100 @T6G_MB_LIB.T6G(SCH_1):PAGE358

NC_USB_HUB_DM3 @T6G_MB_LIB.T6G(SCH_1):NC_USB_HUB_DM3
  U268   12    DM3 GL852GOHY60-GL852G-OHY60,SMLF,IC,AL000852001   I100 @T6G_MB_LIB.T6G(SCH_1):PAGE358

NC_USB_HUB_DM4 @T6G_MB_LIB.T6G(SCH_1):NC_USB_HUB_DM4
  U268   15    DM4 GL852GOHY60-GL852G-OHY60,SMLF,IC,AL000852001   I100 @T6G_MB_LIB.T6G(SCH_1):PAGE358

NC_USB_HUB_DP2 @T6G_MB_LIB.T6G(SCH_1):NC_USB_HUB_DP2
  U268    7    DP2 GL852GOHY60-GL852G-OHY60,SMLF,IC,AL000852001   I100 @T6G_MB_LIB.T6G(SCH_1):PAGE358

NC_USB_HUB_DP3 @T6G_MB_LIB.T6G(SCH_1):NC_USB_HUB_DP3
  U268   13    DP3 GL852GOHY60-GL852G-OHY60,SMLF,IC,AL000852001   I100 @T6G_MB_LIB.T6G(SCH_1):PAGE358

NC_USB_HUB_DP4 @T6G_MB_LIB.T6G(SCH_1):NC_USB_HUB_DP4
  U268   16    DP4 GL852GOHY60-GL852G-OHY60,SMLF,IC,AL000852001   I100 @T6G_MB_LIB.T6G(SCH_1):PAGE358

NC_USB_HUB_SDA @T6G_MB_LIB.T6G(SCH_1):NC_USB_HUB_SDA
  U268   26    SDA GL852GOHY60-GL852G-OHY60,SMLF,IC,AL000852001   I100 @T6G_MB_LIB.T6G(SCH_1):PAGE358

OCP_SFF_AUX_PWR_EN @T6G_MB_LIB.T6G(SCH_1):OCP_SFF_AUX_PWR_EN
 R1671    1      A Q_RES_0402LF-0,5%,1/16W,CHIP,CS00002JB13    I54 @T6G_MB_LIB.T6G(SCH_1):PAGE335
 R1719    1      A Q_RES_0402LF-33.2,1%,1/16W,CHIP,CS03322FB03   I119 @T6G_MB_LIB.T6G(SCH_1):PAGE336
 R3231    1      A Q_RES_0402LF-33.2,1%,1/16W,CHIP,CS03322FB03   I160 @T6G_MB_LIB.T6G(SCH_1):PAGE336
 R1929    2      B Q_RES_0402LF-10K,1%,1/16W,CHIP,CS31002FB08     I8 @T6G_MB_LIB.T6G(SCH_1):PAGE335
 R9031    2      B Q_RES_0402LF-33.2,1%,1/16W,CHIP,CS03322FB03    I22 @T6G_MB_LIB.T6G(SCH_1):PAGE340
 R1145    2      B Q_RES_0402LF-10K,5%,1/16W,EMPTY,CS31002JB08    I76 @T6G_MB_LIB.T6G(SCH_1):PAGE340

OCP_SFF_AUX_PWR_EN_R @T6G_MB_LIB.T6G(SCH_1):OCP_SFF_AUX_PWR_EN_R
 R1671    2      B Q_RES_0402LF-0,5%,1/16W,CHIP,CS00002JB13    I54 @T6G_MB_LIB.T6G(SCH_1):PAGE335
   J38  B12 AUX_PWR_EN SCONN168_ME1016810202011-SCONN168_ME1016810202011,A   I168 @T6G_MB_LIB.T6G(SCH_1):PAGE335

OCP_SFF_AUX_PWR_EN_R1 @T6G_MB_LIB.T6G(SCH_1):OCP_SFF_AUX_PWR_EN_R1
 R1719    2      B Q_RES_0402LF-33.2,1%,1/16W,CHIP,CS03322FB03   I119 @T6G_MB_LIB.T6G(SCH_1):PAGE336
   U66    1     OE 74LVC1G126SE7-74LVC1G126SE-7,SMLF,IC,AL1G0126009   I157 @T6G_MB_LIB.T6G(SCH_1):PAGE336

OCP_SFF_AUX_PWR_EN_R2 @T6G_MB_LIB.T6G(SCH_1):OCP_SFF_AUX_PWR_EN_R2
  U224    1     OE 74LVC1G126SE7-74LVC1G126SE-7,SMLF,IC,AL1G0126009   I159 @T6G_MB_LIB.T6G(SCH_1):PAGE336
 R3231    2      B Q_RES_0402LF-33.2,1%,1/16W,CHIP,CS03322FB03   I160 @T6G_MB_LIB.T6G(SCH_1):PAGE336

OCP_SFF_AUX_PWR_EN_R3 @T6G_MB_LIB.T6G(SCH_1):OCP_SFF_AUX_PWR_EN_R3
 R9030    1      A Q_RES_0402LF-0,5%,1/16W,EMPTY,CS00002JB13    I15 @T6G_MB_LIB.T6G(SCH_1):PAGE340
 R9029    1      A Q_RES_0402LF-0,5%,1/16W,EMPTY,CS00002JB13    I18 @T6G_MB_LIB.T6G(SCH_1):PAGE340
 R9031    1      A Q_RES_0402LF-33.2,1%,1/16W,CHIP,CS03322FB03    I22 @T6G_MB_LIB.T6G(SCH_1):PAGE340
 U9002    4      O 74LVC1G32GW_SMLF-74LVC1G32GW,IC,ALVC1G32007    I74 @T6G_MB_LIB.T6G(SCH_1):PAGE340

OCP_SFF_BIF0_R_N @T6G_MB_LIB.T6G(SCH_1):OCP_SFF_BIF0_R_N
   J38   B7  BIF0# SCONN168_ME1016810202011-SCONN168_ME1016810202011,A   I168 @T6G_MB_LIB.T6G(SCH_1):PAGE335
   R39    2      B Q_RES_0402LF-0,5%,1/16W,CHIP,CS00002JB13    I57 @T6G_MB_LIB.T6G(SCH_1):PAGE335

OCP_SFF_BIF1_R_N @T6G_MB_LIB.T6G(SCH_1):OCP_SFF_BIF1_R_N
   J38   B8  BIF1# SCONN168_ME1016810202011-SCONN168_ME1016810202011,A   I168 @T6G_MB_LIB.T6G(SCH_1):PAGE335
   R40    2      B Q_RES_0402LF-0,5%,1/16W,CHIP,CS00002JB13    I56 @T6G_MB_LIB.T6G(SCH_1):PAGE335

OCP_SFF_BIF2_R_N @T6G_MB_LIB.T6G(SCH_1):OCP_SFF_BIF2_R_N
   J38   B9  BIF2# SCONN168_ME1016810202011-SCONN168_ME1016810202011,A   I168 @T6G_MB_LIB.T6G(SCH_1):PAGE335
   R41    2      B Q_RES_0402LF-0,5%,1/16W,CHIP,CS00002JB13    I55 @T6G_MB_LIB.T6G(SCH_1):PAGE335

OCP_SFF_ID0 @T6G_MB_LIB.T6G(SCH_1):OCP_SFF_ID0
   R32    1      A Q_RES_0402LF-4.7K,1%,1/16W,CHIP,CS24702FB06     I2 @T6G_MB_LIB.T6G(SCH_1):PAGE335
   J38  OB7 SLOT_ID0 SCONN168_ME1016810202011-SCONN168_ME1016810202011,A   I168 @T6G_MB_LIB.T6G(SCH_1):PAGE335
   R31    2      B Q_RES_0402LF-4.7K,1%,1/16W,EMPTY,CS24702FB06     I3 @T6G_MB_LIB.T6G(SCH_1):PAGE335

OCP_SFF_ID1 @T6G_MB_LIB.T6G(SCH_1):OCP_SFF_ID1
   J38  OA6 SLOT_ID1 SCONN168_ME1016810202011-SCONN168_ME1016810202011,A   I168 @T6G_MB_LIB.T6G(SCH_1):PAGE335
   R34    1      A Q_RES_0402LF-4.7K,1%,1/16W,CHIP,CS24702FB06    I12 @T6G_MB_LIB.T6G(SCH_1):PAGE335
   R33    2      B Q_RES_0402LF-4.7K,1%,1/16W,EMPTY,CS24702FB06    I17 @T6G_MB_LIB.T6G(SCH_1):PAGE335

OCP_SFF_ISO1_RBT_ARB_IN @T6G_MB_LIB.T6G(SCH_1):OCP_SFF_ISO1_RBT_ARB_IN
   J38  OA4 RBT_ARB_IN SCONN168_ME1016810202011-SCONN168_ME1016810202011,A   I168 @T6G_MB_LIB.T6G(SCH_1):PAGE335
   U67   11     4B 74CBTLV3126PW-74CBTLV3126PW,SMLF,IC,AL003126K08     I1 @T6G_MB_LIB.T6G(SCH_1):PAGE336

OCP_SFF_ISO2_RBT_ARB_OUT @T6G_MB_LIB.T6G(SCH_1):OCP_SFF_ISO2_RBT_ARB_OUT
   J38  OA5 RBT_ARB_OUT SCONN168_ME1016810202011-SCONN168_ME1016810202011,A   I168 @T6G_MB_LIB.T6G(SCH_1):PAGE335
    U7   11     4B 74CBTLV3126PW-74CBTLV3126PW,SMLF,IC,AL003126K08     I2 @T6G_MB_LIB.T6G(SCH_1):PAGE336

OCP_SFF_ISO_BIF0_EN @T6G_MB_LIB.T6G(SCH_1):OCP_SFF_ISO_BIF0_EN
 R1896    1      A Q_RES_0402LF-100,1%,1/16W,CHIP,CS11002FB07   I123 @T6G_MB_LIB.T6G(SCH_1):PAGE336
   R39    1      A Q_RES_0402LF-0,5%,1/16W,CHIP,CS00002JB13    I57 @T6G_MB_LIB.T6G(SCH_1):PAGE335

OCP_SFF_ISO_BIF1_EN @T6G_MB_LIB.T6G(SCH_1):OCP_SFF_ISO_BIF1_EN
 R1897    1      A Q_RES_0402LF-100,1%,1/16W,CHIP,CS11002FB07   I124 @T6G_MB_LIB.T6G(SCH_1):PAGE336
   R40    1      A Q_RES_0402LF-0,5%,1/16W,CHIP,CS00002JB13    I56 @T6G_MB_LIB.T6G(SCH_1):PAGE335

OCP_SFF_ISO_BIF2_EN @T6G_MB_LIB.T6G(SCH_1):OCP_SFF_ISO_BIF2_EN
 R1898    1      A Q_RES_0402LF-100,1%,1/16W,CHIP,CS11002FB07   I122 @T6G_MB_LIB.T6G(SCH_1):PAGE336
   R41    1      A Q_RES_0402LF-0,5%,1/16W,CHIP,CS00002JB13    I55 @T6G_MB_LIB.T6G(SCH_1):PAGE335

OCP_SFF_MAIN_PWR_EN @T6G_MB_LIB.T6G(SCH_1):OCP_SFF_MAIN_PWR_EN
 R1930    2      B Q_RES_0402LF-10K,1%,1/16W,CHIP,CS31002FB08     I7 @T6G_MB_LIB.T6G(SCH_1):PAGE335
   R38    1      A Q_RES_0402LF-0,5%,1/16W,CHIP,CS00002JB13    I59 @T6G_MB_LIB.T6G(SCH_1):PAGE335
  R959    1      A Q_RES_0402LF-33,5%,1/16W,CHIP,CS03302JB10    I81 @T6G_MB_LIB.T6G(SCH_1):PAGE81

OCP_SFF_MAIN_PWR_EN_R @T6G_MB_LIB.T6G(SCH_1):OCP_SFF_MAIN_PWR_EN_R
   J38  OB2 MAIN_PWR_EN SCONN168_ME1016810202011-SCONN168_ME1016810202011,A   I168 @T6G_MB_LIB.T6G(SCH_1):PAGE335
   R38    2      B Q_RES_0402LF-0,5%,1/16W,CHIP,CS00002JB13    I59 @T6G_MB_LIB.T6G(SCH_1):PAGE335

OCP_SFF_NOT_PRSNT_RBT_ARB_IN @T6G_MB_LIB.T6G(SCH_1):OCP_SFF_NOT_PRSNT_RBT_ARB_IN
  U243    1     B1 NC7SB3157_SMLF-NC7SB3157P6X,NC7SB3157P6X,EMPTY,ALSA    I15 @T6G_MB_LIB.T6G(SCH_1):PAGE258
  U244    1     B1 NC7SB3157_SMLF-NC7SB3157P6X,NC7SB3157P6X,EMPTY,ALSA    I16 @T6G_MB_LIB.T6G(SCH_1):PAGE258

OCP_SFF_P3V3_ADC_ALERT_R @T6G_MB_LIB.T6G(SCH_1):OCP_SFF_P3V3_ADC_ALERT_R
  U266    3 EXT_CLK||INT ISL28022FRZT-ISL28022FRZ-T,SMLF,IC,AL028022003    I30 @T6G_MB_LIB.T6G(SCH_1):PAGE295
 R3563    1      A Q_RES_0402LF-0,5%,1/16W,CHIP,CS00002JB13    I35 @T6G_MB_LIB.T6G(SCH_1):PAGE295
 R4094    2      B Q_RES_0402LF-1K,1%,1/16W,CHIP,CS21002FB06   I151 @T6G_MB_LIB.T6G(SCH_1):PAGE295

OCP_SFF_P3V3_P12V_ADC_ALERT @T6G_MB_LIB.T6G(SCH_1):OCP_SFF_P3V3_P12V_ADC_ALERT
   U18  AA1  PL29B LCMXO3LF9400C5BG484C-LCMXO3LF-9400C-5BG484C,SMLF,IA   I143 @T6G_MB_LIB.T6G(SCH_1):PAGE81
 R1340    1      A Q_RES_0402LF-0,5%,1/16W,CHIP,CS00002JB13   I176 @T6G_MB_LIB.T6G(SCH_1):PAGE81

OCP_SFF_P3V3_P12V_ADC_R_ALERT @T6G_MB_LIB.T6G(SCH_1):OCP_SFF_P3V3_P12V_ADC_R_ALERT
 R3563    2      B Q_RES_0402LF-0,5%,1/16W,CHIP,CS00002JB13    I35 @T6G_MB_LIB.T6G(SCH_1):PAGE295
 R1270    2      B Q_RES_0402LF-0,5%,1/16W,CHIP,CS00002JB13    I23 @T6G_MB_LIB.T6G(SCH_1):PAGE466
 R1340    2      B Q_RES_0402LF-0,5%,1/16W,CHIP,CS00002JB13   I176 @T6G_MB_LIB.T6G(SCH_1):PAGE81
 R1327    2      B Q_RES_0402LF-1K,1%,1/16W,EMPTY,CS21002FB06    I85 @T6G_MB_LIB.T6G(SCH_1):PAGE466

OCP_SFF_PRSNT01_R1_N @T6G_MB_LIB.T6G(SCH_1):OCP_SFF_PRSNT01_R1_N
  U242    1     1A 74LVC2G08DP-74LVC2G08DP,SMLF,EMPTY,ALVC2G08K01    I13 @T6G_MB_LIB.T6G(SCH_1):PAGE258
 R8013    2      B Q_RES_0402LF-0,5%,1/16W,EMPTY,CS00002JB13    I64 @T6G_MB_LIB.T6G(SCH_1):PAGE258
 C8001    1      A Q_CAP_0402-0.1UF,25V,10%,EMPTY,CH4104K1B00    I68 @T6G_MB_LIB.T6G(SCH_1):PAGE258

OCP_SFF_PRSNT01_R_N @T6G_MB_LIB.T6G(SCH_1):OCP_SFF_PRSNT01_R_N
  U240    7     1Y 74LVC2G08DP-74LVC2G08DP,SMLF,EMPTY,ALVC2G08K01    I11 @T6G_MB_LIB.T6G(SCH_1):PAGE258
 R8013    1      A Q_RES_0402LF-0,5%,1/16W,EMPTY,CS00002JB13    I64 @T6G_MB_LIB.T6G(SCH_1):PAGE258

OCP_SFF_PRSNT0_R_N @T6G_MB_LIB.T6G(SCH_1):OCP_SFF_PRSNT0_R_N
   J38  B42 PRSNTB0# SCONN168_ME1016810202011-SCONN168_ME1016810202011,A   I168 @T6G_MB_LIB.T6G(SCH_1):PAGE335
  U240    1     1A 74LVC2G08DP-74LVC2G08DP,SMLF,EMPTY,ALVC2G08K01    I11 @T6G_MB_LIB.T6G(SCH_1):PAGE258
 R1905    2      B Q_RES_0402LF-1K,1%,1/16W,CHIP,CS21002FB06    I15 @T6G_MB_LIB.T6G(SCH_1):PAGE338
  U211    1     1A 74LVC2G07DW7-74LVC2G07DW-7,SMLF,IC,AL002G07003    I29 @T6G_MB_LIB.T6G(SCH_1):PAGE338

OCP_SFF_PRSNT1_R_N @T6G_MB_LIB.T6G(SCH_1):OCP_SFF_PRSNT1_R_N
   J38  A42 PRSNTB1# SCONN168_ME1016810202011-SCONN168_ME1016810202011,A   I168 @T6G_MB_LIB.T6G(SCH_1):PAGE335
  U240    2     1B 74LVC2G08DP-74LVC2G08DP,SMLF,EMPTY,ALVC2G08K01    I11 @T6G_MB_LIB.T6G(SCH_1):PAGE258
 R1907    2      B Q_RES_0402LF-1K,1%,1/16W,CHIP,CS21002FB06    I28 @T6G_MB_LIB.T6G(SCH_1):PAGE338
  U211    3     2A 74LVC2G07DW7-74LVC2G07DW-7,SMLF,IC,AL002G07003    I29 @T6G_MB_LIB.T6G(SCH_1):PAGE338

OCP_SFF_PRSNT23_R1_N @T6G_MB_LIB.T6G(SCH_1):OCP_SFF_PRSNT23_R1_N
  U242    2     1B 74LVC2G08DP-74LVC2G08DP,SMLF,EMPTY,ALVC2G08K01    I13 @T6G_MB_LIB.T6G(SCH_1):PAGE258
 R8014    2      B Q_RES_0402LF-0,5%,1/16W,EMPTY,CS00002JB13    I65 @T6G_MB_LIB.T6G(SCH_1):PAGE258
 C8002    1      A Q_CAP_0402-0.1UF,25V,10%,EMPTY,CH4104K1B00    I70 @T6G_MB_LIB.T6G(SCH_1):PAGE258

OCP_SFF_PRSNT23_R_N @T6G_MB_LIB.T6G(SCH_1):OCP_SFF_PRSNT23_R_N
  U240    3     2Y 74LVC2G08DP-74LVC2G08DP,SMLF,EMPTY,ALVC2G08K01    I12 @T6G_MB_LIB.T6G(SCH_1):PAGE258
 R8014    1      A Q_RES_0402LF-0,5%,1/16W,EMPTY,CS00002JB13    I65 @T6G_MB_LIB.T6G(SCH_1):PAGE258

OCP_SFF_PRSNT2_R_N @T6G_MB_LIB.T6G(SCH_1):OCP_SFF_PRSNT2_R_N
   J38  A12 PRSNTB2# SCONN168_ME1016810202011-SCONN168_ME1016810202011,A   I168 @T6G_MB_LIB.T6G(SCH_1):PAGE335
  U240    5     2A 74LVC2G08DP-74LVC2G08DP,SMLF,EMPTY,ALVC2G08K01    I12 @T6G_MB_LIB.T6G(SCH_1):PAGE258
 R1906    2      B Q_RES_0402LF-1K,1%,1/16W,CHIP,CS21002FB06     I9 @T6G_MB_LIB.T6G(SCH_1):PAGE338
    U8    1     1A 74LVC2G07DW7-74LVC2G07DW-7,SMLF,IC,AL002G07003    I26 @T6G_MB_LIB.T6G(SCH_1):PAGE338

OCP_SFF_PRSNT3_R_N @T6G_MB_LIB.T6G(SCH_1):OCP_SFF_PRSNT3_R_N
   J38  B70 PRSNTB3# SCONN168_ME1016810202011-SCONN168_ME1016810202011,A   I168 @T6G_MB_LIB.T6G(SCH_1):PAGE335
  U240    6     2B 74LVC2G08DP-74LVC2G08DP,SMLF,EMPTY,ALVC2G08K01    I12 @T6G_MB_LIB.T6G(SCH_1):PAGE258
 R1908    2      B Q_RES_0402LF-1K,1%,1/16W,CHIP,CS21002FB06    I24 @T6G_MB_LIB.T6G(SCH_1):PAGE338
    U8    3     2A 74LVC2G07DW7-74LVC2G07DW-7,SMLF,IC,AL002G07003    I26 @T6G_MB_LIB.T6G(SCH_1):PAGE338

OCP_SFF_PRSNTA_R_N @T6G_MB_LIB.T6G(SCH_1):OCP_SFF_PRSNTA_R_N
   J38  A10 PRSNTA# SCONN168_ME1016810202011-SCONN168_ME1016810202011,A   I168 @T6G_MB_LIB.T6G(SCH_1):PAGE335
 R1895    1      A Q_RES_0402LF-0,5%,1/16W,CHIP,CS00002JB13   I169 @T6G_MB_LIB.T6G(SCH_1):PAGE335

OCP_SFF_PRSNT_ALL_R1_N @T6G_MB_LIB.T6G(SCH_1):OCP_SFF_PRSNT_ALL_R1_N
  U243    6      S NC7SB3157_SMLF-NC7SB3157P6X,NC7SB3157P6X,EMPTY,ALSA    I15 @T6G_MB_LIB.T6G(SCH_1):PAGE258
 R3303    2      B Q_RES_0402LF-0,5%,1/16W,CHIP,CS00002JB13    I44 @T6G_MB_LIB.T6G(SCH_1):PAGE258

OCP_SFF_PRSNT_ALL_R3_N @T6G_MB_LIB.T6G(SCH_1):OCP_SFF_PRSNT_ALL_R3_N
  U244    6      S NC7SB3157_SMLF-NC7SB3157P6X,NC7SB3157P6X,EMPTY,ALSA    I16 @T6G_MB_LIB.T6G(SCH_1):PAGE258
 R3304    2      B Q_RES_0402LF-0,5%,1/16W,CHIP,CS00002JB13    I45 @T6G_MB_LIB.T6G(SCH_1):PAGE258

OCP_SFF_PRSNT_ALL_R_N @T6G_MB_LIB.T6G(SCH_1):OCP_SFF_PRSNT_ALL_R_N
  U242    7     1Y 74LVC2G08DP-74LVC2G08DP,SMLF,EMPTY,ALVC2G08K01    I13 @T6G_MB_LIB.T6G(SCH_1):PAGE258
 R3303    1      A Q_RES_0402LF-0,5%,1/16W,CHIP,CS00002JB13    I44 @T6G_MB_LIB.T6G(SCH_1):PAGE258
 R3304    1      A Q_RES_0402LF-0,5%,1/16W,CHIP,CS00002JB13    I45 @T6G_MB_LIB.T6G(SCH_1):PAGE258

OCP_SFF_PWRBRK_BUFF_N @T6G_MB_LIB.T6G(SCH_1):OCP_SFF_PWRBRK_BUFF_N
   R53    2      B Q_RES_0402LF-4.7K,1%,1/16W,CHIP,CS24702FB06    I42 @T6G_MB_LIB.T6G(SCH_1):PAGE337
 R1595    1      A Q_RES_0402LF-33.2,1%,1/16W,CHIP,CS03322FB03    I44 @T6G_MB_LIB.T6G(SCH_1):PAGE337
  U104    4      Y 74LVC1G07GV-74LVC1G07GV,SMLF,IC,AL1G0007001    I38 @T6G_MB_LIB.T6G(SCH_1):PAGE337

OCP_SFF_PWRBRK_N @T6G_MB_LIB.T6G(SCH_1):OCP_SFF_PWRBRK_N
   J38  A70 PWRBRK0# SCONN168_ME1016810202011-SCONN168_ME1016810202011,A   I168 @T6G_MB_LIB.T6G(SCH_1):PAGE335
 R1595    2      B Q_RES_0402LF-33.2,1%,1/16W,CHIP,CS03322FB03    I44 @T6G_MB_LIB.T6G(SCH_1):PAGE337

OCP_SFF_RBT_ARB_IN @T6G_MB_LIB.T6G(SCH_1):OCP_SFF_RBT_ARB_IN
 R1290    2      B Q_RES_0402LF-22,1%,1/16W,EMPTY,CS02202FB02    I98 @T6G_MB_LIB.T6G(SCH_1):PAGE336
  U244    3     B0 NC7SB3157_SMLF-NC7SB3157P6X,NC7SB3157P6X,EMPTY,ALSA    I16 @T6G_MB_LIB.T6G(SCH_1):PAGE258

OCP_SFF_RBT_ARB_IN_MUX1 @T6G_MB_LIB.T6G(SCH_1):OCP_SFF_RBT_ARB_IN_MUX1
  U246    4      A NC7SB3157_SMLF-NC7SB3157P6X,NC7SB3157P6X,EMPTY,ALSA    I17 @T6G_MB_LIB.T6G(SCH_1):PAGE258
 R3305    1      A Q_RES_0402LF-0,5%,1/16W,CHIP,CS00002JB13    I50 @T6G_MB_LIB.T6G(SCH_1):PAGE258

OCP_SFF_RBT_ARB_IN_MUX1_R @T6G_MB_LIB.T6G(SCH_1):OCP_SFF_RBT_ARB_IN_MUX1_R
  U244    4      A NC7SB3157_SMLF-NC7SB3157P6X,NC7SB3157P6X,EMPTY,ALSA    I16 @T6G_MB_LIB.T6G(SCH_1):PAGE258
 R3305    2      B Q_RES_0402LF-0,5%,1/16W,CHIP,CS00002JB13    I50 @T6G_MB_LIB.T6G(SCH_1):PAGE258

OCP_SFF_RBT_ARB_IN_MUX2 @T6G_MB_LIB.T6G(SCH_1):OCP_SFF_RBT_ARB_IN_MUX2
  U243    4      A NC7SB3157_SMLF-NC7SB3157P6X,NC7SB3157P6X,EMPTY,ALSA    I15 @T6G_MB_LIB.T6G(SCH_1):PAGE258
 R3307    1      A Q_RES_0402LF-0,5%,1/16W,CHIP,CS00002JB13    I52 @T6G_MB_LIB.T6G(SCH_1):PAGE258

OCP_SFF_RBT_ARB_IN_MUX2_R @T6G_MB_LIB.T6G(SCH_1):OCP_SFF_RBT_ARB_IN_MUX2_R
  U245    4      A NC7SB3157_SMLF-NC7SB3157P6X,NC7SB3157P6X,EMPTY,ALSA    I18 @T6G_MB_LIB.T6G(SCH_1):PAGE258
 R3307    2      B Q_RES_0402LF-0,5%,1/16W,CHIP,CS00002JB13    I52 @T6G_MB_LIB.T6G(SCH_1):PAGE258

OCP_SFF_RBT_ARB_IN_R @T6G_MB_LIB.T6G(SCH_1):OCP_SFF_RBT_ARB_IN_R
   U67   12     4A 74CBTLV3126PW-74CBTLV3126PW,SMLF,IC,AL003126K08     I1 @T6G_MB_LIB.T6G(SCH_1):PAGE336
 R1290    1      A Q_RES_0402LF-22,1%,1/16W,EMPTY,CS02202FB02    I98 @T6G_MB_LIB.T6G(SCH_1):PAGE336
 R3237    2      B Q_RES_0402LF-0,5%,1/16W,CHIP,CS00002JB13   I156 @T6G_MB_LIB.T6G(SCH_1):PAGE336

OCP_SFF_RBT_ARB_OUT @T6G_MB_LIB.T6G(SCH_1):OCP_SFF_RBT_ARB_OUT
    U7   12     4A 74CBTLV3126PW-74CBTLV3126PW,SMLF,IC,AL003126K08     I2 @T6G_MB_LIB.T6G(SCH_1):PAGE336
 R3237    1      A Q_RES_0402LF-0,5%,1/16W,CHIP,CS00002JB13   I156 @T6G_MB_LIB.T6G(SCH_1):PAGE336
  U243    3     B0 NC7SB3157_SMLF-NC7SB3157P6X,NC7SB3157P6X,EMPTY,ALSA    I15 @T6G_MB_LIB.T6G(SCH_1):PAGE258

OCP_SFF_WAKE_BUFF_N @T6G_MB_LIB.T6G(SCH_1):OCP_SFF_WAKE_BUFF_N
 U8082    4      Y 74LVC1G126SE7-74LVC1G126SE-7,SMLF,IC,AL1G0126009     I8 @T6G_MB_LIB.T6G(SCH_1):PAGE337
 R1594    1      A Q_RES_0402LF-33.2,1%,1/16W,CHIP,CS03322FB03    I31 @T6G_MB_LIB.T6G(SCH_1):PAGE337
 R2488    2      B Q_RES_0402LF-4.7K,1%,1/16W,CHIP,CS24702FB06    I35 @T6G_MB_LIB.T6G(SCH_1):PAGE337

OCP_SFF_WAKE_BUFF_R_N @T6G_MB_LIB.T6G(SCH_1):OCP_SFF_WAKE_BUFF_R_N
  U157    2      A 74LVC1G07GV-74LVC1G07GV,SMLF,IC,AL1G0007001    I25 @T6G_MB_LIB.T6G(SCH_1):PAGE337
 R1594    2      B Q_RES_0402LF-33.2,1%,1/16W,CHIP,CS03322FB03    I31 @T6G_MB_LIB.T6G(SCH_1):PAGE337

OCP_V3_1_P3V3_PLD_PWRGD @T6G_MB_LIB.T6G(SCH_1):OCP_V3_1_P3V3_PLD_PWRGD
 R1143    1      A Q_RES_0402LF-0,5%,1/16W,CHIP,CS00002JB13    I65 @T6G_MB_LIB.T6G(SCH_1):PAGE340
   U30    4      Y SN74LVC1G07DBVR_SMLF-SN74LVC1G07DBVR,IC,AL1G0007024    I66 @T6G_MB_LIB.T6G(SCH_1):PAGE340

OCP_V3_1_P3V3_PLD_R_PWRGD @T6G_MB_LIB.T6G(SCH_1):OCP_V3_1_P3V3_PLD_R_PWRGD
   U18   A9  PT21B LCMXO3LF9400C5BG484C-LCMXO3LF-9400C-5BG484C,SMLF,IA    I94 @T6G_MB_LIB.T6G(SCH_1):PAGE79
 R1144    2      B Q_RES_0402LF-1K,1%,1/16W,CHIP,CS21002FB06    I64 @T6G_MB_LIB.T6G(SCH_1):PAGE340
 R1143    2      B Q_RES_0402LF-0,5%,1/16W,CHIP,CS00002JB13    I65 @T6G_MB_LIB.T6G(SCH_1):PAGE340

OCP_V3_1_P3V3_PWRGD @T6G_MB_LIB.T6G(SCH_1):OCP_V3_1_P3V3_PWRGD
 R1142    1      A Q_RES_0402LF-0,5%,1/16W,CHIP,CS00002JB13    I71 @T6G_MB_LIB.T6G(SCH_1):PAGE340
 R8094    2      B Q_RES_0402LF-0,5%,1/16W,CHIP,CS00002JB13    I85 @T6G_MB_LIB.T6G(SCH_1):PAGE340
 R3783    2      B Q_RES_0402LF-100K,1%,1/16W,EMPTY,CS41002FB09   I131 @T6G_MB_LIB.T6G(SCH_1):PAGE338
 R3794    2      B Q_RES_0402LF-0,5%,1/16W,EMPTY,CS00002JB13   I132 @T6G_MB_LIB.T6G(SCH_1):PAGE338
 U9050    1      A 74LVC1G08W57-74LVC1G08W5-7,SMLF,IC,AL1G0008020    I91 @T6G_MB_LIB.T6G(SCH_1):PAGE340
 R1519    2      B Q_RES_0402LF-0,5%,1/16W,EMPTY,CS00002JB13   I101 @T6G_MB_LIB.T6G(SCH_1):PAGE340

OCP_V3_1_P3V3_R1_PWRGD @T6G_MB_LIB.T6G(SCH_1):OCP_V3_1_P3V3_R1_PWRGD
 U8001    2 RESET_L APX80929SAG7-APX809-29SAG-7,SMLF,IC,AL080929000    I80 @T6G_MB_LIB.T6G(SCH_1):PAGE340
 R8093    1      A Q_RES_0402LF-100K,1%,1/16W,CHIP,CS41002FB09    I84 @T6G_MB_LIB.T6G(SCH_1):PAGE340
 R8094    1      A Q_RES_0402LF-0,5%,1/16W,CHIP,CS00002JB13    I85 @T6G_MB_LIB.T6G(SCH_1):PAGE340
 R8092    2      B Q_RES_0402LF-10K,5%,1/16W,EMPTY,CS31002JB08    I90 @T6G_MB_LIB.T6G(SCH_1):PAGE340

OCP_V3_1_P3V3_R2_PWRGD @T6G_MB_LIB.T6G(SCH_1):OCP_V3_1_P3V3_R2_PWRGD
   U30    2      A SN74LVC1G07DBVR_SMLF-SN74LVC1G07DBVR,IC,AL1G0007024    I66 @T6G_MB_LIB.T6G(SCH_1):PAGE340
 R1142    2      B Q_RES_0402LF-0,5%,1/16W,CHIP,CS00002JB13    I71 @T6G_MB_LIB.T6G(SCH_1):PAGE340

OCP_V3_1_P3V3_R3_PWRGD @T6G_MB_LIB.T6G(SCH_1):OCP_V3_1_P3V3_R3_PWRGD
 R9034    1      A Q_RES_0402LF-33.2,1%,1/16W,CHIP,CS03322FB03     I3 @T6G_MB_LIB.T6G(SCH_1):PAGE340
 R9022    1      A Q_RES_0402LF-33.2,1%,1/16W,CHIP,CS03322FB03    I13 @T6G_MB_LIB.T6G(SCH_1):PAGE340
 R1519    1      A Q_RES_0402LF-0,5%,1/16W,EMPTY,CS00002JB13   I101 @T6G_MB_LIB.T6G(SCH_1):PAGE340
 R1518    2      B Q_RES_0402LF-0,5%,1/16W,CHIP,CS00002JB13   I102 @T6G_MB_LIB.T6G(SCH_1):PAGE340

OCP_V3_2_AUX_PWR_EN @T6G_MB_LIB.T6G(SCH_1):OCP_V3_2_AUX_PWR_EN
 R3203    1      A Q_RES_0402LF-33.2,1%,1/16W,CHIP,CS03322FB03    I81 @T6G_MB_LIB.T6G(SCH_1):PAGE307
 R3234    1      A Q_RES_0402LF-33.2,1%,1/16W,CHIP,CS03322FB03     I6 @T6G_MB_LIB.T6G(SCH_1):PAGE342
 R3164    2      B Q_RES_0402LF-10K,1%,1/16W,CHIP,CS31002FB08    I34 @T6G_MB_LIB.T6G(SCH_1):PAGE341
 R3172    1      A Q_RES_0402LF-0,5%,1/16W,CHIP,CS00002JB13    I42 @T6G_MB_LIB.T6G(SCH_1):PAGE341
 R1175    2      B Q_RES_0402LF-33.2,1%,1/16W,CHIP,CS03322FB03    I42 @T6G_MB_LIB.T6G(SCH_1):PAGE257
 R1172    2      B Q_RES_0402LF-10K,5%,1/16W,EMPTY,CS31002JB08    I51 @T6G_MB_LIB.T6G(SCH_1):PAGE257

OCP_V3_2_AUX_PWR_EN_R @T6G_MB_LIB.T6G(SCH_1):OCP_V3_2_AUX_PWR_EN_R
   J35  B12 AUX_PWR_EN SCONN168_ME1016810202011-SCONN168_ME1016810202011,A   I168 @T6G_MB_LIB.T6G(SCH_1):PAGE341
 R3172    2      B Q_RES_0402LF-0,5%,1/16W,CHIP,CS00002JB13    I42 @T6G_MB_LIB.T6G(SCH_1):PAGE341

OCP_V3_2_AUX_PWR_EN_R1 @T6G_MB_LIB.T6G(SCH_1):OCP_V3_2_AUX_PWR_EN_R1
  U286    1     OE 74LVC1G126SE7-74LVC1G126SE-7,SMLF,IC,AL1G0126009    I80 @T6G_MB_LIB.T6G(SCH_1):PAGE307
 R3203    2      B Q_RES_0402LF-33.2,1%,1/16W,CHIP,CS03322FB03    I81 @T6G_MB_LIB.T6G(SCH_1):PAGE307

OCP_V3_2_AUX_PWR_EN_R2 @T6G_MB_LIB.T6G(SCH_1):OCP_V3_2_AUX_PWR_EN_R2
 R1147    1      A Q_RES_0402LF-0,5%,1/16W,EMPTY,CS00002JB13    I39 @T6G_MB_LIB.T6G(SCH_1):PAGE257
   U37    4      O 74LVC1G32GW_SMLF-74LVC1G32GW,IC,ALVC1G32007    I40 @T6G_MB_LIB.T6G(SCH_1):PAGE257
 R1146    1      A Q_RES_0402LF-0,5%,1/16W,EMPTY,CS00002JB13    I41 @T6G_MB_LIB.T6G(SCH_1):PAGE257
 R1175    1      A Q_RES_0402LF-33.2,1%,1/16W,CHIP,CS03322FB03    I42 @T6G_MB_LIB.T6G(SCH_1):PAGE257

OCP_V3_2_AUX_PWR_EN_R3 @T6G_MB_LIB.T6G(SCH_1):OCP_V3_2_AUX_PWR_EN_R3
 R3234    2      B Q_RES_0402LF-33.2,1%,1/16W,CHIP,CS03322FB03     I6 @T6G_MB_LIB.T6G(SCH_1):PAGE342
  U225    1     OE 74LVC1G126SE7-74LVC1G126SE-7,SMLF,IC,AL1G0126009     I9 @T6G_MB_LIB.T6G(SCH_1):PAGE342

OCP_V3_2_BIF0_R_N @T6G_MB_LIB.T6G(SCH_1):OCP_V3_2_BIF0_R_N
 R3169    2      B Q_RES_0402LF-0,5%,1/16W,CHIP,CS00002JB13    I43 @T6G_MB_LIB.T6G(SCH_1):PAGE341
   J35   B7  BIF0# SCONN168_ME1016810202011-SCONN168_ME1016810202011,A   I168 @T6G_MB_LIB.T6G(SCH_1):PAGE341

OCP_V3_2_BIF1_R_N @T6G_MB_LIB.T6G(SCH_1):OCP_V3_2_BIF1_R_N
   J35   B8  BIF1# SCONN168_ME1016810202011-SCONN168_ME1016810202011,A   I168 @T6G_MB_LIB.T6G(SCH_1):PAGE341
 R3170    2      B Q_RES_0402LF-0,5%,1/16W,CHIP,CS00002JB13    I44 @T6G_MB_LIB.T6G(SCH_1):PAGE341

OCP_V3_2_BIF2_R_N @T6G_MB_LIB.T6G(SCH_1):OCP_V3_2_BIF2_R_N
   J35   B9  BIF2# SCONN168_ME1016810202011-SCONN168_ME1016810202011,A   I168 @T6G_MB_LIB.T6G(SCH_1):PAGE341
 R3171    2      B Q_RES_0402LF-0,5%,1/16W,CHIP,CS00002JB13    I45 @T6G_MB_LIB.T6G(SCH_1):PAGE341

OCP_V3_2_ID0 @T6G_MB_LIB.T6G(SCH_1):OCP_V3_2_ID0
 R3162    2      B Q_RES_0402LF-4.7K,1%,1/16W,CHIP,CS24702FB06    I26 @T6G_MB_LIB.T6G(SCH_1):PAGE341
   J35  OB7 SLOT_ID0 SCONN168_ME1016810202011-SCONN168_ME1016810202011,A   I168 @T6G_MB_LIB.T6G(SCH_1):PAGE341
 R3163    1      A Q_RES_0402LF-4.7K,1%,1/16W,EMPTY,CS24702FB06     I2 @T6G_MB_LIB.T6G(SCH_1):PAGE341

OCP_V3_2_ID1 @T6G_MB_LIB.T6G(SCH_1):OCP_V3_2_ID1
   J35  OA6 SLOT_ID1 SCONN168_ME1016810202011-SCONN168_ME1016810202011,A   I168 @T6G_MB_LIB.T6G(SCH_1):PAGE341
 R3167    1      A Q_RES_0402LF-4.7K,1%,1/16W,CHIP,CS24702FB06     I3 @T6G_MB_LIB.T6G(SCH_1):PAGE341
 R3166    2      B Q_RES_0402LF-4.7K,1%,1/16W,EMPTY,CS24702FB06    I28 @T6G_MB_LIB.T6G(SCH_1):PAGE341

OCP_V3_2_ISO1_RBT_ARB_IN @T6G_MB_LIB.T6G(SCH_1):OCP_V3_2_ISO1_RBT_ARB_IN
  U222   11     4B 74CBTLV3126PW-74CBTLV3126PW,SMLF,IC,AL003126K08    I32 @T6G_MB_LIB.T6G(SCH_1):PAGE307
   J35  OA4 RBT_ARB_IN SCONN168_ME1016810202011-SCONN168_ME1016810202011,A   I168 @T6G_MB_LIB.T6G(SCH_1):PAGE341

OCP_V3_2_ISO2_RBT_ARB_OUT @T6G_MB_LIB.T6G(SCH_1):OCP_V3_2_ISO2_RBT_ARB_OUT
  U223   11     4B 74CBTLV3126PW-74CBTLV3126PW,SMLF,IC,AL003126K08    I78 @T6G_MB_LIB.T6G(SCH_1):PAGE307
   J35  OA5 RBT_ARB_OUT SCONN168_ME1016810202011-SCONN168_ME1016810202011,A   I168 @T6G_MB_LIB.T6G(SCH_1):PAGE341

OCP_V3_2_ISO_BIF0_EN @T6G_MB_LIB.T6G(SCH_1):OCP_V3_2_ISO_BIF0_EN
 R3208    1      A Q_RES_0402LF-100,1%,1/16W,CHIP,CS11002FB07    I37 @T6G_MB_LIB.T6G(SCH_1):PAGE307
 R3169    1      A Q_RES_0402LF-0,5%,1/16W,CHIP,CS00002JB13    I43 @T6G_MB_LIB.T6G(SCH_1):PAGE341

OCP_V3_2_ISO_BIF1_EN @T6G_MB_LIB.T6G(SCH_1):OCP_V3_2_ISO_BIF1_EN
 R3216    1      A Q_RES_0402LF-100,1%,1/16W,CHIP,CS11002FB07    I38 @T6G_MB_LIB.T6G(SCH_1):PAGE307
 R3170    1      A Q_RES_0402LF-0,5%,1/16W,CHIP,CS00002JB13    I44 @T6G_MB_LIB.T6G(SCH_1):PAGE341

OCP_V3_2_ISO_BIF2_EN @T6G_MB_LIB.T6G(SCH_1):OCP_V3_2_ISO_BIF2_EN
 R3217    1      A Q_RES_0402LF-100,1%,1/16W,CHIP,CS11002FB07    I40 @T6G_MB_LIB.T6G(SCH_1):PAGE307
 R3171    1      A Q_RES_0402LF-0,5%,1/16W,CHIP,CS00002JB13    I45 @T6G_MB_LIB.T6G(SCH_1):PAGE341

OCP_V3_2_MAIN_PWR_EN @T6G_MB_LIB.T6G(SCH_1):OCP_V3_2_MAIN_PWR_EN
 R3165    2      B Q_RES_0402LF-10K,1%,1/16W,CHIP,CS31002FB08    I32 @T6G_MB_LIB.T6G(SCH_1):PAGE341
 R3168    1      A Q_RES_0402LF-0,5%,1/16W,CHIP,CS00002JB13    I86 @T6G_MB_LIB.T6G(SCH_1):PAGE341
   U18   D9  PT20D LCMXO3LF9400C5BG484C-LCMXO3LF-9400C-5BG484C,SMLF,IA    I94 @T6G_MB_LIB.T6G(SCH_1):PAGE79

OCP_V3_2_MAIN_PWR_EN_R @T6G_MB_LIB.T6G(SCH_1):OCP_V3_2_MAIN_PWR_EN_R
   J35  OB2 MAIN_PWR_EN SCONN168_ME1016810202011-SCONN168_ME1016810202011,A   I168 @T6G_MB_LIB.T6G(SCH_1):PAGE341
 R3168    2      B Q_RES_0402LF-0,5%,1/16W,CHIP,CS00002JB13    I86 @T6G_MB_LIB.T6G(SCH_1):PAGE341

OCP_V3_2_NOT_PRSNT_RBT_ARB_IN @T6G_MB_LIB.T6G(SCH_1):OCP_V3_2_NOT_PRSNT_RBT_ARB_IN
  U246    1     B1 NC7SB3157_SMLF-NC7SB3157P6X,NC7SB3157P6X,EMPTY,ALSA    I17 @T6G_MB_LIB.T6G(SCH_1):PAGE258
  U245    1     B1 NC7SB3157_SMLF-NC7SB3157P6X,NC7SB3157P6X,EMPTY,ALSA    I18 @T6G_MB_LIB.T6G(SCH_1):PAGE258

OCP_V3_2_P3V3_ADC_ALERT_R @T6G_MB_LIB.T6G(SCH_1):OCP_V3_2_P3V3_ADC_ALERT_R
  U263    3 EXT_CLK||INT ISL28022FRZT-ISL28022FRZ-T,SMLF,IC,AL028022003    I94 @T6G_MB_LIB.T6G(SCH_1):PAGE360
 R3559    1      A Q_RES_0402LF-0,5%,1/16W,CHIP,CS00002JB13    I96 @T6G_MB_LIB.T6G(SCH_1):PAGE360
 R4092    2      B Q_RES_0402LF-1K,1%,1/16W,CHIP,CS21002FB06   I126 @T6G_MB_LIB.T6G(SCH_1):PAGE360

OCP_V3_2_P3V3_P12V_ADC_ALERT @T6G_MB_LIB.T6G(SCH_1):OCP_V3_2_P3V3_P12V_ADC_ALERT
   U18   P1  PL18B LCMXO3LF9400C5BG484C-LCMXO3LF-9400C-5BG484C,SMLF,IA   I143 @T6G_MB_LIB.T6G(SCH_1):PAGE81
 R1339    2      B Q_RES_0402LF-0,5%,1/16W,CHIP,CS00002JB13   I180 @T6G_MB_LIB.T6G(SCH_1):PAGE81

OCP_V3_2_P3V3_P12V_ADC_R_ALERT @T6G_MB_LIB.T6G(SCH_1):OCP_V3_2_P3V3_P12V_ADC_R_ALERT
 R3559    2      B Q_RES_0402LF-0,5%,1/16W,CHIP,CS00002JB13    I96 @T6G_MB_LIB.T6G(SCH_1):PAGE360
 R1271    2      B Q_RES_0402LF-0,5%,1/16W,CHIP,CS00002JB13    I33 @T6G_MB_LIB.T6G(SCH_1):PAGE466
 R1339    1      A Q_RES_0402LF-0,5%,1/16W,CHIP,CS00002JB13   I180 @T6G_MB_LIB.T6G(SCH_1):PAGE81
 R1328    2      B Q_RES_0402LF-1K,1%,1/16W,EMPTY,CS21002FB06    I87 @T6G_MB_LIB.T6G(SCH_1):PAGE466

OCP_V3_2_P3V3_PLD_PWRGD @T6G_MB_LIB.T6G(SCH_1):OCP_V3_2_P3V3_PLD_PWRGD
   U34    4      Y SN74LVC1G07DBVR_SMLF-SN74LVC1G07DBVR,IC,AL1G0007024    I45 @T6G_MB_LIB.T6G(SCH_1):PAGE257
 R1170    1      A Q_RES_0402LF-0,5%,1/16W,CHIP,CS00002JB13    I58 @T6G_MB_LIB.T6G(SCH_1):PAGE257

OCP_V3_2_P3V3_PLD_R_PWRGD @T6G_MB_LIB.T6G(SCH_1):OCP_V3_2_P3V3_PLD_R_PWRGD
   U18  F15  PT42C LCMXO3LF9400C5BG484C-LCMXO3LF-9400C-5BG484C,SMLF,IA    I94 @T6G_MB_LIB.T6G(SCH_1):PAGE79
 R1170    2      B Q_RES_0402LF-0,5%,1/16W,CHIP,CS00002JB13    I58 @T6G_MB_LIB.T6G(SCH_1):PAGE257
 R1171    2      B Q_RES_0402LF-1K,1%,1/16W,CHIP,CS21002FB06    I60 @T6G_MB_LIB.T6G(SCH_1):PAGE257

OCP_V3_2_P3V3_PWRGD @T6G_MB_LIB.T6G(SCH_1):OCP_V3_2_P3V3_PWRGD
 R1169    1      A Q_RES_0402LF-0,5%,1/16W,CHIP,CS00002JB13    I34 @T6G_MB_LIB.T6G(SCH_1):PAGE257
 R8097    2      B Q_RES_0402LF-0,5%,1/16W,CHIP,CS00002JB13    I73 @T6G_MB_LIB.T6G(SCH_1):PAGE257
 R3832    2      B Q_RES_0402LF-0,5%,1/16W,EMPTY,CS00002JB13   I127 @T6G_MB_LIB.T6G(SCH_1):PAGE343
 R3826    2      B Q_RES_0402LF-100K,1%,1/16W,EMPTY,CS41002FB09   I128 @T6G_MB_LIB.T6G(SCH_1):PAGE343
 U9051    1      A 74LVC1G08W57-74LVC1G08W5-7,SMLF,IC,AL1G0008020    I78 @T6G_MB_LIB.T6G(SCH_1):PAGE257
 R1525    1      A Q_RES_0402LF-0,5%,1/16W,EMPTY,CS00002JB13    I88 @T6G_MB_LIB.T6G(SCH_1):PAGE257

OCP_V3_2_P3V3_R1_PWRGD @T6G_MB_LIB.T6G(SCH_1):OCP_V3_2_P3V3_R1_PWRGD
 U8002    2 RESET_L APX80929SAG7-APX809-29SAG-7,SMLF,IC,AL080929000    I67 @T6G_MB_LIB.T6G(SCH_1):PAGE257
 R8096    1      A Q_RES_0402LF-100K,1%,1/16W,CHIP,CS41002FB09    I70 @T6G_MB_LIB.T6G(SCH_1):PAGE257
 R8097    1      A Q_RES_0402LF-0,5%,1/16W,CHIP,CS00002JB13    I73 @T6G_MB_LIB.T6G(SCH_1):PAGE257
 R8095    2      B Q_RES_0402LF-10K,5%,1/16W,EMPTY,CS31002JB08    I77 @T6G_MB_LIB.T6G(SCH_1):PAGE257

OCP_V3_2_P3V3_R2_PWRGD @T6G_MB_LIB.T6G(SCH_1):OCP_V3_2_P3V3_R2_PWRGD
 R1169    2      B Q_RES_0402LF-0,5%,1/16W,CHIP,CS00002JB13    I34 @T6G_MB_LIB.T6G(SCH_1):PAGE257
   U34    2      A SN74LVC1G07DBVR_SMLF-SN74LVC1G07DBVR,IC,AL1G0007024    I45 @T6G_MB_LIB.T6G(SCH_1):PAGE257

OCP_V3_2_P3V3_R3_PWRGD @T6G_MB_LIB.T6G(SCH_1):OCP_V3_2_P3V3_R3_PWRGD
 R1178    1      A Q_RES_0402LF-33.2,1%,1/16W,CHIP,CS03322FB03    I12 @T6G_MB_LIB.T6G(SCH_1):PAGE257
 R1173    1      A Q_RES_0402LF-33.2,1%,1/16W,CHIP,CS03322FB03    I16 @T6G_MB_LIB.T6G(SCH_1):PAGE257
 R1525    2      B Q_RES_0402LF-0,5%,1/16W,EMPTY,CS00002JB13    I88 @T6G_MB_LIB.T6G(SCH_1):PAGE257
 R1524    2      B Q_RES_0402LF-0,5%,1/16W,CHIP,CS00002JB13    I89 @T6G_MB_LIB.T6G(SCH_1):PAGE257

OCP_V3_2_PRSNT01_R1_N @T6G_MB_LIB.T6G(SCH_1):OCP_V3_2_PRSNT01_R1_N
  U242    5     2A 74LVC2G08DP-74LVC2G08DP,SMLF,EMPTY,ALVC2G08K01    I14 @T6G_MB_LIB.T6G(SCH_1):PAGE258
 R8015    2      B Q_RES_0402LF-0,5%,1/16W,EMPTY,CS00002JB13    I66 @T6G_MB_LIB.T6G(SCH_1):PAGE258
 C8003    1      A Q_CAP_0402-0.1UF,25V,10%,EMPTY,CH4104K1B00    I72 @T6G_MB_LIB.T6G(SCH_1):PAGE258

OCP_V3_2_PRSNT01_R_N @T6G_MB_LIB.T6G(SCH_1):OCP_V3_2_PRSNT01_R_N
  U241    7     1Y 74LVC2G08DP-74LVC2G08DP,SMLF,EMPTY,ALVC2G08K01     I1 @T6G_MB_LIB.T6G(SCH_1):PAGE258
 R8015    1      A Q_RES_0402LF-0,5%,1/16W,EMPTY,CS00002JB13    I66 @T6G_MB_LIB.T6G(SCH_1):PAGE258

OCP_V3_2_PRSNT0_R_N @T6G_MB_LIB.T6G(SCH_1):OCP_V3_2_PRSNT0_R_N
   J35  B42 PRSNTB0# SCONN168_ME1016810202011-SCONN168_ME1016810202011,A   I168 @T6G_MB_LIB.T6G(SCH_1):PAGE341
 R3133    2      B Q_RES_0402LF-1K,1%,1/16W,CHIP,CS21002FB06    I14 @T6G_MB_LIB.T6G(SCH_1):PAGE343
   U58    1     1A 74LVC2G07DW7-74LVC2G07DW-7,SMLF,IC,AL002G07003    I28 @T6G_MB_LIB.T6G(SCH_1):PAGE343
  U241    1     1A 74LVC2G08DP-74LVC2G08DP,SMLF,EMPTY,ALVC2G08K01     I1 @T6G_MB_LIB.T6G(SCH_1):PAGE258

OCP_V3_2_PRSNT1_R_N @T6G_MB_LIB.T6G(SCH_1):OCP_V3_2_PRSNT1_R_N
   J35  A42 PRSNTB1# SCONN168_ME1016810202011-SCONN168_ME1016810202011,A   I168 @T6G_MB_LIB.T6G(SCH_1):PAGE341
 R3135    2      B Q_RES_0402LF-1K,1%,1/16W,CHIP,CS21002FB06    I16 @T6G_MB_LIB.T6G(SCH_1):PAGE343
   U58    3     2A 74LVC2G07DW7-74LVC2G07DW-7,SMLF,IC,AL002G07003    I28 @T6G_MB_LIB.T6G(SCH_1):PAGE343
  U241    2     1B 74LVC2G08DP-74LVC2G08DP,SMLF,EMPTY,ALVC2G08K01     I1 @T6G_MB_LIB.T6G(SCH_1):PAGE258

OCP_V3_2_PRSNT23_R1_N @T6G_MB_LIB.T6G(SCH_1):OCP_V3_2_PRSNT23_R1_N
  U242    6     2B 74LVC2G08DP-74LVC2G08DP,SMLF,EMPTY,ALVC2G08K01    I14 @T6G_MB_LIB.T6G(SCH_1):PAGE258
 R8016    2      B Q_RES_0402LF-0,5%,1/16W,EMPTY,CS00002JB13    I67 @T6G_MB_LIB.T6G(SCH_1):PAGE258
 C8004    1      A Q_CAP_0402-0.1UF,25V,10%,EMPTY,CH4104K1B00    I74 @T6G_MB_LIB.T6G(SCH_1):PAGE258

OCP_V3_2_PRSNT23_R_N @T6G_MB_LIB.T6G(SCH_1):OCP_V3_2_PRSNT23_R_N
  U241    3     2Y 74LVC2G08DP-74LVC2G08DP,SMLF,EMPTY,ALVC2G08K01     I2 @T6G_MB_LIB.T6G(SCH_1):PAGE258
 R8016    1      A Q_RES_0402LF-0,5%,1/16W,EMPTY,CS00002JB13    I67 @T6G_MB_LIB.T6G(SCH_1):PAGE258

OCP_V3_2_PRSNT2_R_N @T6G_MB_LIB.T6G(SCH_1):OCP_V3_2_PRSNT2_R_N
   J35  A12 PRSNTB2# SCONN168_ME1016810202011-SCONN168_ME1016810202011,A   I168 @T6G_MB_LIB.T6G(SCH_1):PAGE341
  U241    5     2A 74LVC2G08DP-74LVC2G08DP,SMLF,EMPTY,ALVC2G08K01     I2 @T6G_MB_LIB.T6G(SCH_1):PAGE258
 R3134    2      B Q_RES_0402LF-1K,1%,1/16W,CHIP,CS21002FB06     I4 @T6G_MB_LIB.T6G(SCH_1):PAGE343
   U59    1     1A 74LVC2G07DW7-74LVC2G07DW-7,SMLF,IC,AL002G07003    I22 @T6G_MB_LIB.T6G(SCH_1):PAGE343

OCP_V3_2_PRSNT3_R_N @T6G_MB_LIB.T6G(SCH_1):OCP_V3_2_PRSNT3_R_N
   J35  B70 PRSNTB3# SCONN168_ME1016810202011-SCONN168_ME1016810202011,A   I168 @T6G_MB_LIB.T6G(SCH_1):PAGE341
 R3136    2      B Q_RES_0402LF-1K,1%,1/16W,CHIP,CS21002FB06     I6 @T6G_MB_LIB.T6G(SCH_1):PAGE343
  U241    6     2B 74LVC2G08DP-74LVC2G08DP,SMLF,EMPTY,ALVC2G08K01     I2 @T6G_MB_LIB.T6G(SCH_1):PAGE258
   U59    3     2A 74LVC2G07DW7-74LVC2G07DW-7,SMLF,IC,AL002G07003    I22 @T6G_MB_LIB.T6G(SCH_1):PAGE343

OCP_V3_2_PRSNTA_R_N @T6G_MB_LIB.T6G(SCH_1):OCP_V3_2_PRSNTA_R_N
   J35  A10 PRSNTA# SCONN168_ME1016810202011-SCONN168_ME1016810202011,A   I168 @T6G_MB_LIB.T6G(SCH_1):PAGE341
 R3180    1      A Q_RES_0402LF-0,5%,1/16W,CHIP,CS00002JB13   I150 @T6G_MB_LIB.T6G(SCH_1):PAGE341

OCP_V3_2_PRSNT_ALL_R1_N @T6G_MB_LIB.T6G(SCH_1):OCP_V3_2_PRSNT_ALL_R1_N
  U246    6      S NC7SB3157_SMLF-NC7SB3157P6X,NC7SB3157P6X,EMPTY,ALSA    I17 @T6G_MB_LIB.T6G(SCH_1):PAGE258
 R3308    2      B Q_RES_0402LF-0,5%,1/16W,CHIP,CS00002JB13    I46 @T6G_MB_LIB.T6G(SCH_1):PAGE258

OCP_V3_2_PRSNT_ALL_R3_N @T6G_MB_LIB.T6G(SCH_1):OCP_V3_2_PRSNT_ALL_R3_N
  U245    6      S NC7SB3157_SMLF-NC7SB3157P6X,NC7SB3157P6X,EMPTY,ALSA    I18 @T6G_MB_LIB.T6G(SCH_1):PAGE258
 R3306    2      B Q_RES_0402LF-0,5%,1/16W,CHIP,CS00002JB13    I47 @T6G_MB_LIB.T6G(SCH_1):PAGE258

OCP_V3_2_PRSNT_ALL_R_N @T6G_MB_LIB.T6G(SCH_1):OCP_V3_2_PRSNT_ALL_R_N
  U242    3     2Y 74LVC2G08DP-74LVC2G08DP,SMLF,EMPTY,ALVC2G08K01    I14 @T6G_MB_LIB.T6G(SCH_1):PAGE258
 R3308    1      A Q_RES_0402LF-0,5%,1/16W,CHIP,CS00002JB13    I46 @T6G_MB_LIB.T6G(SCH_1):PAGE258
 R3306    1      A Q_RES_0402LF-0,5%,1/16W,CHIP,CS00002JB13    I47 @T6G_MB_LIB.T6G(SCH_1):PAGE258

OCP_V3_2_PWRBRK_BUFF_N @T6G_MB_LIB.T6G(SCH_1):OCP_V3_2_PWRBRK_BUFF_N
 R3191    1      A Q_RES_0402LF-33.2,1%,1/16W,CHIP,CS03322FB03    I33 @T6G_MB_LIB.T6G(SCH_1):PAGE342
  U218    4      Y 74LVC1G07GV-74LVC1G07GV,SMLF,IC,AL1G0007001    I22 @T6G_MB_LIB.T6G(SCH_1):PAGE342
 R3190    2      B Q_RES_0402LF-4.7K,1%,1/16W,CHIP,CS24702FB06    I34 @T6G_MB_LIB.T6G(SCH_1):PAGE342

OCP_V3_2_PWRBRK_N @T6G_MB_LIB.T6G(SCH_1):OCP_V3_2_PWRBRK_N
   J35  A70 PWRBRK0# SCONN168_ME1016810202011-SCONN168_ME1016810202011,A   I168 @T6G_MB_LIB.T6G(SCH_1):PAGE341
 R3191    2      B Q_RES_0402LF-33.2,1%,1/16W,CHIP,CS03322FB03    I33 @T6G_MB_LIB.T6G(SCH_1):PAGE342

OCP_V3_2_RBT_ARB_IN @T6G_MB_LIB.T6G(SCH_1):OCP_V3_2_RBT_ARB_IN
 R3209    2      B Q_RES_0402LF-22,1%,1/16W,EMPTY,CS02202FB02    I64 @T6G_MB_LIB.T6G(SCH_1):PAGE307
  U245    3     B0 NC7SB3157_SMLF-NC7SB3157P6X,NC7SB3157P6X,EMPTY,ALSA    I18 @T6G_MB_LIB.T6G(SCH_1):PAGE258

OCP_V3_2_RBT_ARB_IN_R @T6G_MB_LIB.T6G(SCH_1):OCP_V3_2_RBT_ARB_IN_R
  U222   12     4A 74CBTLV3126PW-74CBTLV3126PW,SMLF,IC,AL003126K08    I32 @T6G_MB_LIB.T6G(SCH_1):PAGE307
 R3209    1      A Q_RES_0402LF-22,1%,1/16W,EMPTY,CS02202FB02    I64 @T6G_MB_LIB.T6G(SCH_1):PAGE307
 R3244    2      B Q_RES_0402LF-0,5%,1/16W,CHIP,CS00002JB13    I79 @T6G_MB_LIB.T6G(SCH_1):PAGE307

OCP_V3_2_RBT_ARB_OUT @T6G_MB_LIB.T6G(SCH_1):OCP_V3_2_RBT_ARB_OUT
  U223   12     4A 74CBTLV3126PW-74CBTLV3126PW,SMLF,IC,AL003126K08    I78 @T6G_MB_LIB.T6G(SCH_1):PAGE307
 R3244    1      A Q_RES_0402LF-0,5%,1/16W,CHIP,CS00002JB13    I79 @T6G_MB_LIB.T6G(SCH_1):PAGE307
  U246    3     B0 NC7SB3157_SMLF-NC7SB3157P6X,NC7SB3157P6X,EMPTY,ALSA    I17 @T6G_MB_LIB.T6G(SCH_1):PAGE258

OCP_V3_2_WAKE_BUFF_N @T6G_MB_LIB.T6G(SCH_1):OCP_V3_2_WAKE_BUFF_N
  U217    4      Y 74LVC1G126SE7-74LVC1G126SE-7,SMLF,IC,AL1G0126009    I14 @T6G_MB_LIB.T6G(SCH_1):PAGE342
 R3184    2      B Q_RES_0402LF-4.7K,1%,1/16W,CHIP,CS24702FB06    I18 @T6G_MB_LIB.T6G(SCH_1):PAGE342
 R3185    1      A Q_RES_0402LF-33.2,1%,1/16W,CHIP,CS03322FB03    I29 @T6G_MB_LIB.T6G(SCH_1):PAGE342

OCP_V3_2_WAKE_BUFF_R_N @T6G_MB_LIB.T6G(SCH_1):OCP_V3_2_WAKE_BUFF_R_N
 R3185    2      B Q_RES_0402LF-33.2,1%,1/16W,CHIP,CS03322FB03    I29 @T6G_MB_LIB.T6G(SCH_1):PAGE342
  U219    2      A 74LVC1G07GV-74LVC1G07GV,SMLF,IC,AL1G0007001    I32 @T6G_MB_LIB.T6G(SCH_1):PAGE342

OC_ALERT_N @T6G_MB_LIB.T6G(SCH_1):OC_ALERT_N
 R6039    1      A Q_RES_0402LF-0,5%,1/16W,CHIP,CS00002JB13    I20 @T6G_MB_LIB.T6G(SCH_1):PAGE79
   U18  A10 PT23B||PCLKC0_1 LCMXO3LF9400C5BG484C-LCMXO3LF-9400C-5BG484C,SMLF,IA    I94 @T6G_MB_LIB.T6G(SCH_1):PAGE79

OC_P2V5_COMP @T6G_MB_LIB.T6G(SCH_1):OC_P2V5_COMP
 R8107    2      B Q_RES_0402LF-10K,1%,1/16W,EMPTY,CS31002FB08    I81 @T6G_MB_LIB.T6G(SCH_1):PAGE371
 C8014    1      A Q_CAP_C0402-100NF,50V,10%,EMPTY,CH4106K1B01    I87 @T6G_MB_LIB.T6G(SCH_1):PAGE371
 U8005    1     1+ LM4040AIM3X25NOPB-LM4040AIM3X-2.5/NOPB,SMLF,EMPTY,A   I101 @T6G_MB_LIB.T6G(SCH_1):PAGE371
 U8006    1    IN- AP331AWG7-AP331AWG-7,SMLF,EMPTY,AL000331011   I104 @T6G_MB_LIB.T6G(SCH_1):PAGE371

P0V9_CPU0_RT0_2A @T6G_MB_LIB.T6G(SCH_1):P0V9_CPU0_RT0_2A
 U6010 AC17 PWR_2A_1 PT5161LRS-PT5161LRS,SMLF,IC,AJ051610U03     I3 @T6G_MB_LIB.T6G(SCH_1):PAGE386
 U6010 AC20 PWR_2A_2 PT5161LRS-PT5161LRS,SMLF,IC,AJ051610U03     I3 @T6G_MB_LIB.T6G(SCH_1):PAGE386
 U6010 AK17 PWR_2A_3 PT5161LRS-PT5161LRS,SMLF,IC,AJ051610U03     I3 @T6G_MB_LIB.T6G(SCH_1):PAGE386
 U6010 AK20 PWR_2A_4 PT5161LRS-PT5161LRS,SMLF,IC,AJ051610U03     I3 @T6G_MB_LIB.T6G(SCH_1):PAGE386
 U6010 AU17 PWR_2A_5 PT5161LRS-PT5161LRS,SMLF,IC,AJ051610U03     I3 @T6G_MB_LIB.T6G(SCH_1):PAGE386
 U6010 AU20 PWR_2A_6 PT5161LRS-PT5161LRS,SMLF,IC,AJ051610U03     I3 @T6G_MB_LIB.T6G(SCH_1):PAGE386
 U6010 DN17 PWR_2A_11 PT5161LRS-PT5161LRS,SMLF,IC,AJ051610U03     I3 @T6G_MB_LIB.T6G(SCH_1):PAGE386
 U6010 DN20 PWR_2A_12 PT5161LRS-PT5161LRS,SMLF,IC,AJ051610U03     I3 @T6G_MB_LIB.T6G(SCH_1):PAGE386
 U6010 DY17 PWR_2A_13 PT5161LRS-PT5161LRS,SMLF,IC,AJ051610U03     I3 @T6G_MB_LIB.T6G(SCH_1):PAGE386
 U6010 DY20 PWR_2A_14 PT5161LRS-PT5161LRS,SMLF,IC,AJ051610U03     I3 @T6G_MB_LIB.T6G(SCH_1):PAGE386
 U6010 EG17 PWR_2A_15 PT5161LRS-PT5161LRS,SMLF,IC,AJ051610U03     I3 @T6G_MB_LIB.T6G(SCH_1):PAGE386
 U6010 EG20 PWR_2A_16 PT5161LRS-PT5161LRS,SMLF,IC,AJ051610U03     I3 @T6G_MB_LIB.T6G(SCH_1):PAGE386
 U6010 EP17 PWR_2A_17 PT5161LRS-PT5161LRS,SMLF,IC,AJ051610U03     I3 @T6G_MB_LIB.T6G(SCH_1):PAGE386
 U6010 EP20 PWR_2A_18 PT5161LRS-PT5161LRS,SMLF,IC,AJ051610U03     I3 @T6G_MB_LIB.T6G(SCH_1):PAGE386
 U6010  T17 PWR_2A_19 PT5161LRS-PT5161LRS,SMLF,IC,AJ051610U03     I3 @T6G_MB_LIB.T6G(SCH_1):PAGE386
 U6010  T20 PWR_2A_20 PT5161LRS-PT5161LRS,SMLF,IC,AJ051610U03     I3 @T6G_MB_LIB.T6G(SCH_1):PAGE386
  R962    2      B Q_RES_0603LF-0,5%,1/4W,CHIP,CS00006J900    I11 @T6G_MB_LIB.T6G(SCH_1):PAGE388
   L12    2      2 Q_INDUCTOR_SMLF-100NH/16A,IND,CV+10G0MZ04    I30 @T6G_MB_LIB.T6G(SCH_1):PAGE388
  C576    1      A Q_CAP_C0201-0.1UF,10V,10%,X7S,CH4102K6E00    I38 @T6G_MB_LIB.T6G(SCH_1):PAGE388
  C580    1      A Q_CAP_C0201-0.1UF,10V,10%,X7S,CH4102K6E00    I39 @T6G_MB_LIB.T6G(SCH_1):PAGE388
  C555    1      A Q_CAP_0201-1UF,4V,20%,X6S,CH-10KMEE00    I40 @T6G_MB_LIB.T6G(SCH_1):PAGE388
  C561    1      A Q_CAP_C0402-10UF,6.3V,20%,X6S,CH6101MEB01    I41 @T6G_MB_LIB.T6G(SCH_1):PAGE388
  C539    1      A Q_CAP_0201-1UF,4V,20%,X6S,CH-10KMEE00    I42 @T6G_MB_LIB.T6G(SCH_1):PAGE388
  C562    1      A Q_CAP_0201-1UF,4V,20%,X6S,CH-10KMEE00    I43 @T6G_MB_LIB.T6G(SCH_1):PAGE388
  C579    1      A Q_CAP_C0402-10UF,6.3V,20%,X6S,CH6101MEB01    I44 @T6G_MB_LIB.T6G(SCH_1):PAGE388
  C554    1      A Q_CAP_0402-4.7UF,6.3V,20%,X6S,CH5471MEB01    I45 @T6G_MB_LIB.T6G(SCH_1):PAGE388
  C571    1      A Q_CAP_0402-4.7UF,6.3V,20%,X6S,CH5471MEB01    I46 @T6G_MB_LIB.T6G(SCH_1):PAGE388
  C541    1      A Q_CAP_C0201-0.1UF,10V,10%,X7S,CH4102K6E00    I48 @T6G_MB_LIB.T6G(SCH_1):PAGE388
  C582    1      A Q_CAP_C0201-0.1UF,10V,10%,X7S,CH4102K6E00    I49 @T6G_MB_LIB.T6G(SCH_1):PAGE388
  C523    1      A Q_CAP_C0201-0.1UF,10V,10%,X7S,CH4102K6E00    I50 @T6G_MB_LIB.T6G(SCH_1):PAGE388
  C585    1      A Q_CAP_C0201-0.1UF,10V,10%,X7S,CH4102K6E00    I51 @T6G_MB_LIB.T6G(SCH_1):PAGE388
  C570    1      A Q_CAP_0201-1UF,4V,20%,X6S,CH-10KMEE00    I52 @T6G_MB_LIB.T6G(SCH_1):PAGE388
  C573    1      A Q_CAP_0201-1UF,4V,20%,X6S,CH-10KMEE00    I53 @T6G_MB_LIB.T6G(SCH_1):PAGE388
  C557    1      A Q_CAP_0402-4.7UF,6.3V,20%,X6S,CH5471MEB01    I54 @T6G_MB_LIB.T6G(SCH_1):PAGE388
  C572    1      A Q_CAP_0402-4.7UF,6.3V,20%,X6S,CH5471MEB01    I55 @T6G_MB_LIB.T6G(SCH_1):PAGE388
  C577    1      A Q_CAP_0201-1UF,4V,20%,X6S,CH-10KMEE00    I56 @T6G_MB_LIB.T6G(SCH_1):PAGE388
  C581    1      A Q_CAP_0201-1UF,4V,20%,X6S,CH-10KMEE00    I57 @T6G_MB_LIB.T6G(SCH_1):PAGE388
  C525    1      A Q_CAP_0201-1UF,4V,20%,X6S,CH-10KMEE00    I58 @T6G_MB_LIB.T6G(SCH_1):PAGE388
  C529    1      A Q_CAP_0201-1UF,4V,20%,X6S,CH-10KMEE00    I59 @T6G_MB_LIB.T6G(SCH_1):PAGE388
  C558    1      A Q_CAP_C0201-0.1UF,10V,10%,X7S,CH4102K6E00    I60 @T6G_MB_LIB.T6G(SCH_1):PAGE388
  C543    1      A Q_CAP_C0201-0.1UF,10V,10%,X7S,CH4102K6E00    I62 @T6G_MB_LIB.T6G(SCH_1):PAGE388
  C521    1      A Q_CAP_0201-1UF,4V,20%,X6S,CH-10KMEE00    I65 @T6G_MB_LIB.T6G(SCH_1):PAGE388
  C526    1      A Q_CAP_0201-1UF,4V,20%,X6S,CH-10KMEE00    I66 @T6G_MB_LIB.T6G(SCH_1):PAGE388
  C550    1      A Q_CAP_C0805-100UF,4V,20%,X6S,CH710KMEA01    I67 @T6G_MB_LIB.T6G(SCH_1):PAGE388
  C556    1      A Q_CAP_C0805-100UF,4V,20%,X6S,CH710KMEA01    I69 @T6G_MB_LIB.T6G(SCH_1):PAGE388
  C560    1      A Q_CAP_C0805-100UF,4V,20%,X6S,CH710KMEA01    I70 @T6G_MB_LIB.T6G(SCH_1):PAGE388
  C564    1      A Q_CAP_C0805-100UF,4V,20%,X6S,CH710KMEA01    I71 @T6G_MB_LIB.T6G(SCH_1):PAGE388
  C586    1      A Q_CAP_C0402-22UF,4V,20%,X6S,CH622KMEB02    I75 @T6G_MB_LIB.T6G(SCH_1):PAGE388
  C565    1      A Q_CAP_C0402-22UF,4V,20%,X6S,CH622KMEB02    I76 @T6G_MB_LIB.T6G(SCH_1):PAGE388
  C575    1      A Q_CAP_C0402-22UF,4V,20%,X6S,CH622KMEB02    I77 @T6G_MB_LIB.T6G(SCH_1):PAGE388
  C568    1      A Q_CAP_C0402-22UF,4V,20%,X6S,CH622KMEB02    I78 @T6G_MB_LIB.T6G(SCH_1):PAGE388
  C584    1      A Q_CAP_C0402-10UF,6.3V,20%,X6S,CH6101MEB01    I82 @T6G_MB_LIB.T6G(SCH_1):PAGE388
  C567    1      A Q_CAP_C0402-10UF,6.3V,20%,X6S,CH6101MEB01    I83 @T6G_MB_LIB.T6G(SCH_1):PAGE388
  C583    1      A Q_CAP_C0201-0.1UF,10V,10%,X7S,CH4102K6E00    I93 @T6G_MB_LIB.T6G(SCH_1):PAGE388
  C566    1      A Q_CAP_C0201-0.1UF,10V,10%,X7S,CH4102K6E00    I94 @T6G_MB_LIB.T6G(SCH_1):PAGE388
 C7008    1      A Q_CAPP_SMLF-470UF,2.5V,20%,SPCAP,CH747LM8818    I99 @T6G_MB_LIB.T6G(SCH_1):PAGE388
 C7009    1      A Q_CAPP_SMLF-470UF,2.5V,20%,SPCAP,CH747LM8818   I100 @T6G_MB_LIB.T6G(SCH_1):PAGE388
 C7010    1      A Q_CAP_C0805-100UF,4V,20%,X6S,CH710KMEA01   I101 @T6G_MB_LIB.T6G(SCH_1):PAGE388

P0V9_CPU0_RT0_2A_2D @T6G_MB_LIB.T6G(SCH_1):P0V9_CPU0_RT0_2A_2D
 U6010 BD17 PWR_2A_7 PT5161LRS-PT5161LRS,SMLF,IC,AJ051610U03     I3 @T6G_MB_LIB.T6G(SCH_1):PAGE386
 U6010 BD20 PWR_2A_8 PT5161LRS-PT5161LRS,SMLF,IC,AJ051610U03     I3 @T6G_MB_LIB.T6G(SCH_1):PAGE386
 U6010 DF17 PWR_2A_9 PT5161LRS-PT5161LRS,SMLF,IC,AJ051610U03     I3 @T6G_MB_LIB.T6G(SCH_1):PAGE386
 U6010 DF20 PWR_2A_10 PT5161LRS-PT5161LRS,SMLF,IC,AJ051610U03     I3 @T6G_MB_LIB.T6G(SCH_1):PAGE386
  R961    2      B Q_RES_0603LF-0,5%,1/4W,EMPTY,CS00006J900    I10 @T6G_MB_LIB.T6G(SCH_1):PAGE388
  R962    1      A Q_RES_0603LF-0,5%,1/4W,CHIP,CS00006J900    I11 @T6G_MB_LIB.T6G(SCH_1):PAGE388
  C538    1      A Q_CAP_C0201-0.1UF,10V,10%,X7S,CH4102K6E00    I32 @T6G_MB_LIB.T6G(SCH_1):PAGE388
  C544    1      A Q_CAP_C0201-0.1UF,10V,10%,X7S,CH4102K6E00    I36 @T6G_MB_LIB.T6G(SCH_1):PAGE388
  C542    1      A Q_CAP_0201-1UF,4V,20%,X6S,CH-10KMEE00    I90 @T6G_MB_LIB.T6G(SCH_1):PAGE388
  C545    1      A Q_CAP_0201-1UF,4V,20%,X6S,CH-10KMEE00    I91 @T6G_MB_LIB.T6G(SCH_1):PAGE388

P0V9_CPU0_RT1_2A @T6G_MB_LIB.T6G(SCH_1):P0V9_CPU0_RT1_2A
 U6011 AC17 PWR_2A_1 PT5161LRS-PT5161LRS,SMLF,IC,AJ051610U03     I5 @T6G_MB_LIB.T6G(SCH_1):PAGE409
 U6011 AC20 PWR_2A_2 PT5161LRS-PT5161LRS,SMLF,IC,AJ051610U03     I5 @T6G_MB_LIB.T6G(SCH_1):PAGE409
 U6011 AK17 PWR_2A_3 PT5161LRS-PT5161LRS,SMLF,IC,AJ051610U03     I5 @T6G_MB_LIB.T6G(SCH_1):PAGE409
 U6011 AK20 PWR_2A_4 PT5161LRS-PT5161LRS,SMLF,IC,AJ051610U03     I5 @T6G_MB_LIB.T6G(SCH_1):PAGE409
 U6011 AU17 PWR_2A_5 PT5161LRS-PT5161LRS,SMLF,IC,AJ051610U03     I5 @T6G_MB_LIB.T6G(SCH_1):PAGE409
 U6011 AU20 PWR_2A_6 PT5161LRS-PT5161LRS,SMLF,IC,AJ051610U03     I5 @T6G_MB_LIB.T6G(SCH_1):PAGE409
 U6011 DN17 PWR_2A_11 PT5161LRS-PT5161LRS,SMLF,IC,AJ051610U03     I5 @T6G_MB_LIB.T6G(SCH_1):PAGE409
 U6011 DN20 PWR_2A_12 PT5161LRS-PT5161LRS,SMLF,IC,AJ051610U03     I5 @T6G_MB_LIB.T6G(SCH_1):PAGE409
 U6011 DY17 PWR_2A_13 PT5161LRS-PT5161LRS,SMLF,IC,AJ051610U03     I5 @T6G_MB_LIB.T6G(SCH_1):PAGE409
 U6011 DY20 PWR_2A_14 PT5161LRS-PT5161LRS,SMLF,IC,AJ051610U03     I5 @T6G_MB_LIB.T6G(SCH_1):PAGE409
 U6011 EG17 PWR_2A_15 PT5161LRS-PT5161LRS,SMLF,IC,AJ051610U03     I5 @T6G_MB_LIB.T6G(SCH_1):PAGE409
 U6011 EG20 PWR_2A_16 PT5161LRS-PT5161LRS,SMLF,IC,AJ051610U03     I5 @T6G_MB_LIB.T6G(SCH_1):PAGE409
 U6011 EP17 PWR_2A_17 PT5161LRS-PT5161LRS,SMLF,IC,AJ051610U03     I5 @T6G_MB_LIB.T6G(SCH_1):PAGE409
 U6011 EP20 PWR_2A_18 PT5161LRS-PT5161LRS,SMLF,IC,AJ051610U03     I5 @T6G_MB_LIB.T6G(SCH_1):PAGE409
 U6011  T17 PWR_2A_19 PT5161LRS-PT5161LRS,SMLF,IC,AJ051610U03     I5 @T6G_MB_LIB.T6G(SCH_1):PAGE409
 U6011  T20 PWR_2A_20 PT5161LRS-PT5161LRS,SMLF,IC,AJ051610U03     I5 @T6G_MB_LIB.T6G(SCH_1):PAGE409
 R1011    2      B Q_RES_0603LF-0,5%,1/4W,CHIP,CS00006J900    I36 @T6G_MB_LIB.T6G(SCH_1):PAGE411
  C662    1      A Q_CAP_C0201-0.1UF,10V,10%,X7S,CH4102K6E00    I37 @T6G_MB_LIB.T6G(SCH_1):PAGE411
  C609    1      A Q_CAP_0201-1UF,4V,20%,X6S,CH-10KMEE00    I38 @T6G_MB_LIB.T6G(SCH_1):PAGE411
  C618    1      A Q_CAP_0201-1UF,4V,20%,X6S,CH-10KMEE00    I39 @T6G_MB_LIB.T6G(SCH_1):PAGE411
  C626    1      A Q_CAP_C0402-10UF,6.3V,20%,X6S,CH6101MEB01    I40 @T6G_MB_LIB.T6G(SCH_1):PAGE411
  C645    1      A Q_CAP_C0402-10UF,6.3V,20%,X6S,CH6101MEB01    I41 @T6G_MB_LIB.T6G(SCH_1):PAGE411
  C616    1      A Q_CAP_C0201-0.1UF,10V,10%,X7S,CH4102K6E00    I42 @T6G_MB_LIB.T6G(SCH_1):PAGE411
  C657    1      A Q_CAP_C0201-0.1UF,10V,10%,X7S,CH4102K6E00    I43 @T6G_MB_LIB.T6G(SCH_1):PAGE411
  C607    1      A Q_CAP_0201-1UF,4V,20%,X6S,CH-10KMEE00    I44 @T6G_MB_LIB.T6G(SCH_1):PAGE411
  C643    1      A Q_CAP_0201-1UF,4V,20%,X6S,CH-10KMEE00    I45 @T6G_MB_LIB.T6G(SCH_1):PAGE411
  C635    1      A Q_CAP_C0201-0.1UF,10V,10%,X7S,CH4102K6E00    I46 @T6G_MB_LIB.T6G(SCH_1):PAGE411
  C627    1      A Q_CAP_C0201-0.1UF,10V,10%,X7S,CH4102K6E00    I47 @T6G_MB_LIB.T6G(SCH_1):PAGE411
  C647    1      A Q_CAP_0201-1UF,4V,20%,X6S,CH-10KMEE00    I48 @T6G_MB_LIB.T6G(SCH_1):PAGE411
  C654    1      A Q_CAP_0201-1UF,4V,20%,X6S,CH-10KMEE00    I49 @T6G_MB_LIB.T6G(SCH_1):PAGE411
  C644    1      A Q_CAP_0402-4.7UF,6.3V,20%,X6S,CH5471MEB01    I50 @T6G_MB_LIB.T6G(SCH_1):PAGE411
  C638    1      A Q_CAP_0402-4.7UF,6.3V,20%,X6S,CH5471MEB01    I51 @T6G_MB_LIB.T6G(SCH_1):PAGE411
  C649    1      A Q_CAP_0402-4.7UF,6.3V,20%,X6S,CH5471MEB01    I52 @T6G_MB_LIB.T6G(SCH_1):PAGE411
  C653    1      A Q_CAP_0201-1UF,4V,20%,X6S,CH-10KMEE00    I53 @T6G_MB_LIB.T6G(SCH_1):PAGE411
  C631    1      A Q_CAP_C0201-0.1UF,10V,10%,X7S,CH4102K6E00    I55 @T6G_MB_LIB.T6G(SCH_1):PAGE411
  C650    1      A Q_CAP_C0201-0.1UF,10V,10%,X7S,CH4102K6E00    I58 @T6G_MB_LIB.T6G(SCH_1):PAGE411
  C620    1      A Q_CAP_0201-1UF,4V,20%,X6S,CH-10KMEE00    I59 @T6G_MB_LIB.T6G(SCH_1):PAGE411
  C613    1      A Q_CAP_0201-1UF,4V,20%,X6S,CH-10KMEE00    I61 @T6G_MB_LIB.T6G(SCH_1):PAGE411
   L14    2      2 Q_INDUCTOR_SMLF-100NH/16A,IND,CV+10G0MZ04    I63 @T6G_MB_LIB.T6G(SCH_1):PAGE411
  C625    1      A Q_CAP_C0805-100UF,4V,20%,X6S,CH710KMEA01    I64 @T6G_MB_LIB.T6G(SCH_1):PAGE411
  C628    1      A Q_CAP_C0805-100UF,4V,20%,X6S,CH710KMEA01    I65 @T6G_MB_LIB.T6G(SCH_1):PAGE411
  C633    1      A Q_CAP_C0805-100UF,4V,20%,X6S,CH710KMEA01    I69 @T6G_MB_LIB.T6G(SCH_1):PAGE411
  C637    1      A Q_CAP_C0805-100UF,4V,20%,X6S,CH710KMEA01    I70 @T6G_MB_LIB.T6G(SCH_1):PAGE411
  C634    1      A Q_CAP_C0402-22UF,4V,20%,X6S,CH622KMEB02    I71 @T6G_MB_LIB.T6G(SCH_1):PAGE411
  C663    1      A Q_CAP_C0402-22UF,4V,20%,X6S,CH622KMEB02    I72 @T6G_MB_LIB.T6G(SCH_1):PAGE411
  C630    1      A Q_CAP_C0402-22UF,4V,20%,X6S,CH622KMEB02    I73 @T6G_MB_LIB.T6G(SCH_1):PAGE411
  C656    1      A Q_CAP_C0402-22UF,4V,20%,X6S,CH622KMEB02    I77 @T6G_MB_LIB.T6G(SCH_1):PAGE411
  C661    1      A Q_CAP_C0402-10UF,6.3V,20%,X6S,CH6101MEB01    I78 @T6G_MB_LIB.T6G(SCH_1):PAGE411
  C648    1      A Q_CAP_C0402-10UF,6.3V,20%,X6S,CH6101MEB01    I79 @T6G_MB_LIB.T6G(SCH_1):PAGE411
  C614    1      A Q_CAP_C0201-0.1UF,10V,10%,X7S,CH4102K6E00    I85 @T6G_MB_LIB.T6G(SCH_1):PAGE411
  C622    1      A Q_CAP_0201-1UF,4V,20%,X6S,CH-10KMEE00    I86 @T6G_MB_LIB.T6G(SCH_1):PAGE411
  C652    1      A Q_CAP_0402-4.7UF,6.3V,20%,X6S,CH5471MEB01    I87 @T6G_MB_LIB.T6G(SCH_1):PAGE411
  C658    1      A Q_CAP_C0201-0.1UF,10V,10%,X7S,CH4102K6E00    I92 @T6G_MB_LIB.T6G(SCH_1):PAGE411
  C659    1      A Q_CAP_C0201-0.1UF,10V,10%,X7S,CH4102K6E00    I93 @T6G_MB_LIB.T6G(SCH_1):PAGE411
  C660    1      A Q_CAP_0201-1UF,4V,20%,X6S,CH-10KMEE00    I94 @T6G_MB_LIB.T6G(SCH_1):PAGE411
 C7011    1      A Q_CAPP_SMLF-470UF,2.5V,20%,SPCAP,CH747LM8818    I95 @T6G_MB_LIB.T6G(SCH_1):PAGE411
 C7012    1      A Q_CAPP_SMLF-470UF,2.5V,20%,SPCAP,CH747LM8818    I96 @T6G_MB_LIB.T6G(SCH_1):PAGE411
 C7013    1      A Q_CAP_C0805-100UF,4V,20%,X6S,CH710KMEA01    I97 @T6G_MB_LIB.T6G(SCH_1):PAGE411

P0V9_CPU0_RT1_2A_2D @T6G_MB_LIB.T6G(SCH_1):P0V9_CPU0_RT1_2A_2D
 U6011 BD17 PWR_2A_7 PT5161LRS-PT5161LRS,SMLF,IC,AJ051610U03     I5 @T6G_MB_LIB.T6G(SCH_1):PAGE409
 U6011 BD20 PWR_2A_8 PT5161LRS-PT5161LRS,SMLF,IC,AJ051610U03     I5 @T6G_MB_LIB.T6G(SCH_1):PAGE409
 U6011 DF17 PWR_2A_9 PT5161LRS-PT5161LRS,SMLF,IC,AJ051610U03     I5 @T6G_MB_LIB.T6G(SCH_1):PAGE409
 U6011 DF20 PWR_2A_10 PT5161LRS-PT5161LRS,SMLF,IC,AJ051610U03     I5 @T6G_MB_LIB.T6G(SCH_1):PAGE409
 R1010    2      B Q_RES_0603LF-0,5%,1/4W,EMPTY,CS00006J900    I10 @T6G_MB_LIB.T6G(SCH_1):PAGE411
  C617    1      A Q_CAP_C0201-0.1UF,10V,10%,X7S,CH4102K6E00    I32 @T6G_MB_LIB.T6G(SCH_1):PAGE411
  C623    1      A Q_CAP_C0201-0.1UF,10V,10%,X7S,CH4102K6E00    I34 @T6G_MB_LIB.T6G(SCH_1):PAGE411
 R1011    1      A Q_RES_0603LF-0,5%,1/4W,CHIP,CS00006J900    I36 @T6G_MB_LIB.T6G(SCH_1):PAGE411
  C621    1      A Q_CAP_0201-1UF,4V,20%,X6S,CH-10KMEE00    I90 @T6G_MB_LIB.T6G(SCH_1):PAGE411
  C624    1      A Q_CAP_0201-1UF,4V,20%,X6S,CH-10KMEE00    I91 @T6G_MB_LIB.T6G(SCH_1):PAGE411

P0V9_CPU0_RT2_2A @T6G_MB_LIB.T6G(SCH_1):P0V9_CPU0_RT2_2A
 U6012 AC17 PWR_2A_1 PT5161LRS-PT5161LRS,SMLF,IC,AJ051610U03     I6 @T6G_MB_LIB.T6G(SCH_1):PAGE420
 U6012 AC20 PWR_2A_2 PT5161LRS-PT5161LRS,SMLF,IC,AJ051610U03     I6 @T6G_MB_LIB.T6G(SCH_1):PAGE420
 U6012 AK17 PWR_2A_3 PT5161LRS-PT5161LRS,SMLF,IC,AJ051610U03     I6 @T6G_MB_LIB.T6G(SCH_1):PAGE420
 U6012 AK20 PWR_2A_4 PT5161LRS-PT5161LRS,SMLF,IC,AJ051610U03     I6 @T6G_MB_LIB.T6G(SCH_1):PAGE420
 U6012 AU17 PWR_2A_5 PT5161LRS-PT5161LRS,SMLF,IC,AJ051610U03     I6 @T6G_MB_LIB.T6G(SCH_1):PAGE420
 U6012 AU20 PWR_2A_6 PT5161LRS-PT5161LRS,SMLF,IC,AJ051610U03     I6 @T6G_MB_LIB.T6G(SCH_1):PAGE420
 U6012 DN17 PWR_2A_11 PT5161LRS-PT5161LRS,SMLF,IC,AJ051610U03     I6 @T6G_MB_LIB.T6G(SCH_1):PAGE420
 U6012 DN20 PWR_2A_12 PT5161LRS-PT5161LRS,SMLF,IC,AJ051610U03     I6 @T6G_MB_LIB.T6G(SCH_1):PAGE420
 U6012 DY17 PWR_2A_13 PT5161LRS-PT5161LRS,SMLF,IC,AJ051610U03     I6 @T6G_MB_LIB.T6G(SCH_1):PAGE420
 U6012 DY20 PWR_2A_14 PT5161LRS-PT5161LRS,SMLF,IC,AJ051610U03     I6 @T6G_MB_LIB.T6G(SCH_1):PAGE420
 U6012 EG17 PWR_2A_15 PT5161LRS-PT5161LRS,SMLF,IC,AJ051610U03     I6 @T6G_MB_LIB.T6G(SCH_1):PAGE420
 U6012 EG20 PWR_2A_16 PT5161LRS-PT5161LRS,SMLF,IC,AJ051610U03     I6 @T6G_MB_LIB.T6G(SCH_1):PAGE420
 U6012 EP17 PWR_2A_17 PT5161LRS-PT5161LRS,SMLF,IC,AJ051610U03     I6 @T6G_MB_LIB.T6G(SCH_1):PAGE420
 U6012 EP20 PWR_2A_18 PT5161LRS-PT5161LRS,SMLF,IC,AJ051610U03     I6 @T6G_MB_LIB.T6G(SCH_1):PAGE420
 U6012  T17 PWR_2A_19 PT5161LRS-PT5161LRS,SMLF,IC,AJ051610U03     I6 @T6G_MB_LIB.T6G(SCH_1):PAGE420
 U6012  T20 PWR_2A_20 PT5161LRS-PT5161LRS,SMLF,IC,AJ051610U03     I6 @T6G_MB_LIB.T6G(SCH_1):PAGE420
 R1053    2      B Q_RES_0603LF-0,5%,1/4W,CHIP,CS00006J900    I22 @T6G_MB_LIB.T6G(SCH_1):PAGE422
   L21    2      2 Q_INDUCTOR_SMLF-100NH/16A,IND,CV+10G0MZ04    I30 @T6G_MB_LIB.T6G(SCH_1):PAGE422
  C982    1      A Q_CAP_C0201-0.1UF,10V,10%,X7S,CH4102K6E00    I34 @T6G_MB_LIB.T6G(SCH_1):PAGE422
  C984    1      A Q_CAP_C0201-0.1UF,10V,10%,X7S,CH4102K6E00    I35 @T6G_MB_LIB.T6G(SCH_1):PAGE422
  C790    1      A Q_CAP_C0201-0.1UF,10V,10%,X7S,CH4102K6E00    I40 @T6G_MB_LIB.T6G(SCH_1):PAGE422
  C987    1      A Q_CAP_C0201-0.1UF,10V,10%,X7S,CH4102K6E00    I41 @T6G_MB_LIB.T6G(SCH_1):PAGE422
  C800    1      A Q_CAP_C0201-0.1UF,10V,10%,X7S,CH4102K6E00    I42 @T6G_MB_LIB.T6G(SCH_1):PAGE422
  C784    1      A Q_CAP_C0201-0.1UF,10V,10%,X7S,CH4102K6E00    I43 @T6G_MB_LIB.T6G(SCH_1):PAGE422
  C797    1      A Q_CAP_0201-1UF,4V,20%,X6S,CH-10KMEE00    I44 @T6G_MB_LIB.T6G(SCH_1):PAGE422
  C781    1      A Q_CAP_0201-1UF,4V,20%,X6S,CH-10KMEE00    I45 @T6G_MB_LIB.T6G(SCH_1):PAGE422
  C788    1      A Q_CAP_0201-1UF,4V,20%,X6S,CH-10KMEE00    I46 @T6G_MB_LIB.T6G(SCH_1):PAGE422
  C796    1      A Q_CAP_C0402-10UF,6.3V,20%,X6S,CH6101MEB01    I47 @T6G_MB_LIB.T6G(SCH_1):PAGE422
  C795    1      A Q_CAP_C0805-100UF,4V,20%,X6S,CH710KMEA01    I48 @T6G_MB_LIB.T6G(SCH_1):PAGE422
  C981    1      A Q_CAP_0402-4.7UF,6.3V,20%,X6S,CH5471MEB01    I49 @T6G_MB_LIB.T6G(SCH_1):PAGE422
  C798    1      A Q_CAP_C0805-100UF,4V,20%,X6S,CH710KMEA01    I50 @T6G_MB_LIB.T6G(SCH_1):PAGE422
  C802    1      A Q_CAP_C0805-100UF,4V,20%,X6S,CH710KMEA01    I51 @T6G_MB_LIB.T6G(SCH_1):PAGE422
  C792    1      A Q_CAP_0201-1UF,4V,20%,X6S,CH-10KMEE00    I52 @T6G_MB_LIB.T6G(SCH_1):PAGE422
  C975    1      A Q_CAP_0201-1UF,4V,20%,X6S,CH-10KMEE00    I54 @T6G_MB_LIB.T6G(SCH_1):PAGE422
  C979    1      A Q_CAP_0201-1UF,4V,20%,X6S,CH-10KMEE00    I55 @T6G_MB_LIB.T6G(SCH_1):PAGE422
  C967    1      A Q_CAP_0402-4.7UF,6.3V,20%,X6S,CH5471MEB01    I56 @T6G_MB_LIB.T6G(SCH_1):PAGE422
  C970    1      A Q_CAP_0402-4.7UF,6.3V,20%,X6S,CH5471MEB01    I57 @T6G_MB_LIB.T6G(SCH_1):PAGE422
  C966    1      A Q_CAP_C0805-100UF,4V,20%,X6S,CH710KMEA01    I58 @T6G_MB_LIB.T6G(SCH_1):PAGE422
  C969    1      A Q_CAP_C0402-22UF,4V,20%,X6S,CH622KMEB02    I59 @T6G_MB_LIB.T6G(SCH_1):PAGE422
  C977    1      A Q_CAP_0402-4.7UF,6.3V,20%,X6S,CH5471MEB01    I60 @T6G_MB_LIB.T6G(SCH_1):PAGE422
  C978    1      A Q_CAP_0201-1UF,4V,20%,X6S,CH-10KMEE00    I61 @T6G_MB_LIB.T6G(SCH_1):PAGE422
  C783    1      A Q_CAP_0201-1UF,4V,20%,X6S,CH-10KMEE00    I62 @T6G_MB_LIB.T6G(SCH_1):PAGE422
  C988    1      A Q_CAP_C0402-22UF,4V,20%,X6S,CH622KMEB02    I63 @T6G_MB_LIB.T6G(SCH_1):PAGE422
  C974    1      A Q_CAP_C0402-22UF,4V,20%,X6S,CH622KMEB02    I64 @T6G_MB_LIB.T6G(SCH_1):PAGE422
  C799    1      A Q_CAP_C0402-22UF,4V,20%,X6S,CH622KMEB02    I65 @T6G_MB_LIB.T6G(SCH_1):PAGE422
  C983    1      A Q_CAP_0201-1UF,4V,20%,X6S,CH-10KMEE00    I66 @T6G_MB_LIB.T6G(SCH_1):PAGE422
  C804    1      A Q_CAP_C0201-0.1UF,10V,10%,X7S,CH4102K6E00    I68 @T6G_MB_LIB.T6G(SCH_1):PAGE422
  C968    1      A Q_CAP_C0201-0.1UF,10V,10%,X7S,CH4102K6E00    I69 @T6G_MB_LIB.T6G(SCH_1):PAGE422
  C786    1      A Q_CAP_0201-1UF,4V,20%,X6S,CH-10KMEE00    I72 @T6G_MB_LIB.T6G(SCH_1):PAGE422
  C779    1      A Q_CAP_0201-1UF,4V,20%,X6S,CH-10KMEE00    I73 @T6G_MB_LIB.T6G(SCH_1):PAGE422
  C986    1      A Q_CAP_C0402-10UF,6.3V,20%,X6S,CH6101MEB01    I74 @T6G_MB_LIB.T6G(SCH_1):PAGE422
  C973    1      A Q_CAP_C0402-10UF,6.3V,20%,X6S,CH6101MEB01    I75 @T6G_MB_LIB.T6G(SCH_1):PAGE422
  C803    1      A Q_CAP_C0402-10UF,6.3V,20%,X6S,CH6101MEB01    I87 @T6G_MB_LIB.T6G(SCH_1):PAGE422
  C972    1      A Q_CAP_C0201-0.1UF,10V,10%,X7S,CH4102K6E00    I92 @T6G_MB_LIB.T6G(SCH_1):PAGE422
  C985    1      A Q_CAP_C0201-0.1UF,10V,10%,X7S,CH4102K6E00    I93 @T6G_MB_LIB.T6G(SCH_1):PAGE422
 C7014    1      A Q_CAPP_SMLF-470UF,2.5V,20%,SPCAP,CH747LM8818    I94 @T6G_MB_LIB.T6G(SCH_1):PAGE422
 C7015    1      A Q_CAPP_SMLF-470UF,2.5V,20%,SPCAP,CH747LM8818    I95 @T6G_MB_LIB.T6G(SCH_1):PAGE422
 C7016    1      A Q_CAP_C0805-100UF,4V,20%,X6S,CH710KMEA01    I96 @T6G_MB_LIB.T6G(SCH_1):PAGE422

P0V9_CPU0_RT2_2A_2D @T6G_MB_LIB.T6G(SCH_1):P0V9_CPU0_RT2_2A_2D
 U6012 BD17 PWR_2A_7 PT5161LRS-PT5161LRS,SMLF,IC,AJ051610U03     I6 @T6G_MB_LIB.T6G(SCH_1):PAGE420
 U6012 BD20 PWR_2A_8 PT5161LRS-PT5161LRS,SMLF,IC,AJ051610U03     I6 @T6G_MB_LIB.T6G(SCH_1):PAGE420
 U6012 DF17 PWR_2A_9 PT5161LRS-PT5161LRS,SMLF,IC,AJ051610U03     I6 @T6G_MB_LIB.T6G(SCH_1):PAGE420
 U6012 DF20 PWR_2A_10 PT5161LRS-PT5161LRS,SMLF,IC,AJ051610U03     I6 @T6G_MB_LIB.T6G(SCH_1):PAGE420
 R1051    2      B Q_RES_0603LF-0,5%,1/4W,EMPTY,CS00006J900    I21 @T6G_MB_LIB.T6G(SCH_1):PAGE422
 R1053    1      A Q_RES_0603LF-0,5%,1/4W,CHIP,CS00006J900    I22 @T6G_MB_LIB.T6G(SCH_1):PAGE422
  C791    1      A Q_CAP_C0201-0.1UF,10V,10%,X7S,CH4102K6E00    I36 @T6G_MB_LIB.T6G(SCH_1):PAGE422
  C794    1      A Q_CAP_C0201-0.1UF,10V,10%,X7S,CH4102K6E00    I39 @T6G_MB_LIB.T6G(SCH_1):PAGE422
  C787    1      A Q_CAP_0201-1UF,4V,20%,X6S,CH-10KMEE00    I90 @T6G_MB_LIB.T6G(SCH_1):PAGE422
  C793    1      A Q_CAP_0201-1UF,4V,20%,X6S,CH-10KMEE00    I91 @T6G_MB_LIB.T6G(SCH_1):PAGE422

P0V9_CPU0_RT3_2A @T6G_MB_LIB.T6G(SCH_1):P0V9_CPU0_RT3_2A
 U6013 AC17 PWR_2A_1 PT5161LRS-PT5161LRS,SMLF,IC,AJ051610U03     I6 @T6G_MB_LIB.T6G(SCH_1):PAGE431
 U6013 AC20 PWR_2A_2 PT5161LRS-PT5161LRS,SMLF,IC,AJ051610U03     I6 @T6G_MB_LIB.T6G(SCH_1):PAGE431
 U6013 AK17 PWR_2A_3 PT5161LRS-PT5161LRS,SMLF,IC,AJ051610U03     I6 @T6G_MB_LIB.T6G(SCH_1):PAGE431
 U6013 AK20 PWR_2A_4 PT5161LRS-PT5161LRS,SMLF,IC,AJ051610U03     I6 @T6G_MB_LIB.T6G(SCH_1):PAGE431
 U6013 AU17 PWR_2A_5 PT5161LRS-PT5161LRS,SMLF,IC,AJ051610U03     I6 @T6G_MB_LIB.T6G(SCH_1):PAGE431
 U6013 AU20 PWR_2A_6 PT5161LRS-PT5161LRS,SMLF,IC,AJ051610U03     I6 @T6G_MB_LIB.T6G(SCH_1):PAGE431
 U6013 DN17 PWR_2A_11 PT5161LRS-PT5161LRS,SMLF,IC,AJ051610U03     I6 @T6G_MB_LIB.T6G(SCH_1):PAGE431
 U6013 DN20 PWR_2A_12 PT5161LRS-PT5161LRS,SMLF,IC,AJ051610U03     I6 @T6G_MB_LIB.T6G(SCH_1):PAGE431
 U6013 DY17 PWR_2A_13 PT5161LRS-PT5161LRS,SMLF,IC,AJ051610U03     I6 @T6G_MB_LIB.T6G(SCH_1):PAGE431
 U6013 DY20 PWR_2A_14 PT5161LRS-PT5161LRS,SMLF,IC,AJ051610U03     I6 @T6G_MB_LIB.T6G(SCH_1):PAGE431
 U6013 EG17 PWR_2A_15 PT5161LRS-PT5161LRS,SMLF,IC,AJ051610U03     I6 @T6G_MB_LIB.T6G(SCH_1):PAGE431
 U6013 EG20 PWR_2A_16 PT5161LRS-PT5161LRS,SMLF,IC,AJ051610U03     I6 @T6G_MB_LIB.T6G(SCH_1):PAGE431
 U6013 EP17 PWR_2A_17 PT5161LRS-PT5161LRS,SMLF,IC,AJ051610U03     I6 @T6G_MB_LIB.T6G(SCH_1):PAGE431
 U6013 EP20 PWR_2A_18 PT5161LRS-PT5161LRS,SMLF,IC,AJ051610U03     I6 @T6G_MB_LIB.T6G(SCH_1):PAGE431
 U6013  T17 PWR_2A_19 PT5161LRS-PT5161LRS,SMLF,IC,AJ051610U03     I6 @T6G_MB_LIB.T6G(SCH_1):PAGE431
 U6013  T20 PWR_2A_20 PT5161LRS-PT5161LRS,SMLF,IC,AJ051610U03     I6 @T6G_MB_LIB.T6G(SCH_1):PAGE431
 R1095    2      B Q_RES_0603LF-0,5%,1/4W,CHIP,CS00006J900    I36 @T6G_MB_LIB.T6G(SCH_1):PAGE433
 C1024    1      A Q_CAP_0201-1UF,4V,20%,X6S,CH-10KMEE00    I37 @T6G_MB_LIB.T6G(SCH_1):PAGE433
 C1027    1      A Q_CAP_0201-1UF,4V,20%,X6S,CH-10KMEE00    I38 @T6G_MB_LIB.T6G(SCH_1):PAGE433
 C1023    1      A Q_CAP_C0402-10UF,6.3V,20%,X6S,CH6101MEB01    I39 @T6G_MB_LIB.T6G(SCH_1):PAGE433
 C1036    1      A Q_CAP_C0402-10UF,6.3V,20%,X6S,CH6101MEB01    I40 @T6G_MB_LIB.T6G(SCH_1):PAGE433
 C1010    1      A Q_CAP_C0201-0.1UF,10V,10%,X7S,CH4102K6E00    I41 @T6G_MB_LIB.T6G(SCH_1):PAGE433
 C1052    1      A Q_CAP_C0201-0.1UF,10V,10%,X7S,CH4102K6E00    I42 @T6G_MB_LIB.T6G(SCH_1):PAGE433
 C1055    1      A Q_CAP_C0201-0.1UF,10V,10%,X7S,CH4102K6E00    I43 @T6G_MB_LIB.T6G(SCH_1):PAGE433
 C1035    1      A Q_CAP_C0201-0.1UF,10V,10%,X7S,CH4102K6E00    I44 @T6G_MB_LIB.T6G(SCH_1):PAGE433
 C1031    1      A Q_CAP_0201-1UF,4V,20%,X6S,CH-10KMEE00    I45 @T6G_MB_LIB.T6G(SCH_1):PAGE433
 C1006    1      A Q_CAP_0201-1UF,4V,20%,X6S,CH-10KMEE00    I46 @T6G_MB_LIB.T6G(SCH_1):PAGE433
 C1034    1      A Q_CAP_0402-4.7UF,6.3V,20%,X6S,CH5471MEB01    I47 @T6G_MB_LIB.T6G(SCH_1):PAGE433
 C1039    1      A Q_CAP_0201-1UF,4V,20%,X6S,CH-10KMEE00    I48 @T6G_MB_LIB.T6G(SCH_1):PAGE433
 C1015    1      A Q_CAP_0201-1UF,4V,20%,X6S,CH-10KMEE00    I49 @T6G_MB_LIB.T6G(SCH_1):PAGE433
 C1054    1      A Q_CAP_0402-4.7UF,6.3V,20%,X6S,CH5471MEB01    I50 @T6G_MB_LIB.T6G(SCH_1):PAGE433
 C1056    1      A Q_CAP_0402-4.7UF,6.3V,20%,X6S,CH5471MEB01    I51 @T6G_MB_LIB.T6G(SCH_1):PAGE433
 C1008    1      A Q_CAP_C0201-0.1UF,10V,10%,X7S,CH4102K6E00    I52 @T6G_MB_LIB.T6G(SCH_1):PAGE433
 C1011    1      A Q_CAP_C0201-0.1UF,10V,10%,X7S,CH4102K6E00    I53 @T6G_MB_LIB.T6G(SCH_1):PAGE433
 C1043    1      A Q_CAP_C0201-0.1UF,10V,10%,X7S,CH4102K6E00    I54 @T6G_MB_LIB.T6G(SCH_1):PAGE433
 C1047    1      A Q_CAP_C0201-0.1UF,10V,10%,X7S,CH4102K6E00    I56 @T6G_MB_LIB.T6G(SCH_1):PAGE433
 C1019    1      A Q_CAP_0201-1UF,4V,20%,X6S,CH-10KMEE00    I57 @T6G_MB_LIB.T6G(SCH_1):PAGE433
 C1046    1      A Q_CAP_0201-1UF,4V,20%,X6S,CH-10KMEE00    I59 @T6G_MB_LIB.T6G(SCH_1):PAGE433
 C1050    1      A Q_CAP_0201-1UF,4V,20%,X6S,CH-10KMEE00    I60 @T6G_MB_LIB.T6G(SCH_1):PAGE433
 C1013    1      A Q_CAP_0201-1UF,4V,20%,X6S,CH-10KMEE00    I62 @T6G_MB_LIB.T6G(SCH_1):PAGE433
 C1017    1      A Q_CAP_0201-1UF,4V,20%,X6S,CH-10KMEE00    I63 @T6G_MB_LIB.T6G(SCH_1):PAGE433
   L23    2      2 Q_INDUCTOR_SMLF-100NH/16A,IND,CV+10G0MZ04    I65 @T6G_MB_LIB.T6G(SCH_1):PAGE433
 C1022    1      A Q_CAP_C0805-100UF,4V,20%,X6S,CH710KMEA01    I66 @T6G_MB_LIB.T6G(SCH_1):PAGE433
 C1025    1      A Q_CAP_C0805-100UF,4V,20%,X6S,CH710KMEA01    I67 @T6G_MB_LIB.T6G(SCH_1):PAGE433
 C1029    1      A Q_CAP_C0805-100UF,4V,20%,X6S,CH710KMEA01    I70 @T6G_MB_LIB.T6G(SCH_1):PAGE433
 C1033    1      A Q_CAP_C0805-100UF,4V,20%,X6S,CH710KMEA01    I71 @T6G_MB_LIB.T6G(SCH_1):PAGE433
 C1026    1      A Q_CAP_C0402-22UF,4V,20%,X6S,CH622KMEB02    I72 @T6G_MB_LIB.T6G(SCH_1):PAGE433
 C1030    1      A Q_CAP_C0402-22UF,4V,20%,X6S,CH622KMEB02    I77 @T6G_MB_LIB.T6G(SCH_1):PAGE433
 C1041    1      A Q_CAP_C0402-22UF,4V,20%,X6S,CH622KMEB02    I78 @T6G_MB_LIB.T6G(SCH_1):PAGE433
 C1037    1      A Q_CAP_C0402-10UF,6.3V,20%,X6S,CH6101MEB01    I79 @T6G_MB_LIB.T6G(SCH_1):PAGE433
 C1049    1      A Q_CAP_C0402-10UF,6.3V,20%,X6S,CH6101MEB01    I80 @T6G_MB_LIB.T6G(SCH_1):PAGE433
 C1040    1      A Q_CAP_C0402-22UF,4V,20%,X6S,CH622KMEB02    I86 @T6G_MB_LIB.T6G(SCH_1):PAGE433
 C1045    1      A Q_CAP_0402-4.7UF,6.3V,20%,X6S,CH5471MEB01    I87 @T6G_MB_LIB.T6G(SCH_1):PAGE433
 C1051    1      A Q_CAP_C0201-0.1UF,10V,10%,X7S,CH4102K6E00    I92 @T6G_MB_LIB.T6G(SCH_1):PAGE433
 C1053    1      A Q_CAP_C0201-0.1UF,10V,10%,X7S,CH4102K6E00    I93 @T6G_MB_LIB.T6G(SCH_1):PAGE433
 C7017    1      A Q_CAPP_SMLF-470UF,2.5V,20%,SPCAP,CH747LM8818    I94 @T6G_MB_LIB.T6G(SCH_1):PAGE433
 C7018    1      A Q_CAPP_SMLF-470UF,2.5V,20%,SPCAP,CH747LM8818    I95 @T6G_MB_LIB.T6G(SCH_1):PAGE433
 C7019    1      A Q_CAP_C0805-100UF,4V,20%,X6S,CH710KMEA01    I96 @T6G_MB_LIB.T6G(SCH_1):PAGE433

P0V9_CPU0_RT3_2A_2D @T6G_MB_LIB.T6G(SCH_1):P0V9_CPU0_RT3_2A_2D
 U6013 BD17 PWR_2A_7 PT5161LRS-PT5161LRS,SMLF,IC,AJ051610U03     I6 @T6G_MB_LIB.T6G(SCH_1):PAGE431
 U6013 BD20 PWR_2A_8 PT5161LRS-PT5161LRS,SMLF,IC,AJ051610U03     I6 @T6G_MB_LIB.T6G(SCH_1):PAGE431
 U6013 DF17 PWR_2A_9 PT5161LRS-PT5161LRS,SMLF,IC,AJ051610U03     I6 @T6G_MB_LIB.T6G(SCH_1):PAGE431
 U6013 DF20 PWR_2A_10 PT5161LRS-PT5161LRS,SMLF,IC,AJ051610U03     I6 @T6G_MB_LIB.T6G(SCH_1):PAGE431
 R1094    2      B Q_RES_0603LF-0,5%,1/4W,EMPTY,CS00006J900     I7 @T6G_MB_LIB.T6G(SCH_1):PAGE433
 C1014    1      A Q_CAP_C0201-0.1UF,10V,10%,X7S,CH4102K6E00    I30 @T6G_MB_LIB.T6G(SCH_1):PAGE433
 C1021    1      A Q_CAP_C0201-0.1UF,10V,10%,X7S,CH4102K6E00    I35 @T6G_MB_LIB.T6G(SCH_1):PAGE433
 R1095    1      A Q_RES_0603LF-0,5%,1/4W,CHIP,CS00006J900    I36 @T6G_MB_LIB.T6G(SCH_1):PAGE433
 C1018    1      A Q_CAP_0201-1UF,4V,20%,X6S,CH-10KMEE00    I90 @T6G_MB_LIB.T6G(SCH_1):PAGE433
 C1020    1      A Q_CAP_0201-1UF,4V,20%,X6S,CH-10KMEE00    I91 @T6G_MB_LIB.T6G(SCH_1):PAGE433

P0V9_CPU0_RT_2D @T6G_MB_LIB.T6G(SCH_1):P0V9_CPU0_RT_2D
PR6530    2      B Q_RES_0402LF-49.9,1%,1/16W,CHIP,CS04992FB07    I34 @T6G_MB_LIB.T6G(SCH_1):PAGE475
PC6565    1      A Q_CAP_C0402-100NF,50V,10%,X7R,CH4106K1B01    I33 @T6G_MB_LIB.T6G(SCH_1):PAGE476
PL6505    2      2 Q_INDUCTOR_SMLF-120NH/69A,IND,CV+12^0EZ03    I34 @T6G_MB_LIB.T6G(SCH_1):PAGE476
PR6556    2      B Q_RES_0402LF-0,5%,1/16W,CHIP,CS00002JB13    I42 @T6G_MB_LIB.T6G(SCH_1):PAGE476
PR6557    1      A Q_RES_0603LF-499,1%,1/10W,CHIP,CS14993F901   I187 @T6G_MB_LIB.T6G(SCH_1):PAGE476
PC6566_1    1      A Q_CAP_C0805-22UF,4V,20%,X6S,CH622KMEA03   I202 @T6G_MB_LIB.T6G(SCH_1):PAGE476
PC6572    1      A Q_CAPP_SMLF-390UF,2.5V,20%,ALUM,CC7390JMZ13   I222 @T6G_MB_LIB.T6G(SCH_1):PAGE476
PC6567_1    1      A Q_CAP_C0805-22UF,4V,20%,X6S,CH622KMEA03   I223 @T6G_MB_LIB.T6G(SCH_1):PAGE476
PC6568    1      A Q_CAPP_SMLF-470UF,2.5V,20%,SPCAP,CH747LM8818   I224 @T6G_MB_LIB.T6G(SCH_1):PAGE476
PC6569    1      A Q_CAPP_SMLF-470UF,2.5V,20%,SPCAP,CH747LM8818   I225 @T6G_MB_LIB.T6G(SCH_1):PAGE476
PC6570    1      A Q_CAPP_SMLF-470UF,2.5V,20%,SPCAP,CH747LM8818   I226 @T6G_MB_LIB.T6G(SCH_1):PAGE476
PC6571    1      A Q_CAPP_SMLF-390UF,2.5V,20%,ALUM,CC7390JMZ13   I227 @T6G_MB_LIB.T6G(SCH_1):PAGE476
PC6574    1      A Q_CAPP_SMLF-390UF,2.5V,20%,ALUM,CC7390JMZ13   I236 @T6G_MB_LIB.T6G(SCH_1):PAGE476
PC6573    1      A Q_CAPP_SMLF-390UF,2.5V,20%,ALUM,CC7390JMZ13   I238 @T6G_MB_LIB.T6G(SCH_1):PAGE476
 PC534    1      A Q_CAPP_SMLF-470UF,2.5V,20%,SPCAP,CH747LM8818   I239 @T6G_MB_LIB.T6G(SCH_1):PAGE476
PC6811    1      A Q_CAPP_SMLF-470UF,2.5V,20%,SPCAP,CH747LM8818   I247 @T6G_MB_LIB.T6G(SCH_1):PAGE476
PC6812    1      A Q_CAPP_SMLF-470UF,2.5V,20%,SPCAP,CH747LM8818   I248 @T6G_MB_LIB.T6G(SCH_1):PAGE476
PC6587_2    1      A Q_CAP_C0805-22UF,4V,20%,X6S,CH622KMEA03   I250 @T6G_MB_LIB.T6G(SCH_1):PAGE476
PC6586_2    1      A Q_CAP_C0805-22UF,4V,20%,X6S,CH622KMEA03   I251 @T6G_MB_LIB.T6G(SCH_1):PAGE476
PC6806    1      A Q_CAP_C0402-100NF,50V,10%,X7R,CH4106K1B01   I255 @T6G_MB_LIB.T6G(SCH_1):PAGE476
PL6506    2      2 Q_INDUCTOR_SMLF-120NH/69A,IND,CV+12^0EZ03   I257 @T6G_MB_LIB.T6G(SCH_1):PAGE476
PR6564    2      B Q_RES_0402LF-0,5%,1/16W,CHIP,CS00002JB13   I263 @T6G_MB_LIB.T6G(SCH_1):PAGE476
 U6010 BL17 PWR_2D_1 PT5161LRS-PT5161LRS,SMLF,IC,AJ051610U03     I3 @T6G_MB_LIB.T6G(SCH_1):PAGE386
 U6010 BL20 PWR_2D_2 PT5161LRS-PT5161LRS,SMLF,IC,AJ051610U03     I3 @T6G_MB_LIB.T6G(SCH_1):PAGE386
 U6010 CW17 PWR_2D_3 PT5161LRS-PT5161LRS,SMLF,IC,AJ051610U03     I3 @T6G_MB_LIB.T6G(SCH_1):PAGE386
 U6010 CW20 PWR_2D_4 PT5161LRS-PT5161LRS,SMLF,IC,AJ051610U03     I3 @T6G_MB_LIB.T6G(SCH_1):PAGE386
  R961    1      A Q_RES_0603LF-0,5%,1/4W,EMPTY,CS00006J900    I10 @T6G_MB_LIB.T6G(SCH_1):PAGE388
   L12    1      1 Q_INDUCTOR_SMLF-100NH/16A,IND,CV+10G0MZ04    I30 @T6G_MB_LIB.T6G(SCH_1):PAGE388
  C559    1      A Q_CAP_C0805-100UF,4V,20%,X6S,CH710KMEA01    I72 @T6G_MB_LIB.T6G(SCH_1):PAGE388
  C574    1      A Q_CAP_C0402-10UF,6.3V,20%,X6S,CH6101MEB01    I73 @T6G_MB_LIB.T6G(SCH_1):PAGE388
  C563    1      A Q_CAP_C0402-22UF,4V,20%,X6S,CH622KMEB02    I74 @T6G_MB_LIB.T6G(SCH_1):PAGE388
  C569    1      A Q_CAP_0402-4.7UF,6.3V,20%,X6S,CH5471MEB01    I79 @T6G_MB_LIB.T6G(SCH_1):PAGE388
  C528    1      A Q_CAP_0201-1UF,4V,20%,X6S,CH-10KMEE00    I80 @T6G_MB_LIB.T6G(SCH_1):PAGE388
  C522    1      A Q_CAP_C0201-0.1UF,10V,10%,X7S,CH4102K6E00    I81 @T6G_MB_LIB.T6G(SCH_1):PAGE388
  C524    1      A Q_CAP_C0201-0.1UF,10V,10%,X7S,CH4102K6E00    I84 @T6G_MB_LIB.T6G(SCH_1):PAGE388
  C578    1      A Q_CAP_C0201-0.1UF,10V,10%,X7S,CH4102K6E00    I85 @T6G_MB_LIB.T6G(SCH_1):PAGE388
  C540    1      A Q_CAP_C0201-0.1UF,10V,10%,X7S,CH4102K6E00    I87 @T6G_MB_LIB.T6G(SCH_1):PAGE388
 U6011 BL17 PWR_2D_1 PT5161LRS-PT5161LRS,SMLF,IC,AJ051610U03     I5 @T6G_MB_LIB.T6G(SCH_1):PAGE409
 U6011 BL20 PWR_2D_2 PT5161LRS-PT5161LRS,SMLF,IC,AJ051610U03     I5 @T6G_MB_LIB.T6G(SCH_1):PAGE409
 U6011 CW17 PWR_2D_3 PT5161LRS-PT5161LRS,SMLF,IC,AJ051610U03     I5 @T6G_MB_LIB.T6G(SCH_1):PAGE409
 U6011 CW20 PWR_2D_4 PT5161LRS-PT5161LRS,SMLF,IC,AJ051610U03     I5 @T6G_MB_LIB.T6G(SCH_1):PAGE409
 R1010    1      A Q_RES_0603LF-0,5%,1/4W,EMPTY,CS00006J900    I10 @T6G_MB_LIB.T6G(SCH_1):PAGE411
   L14    1      1 Q_INDUCTOR_SMLF-100NH/16A,IND,CV+10G0MZ04    I63 @T6G_MB_LIB.T6G(SCH_1):PAGE411
  C632    1      A Q_CAP_C0805-100UF,4V,20%,X6S,CH710KMEA01    I67 @T6G_MB_LIB.T6G(SCH_1):PAGE411
  C636    1      A Q_CAP_C0402-22UF,4V,20%,X6S,CH622KMEB02    I68 @T6G_MB_LIB.T6G(SCH_1):PAGE411
  C646    1      A Q_CAP_C0402-10UF,6.3V,20%,X6S,CH6101MEB01    I74 @T6G_MB_LIB.T6G(SCH_1):PAGE411
  C651    1      A Q_CAP_0402-4.7UF,6.3V,20%,X6S,CH5471MEB01    I75 @T6G_MB_LIB.T6G(SCH_1):PAGE411
  C655    1      A Q_CAP_0201-1UF,4V,20%,X6S,CH-10KMEE00    I76 @T6G_MB_LIB.T6G(SCH_1):PAGE411
  C608    1      A Q_CAP_C0201-0.1UF,10V,10%,X7S,CH4102K6E00    I81 @T6G_MB_LIB.T6G(SCH_1):PAGE411
  C610    1      A Q_CAP_C0201-0.1UF,10V,10%,X7S,CH4102K6E00    I82 @T6G_MB_LIB.T6G(SCH_1):PAGE411
  C615    1      A Q_CAP_C0201-0.1UF,10V,10%,X7S,CH4102K6E00    I83 @T6G_MB_LIB.T6G(SCH_1):PAGE411
  C619    1      A Q_CAP_C0201-0.1UF,10V,10%,X7S,CH4102K6E00    I84 @T6G_MB_LIB.T6G(SCH_1):PAGE411
 U6012 BL17 PWR_2D_1 PT5161LRS-PT5161LRS,SMLF,IC,AJ051610U03     I6 @T6G_MB_LIB.T6G(SCH_1):PAGE420
 U6012 BL20 PWR_2D_2 PT5161LRS-PT5161LRS,SMLF,IC,AJ051610U03     I6 @T6G_MB_LIB.T6G(SCH_1):PAGE420
 U6012 CW17 PWR_2D_3 PT5161LRS-PT5161LRS,SMLF,IC,AJ051610U03     I6 @T6G_MB_LIB.T6G(SCH_1):PAGE420
 U6012 CW20 PWR_2D_4 PT5161LRS-PT5161LRS,SMLF,IC,AJ051610U03     I6 @T6G_MB_LIB.T6G(SCH_1):PAGE420
 R1051    1      A Q_RES_0603LF-0,5%,1/4W,EMPTY,CS00006J900    I21 @T6G_MB_LIB.T6G(SCH_1):PAGE422
   L21    1      1 Q_INDUCTOR_SMLF-100NH/16A,IND,CV+10G0MZ04    I30 @T6G_MB_LIB.T6G(SCH_1):PAGE422
  C801    1      A Q_CAP_C0805-100UF,4V,20%,X6S,CH710KMEA01    I77 @T6G_MB_LIB.T6G(SCH_1):PAGE422
  C805    1      A Q_CAP_C0402-22UF,4V,20%,X6S,CH622KMEB02    I78 @T6G_MB_LIB.T6G(SCH_1):PAGE422
  C971    1      A Q_CAP_C0402-10UF,6.3V,20%,X6S,CH6101MEB01    I79 @T6G_MB_LIB.T6G(SCH_1):PAGE422
  C976    1      A Q_CAP_0402-4.7UF,6.3V,20%,X6S,CH5471MEB01    I80 @T6G_MB_LIB.T6G(SCH_1):PAGE422
  C980    1      A Q_CAP_0201-1UF,4V,20%,X6S,CH-10KMEE00    I81 @T6G_MB_LIB.T6G(SCH_1):PAGE422
  C780    1      A Q_CAP_C0201-0.1UF,10V,10%,X7S,CH4102K6E00    I82 @T6G_MB_LIB.T6G(SCH_1):PAGE422
  C782    1      A Q_CAP_C0201-0.1UF,10V,10%,X7S,CH4102K6E00    I83 @T6G_MB_LIB.T6G(SCH_1):PAGE422
  C785    1      A Q_CAP_C0201-0.1UF,10V,10%,X7S,CH4102K6E00    I84 @T6G_MB_LIB.T6G(SCH_1):PAGE422
  C789    1      A Q_CAP_C0201-0.1UF,10V,10%,X7S,CH4102K6E00    I86 @T6G_MB_LIB.T6G(SCH_1):PAGE422
 U6013 BL17 PWR_2D_1 PT5161LRS-PT5161LRS,SMLF,IC,AJ051610U03     I6 @T6G_MB_LIB.T6G(SCH_1):PAGE431
 U6013 BL20 PWR_2D_2 PT5161LRS-PT5161LRS,SMLF,IC,AJ051610U03     I6 @T6G_MB_LIB.T6G(SCH_1):PAGE431
 U6013 CW17 PWR_2D_3 PT5161LRS-PT5161LRS,SMLF,IC,AJ051610U03     I6 @T6G_MB_LIB.T6G(SCH_1):PAGE431
 U6013 CW20 PWR_2D_4 PT5161LRS-PT5161LRS,SMLF,IC,AJ051610U03     I6 @T6G_MB_LIB.T6G(SCH_1):PAGE431
 R1094    1      A Q_RES_0603LF-0,5%,1/4W,EMPTY,CS00006J900     I7 @T6G_MB_LIB.T6G(SCH_1):PAGE433
   L23    1      1 Q_INDUCTOR_SMLF-100NH/16A,IND,CV+10G0MZ04    I65 @T6G_MB_LIB.T6G(SCH_1):PAGE433
 C1028    1      A Q_CAP_C0805-100UF,4V,20%,X6S,CH710KMEA01    I69 @T6G_MB_LIB.T6G(SCH_1):PAGE433
 C1044    1      A Q_CAP_C0402-10UF,6.3V,20%,X6S,CH6101MEB01    I73 @T6G_MB_LIB.T6G(SCH_1):PAGE433
 C1032    1      A Q_CAP_C0402-22UF,4V,20%,X6S,CH622KMEB02    I74 @T6G_MB_LIB.T6G(SCH_1):PAGE433
 C1038    1      A Q_CAP_0402-4.7UF,6.3V,20%,X6S,CH5471MEB01    I75 @T6G_MB_LIB.T6G(SCH_1):PAGE433
 C1016    1      A Q_CAP_0201-1UF,4V,20%,X6S,CH-10KMEE00    I76 @T6G_MB_LIB.T6G(SCH_1):PAGE433
 C1007    1      A Q_CAP_C0201-0.1UF,10V,10%,X7S,CH4102K6E00    I81 @T6G_MB_LIB.T6G(SCH_1):PAGE433
 C1009    1      A Q_CAP_C0201-0.1UF,10V,10%,X7S,CH4102K6E00    I82 @T6G_MB_LIB.T6G(SCH_1):PAGE433
 C1012    1      A Q_CAP_C0201-0.1UF,10V,10%,X7S,CH4102K6E00    I84 @T6G_MB_LIB.T6G(SCH_1):PAGE433
 C1048    1      A Q_CAP_C0201-0.1UF,10V,10%,X7S,CH4102K6E00    I85 @T6G_MB_LIB.T6G(SCH_1):PAGE433
PJ09_P0_P    1      1 Q_SHORT_SM-EMPTY,SHORT16   I214 @T6G_MB_LIB.T6G(SCH_1):PAGE475
 C7003    1      A Q_CAP_C0805-47UF,4V,20%,X6S,CH647KMEA04    I95 @T6G_MB_LIB.T6G(SCH_1):PAGE388
 C7002    1      A Q_CAP_C0805-47UF,4V,20%,X6S,CH647KMEA04    I96 @T6G_MB_LIB.T6G(SCH_1):PAGE388
 C7001    1      A Q_CAPP_SMLF-470UF,2.5V,20%,SPCAP,CH747LM8818    I97 @T6G_MB_LIB.T6G(SCH_1):PAGE388
 C7000    1      A Q_CAPP_SMLF-470UF,2.5V,20%,SPCAP,CH747LM8818    I98 @T6G_MB_LIB.T6G(SCH_1):PAGE388
 C7032    1      A Q_CAPP_SMLF-470UF,2.5V,20%,SPCAP,CH747LM8818   I102 @T6G_MB_LIB.T6G(SCH_1):PAGE388
 C7033    1      A Q_CAP_C0805-47UF,4V,20%,X6S,CH647KMEA04   I103 @T6G_MB_LIB.T6G(SCH_1):PAGE388
 C7034    1      A Q_CAP_C0805-47UF,4V,20%,X6S,CH647KMEA04   I104 @T6G_MB_LIB.T6G(SCH_1):PAGE388
 C7035    1      A Q_CAP_C0805-47UF,4V,20%,X6S,CH647KMEA04   I105 @T6G_MB_LIB.T6G(SCH_1):PAGE388
 C7036    1      A Q_CAP_C0805-47UF,4V,20%,X6S,CH647KMEA04   I106 @T6G_MB_LIB.T6G(SCH_1):PAGE388

P0V9_CPU1_RT0_2A @T6G_MB_LIB.T6G(SCH_1):P0V9_CPU1_RT0_2A
 U6014 AC17 PWR_2A_1 PT5161LRS-PT5161LRS,SMLF,IC,AJ051610U03     I1 @T6G_MB_LIB.T6G(SCH_1):PAGE400
 U6014 AC20 PWR_2A_2 PT5161LRS-PT5161LRS,SMLF,IC,AJ051610U03     I1 @T6G_MB_LIB.T6G(SCH_1):PAGE400
 U6014 AK17 PWR_2A_3 PT5161LRS-PT5161LRS,SMLF,IC,AJ051610U03     I1 @T6G_MB_LIB.T6G(SCH_1):PAGE400
 U6014 AK20 PWR_2A_4 PT5161LRS-PT5161LRS,SMLF,IC,AJ051610U03     I1 @T6G_MB_LIB.T6G(SCH_1):PAGE400
 U6014 AU17 PWR_2A_5 PT5161LRS-PT5161LRS,SMLF,IC,AJ051610U03     I1 @T6G_MB_LIB.T6G(SCH_1):PAGE400
 U6014 AU20 PWR_2A_6 PT5161LRS-PT5161LRS,SMLF,IC,AJ051610U03     I1 @T6G_MB_LIB.T6G(SCH_1):PAGE400
 U6014 DN17 PWR_2A_11 PT5161LRS-PT5161LRS,SMLF,IC,AJ051610U03     I1 @T6G_MB_LIB.T6G(SCH_1):PAGE400
 U6014 DN20 PWR_2A_12 PT5161LRS-PT5161LRS,SMLF,IC,AJ051610U03     I1 @T6G_MB_LIB.T6G(SCH_1):PAGE400
 U6014 DY17 PWR_2A_13 PT5161LRS-PT5161LRS,SMLF,IC,AJ051610U03     I1 @T6G_MB_LIB.T6G(SCH_1):PAGE400
 U6014 DY20 PWR_2A_14 PT5161LRS-PT5161LRS,SMLF,IC,AJ051610U03     I1 @T6G_MB_LIB.T6G(SCH_1):PAGE400
 U6014 EG17 PWR_2A_15 PT5161LRS-PT5161LRS,SMLF,IC,AJ051610U03     I1 @T6G_MB_LIB.T6G(SCH_1):PAGE400
 U6014 EG20 PWR_2A_16 PT5161LRS-PT5161LRS,SMLF,IC,AJ051610U03     I1 @T6G_MB_LIB.T6G(SCH_1):PAGE400
 U6014 EP17 PWR_2A_17 PT5161LRS-PT5161LRS,SMLF,IC,AJ051610U03     I1 @T6G_MB_LIB.T6G(SCH_1):PAGE400
 U6014 EP20 PWR_2A_18 PT5161LRS-PT5161LRS,SMLF,IC,AJ051610U03     I1 @T6G_MB_LIB.T6G(SCH_1):PAGE400
 U6014  T17 PWR_2A_19 PT5161LRS-PT5161LRS,SMLF,IC,AJ051610U03     I1 @T6G_MB_LIB.T6G(SCH_1):PAGE400
 U6014  T20 PWR_2A_20 PT5161LRS-PT5161LRS,SMLF,IC,AJ051610U03     I1 @T6G_MB_LIB.T6G(SCH_1):PAGE400
  C222    1      A Q_CAP_0201-1UF,4V,20%,X6S,CH-10KMEE00    I42 @T6G_MB_LIB.T6G(SCH_1):PAGE398
  C220    1      A Q_CAP_C0805-100UF,4V,20%,X6S,CH710KMEA01    I44 @T6G_MB_LIB.T6G(SCH_1):PAGE398
  C135    1      A Q_CAP_0201-1UF,4V,20%,X6S,CH-10KMEE00    I46 @T6G_MB_LIB.T6G(SCH_1):PAGE398
  C243    1      A Q_CAP_0201-1UF,4V,20%,X6S,CH-10KMEE00    I47 @T6G_MB_LIB.T6G(SCH_1):PAGE398
  C138    1      A Q_CAP_0201-1UF,4V,20%,X6S,CH-10KMEE00    I48 @T6G_MB_LIB.T6G(SCH_1):PAGE398
  C257    1      A Q_CAP_0201-1UF,4V,20%,X6S,CH-10KMEE00    I49 @T6G_MB_LIB.T6G(SCH_1):PAGE398
  C221    1      A Q_CAP_0402-4.7UF,6.3V,20%,X6S,CH5471MEB01    I50 @T6G_MB_LIB.T6G(SCH_1):PAGE398
  C258    1      A Q_CAP_0402-4.7UF,6.3V,20%,X6S,CH5471MEB01    I51 @T6G_MB_LIB.T6G(SCH_1):PAGE398
  C225    1      A Q_CAP_C0805-100UF,4V,20%,X6S,CH710KMEA01    I52 @T6G_MB_LIB.T6G(SCH_1):PAGE398
  C240    1      A Q_CAP_C0805-100UF,4V,20%,X6S,CH710KMEA01    I53 @T6G_MB_LIB.T6G(SCH_1):PAGE398
  C284    1      A Q_CAP_C0402-22UF,4V,20%,X6S,CH622KMEB02    I54 @T6G_MB_LIB.T6G(SCH_1):PAGE398
  C188    1      A Q_CAP_0201-1UF,4V,20%,X6S,CH-10KMEE00    I55 @T6G_MB_LIB.T6G(SCH_1):PAGE398
  C265    1      A Q_CAP_0201-1UF,4V,20%,X6S,CH-10KMEE00    I56 @T6G_MB_LIB.T6G(SCH_1):PAGE398
  C227    1      A Q_CAP_0402-4.7UF,6.3V,20%,X6S,CH5471MEB01    I57 @T6G_MB_LIB.T6G(SCH_1):PAGE398
  C186    1      A Q_CAP_0201-1UF,4V,20%,X6S,CH-10KMEE00    I58 @T6G_MB_LIB.T6G(SCH_1):PAGE398
  C280    1      A Q_CAP_0201-1UF,4V,20%,X6S,CH-10KMEE00    I59 @T6G_MB_LIB.T6G(SCH_1):PAGE398
  C190    1      A Q_CAP_0201-1UF,4V,20%,X6S,CH-10KMEE00    I62 @T6G_MB_LIB.T6G(SCH_1):PAGE398
  C285    1      A Q_CAP_0201-1UF,4V,20%,X6S,CH-10KMEE00    I63 @T6G_MB_LIB.T6G(SCH_1):PAGE398
  C255    1      A Q_CAP_C0402-22UF,4V,20%,X6S,CH622KMEB02    I64 @T6G_MB_LIB.T6G(SCH_1):PAGE398
  C262    1      A Q_CAP_C0402-22UF,4V,20%,X6S,CH622KMEB02    I65 @T6G_MB_LIB.T6G(SCH_1):PAGE398
  C259    1      A Q_CAP_C0402-22UF,4V,20%,X6S,CH622KMEB02    I66 @T6G_MB_LIB.T6G(SCH_1):PAGE398
  C254    1      A Q_CAP_C0402-10UF,6.3V,20%,X6S,CH6101MEB01    I67 @T6G_MB_LIB.T6G(SCH_1):PAGE398
  C286    1      A Q_CAP_C0402-10UF,6.3V,20%,X6S,CH6101MEB01    I68 @T6G_MB_LIB.T6G(SCH_1):PAGE398
  C250    1      A Q_CAP_C0402-10UF,6.3V,20%,X6S,CH6101MEB01    I70 @T6G_MB_LIB.T6G(SCH_1):PAGE398
  C269    1      A Q_CAP_C0402-10UF,6.3V,20%,X6S,CH6101MEB01    I71 @T6G_MB_LIB.T6G(SCH_1):PAGE398
  C241    1      A Q_CAP_0402-4.7UF,6.3V,20%,X6S,CH5471MEB01    I72 @T6G_MB_LIB.T6G(SCH_1):PAGE398
  C247    1      A Q_CAP_C0805-100UF,4V,20%,X6S,CH710KMEA01    I73 @T6G_MB_LIB.T6G(SCH_1):PAGE398
    L4    2      2 Q_INDUCTOR_SMLF-100NH/16A,IND,CV+10G0MZ04    I74 @T6G_MB_LIB.T6G(SCH_1):PAGE398
  C282    1      A Q_CAP_C0201-0.1UF,10V,10%,X7S,CH4102K6E00    I80 @T6G_MB_LIB.T6G(SCH_1):PAGE398
  C264    1      A Q_CAP_C0201-0.1UF,10V,10%,X7S,CH4102K6E00    I81 @T6G_MB_LIB.T6G(SCH_1):PAGE398
  C141    1      A Q_CAP_C0201-0.1UF,10V,10%,X7S,CH4102K6E00    I82 @T6G_MB_LIB.T6G(SCH_1):PAGE398
  C192    1      A Q_CAP_C0201-0.1UF,10V,10%,X7S,CH4102K6E00    I83 @T6G_MB_LIB.T6G(SCH_1):PAGE398
  C260    1      A Q_CAP_C0201-0.1UF,10V,10%,X7S,CH4102K6E00    I84 @T6G_MB_LIB.T6G(SCH_1):PAGE398
  C184    1      A Q_CAP_C0201-0.1UF,10V,10%,X7S,CH4102K6E00    I85 @T6G_MB_LIB.T6G(SCH_1):PAGE398
  C253    1      A Q_CAP_C0201-0.1UF,10V,10%,X7S,CH4102K6E00    I86 @T6G_MB_LIB.T6G(SCH_1):PAGE398
  C228    1      A Q_CAP_C0201-0.1UF,10V,10%,X7S,CH4102K6E00    I87 @T6G_MB_LIB.T6G(SCH_1):PAGE398
 R6705    2      B Q_RES_0603LF-0,5%,1/4W,CHIP,CS00006J900    I95 @T6G_MB_LIB.T6G(SCH_1):PAGE398
  C281    1      A Q_CAP_C0201-0.1UF,10V,10%,X7S,CH4102K6E00   I101 @T6G_MB_LIB.T6G(SCH_1):PAGE398
  C283    1      A Q_CAP_C0201-0.1UF,10V,10%,X7S,CH4102K6E00   I102 @T6G_MB_LIB.T6G(SCH_1):PAGE398
 C7020    1      A Q_CAPP_SMLF-470UF,2.5V,20%,SPCAP,CH747LM8818   I103 @T6G_MB_LIB.T6G(SCH_1):PAGE398
 C7021    1      A Q_CAPP_SMLF-470UF,2.5V,20%,SPCAP,CH747LM8818   I104 @T6G_MB_LIB.T6G(SCH_1):PAGE398
 C7022    1      A Q_CAP_C0805-100UF,4V,20%,X6S,CH710KMEA01   I105 @T6G_MB_LIB.T6G(SCH_1):PAGE398

P0V9_CPU1_RT0_2A_2D @T6G_MB_LIB.T6G(SCH_1):P0V9_CPU1_RT0_2A_2D
 U6014 BD17 PWR_2A_7 PT5161LRS-PT5161LRS,SMLF,IC,AJ051610U03     I1 @T6G_MB_LIB.T6G(SCH_1):PAGE400
 U6014 BD20 PWR_2A_8 PT5161LRS-PT5161LRS,SMLF,IC,AJ051610U03     I1 @T6G_MB_LIB.T6G(SCH_1):PAGE400
 U6014 DF17 PWR_2A_9 PT5161LRS-PT5161LRS,SMLF,IC,AJ051610U03     I1 @T6G_MB_LIB.T6G(SCH_1):PAGE400
 U6014 DF20 PWR_2A_10 PT5161LRS-PT5161LRS,SMLF,IC,AJ051610U03     I1 @T6G_MB_LIB.T6G(SCH_1):PAGE400
  C198    1      A Q_CAP_C0201-0.1UF,10V,10%,X7S,CH4102K6E00    I92 @T6G_MB_LIB.T6G(SCH_1):PAGE398
  C191    1      A Q_CAP_C0201-0.1UF,10V,10%,X7S,CH4102K6E00    I93 @T6G_MB_LIB.T6G(SCH_1):PAGE398
 R6705    1      A Q_RES_0603LF-0,5%,1/4W,CHIP,CS00006J900    I95 @T6G_MB_LIB.T6G(SCH_1):PAGE398
 R6704    2      B Q_RES_0603LF-0,5%,1/4W,EMPTY,CS00006J900    I96 @T6G_MB_LIB.T6G(SCH_1):PAGE398
  C187    1      A Q_CAP_0201-1UF,4V,20%,X6S,CH-10KMEE00    I99 @T6G_MB_LIB.T6G(SCH_1):PAGE398
  C201    1      A Q_CAP_0201-1UF,4V,20%,X6S,CH-10KMEE00   I100 @T6G_MB_LIB.T6G(SCH_1):PAGE398

P0V9_CPU1_RT1_2A @T6G_MB_LIB.T6G(SCH_1):P0V9_CPU1_RT1_2A
 U6015 AC17 PWR_2A_1 PT5161LRS-PT5161LRS,SMLF,IC,AJ051610U03     I5 @T6G_MB_LIB.T6G(SCH_1):PAGE391
 U6015 AC20 PWR_2A_2 PT5161LRS-PT5161LRS,SMLF,IC,AJ051610U03     I5 @T6G_MB_LIB.T6G(SCH_1):PAGE391
 U6015 AK17 PWR_2A_3 PT5161LRS-PT5161LRS,SMLF,IC,AJ051610U03     I5 @T6G_MB_LIB.T6G(SCH_1):PAGE391
 U6015 AK20 PWR_2A_4 PT5161LRS-PT5161LRS,SMLF,IC,AJ051610U03     I5 @T6G_MB_LIB.T6G(SCH_1):PAGE391
 U6015 AU17 PWR_2A_5 PT5161LRS-PT5161LRS,SMLF,IC,AJ051610U03     I5 @T6G_MB_LIB.T6G(SCH_1):PAGE391
 U6015 AU20 PWR_2A_6 PT5161LRS-PT5161LRS,SMLF,IC,AJ051610U03     I5 @T6G_MB_LIB.T6G(SCH_1):PAGE391
 U6015 DN17 PWR_2A_11 PT5161LRS-PT5161LRS,SMLF,IC,AJ051610U03     I5 @T6G_MB_LIB.T6G(SCH_1):PAGE391
 U6015 DN20 PWR_2A_12 PT5161LRS-PT5161LRS,SMLF,IC,AJ051610U03     I5 @T6G_MB_LIB.T6G(SCH_1):PAGE391
 U6015 DY17 PWR_2A_13 PT5161LRS-PT5161LRS,SMLF,IC,AJ051610U03     I5 @T6G_MB_LIB.T6G(SCH_1):PAGE391
 U6015 DY20 PWR_2A_14 PT5161LRS-PT5161LRS,SMLF,IC,AJ051610U03     I5 @T6G_MB_LIB.T6G(SCH_1):PAGE391
 U6015 EG17 PWR_2A_15 PT5161LRS-PT5161LRS,SMLF,IC,AJ051610U03     I5 @T6G_MB_LIB.T6G(SCH_1):PAGE391
 U6015 EG20 PWR_2A_16 PT5161LRS-PT5161LRS,SMLF,IC,AJ051610U03     I5 @T6G_MB_LIB.T6G(SCH_1):PAGE391
 U6015 EP17 PWR_2A_17 PT5161LRS-PT5161LRS,SMLF,IC,AJ051610U03     I5 @T6G_MB_LIB.T6G(SCH_1):PAGE391
 U6015 EP20 PWR_2A_18 PT5161LRS-PT5161LRS,SMLF,IC,AJ051610U03     I5 @T6G_MB_LIB.T6G(SCH_1):PAGE391
 U6015  T17 PWR_2A_19 PT5161LRS-PT5161LRS,SMLF,IC,AJ051610U03     I5 @T6G_MB_LIB.T6G(SCH_1):PAGE391
 U6015  T20 PWR_2A_20 PT5161LRS-PT5161LRS,SMLF,IC,AJ051610U03     I5 @T6G_MB_LIB.T6G(SCH_1):PAGE391
  R712    2      B Q_RES_0603LF-0,5%,1/4W,CHIP,CS00006J900    I11 @T6G_MB_LIB.T6G(SCH_1):PAGE443
    L6    2      2 Q_INDUCTOR_SMLF-100NH/16A,IND,CV+10G0MZ04    I30 @T6G_MB_LIB.T6G(SCH_1):PAGE443
  C340    1      A Q_CAP_C0201-0.1UF,10V,10%,X7S,CH4102K6E00    I38 @T6G_MB_LIB.T6G(SCH_1):PAGE443
  C344    1      A Q_CAP_C0201-0.1UF,10V,10%,X7S,CH4102K6E00    I39 @T6G_MB_LIB.T6G(SCH_1):PAGE443
  C294    1      A Q_CAP_0201-1UF,4V,20%,X6S,CH-10KMEE00    I40 @T6G_MB_LIB.T6G(SCH_1):PAGE443
  C332    1      A Q_CAP_C0402-10UF,6.3V,20%,X6S,CH6101MEB01    I41 @T6G_MB_LIB.T6G(SCH_1):PAGE443
  C307    1      A Q_CAP_0201-1UF,4V,20%,X6S,CH-10KMEE00    I42 @T6G_MB_LIB.T6G(SCH_1):PAGE443
  C326    1      A Q_CAP_0201-1UF,4V,20%,X6S,CH-10KMEE00    I43 @T6G_MB_LIB.T6G(SCH_1):PAGE443
  C321    1      A Q_CAP_C0402-10UF,6.3V,20%,X6S,CH6101MEB01    I44 @T6G_MB_LIB.T6G(SCH_1):PAGE443
  C325    1      A Q_CAP_0402-4.7UF,6.3V,20%,X6S,CH5471MEB01    I45 @T6G_MB_LIB.T6G(SCH_1):PAGE443
  C331    1      A Q_CAP_0402-4.7UF,6.3V,20%,X6S,CH5471MEB01    I46 @T6G_MB_LIB.T6G(SCH_1):PAGE443
  C330    1      A Q_CAP_0201-1UF,4V,20%,X6S,CH-10KMEE00    I47 @T6G_MB_LIB.T6G(SCH_1):PAGE443
  C312    1      A Q_CAP_C0201-0.1UF,10V,10%,X7S,CH4102K6E00    I48 @T6G_MB_LIB.T6G(SCH_1):PAGE443
  C349    1      A Q_CAP_C0201-0.1UF,10V,10%,X7S,CH4102K6E00    I49 @T6G_MB_LIB.T6G(SCH_1):PAGE443
  C291    1      A Q_CAP_C0201-0.1UF,10V,10%,X7S,CH4102K6E00    I50 @T6G_MB_LIB.T6G(SCH_1):PAGE443
  C319    1      A Q_CAP_C0201-0.1UF,10V,10%,X7S,CH4102K6E00    I51 @T6G_MB_LIB.T6G(SCH_1):PAGE443
  C314    1      A Q_CAP_0201-1UF,4V,20%,X6S,CH-10KMEE00    I52 @T6G_MB_LIB.T6G(SCH_1):PAGE443
  C337    1      A Q_CAP_0201-1UF,4V,20%,X6S,CH-10KMEE00    I53 @T6G_MB_LIB.T6G(SCH_1):PAGE443
  C343    1      A Q_CAP_0402-4.7UF,6.3V,20%,X6S,CH5471MEB01    I54 @T6G_MB_LIB.T6G(SCH_1):PAGE443
  C336    1      A Q_CAP_0402-4.7UF,6.3V,20%,X6S,CH5471MEB01    I55 @T6G_MB_LIB.T6G(SCH_1):PAGE443
  C346    1      A Q_CAP_0201-1UF,4V,20%,X6S,CH-10KMEE00    I57 @T6G_MB_LIB.T6G(SCH_1):PAGE443
  C293    1      A Q_CAP_0201-1UF,4V,20%,X6S,CH-10KMEE00    I58 @T6G_MB_LIB.T6G(SCH_1):PAGE443
  C301    1      A Q_CAP_0201-1UF,4V,20%,X6S,CH-10KMEE00    I59 @T6G_MB_LIB.T6G(SCH_1):PAGE443
  C322    1      A Q_CAP_C0201-0.1UF,10V,10%,X7S,CH4102K6E00    I60 @T6G_MB_LIB.T6G(SCH_1):PAGE443
  C334    1      A Q_CAP_C0201-0.1UF,10V,10%,X7S,CH4102K6E00    I62 @T6G_MB_LIB.T6G(SCH_1):PAGE443
  C289    1      A Q_CAP_0201-1UF,4V,20%,X6S,CH-10KMEE00    I65 @T6G_MB_LIB.T6G(SCH_1):PAGE443
  C353    1      A Q_CAP_0201-1UF,4V,20%,X6S,CH-10KMEE00    I66 @T6G_MB_LIB.T6G(SCH_1):PAGE443
  C317    1      A Q_CAP_C0805-100UF,4V,20%,X6S,CH710KMEA01    I67 @T6G_MB_LIB.T6G(SCH_1):PAGE443
  C320    1      A Q_CAP_C0805-100UF,4V,20%,X6S,CH710KMEA01    I69 @T6G_MB_LIB.T6G(SCH_1):PAGE443
  C324    1      A Q_CAP_C0805-100UF,4V,20%,X6S,CH710KMEA01    I70 @T6G_MB_LIB.T6G(SCH_1):PAGE443
  C328    1      A Q_CAP_C0805-100UF,4V,20%,X6S,CH710KMEA01    I71 @T6G_MB_LIB.T6G(SCH_1):PAGE443
  C329    1      A Q_CAP_C0402-22UF,4V,20%,X6S,CH622KMEB02    I74 @T6G_MB_LIB.T6G(SCH_1):PAGE443
  C335    1      A Q_CAP_C0402-22UF,4V,20%,X6S,CH622KMEB02    I75 @T6G_MB_LIB.T6G(SCH_1):PAGE443
  C351    1      A Q_CAP_C0402-22UF,4V,20%,X6S,CH622KMEB02    I76 @T6G_MB_LIB.T6G(SCH_1):PAGE443
  C318    1      A Q_CAP_C0402-22UF,4V,20%,X6S,CH622KMEB02    I77 @T6G_MB_LIB.T6G(SCH_1):PAGE443
  C339    1      A Q_CAP_C0402-10UF,6.3V,20%,X6S,CH6101MEB01    I80 @T6G_MB_LIB.T6G(SCH_1):PAGE443
  C354    1      A Q_CAP_C0402-10UF,6.3V,20%,X6S,CH6101MEB01    I81 @T6G_MB_LIB.T6G(SCH_1):PAGE443
  C341    1      A Q_CAP_C0201-0.1UF,10V,10%,X7S,CH4102K6E00    I92 @T6G_MB_LIB.T6G(SCH_1):PAGE443
  C350    1      A Q_CAP_C0201-0.1UF,10V,10%,X7S,CH4102K6E00    I93 @T6G_MB_LIB.T6G(SCH_1):PAGE443
 C7023    1      A Q_CAPP_SMLF-470UF,2.5V,20%,SPCAP,CH747LM8818    I94 @T6G_MB_LIB.T6G(SCH_1):PAGE443
 C7024    1      A Q_CAPP_SMLF-470UF,2.5V,20%,SPCAP,CH747LM8818    I95 @T6G_MB_LIB.T6G(SCH_1):PAGE443
 C7025    1      A Q_CAP_C0805-100UF,4V,20%,X6S,CH710KMEA01    I96 @T6G_MB_LIB.T6G(SCH_1):PAGE443

P0V9_CPU1_RT1_2A_2D @T6G_MB_LIB.T6G(SCH_1):P0V9_CPU1_RT1_2A_2D
 U6015 BD17 PWR_2A_7 PT5161LRS-PT5161LRS,SMLF,IC,AJ051610U03     I5 @T6G_MB_LIB.T6G(SCH_1):PAGE391
 U6015 BD20 PWR_2A_8 PT5161LRS-PT5161LRS,SMLF,IC,AJ051610U03     I5 @T6G_MB_LIB.T6G(SCH_1):PAGE391
 U6015 DF17 PWR_2A_9 PT5161LRS-PT5161LRS,SMLF,IC,AJ051610U03     I5 @T6G_MB_LIB.T6G(SCH_1):PAGE391
 U6015 DF20 PWR_2A_10 PT5161LRS-PT5161LRS,SMLF,IC,AJ051610U03     I5 @T6G_MB_LIB.T6G(SCH_1):PAGE391
  R705    2      B Q_RES_0603LF-0,5%,1/4W,EMPTY,CS00006J900    I10 @T6G_MB_LIB.T6G(SCH_1):PAGE443
  R712    1      A Q_RES_0603LF-0,5%,1/4W,CHIP,CS00006J900    I11 @T6G_MB_LIB.T6G(SCH_1):PAGE443
  C313    1      A Q_CAP_C0201-0.1UF,10V,10%,X7S,CH4102K6E00    I34 @T6G_MB_LIB.T6G(SCH_1):PAGE443
  C316    1      A Q_CAP_C0201-0.1UF,10V,10%,X7S,CH4102K6E00    I37 @T6G_MB_LIB.T6G(SCH_1):PAGE443
  C306    1      A Q_CAP_0201-1UF,4V,20%,X6S,CH-10KMEE00    I90 @T6G_MB_LIB.T6G(SCH_1):PAGE443
  C315    1      A Q_CAP_0201-1UF,4V,20%,X6S,CH-10KMEE00    I91 @T6G_MB_LIB.T6G(SCH_1):PAGE443

P0V9_CPU1_RT2_2A @T6G_MB_LIB.T6G(SCH_1):P0V9_CPU1_RT2_2A
 U6016 AC17 PWR_2A_1 PT5161LRS-PT5161LRS,SMLF,IC,AJ051610U03     I7 @T6G_MB_LIB.T6G(SCH_1):PAGE452
 U6016 AC20 PWR_2A_2 PT5161LRS-PT5161LRS,SMLF,IC,AJ051610U03     I7 @T6G_MB_LIB.T6G(SCH_1):PAGE452
 U6016 AK17 PWR_2A_3 PT5161LRS-PT5161LRS,SMLF,IC,AJ051610U03     I7 @T6G_MB_LIB.T6G(SCH_1):PAGE452
 U6016 AK20 PWR_2A_4 PT5161LRS-PT5161LRS,SMLF,IC,AJ051610U03     I7 @T6G_MB_LIB.T6G(SCH_1):PAGE452
 U6016 AU17 PWR_2A_5 PT5161LRS-PT5161LRS,SMLF,IC,AJ051610U03     I7 @T6G_MB_LIB.T6G(SCH_1):PAGE452
 U6016 AU20 PWR_2A_6 PT5161LRS-PT5161LRS,SMLF,IC,AJ051610U03     I7 @T6G_MB_LIB.T6G(SCH_1):PAGE452
 U6016 DN17 PWR_2A_11 PT5161LRS-PT5161LRS,SMLF,IC,AJ051610U03     I7 @T6G_MB_LIB.T6G(SCH_1):PAGE452
 U6016 DN20 PWR_2A_12 PT5161LRS-PT5161LRS,SMLF,IC,AJ051610U03     I7 @T6G_MB_LIB.T6G(SCH_1):PAGE452
 U6016 DY17 PWR_2A_13 PT5161LRS-PT5161LRS,SMLF,IC,AJ051610U03     I7 @T6G_MB_LIB.T6G(SCH_1):PAGE452
 U6016 DY20 PWR_2A_14 PT5161LRS-PT5161LRS,SMLF,IC,AJ051610U03     I7 @T6G_MB_LIB.T6G(SCH_1):PAGE452
 U6016 EG17 PWR_2A_15 PT5161LRS-PT5161LRS,SMLF,IC,AJ051610U03     I7 @T6G_MB_LIB.T6G(SCH_1):PAGE452
 U6016 EG20 PWR_2A_16 PT5161LRS-PT5161LRS,SMLF,IC,AJ051610U03     I7 @T6G_MB_LIB.T6G(SCH_1):PAGE452
 U6016 EP17 PWR_2A_17 PT5161LRS-PT5161LRS,SMLF,IC,AJ051610U03     I7 @T6G_MB_LIB.T6G(SCH_1):PAGE452
 U6016 EP20 PWR_2A_18 PT5161LRS-PT5161LRS,SMLF,IC,AJ051610U03     I7 @T6G_MB_LIB.T6G(SCH_1):PAGE452
 U6016  T17 PWR_2A_19 PT5161LRS-PT5161LRS,SMLF,IC,AJ051610U03     I7 @T6G_MB_LIB.T6G(SCH_1):PAGE452
 U6016  T20 PWR_2A_20 PT5161LRS-PT5161LRS,SMLF,IC,AJ051610U03     I7 @T6G_MB_LIB.T6G(SCH_1):PAGE452
  C421    1      A Q_CAP_C0201-0.1UF,10V,10%,X7S,CH4102K6E00    I31 @T6G_MB_LIB.T6G(SCH_1):PAGE454
  C427    1      A Q_CAP_C0201-0.1UF,10V,10%,X7S,CH4102K6E00    I37 @T6G_MB_LIB.T6G(SCH_1):PAGE454
  C393    1      A Q_CAP_C0201-0.1UF,10V,10%,X7S,CH4102K6E00    I38 @T6G_MB_LIB.T6G(SCH_1):PAGE454
  C430    1      A Q_CAP_C0201-0.1UF,10V,10%,X7S,CH4102K6E00    I39 @T6G_MB_LIB.T6G(SCH_1):PAGE454
  C400    1      A Q_CAP_C0201-0.1UF,10V,10%,X7S,CH4102K6E00    I40 @T6G_MB_LIB.T6G(SCH_1):PAGE454
  R859    2      B Q_RES_0603LF-0,5%,1/4W,CHIP,CS00006J900    I41 @T6G_MB_LIB.T6G(SCH_1):PAGE454
  C384    1      A Q_CAP_0201-1UF,4V,20%,X6S,CH-10KMEE00    I42 @T6G_MB_LIB.T6G(SCH_1):PAGE454
  C387    1      A Q_CAP_0201-1UF,4V,20%,X6S,CH-10KMEE00    I43 @T6G_MB_LIB.T6G(SCH_1):PAGE454
  C410    1      A Q_CAP_C0402-10UF,6.3V,20%,X6S,CH6101MEB01    I44 @T6G_MB_LIB.T6G(SCH_1):PAGE454
  C420    1      A Q_CAP_C0402-10UF,6.3V,20%,X6S,CH6101MEB01    I45 @T6G_MB_LIB.T6G(SCH_1):PAGE454
  C398    1      A Q_CAP_C0805-100UF,4V,20%,X6S,CH710KMEA01    I46 @T6G_MB_LIB.T6G(SCH_1):PAGE454
  C401    1      A Q_CAP_C0805-100UF,4V,20%,X6S,CH710KMEA01    I47 @T6G_MB_LIB.T6G(SCH_1):PAGE454
  C406    1      A Q_CAP_0402-4.7UF,6.3V,20%,X6S,CH5471MEB01    I48 @T6G_MB_LIB.T6G(SCH_1):PAGE454
  C407    1      A Q_CAP_0201-1UF,4V,20%,X6S,CH-10KMEE00    I49 @T6G_MB_LIB.T6G(SCH_1):PAGE454
  C391    1      A Q_CAP_0201-1UF,4V,20%,X6S,CH-10KMEE00    I50 @T6G_MB_LIB.T6G(SCH_1):PAGE454
  C415    1      A Q_CAP_0201-1UF,4V,20%,X6S,CH-10KMEE00    I51 @T6G_MB_LIB.T6G(SCH_1):PAGE454
  C418    1      A Q_CAP_0201-1UF,4V,20%,X6S,CH-10KMEE00    I52 @T6G_MB_LIB.T6G(SCH_1):PAGE454
  C422    1      A Q_CAP_0201-1UF,4V,20%,X6S,CH-10KMEE00    I53 @T6G_MB_LIB.T6G(SCH_1):PAGE454
  C416    1      A Q_CAP_0402-4.7UF,6.3V,20%,X6S,CH5471MEB01    I54 @T6G_MB_LIB.T6G(SCH_1):PAGE454
  C413    1      A Q_CAP_0402-4.7UF,6.3V,20%,X6S,CH5471MEB01    I55 @T6G_MB_LIB.T6G(SCH_1):PAGE454
  C417    1      A Q_CAP_C0402-22UF,4V,20%,X6S,CH622KMEB02    I56 @T6G_MB_LIB.T6G(SCH_1):PAGE454
  C412    1      A Q_CAP_0402-4.7UF,6.3V,20%,X6S,CH5471MEB01    I57 @T6G_MB_LIB.T6G(SCH_1):PAGE454
  C386    1      A Q_CAP_0201-1UF,4V,20%,X6S,CH-10KMEE00    I58 @T6G_MB_LIB.T6G(SCH_1):PAGE454
  C399    1      A Q_CAP_C0402-22UF,4V,20%,X6S,CH622KMEB02    I59 @T6G_MB_LIB.T6G(SCH_1):PAGE454
  C402    1      A Q_CAP_C0402-22UF,4V,20%,X6S,CH622KMEB02    I60 @T6G_MB_LIB.T6G(SCH_1):PAGE454
  C403    1      A Q_CAP_C0201-0.1UF,10V,10%,X7S,CH4102K6E00    I61 @T6G_MB_LIB.T6G(SCH_1):PAGE454
  C411    1      A Q_CAP_C0201-0.1UF,10V,10%,X7S,CH4102K6E00    I62 @T6G_MB_LIB.T6G(SCH_1):PAGE454
  C395    1      A Q_CAP_C0201-0.1UF,10V,10%,X7S,CH4102K6E00    I64 @T6G_MB_LIB.T6G(SCH_1):PAGE454
  C425    1      A Q_CAP_0201-1UF,4V,20%,X6S,CH-10KMEE00    I67 @T6G_MB_LIB.T6G(SCH_1):PAGE454
  C389    1      A Q_CAP_0201-1UF,4V,20%,X6S,CH-10KMEE00    I68 @T6G_MB_LIB.T6G(SCH_1):PAGE454
  C424    1      A Q_CAP_C0402-22UF,4V,20%,X6S,CH622KMEB02    I69 @T6G_MB_LIB.T6G(SCH_1):PAGE454
  C429    1      A Q_CAP_C0402-10UF,6.3V,20%,X6S,CH6101MEB01    I70 @T6G_MB_LIB.T6G(SCH_1):PAGE454
  C382    1      A Q_CAP_0201-1UF,4V,20%,X6S,CH-10KMEE00    I71 @T6G_MB_LIB.T6G(SCH_1):PAGE454
  C431    1      A Q_CAP_C0402-10UF,6.3V,20%,X6S,CH6101MEB01    I72 @T6G_MB_LIB.T6G(SCH_1):PAGE454
    L8    2      2 Q_INDUCTOR_SMLF-100NH/16A,IND,CV+10G0MZ04    I74 @T6G_MB_LIB.T6G(SCH_1):PAGE454
  C405    1      A Q_CAP_C0805-100UF,4V,20%,X6S,CH710KMEA01    I86 @T6G_MB_LIB.T6G(SCH_1):PAGE454
  C409    1      A Q_CAP_C0805-100UF,4V,20%,X6S,CH710KMEA01    I87 @T6G_MB_LIB.T6G(SCH_1):PAGE454
  C426    1      A Q_CAP_C0201-0.1UF,10V,10%,X7S,CH4102K6E00    I92 @T6G_MB_LIB.T6G(SCH_1):PAGE454
  C428    1      A Q_CAP_C0201-0.1UF,10V,10%,X7S,CH4102K6E00    I93 @T6G_MB_LIB.T6G(SCH_1):PAGE454
 C7026    1      A Q_CAPP_SMLF-470UF,2.5V,20%,SPCAP,CH747LM8818    I98 @T6G_MB_LIB.T6G(SCH_1):PAGE454
 C7027    1      A Q_CAPP_SMLF-470UF,2.5V,20%,SPCAP,CH747LM8818    I99 @T6G_MB_LIB.T6G(SCH_1):PAGE454
 C7028    1      A Q_CAP_C0805-100UF,4V,20%,X6S,CH710KMEA01   I100 @T6G_MB_LIB.T6G(SCH_1):PAGE454

P0V9_CPU1_RT2_2A_2D @T6G_MB_LIB.T6G(SCH_1):P0V9_CPU1_RT2_2A_2D
 U6016 BD17 PWR_2A_7 PT5161LRS-PT5161LRS,SMLF,IC,AJ051610U03     I7 @T6G_MB_LIB.T6G(SCH_1):PAGE452
 U6016 BD20 PWR_2A_8 PT5161LRS-PT5161LRS,SMLF,IC,AJ051610U03     I7 @T6G_MB_LIB.T6G(SCH_1):PAGE452
 U6016 DF17 PWR_2A_9 PT5161LRS-PT5161LRS,SMLF,IC,AJ051610U03     I7 @T6G_MB_LIB.T6G(SCH_1):PAGE452
 U6016 DF20 PWR_2A_10 PT5161LRS-PT5161LRS,SMLF,IC,AJ051610U03     I7 @T6G_MB_LIB.T6G(SCH_1):PAGE452
  R858    2      B Q_RES_0603LF-0,5%,1/4W,EMPTY,CS00006J900    I20 @T6G_MB_LIB.T6G(SCH_1):PAGE454
  C396    1      A Q_CAP_C0201-0.1UF,10V,10%,X7S,CH4102K6E00    I35 @T6G_MB_LIB.T6G(SCH_1):PAGE454
  C397    1      A Q_CAP_C0201-0.1UF,10V,10%,X7S,CH4102K6E00    I36 @T6G_MB_LIB.T6G(SCH_1):PAGE454
  R859    1      A Q_RES_0603LF-0,5%,1/4W,CHIP,CS00006J900    I41 @T6G_MB_LIB.T6G(SCH_1):PAGE454
  C390    1      A Q_CAP_0201-1UF,4V,20%,X6S,CH-10KMEE00    I90 @T6G_MB_LIB.T6G(SCH_1):PAGE454
  C394    1      A Q_CAP_0201-1UF,4V,20%,X6S,CH-10KMEE00    I91 @T6G_MB_LIB.T6G(SCH_1):PAGE454

P0V9_CPU1_RT3_2A @T6G_MB_LIB.T6G(SCH_1):P0V9_CPU1_RT3_2A
 U6017 AC17 PWR_2A_1 PT5161LRS-PT5161LRS,SMLF,IC,AJ051610U03     I5 @T6G_MB_LIB.T6G(SCH_1):PAGE463
 U6017 AC20 PWR_2A_2 PT5161LRS-PT5161LRS,SMLF,IC,AJ051610U03     I5 @T6G_MB_LIB.T6G(SCH_1):PAGE463
 U6017 AK17 PWR_2A_3 PT5161LRS-PT5161LRS,SMLF,IC,AJ051610U03     I5 @T6G_MB_LIB.T6G(SCH_1):PAGE463
 U6017 AK20 PWR_2A_4 PT5161LRS-PT5161LRS,SMLF,IC,AJ051610U03     I5 @T6G_MB_LIB.T6G(SCH_1):PAGE463
 U6017 AU17 PWR_2A_5 PT5161LRS-PT5161LRS,SMLF,IC,AJ051610U03     I5 @T6G_MB_LIB.T6G(SCH_1):PAGE463
 U6017 AU20 PWR_2A_6 PT5161LRS-PT5161LRS,SMLF,IC,AJ051610U03     I5 @T6G_MB_LIB.T6G(SCH_1):PAGE463
 U6017 DN17 PWR_2A_11 PT5161LRS-PT5161LRS,SMLF,IC,AJ051610U03     I5 @T6G_MB_LIB.T6G(SCH_1):PAGE463
 U6017 DN20 PWR_2A_12 PT5161LRS-PT5161LRS,SMLF,IC,AJ051610U03     I5 @T6G_MB_LIB.T6G(SCH_1):PAGE463
 U6017 DY17 PWR_2A_13 PT5161LRS-PT5161LRS,SMLF,IC,AJ051610U03     I5 @T6G_MB_LIB.T6G(SCH_1):PAGE463
 U6017 DY20 PWR_2A_14 PT5161LRS-PT5161LRS,SMLF,IC,AJ051610U03     I5 @T6G_MB_LIB.T6G(SCH_1):PAGE463
 U6017 EG17 PWR_2A_15 PT5161LRS-PT5161LRS,SMLF,IC,AJ051610U03     I5 @T6G_MB_LIB.T6G(SCH_1):PAGE463
 U6017 EG20 PWR_2A_16 PT5161LRS-PT5161LRS,SMLF,IC,AJ051610U03     I5 @T6G_MB_LIB.T6G(SCH_1):PAGE463
 U6017 EP17 PWR_2A_17 PT5161LRS-PT5161LRS,SMLF,IC,AJ051610U03     I5 @T6G_MB_LIB.T6G(SCH_1):PAGE463
 U6017 EP20 PWR_2A_18 PT5161LRS-PT5161LRS,SMLF,IC,AJ051610U03     I5 @T6G_MB_LIB.T6G(SCH_1):PAGE463
 U6017  T17 PWR_2A_19 PT5161LRS-PT5161LRS,SMLF,IC,AJ051610U03     I5 @T6G_MB_LIB.T6G(SCH_1):PAGE463
 U6017  T20 PWR_2A_20 PT5161LRS-PT5161LRS,SMLF,IC,AJ051610U03     I5 @T6G_MB_LIB.T6G(SCH_1):PAGE463
  R900    2      B Q_RES_0603LF-0,5%,1/4W,CHIP,CS00006J900    I36 @T6G_MB_LIB.T6G(SCH_1):PAGE465
  C495    1      A Q_CAP_C0201-0.1UF,10V,10%,X7S,CH4102K6E00    I37 @T6G_MB_LIB.T6G(SCH_1):PAGE465
  C470    1      A Q_CAP_0201-1UF,4V,20%,X6S,CH-10KMEE00    I38 @T6G_MB_LIB.T6G(SCH_1):PAGE465
  C459    1      A Q_CAP_0201-1UF,4V,20%,X6S,CH-10KMEE00    I39 @T6G_MB_LIB.T6G(SCH_1):PAGE465
  C480    1      A Q_CAP_C0402-10UF,6.3V,20%,X6S,CH6101MEB01    I40 @T6G_MB_LIB.T6G(SCH_1):PAGE465
  C490    1      A Q_CAP_C0402-10UF,6.3V,20%,X6S,CH6101MEB01    I41 @T6G_MB_LIB.T6G(SCH_1):PAGE465
  C500    1      A Q_CAP_C0201-0.1UF,10V,10%,X7S,CH4102K6E00    I42 @T6G_MB_LIB.T6G(SCH_1):PAGE465
  C473    1      A Q_CAP_C0201-0.1UF,10V,10%,X7S,CH4102K6E00    I43 @T6G_MB_LIB.T6G(SCH_1):PAGE465
  C448    1      A Q_CAP_0201-1UF,4V,20%,X6S,CH-10KMEE00    I44 @T6G_MB_LIB.T6G(SCH_1):PAGE465
  C453    1      A Q_CAP_0201-1UF,4V,20%,X6S,CH-10KMEE00    I45 @T6G_MB_LIB.T6G(SCH_1):PAGE465
  C477    1      A Q_CAP_C0201-0.1UF,10V,10%,X7S,CH4102K6E00    I46 @T6G_MB_LIB.T6G(SCH_1):PAGE465
  C450    1      A Q_CAP_C0201-0.1UF,10V,10%,X7S,CH4102K6E00    I47 @T6G_MB_LIB.T6G(SCH_1):PAGE465
  C485    1      A Q_CAP_0201-1UF,4V,20%,X6S,CH-10KMEE00    I48 @T6G_MB_LIB.T6G(SCH_1):PAGE465
  C488    1      A Q_CAP_0201-1UF,4V,20%,X6S,CH-10KMEE00    I49 @T6G_MB_LIB.T6G(SCH_1):PAGE465
  C472    1      A Q_CAP_0402-4.7UF,6.3V,20%,X6S,CH5471MEB01    I50 @T6G_MB_LIB.T6G(SCH_1):PAGE465
  C469    1      A Q_CAP_0402-4.7UF,6.3V,20%,X6S,CH5471MEB01    I51 @T6G_MB_LIB.T6G(SCH_1):PAGE465
  C494    1      A Q_CAP_0402-4.7UF,6.3V,20%,X6S,CH5471MEB01    I52 @T6G_MB_LIB.T6G(SCH_1):PAGE465
  C491    1      A Q_CAP_0201-1UF,4V,20%,X6S,CH-10KMEE00    I53 @T6G_MB_LIB.T6G(SCH_1):PAGE465
  C492    1      A Q_CAP_0201-1UF,4V,20%,X6S,CH-10KMEE00    I54 @T6G_MB_LIB.T6G(SCH_1):PAGE465
  C481    1      A Q_CAP_C0201-0.1UF,10V,10%,X7S,CH4102K6E00    I56 @T6G_MB_LIB.T6G(SCH_1):PAGE465
  C457    1      A Q_CAP_C0201-0.1UF,10V,10%,X7S,CH4102K6E00    I57 @T6G_MB_LIB.T6G(SCH_1):PAGE465
  C497    1      A Q_CAP_0201-1UF,4V,20%,X6S,CH-10KMEE00    I60 @T6G_MB_LIB.T6G(SCH_1):PAGE465
  C455    1      A Q_CAP_0201-1UF,4V,20%,X6S,CH-10KMEE00    I61 @T6G_MB_LIB.T6G(SCH_1):PAGE465
   L10    2      2 Q_INDUCTOR_SMLF-100NH/16A,IND,CV+10G0MZ04    I63 @T6G_MB_LIB.T6G(SCH_1):PAGE465
  C466    1      A Q_CAP_C0805-100UF,4V,20%,X6S,CH710KMEA01    I64 @T6G_MB_LIB.T6G(SCH_1):PAGE465
  C471    1      A Q_CAP_C0805-100UF,4V,20%,X6S,CH710KMEA01    I65 @T6G_MB_LIB.T6G(SCH_1):PAGE465
  C475    1      A Q_CAP_C0805-100UF,4V,20%,X6S,CH710KMEA01    I69 @T6G_MB_LIB.T6G(SCH_1):PAGE465
  C501    1      A Q_CAP_C0402-22UF,4V,20%,X6S,CH622KMEB02    I70 @T6G_MB_LIB.T6G(SCH_1):PAGE465
  C476    1      A Q_CAP_C0402-22UF,4V,20%,X6S,CH622KMEB02    I71 @T6G_MB_LIB.T6G(SCH_1):PAGE465
  C487    1      A Q_CAP_C0402-22UF,4V,20%,X6S,CH622KMEB02    I75 @T6G_MB_LIB.T6G(SCH_1):PAGE465
  C499    1      A Q_CAP_C0402-10UF,6.3V,20%,X6S,CH6101MEB01    I76 @T6G_MB_LIB.T6G(SCH_1):PAGE465
  C482    1      A Q_CAP_C0402-10UF,6.3V,20%,X6S,CH6101MEB01    I77 @T6G_MB_LIB.T6G(SCH_1):PAGE465
  C462    1      A Q_CAP_C0201-0.1UF,10V,10%,X7S,CH4102K6E00    I83 @T6G_MB_LIB.T6G(SCH_1):PAGE465
  C452    1      A Q_CAP_0201-1UF,4V,20%,X6S,CH-10KMEE00    I84 @T6G_MB_LIB.T6G(SCH_1):PAGE465
  C486    1      A Q_CAP_C0402-22UF,4V,20%,X6S,CH622KMEB02    I85 @T6G_MB_LIB.T6G(SCH_1):PAGE465
  C483    1      A Q_CAP_0402-4.7UF,6.3V,20%,X6S,CH5471MEB01    I86 @T6G_MB_LIB.T6G(SCH_1):PAGE465
  C479    1      A Q_CAP_C0805-100UF,4V,20%,X6S,CH710KMEA01    I87 @T6G_MB_LIB.T6G(SCH_1):PAGE465
  C496    1      A Q_CAP_C0201-0.1UF,10V,10%,X7S,CH4102K6E00    I92 @T6G_MB_LIB.T6G(SCH_1):PAGE465
  C498    1      A Q_CAP_C0201-0.1UF,10V,10%,X7S,CH4102K6E00    I93 @T6G_MB_LIB.T6G(SCH_1):PAGE465
 C7029    1      A Q_CAPP_SMLF-470UF,2.5V,20%,SPCAP,CH747LM8818    I94 @T6G_MB_LIB.T6G(SCH_1):PAGE465
 C7030    1      A Q_CAPP_SMLF-470UF,2.5V,20%,SPCAP,CH747LM8818    I95 @T6G_MB_LIB.T6G(SCH_1):PAGE465
 C7031    1      A Q_CAP_C0805-100UF,4V,20%,X6S,CH710KMEA01    I96 @T6G_MB_LIB.T6G(SCH_1):PAGE465

P0V9_CPU1_RT3_2A_2D @T6G_MB_LIB.T6G(SCH_1):P0V9_CPU1_RT3_2A_2D
 U6017 BD17 PWR_2A_7 PT5161LRS-PT5161LRS,SMLF,IC,AJ051610U03     I5 @T6G_MB_LIB.T6G(SCH_1):PAGE463
 U6017 BD20 PWR_2A_8 PT5161LRS-PT5161LRS,SMLF,IC,AJ051610U03     I5 @T6G_MB_LIB.T6G(SCH_1):PAGE463
 U6017 DF17 PWR_2A_9 PT5161LRS-PT5161LRS,SMLF,IC,AJ051610U03     I5 @T6G_MB_LIB.T6G(SCH_1):PAGE463
 U6017 DF20 PWR_2A_10 PT5161LRS-PT5161LRS,SMLF,IC,AJ051610U03     I5 @T6G_MB_LIB.T6G(SCH_1):PAGE463
  R898    2      B Q_RES_0603LF-0,5%,1/4W,EMPTY,CS00006J900     I8 @T6G_MB_LIB.T6G(SCH_1):PAGE465
  C463    1      A Q_CAP_C0201-0.1UF,10V,10%,X7S,CH4102K6E00    I34 @T6G_MB_LIB.T6G(SCH_1):PAGE465
  C464    1      A Q_CAP_C0201-0.1UF,10V,10%,X7S,CH4102K6E00    I35 @T6G_MB_LIB.T6G(SCH_1):PAGE465
  R900    1      A Q_RES_0603LF-0,5%,1/4W,CHIP,CS00006J900    I36 @T6G_MB_LIB.T6G(SCH_1):PAGE465
  C456    1      A Q_CAP_0201-1UF,4V,20%,X6S,CH-10KMEE00    I90 @T6G_MB_LIB.T6G(SCH_1):PAGE465
  C460    1      A Q_CAP_0201-1UF,4V,20%,X6S,CH-10KMEE00    I91 @T6G_MB_LIB.T6G(SCH_1):PAGE465

P0V9_CPU1_RT_2D @T6G_MB_LIB.T6G(SCH_1):P0V9_CPU1_RT_2D
 U6014 BL17 PWR_2D_1 PT5161LRS-PT5161LRS,SMLF,IC,AJ051610U03     I1 @T6G_MB_LIB.T6G(SCH_1):PAGE400
 U6014 BL20 PWR_2D_2 PT5161LRS-PT5161LRS,SMLF,IC,AJ051610U03     I1 @T6G_MB_LIB.T6G(SCH_1):PAGE400
 U6014 CW17 PWR_2D_3 PT5161LRS-PT5161LRS,SMLF,IC,AJ051610U03     I1 @T6G_MB_LIB.T6G(SCH_1):PAGE400
 U6014 CW20 PWR_2D_4 PT5161LRS-PT5161LRS,SMLF,IC,AJ051610U03     I1 @T6G_MB_LIB.T6G(SCH_1):PAGE400
PR6600    2      B Q_RES_0402LF-49.9,1%,1/16W,CHIP,CS04992FB07    I23 @T6G_MB_LIB.T6G(SCH_1):PAGE477
PR6631    2      B Q_RES_0402LF-0,5%,1/16W,CHIP,CS00002JB13    I16 @T6G_MB_LIB.T6G(SCH_1):PAGE478
PL6512    2      2 Q_INDUCTOR_SMLF-120NH/69A,IND,CV+12^0EZ03    I22 @T6G_MB_LIB.T6G(SCH_1):PAGE478
PC6807    1      A Q_CAP_C0402-100NF,50V,10%,X7R,CH4106K1B01    I23 @T6G_MB_LIB.T6G(SCH_1):PAGE478
PC6642_2    1      A Q_CAP_C0805-22UF,4V,20%,X6S,CH622KMEA03    I29 @T6G_MB_LIB.T6G(SCH_1):PAGE478
PC6643_2    1      A Q_CAP_C0805-22UF,4V,20%,X6S,CH622KMEA03    I30 @T6G_MB_LIB.T6G(SCH_1):PAGE478
PC6813    1      A Q_CAPP_SMLF-470UF,2.5V,20%,SPCAP,CH747LM8818    I31 @T6G_MB_LIB.T6G(SCH_1):PAGE478
PC6814    1      A Q_CAPP_SMLF-470UF,2.5V,20%,SPCAP,CH747LM8818    I32 @T6G_MB_LIB.T6G(SCH_1):PAGE478
PR6626    2      B Q_RES_0402LF-0,5%,1/16W,CHIP,CS00002JB13    I59 @T6G_MB_LIB.T6G(SCH_1):PAGE478
PL6511    2      2 Q_INDUCTOR_SMLF-120NH/69A,IND,CV+12^0EZ03    I65 @T6G_MB_LIB.T6G(SCH_1):PAGE478
PC6623    1      A Q_CAP_C0402-100NF,50V,10%,X7R,CH4106K1B01    I66 @T6G_MB_LIB.T6G(SCH_1):PAGE478
PC6624_1    1      A Q_CAP_C0805-22UF,4V,20%,X6S,CH622KMEA03    I67 @T6G_MB_LIB.T6G(SCH_1):PAGE478
PC6625_1    1      A Q_CAP_C0805-22UF,4V,20%,X6S,CH622KMEA03    I68 @T6G_MB_LIB.T6G(SCH_1):PAGE478
PC6626    1      A Q_CAPP_SMLF-470UF,2.5V,20%,SPCAP,CH747LM8818    I69 @T6G_MB_LIB.T6G(SCH_1):PAGE478
PC6627    1      A Q_CAPP_SMLF-470UF,2.5V,20%,SPCAP,CH747LM8818    I70 @T6G_MB_LIB.T6G(SCH_1):PAGE478
PC6815    1      A Q_CAPP_SMLF-470UF,2.5V,20%,SPCAP,CH747LM8818    I82 @T6G_MB_LIB.T6G(SCH_1):PAGE478
PC6631    1      A Q_CAPP_SMLF-390UF,2.5V,20%,ALUM,CC7390JMZ13    I83 @T6G_MB_LIB.T6G(SCH_1):PAGE478
PC6632    1      A Q_CAPP_SMLF-390UF,2.5V,20%,ALUM,CC7390JMZ13    I84 @T6G_MB_LIB.T6G(SCH_1):PAGE478
PC6628    1      A Q_CAPP_SMLF-470UF,2.5V,20%,SPCAP,CH747LM8818    I93 @T6G_MB_LIB.T6G(SCH_1):PAGE478
PC6629    1      A Q_CAPP_SMLF-390UF,2.5V,20%,ALUM,CC7390JMZ13    I94 @T6G_MB_LIB.T6G(SCH_1):PAGE478
PC6630    1      A Q_CAPP_SMLF-390UF,2.5V,20%,ALUM,CC7390JMZ13    I95 @T6G_MB_LIB.T6G(SCH_1):PAGE478
PR6625    1      A Q_RES_0603LF-499,1%,1/10W,CHIP,CS14993F901    I97 @T6G_MB_LIB.T6G(SCH_1):PAGE478
  C229    1      A Q_CAP_C0805-100UF,4V,20%,X6S,CH710KMEA01    I34 @T6G_MB_LIB.T6G(SCH_1):PAGE398
  C244    1      A Q_CAP_C0402-22UF,4V,20%,X6S,CH622KMEB02    I35 @T6G_MB_LIB.T6G(SCH_1):PAGE398
  C261    1      A Q_CAP_C0402-10UF,6.3V,20%,X6S,CH6101MEB01    I36 @T6G_MB_LIB.T6G(SCH_1):PAGE398
  C256    1      A Q_CAP_0402-4.7UF,6.3V,20%,X6S,CH5471MEB01    I39 @T6G_MB_LIB.T6G(SCH_1):PAGE398
  C185    1      A Q_CAP_0201-1UF,4V,20%,X6S,CH-10KMEE00    I40 @T6G_MB_LIB.T6G(SCH_1):PAGE398
    L4    1      1 Q_INDUCTOR_SMLF-100NH/16A,IND,CV+10G0MZ04    I74 @T6G_MB_LIB.T6G(SCH_1):PAGE398
  C189    1      A Q_CAP_C0201-0.1UF,10V,10%,X7S,CH4102K6E00    I75 @T6G_MB_LIB.T6G(SCH_1):PAGE398
  C266    1      A Q_CAP_C0201-0.1UF,10V,10%,X7S,CH4102K6E00    I76 @T6G_MB_LIB.T6G(SCH_1):PAGE398
  C139    1      A Q_CAP_C0201-0.1UF,10V,10%,X7S,CH4102K6E00    I77 @T6G_MB_LIB.T6G(SCH_1):PAGE398
  C137    1      A Q_CAP_C0201-0.1UF,10V,10%,X7S,CH4102K6E00    I78 @T6G_MB_LIB.T6G(SCH_1):PAGE398
 R6704    1      A Q_RES_0603LF-0,5%,1/4W,EMPTY,CS00006J900    I96 @T6G_MB_LIB.T6G(SCH_1):PAGE398
 U6015 BL17 PWR_2D_1 PT5161LRS-PT5161LRS,SMLF,IC,AJ051610U03     I5 @T6G_MB_LIB.T6G(SCH_1):PAGE391
 U6015 BL20 PWR_2D_2 PT5161LRS-PT5161LRS,SMLF,IC,AJ051610U03     I5 @T6G_MB_LIB.T6G(SCH_1):PAGE391
 U6015 CW17 PWR_2D_3 PT5161LRS-PT5161LRS,SMLF,IC,AJ051610U03     I5 @T6G_MB_LIB.T6G(SCH_1):PAGE391
 U6015 CW20 PWR_2D_4 PT5161LRS-PT5161LRS,SMLF,IC,AJ051610U03     I5 @T6G_MB_LIB.T6G(SCH_1):PAGE391
  R705    1      A Q_RES_0603LF-0,5%,1/4W,EMPTY,CS00006J900    I10 @T6G_MB_LIB.T6G(SCH_1):PAGE443
    L6    1      1 Q_INDUCTOR_SMLF-100NH/16A,IND,CV+10G0MZ04    I30 @T6G_MB_LIB.T6G(SCH_1):PAGE443
  C323    1      A Q_CAP_C0805-100UF,4V,20%,X6S,CH710KMEA01    I72 @T6G_MB_LIB.T6G(SCH_1):PAGE443
  C327    1      A Q_CAP_C0402-22UF,4V,20%,X6S,CH622KMEB02    I73 @T6G_MB_LIB.T6G(SCH_1):PAGE443
  C338    1      A Q_CAP_0402-4.7UF,6.3V,20%,X6S,CH5471MEB01    I78 @T6G_MB_LIB.T6G(SCH_1):PAGE443
  C342    1      A Q_CAP_0201-1UF,4V,20%,X6S,CH-10KMEE00    I79 @T6G_MB_LIB.T6G(SCH_1):PAGE443
  C300    1      A Q_CAP_C0201-0.1UF,10V,10%,X7S,CH4102K6E00    I82 @T6G_MB_LIB.T6G(SCH_1):PAGE443
  C311    1      A Q_CAP_C0201-0.1UF,10V,10%,X7S,CH4102K6E00    I84 @T6G_MB_LIB.T6G(SCH_1):PAGE443
  C292    1      A Q_CAP_C0201-0.1UF,10V,10%,X7S,CH4102K6E00    I85 @T6G_MB_LIB.T6G(SCH_1):PAGE443
  C290    1      A Q_CAP_C0201-0.1UF,10V,10%,X7S,CH4102K6E00    I86 @T6G_MB_LIB.T6G(SCH_1):PAGE443
  C333    1      A Q_CAP_C0402-10UF,6.3V,20%,X6S,CH6101MEB01    I87 @T6G_MB_LIB.T6G(SCH_1):PAGE443
 U6016 BL17 PWR_2D_1 PT5161LRS-PT5161LRS,SMLF,IC,AJ051610U03     I7 @T6G_MB_LIB.T6G(SCH_1):PAGE452
 U6016 BL20 PWR_2D_2 PT5161LRS-PT5161LRS,SMLF,IC,AJ051610U03     I7 @T6G_MB_LIB.T6G(SCH_1):PAGE452
 U6016 CW17 PWR_2D_3 PT5161LRS-PT5161LRS,SMLF,IC,AJ051610U03     I7 @T6G_MB_LIB.T6G(SCH_1):PAGE452
 U6016 CW20 PWR_2D_4 PT5161LRS-PT5161LRS,SMLF,IC,AJ051610U03     I7 @T6G_MB_LIB.T6G(SCH_1):PAGE452
  R858    1      A Q_RES_0603LF-0,5%,1/4W,EMPTY,CS00006J900    I20 @T6G_MB_LIB.T6G(SCH_1):PAGE454
    L8    1      1 Q_INDUCTOR_SMLF-100NH/16A,IND,CV+10G0MZ04    I74 @T6G_MB_LIB.T6G(SCH_1):PAGE454
  C404    1      A Q_CAP_C0805-100UF,4V,20%,X6S,CH710KMEA01    I76 @T6G_MB_LIB.T6G(SCH_1):PAGE454
  C408    1      A Q_CAP_C0402-22UF,4V,20%,X6S,CH622KMEB02    I77 @T6G_MB_LIB.T6G(SCH_1):PAGE454
  C414    1      A Q_CAP_C0402-10UF,6.3V,20%,X6S,CH6101MEB01    I78 @T6G_MB_LIB.T6G(SCH_1):PAGE454
  C419    1      A Q_CAP_0402-4.7UF,6.3V,20%,X6S,CH5471MEB01    I79 @T6G_MB_LIB.T6G(SCH_1):PAGE454
  C423    1      A Q_CAP_0201-1UF,4V,20%,X6S,CH-10KMEE00    I80 @T6G_MB_LIB.T6G(SCH_1):PAGE454
  C383    1      A Q_CAP_C0201-0.1UF,10V,10%,X7S,CH4102K6E00    I82 @T6G_MB_LIB.T6G(SCH_1):PAGE454
  C385    1      A Q_CAP_C0201-0.1UF,10V,10%,X7S,CH4102K6E00    I83 @T6G_MB_LIB.T6G(SCH_1):PAGE454
  C388    1      A Q_CAP_C0201-0.1UF,10V,10%,X7S,CH4102K6E00    I84 @T6G_MB_LIB.T6G(SCH_1):PAGE454
  C392    1      A Q_CAP_C0201-0.1UF,10V,10%,X7S,CH4102K6E00    I85 @T6G_MB_LIB.T6G(SCH_1):PAGE454
 U6017 BL17 PWR_2D_1 PT5161LRS-PT5161LRS,SMLF,IC,AJ051610U03     I5 @T6G_MB_LIB.T6G(SCH_1):PAGE463
 U6017 BL20 PWR_2D_2 PT5161LRS-PT5161LRS,SMLF,IC,AJ051610U03     I5 @T6G_MB_LIB.T6G(SCH_1):PAGE463
 U6017 CW17 PWR_2D_3 PT5161LRS-PT5161LRS,SMLF,IC,AJ051610U03     I5 @T6G_MB_LIB.T6G(SCH_1):PAGE463
 U6017 CW20 PWR_2D_4 PT5161LRS-PT5161LRS,SMLF,IC,AJ051610U03     I5 @T6G_MB_LIB.T6G(SCH_1):PAGE463
  R898    1      A Q_RES_0603LF-0,5%,1/4W,EMPTY,CS00006J900     I8 @T6G_MB_LIB.T6G(SCH_1):PAGE465
   L10    1      1 Q_INDUCTOR_SMLF-100NH/16A,IND,CV+10G0MZ04    I63 @T6G_MB_LIB.T6G(SCH_1):PAGE465
  C474    1      A Q_CAP_C0805-100UF,4V,20%,X6S,CH710KMEA01    I67 @T6G_MB_LIB.T6G(SCH_1):PAGE465
  C478    1      A Q_CAP_C0402-22UF,4V,20%,X6S,CH622KMEB02    I68 @T6G_MB_LIB.T6G(SCH_1):PAGE465
  C489    1      A Q_CAP_C0402-10UF,6.3V,20%,X6S,CH6101MEB01    I72 @T6G_MB_LIB.T6G(SCH_1):PAGE465
  C484    1      A Q_CAP_0402-4.7UF,6.3V,20%,X6S,CH5471MEB01    I73 @T6G_MB_LIB.T6G(SCH_1):PAGE465
  C454    1      A Q_CAP_0201-1UF,4V,20%,X6S,CH-10KMEE00    I74 @T6G_MB_LIB.T6G(SCH_1):PAGE465
  C449    1      A Q_CAP_C0201-0.1UF,10V,10%,X7S,CH4102K6E00    I78 @T6G_MB_LIB.T6G(SCH_1):PAGE465
  C451    1      A Q_CAP_C0201-0.1UF,10V,10%,X7S,CH4102K6E00    I79 @T6G_MB_LIB.T6G(SCH_1):PAGE465
  C493    1      A Q_CAP_C0201-0.1UF,10V,10%,X7S,CH4102K6E00    I80 @T6G_MB_LIB.T6G(SCH_1):PAGE465
  C458    1      A Q_CAP_C0201-0.1UF,10V,10%,X7S,CH4102K6E00    I82 @T6G_MB_LIB.T6G(SCH_1):PAGE465
PJ09_P1_P    1      1 Q_SHORT_SM-EMPTY,SHORT16    I95 @T6G_MB_LIB.T6G(SCH_1):PAGE477
 C7004    1      A Q_CAPP_SMLF-470UF,2.5V,20%,SPCAP,CH747LM8818    I94 @T6G_MB_LIB.T6G(SCH_1):PAGE454
 C7005    1      A Q_CAPP_SMLF-470UF,2.5V,20%,SPCAP,CH747LM8818    I95 @T6G_MB_LIB.T6G(SCH_1):PAGE454
 C7006    1      A Q_CAP_C0805-47UF,4V,20%,X6S,CH647KMEA04    I96 @T6G_MB_LIB.T6G(SCH_1):PAGE454
 C7007    1      A Q_CAP_C0805-47UF,4V,20%,X6S,CH647KMEA04    I97 @T6G_MB_LIB.T6G(SCH_1):PAGE454
 C7037    1      A Q_CAPP_SMLF-470UF,2.5V,20%,SPCAP,CH747LM8818   I101 @T6G_MB_LIB.T6G(SCH_1):PAGE454
 C7038    1      A Q_CAP_C0805-47UF,4V,20%,X6S,CH647KMEA04   I102 @T6G_MB_LIB.T6G(SCH_1):PAGE454
 C7039    1      A Q_CAP_C0805-47UF,4V,20%,X6S,CH647KMEA04   I103 @T6G_MB_LIB.T6G(SCH_1):PAGE454
 C7040    1      A Q_CAP_C0805-47UF,4V,20%,X6S,CH647KMEA04   I104 @T6G_MB_LIB.T6G(SCH_1):PAGE454
 C7041    1      A Q_CAP_C0805-47UF,4V,20%,X6S,CH647KMEA04   I105 @T6G_MB_LIB.T6G(SCH_1):PAGE454

P0V9_RETIMER_CPU0_ADDR @T6G_MB_LIB.T6G(SCH_1):P0V9_RETIMER_CPU0_ADDR
PU6502   34 ADDR_CFG ISL69260IRAZT-ISL69260IRAZ-T,SMLF,IC,AL069260000    I42 @T6G_MB_LIB.T6G(SCH_1):PAGE475
PR6603    2      B Q_RES_0402LF-0,5%,1/16W,CHIP,CS00002JB13   I183 @T6G_MB_LIB.T6G(SCH_1):PAGE475

P0V9_RETIMER_CPU0_CFP @T6G_MB_LIB.T6G(SCH_1):P0V9_RETIMER_CPU0_CFP
PU6502   33    CFP ISL69260IRAZT-ISL69260IRAZ-T,SMLF,IC,AL069260000    I42 @T6G_MB_LIB.T6G(SCH_1):PAGE475
  R652    2      B Q_RES_0402LF-1K,1%,1/16W,CHIP,CS21002FB06   I128 @T6G_MB_LIB.T6G(SCH_1):PAGE475

P0V9_RETIMER_CPU0_EN @T6G_MB_LIB.T6G(SCH_1):P0V9_RETIMER_CPU0_EN
  R651    1      A Q_RES_0402LF-0,5%,1/16W,CHIP,CS00002JB13   I120 @T6G_MB_LIB.T6G(SCH_1):PAGE475
 R6854    1      A Q_RES_0402LF-33,5%,1/16W,CHIP,CS03302JB10   I364 @T6G_MB_LIB.T6G(SCH_1):PAGE80

P0V9_RETIMER_CPU0_EN0_R @T6G_MB_LIB.T6G(SCH_1):P0V9_RETIMER_CPU0_EN0_R
PU6502   13    EN0 ISL69260IRAZT-ISL69260IRAZ-T,SMLF,IC,AL069260000    I42 @T6G_MB_LIB.T6G(SCH_1):PAGE475
  R651    2      B Q_RES_0402LF-0,5%,1/16W,CHIP,CS00002JB13   I120 @T6G_MB_LIB.T6G(SCH_1):PAGE475
 R6786    1      A Q_RES_0402LF-1K,1%,1/16W,CHIP,CS21002FB06   I208 @T6G_MB_LIB.T6G(SCH_1):PAGE475

P0V9_RETIMER_CPU0_EN1_R @T6G_MB_LIB.T6G(SCH_1):P0V9_RETIMER_CPU0_EN1_R
PU6502   20    EN1 ISL69260IRAZT-ISL69260IRAZ-T,SMLF,IC,AL069260000    I42 @T6G_MB_LIB.T6G(SCH_1):PAGE475
 R6801    2      B Q_RES_0402LF-0,5%,1/16W,CHIP,CS00002JB13   I161 @T6G_MB_LIB.T6G(SCH_1):PAGE475

P0V9_RETIMER_CPU0_EN_R2 @T6G_MB_LIB.T6G(SCH_1):P0V9_RETIMER_CPU0_EN_R2
   U18 AA10 PB22A||PCLKT2_0 LCMXO3LF9400C5BG484C-LCMXO3LF-9400C-5BG484C,SMLF,IA   I216 @T6G_MB_LIB.T6G(SCH_1):PAGE80
 R6854    2      B Q_RES_0402LF-33,5%,1/16W,CHIP,CS03302JB10   I364 @T6G_MB_LIB.T6G(SCH_1):PAGE80

P0V9_RETIMER_CPU0_IMON1 @T6G_MB_LIB.T6G(SCH_1):P0V9_RETIMER_CPU0_IMON1
PU6502   23    CS7 ISL69260IRAZT-ISL69260IRAZ-T,SMLF,IC,AL069260000    I42 @T6G_MB_LIB.T6G(SCH_1):PAGE475
PU6503   38   IOUT ISL99390FRZTR5935-ISL99390FRZ-TR5935,SMLF,IC,AL099A    I53 @T6G_MB_LIB.T6G(SCH_1):PAGE476

P0V9_RETIMER_CPU0_IMON2 @T6G_MB_LIB.T6G(SCH_1):P0V9_RETIMER_CPU0_IMON2
PU6502   24    CS6 ISL69260IRAZT-ISL69260IRAZ-T,SMLF,IC,AL069260000    I42 @T6G_MB_LIB.T6G(SCH_1):PAGE475
PU6504   38   IOUT ISL99390FRZTR5935-ISL99390FRZ-TR5935,SMLF,IC,AL099A   I270 @T6G_MB_LIB.T6G(SCH_1):PAGE476

P0V9_RETIMER_CPU0_INALERT @T6G_MB_LIB.T6G(SCH_1):P0V9_RETIMER_CPU0_INALERT
PU6502   15 NPINALERT#||NPSYSCRIT# ISL69260IRAZT-ISL69260IRAZ-T,SMLF,IC,AL069260000    I42 @T6G_MB_LIB.T6G(SCH_1):PAGE475
  R655    2      B Q_RES_0402LF-1K,1%,1/16W,CHIP,CS21002FB06   I127 @T6G_MB_LIB.T6G(SCH_1):PAGE475

P0V9_RETIMER_CPU0_LSET1 @T6G_MB_LIB.T6G(SCH_1):P0V9_RETIMER_CPU0_LSET1
PU6503   37   LSET ISL99390FRZTR5935-ISL99390FRZ-TR5935,SMLF,IC,AL099A    I53 @T6G_MB_LIB.T6G(SCH_1):PAGE476
PR6553    1      A Q_RES_0402LF-8.87K,1%,1/16W,EMPTY,CS28872FB01   I220 @T6G_MB_LIB.T6G(SCH_1):PAGE476

P0V9_RETIMER_CPU0_LSET2 @T6G_MB_LIB.T6G(SCH_1):P0V9_RETIMER_CPU0_LSET2
PU6504   37   LSET ISL99390FRZTR5935-ISL99390FRZ-TR5935,SMLF,IC,AL099A   I270 @T6G_MB_LIB.T6G(SCH_1):PAGE476
PR6561    1      A Q_RES_0402LF-8.87K,1%,1/16W,EMPTY,CS28872FB01   I276 @T6G_MB_LIB.T6G(SCH_1):PAGE476

P0V9_RETIMER_CPU0_PMSCL @T6G_MB_LIB.T6G(SCH_1):P0V9_RETIMER_CPU0_PMSCL
  R646    1      A Q_RES_0402LF-0,5%,1/16W,CHIP,CS00002JB13    I94 @T6G_MB_LIB.T6G(SCH_1):PAGE475
 R6856    2      B Q_RES_0402LF-33,5%,1/16W,CHIP,CS03302JB10   I226 @T6G_MB_LIB.T6G(SCH_1):PAGE349

P0V9_RETIMER_CPU0_PMSCL_R @T6G_MB_LIB.T6G(SCH_1):P0V9_RETIMER_CPU0_PMSCL_R
PU6502   10  PMSCL ISL69260IRAZT-ISL69260IRAZ-T,SMLF,IC,AL069260000    I42 @T6G_MB_LIB.T6G(SCH_1):PAGE475
  R646    2      B Q_RES_0402LF-0,5%,1/16W,CHIP,CS00002JB13    I94 @T6G_MB_LIB.T6G(SCH_1):PAGE475

P0V9_RETIMER_CPU0_PMSDA @T6G_MB_LIB.T6G(SCH_1):P0V9_RETIMER_CPU0_PMSDA
  R647    1      A Q_RES_0402LF-0,5%,1/16W,CHIP,CS00002JB13    I95 @T6G_MB_LIB.T6G(SCH_1):PAGE475
 R6857    2      B Q_RES_0402LF-33,5%,1/16W,CHIP,CS03302JB10   I227 @T6G_MB_LIB.T6G(SCH_1):PAGE349

P0V9_RETIMER_CPU0_PMSDA_R @T6G_MB_LIB.T6G(SCH_1):P0V9_RETIMER_CPU0_PMSDA_R
PU6502    9  PMSDA ISL69260IRAZT-ISL69260IRAZ-T,SMLF,IC,AL069260000    I42 @T6G_MB_LIB.T6G(SCH_1):PAGE475
  R647    2      B Q_RES_0402LF-0,5%,1/16W,CHIP,CS00002JB13    I95 @T6G_MB_LIB.T6G(SCH_1):PAGE475

P0V9_RETIMER_CPU0_PVCC @T6G_MB_LIB.T6G(SCH_1):P0V9_RETIMER_CPU0_PVCC
PC6550_09P0_1    1      A Q_CAP_C0402-2.2UF,10V,10%,X6S,CH5222KEB01    I47 @T6G_MB_LIB.T6G(SCH_1):PAGE476
PU6503    4   PVCC ISL99390FRZTR5935-ISL99390FRZ-TR5935,SMLF,IC,AL099A    I53 @T6G_MB_LIB.T6G(SCH_1):PAGE476
PR6552    1      A Q_RES_0402LF-2.2,5%,1/16W,CHIP,TMP_QCS-2202JB25    I58 @T6G_MB_LIB.T6G(SCH_1):PAGE476
PR6550    2      B Q_RES_0402LF-0,5%,1/16W,CHIP,CS00002JB13   I183 @T6G_MB_LIB.T6G(SCH_1):PAGE476
PR6551    2      B Q_RES_0402LF-0,5%,1/16W,EMPTY,CS00002JB13   I185 @T6G_MB_LIB.T6G(SCH_1):PAGE476
PC6551_09P0_2    1      A Q_CAP_C0402-2.2UF,10V,10%,X6S,CH5222KEB01   I267 @T6G_MB_LIB.T6G(SCH_1):PAGE476
PR6560    1      A Q_RES_0402LF-2.2,5%,1/16W,CHIP,TMP_QCS-2202JB25   I269 @T6G_MB_LIB.T6G(SCH_1):PAGE476
PU6504    4   PVCC ISL99390FRZTR5935-ISL99390FRZ-TR5935,SMLF,IC,AL099A   I270 @T6G_MB_LIB.T6G(SCH_1):PAGE476

P0V9_RETIMER_CPU0_PWM1 @T6G_MB_LIB.T6G(SCH_1):P0V9_RETIMER_CPU0_PWM1
PU6502    8   PWM7 ISL69260IRAZT-ISL69260IRAZ-T,SMLF,IC,AL069260000    I42 @T6G_MB_LIB.T6G(SCH_1):PAGE475
PU6503   34    PWM ISL99390FRZTR5935-ISL99390FRZ-TR5935,SMLF,IC,AL099A    I53 @T6G_MB_LIB.T6G(SCH_1):PAGE476

P0V9_RETIMER_CPU0_PWM2 @T6G_MB_LIB.T6G(SCH_1):P0V9_RETIMER_CPU0_PWM2
PU6502    7   PWM6 ISL69260IRAZT-ISL69260IRAZ-T,SMLF,IC,AL069260000    I42 @T6G_MB_LIB.T6G(SCH_1):PAGE475
PU6504   34    PWM ISL99390FRZTR5935-ISL99390FRZ-TR5935,SMLF,IC,AL099A   I270 @T6G_MB_LIB.T6G(SCH_1):PAGE476

P0V9_RETIMER_CPU0_SENSE_R_P @T6G_MB_LIB.T6G(SCH_1):P0V9_RETIMER_CPU0_SENSE_R_P
PU6502   21  VSEN0 ISL69260IRAZT-ISL69260IRAZ-T,SMLF,IC,AL069260000    I42 @T6G_MB_LIB.T6G(SCH_1):PAGE475
PR6531    2      B Q_RES_0402LF-0,5%,1/16W,CHIP,CS00002JB13   I105 @T6G_MB_LIB.T6G(SCH_1):PAGE475
PC6540    1      A Q_CAP_0402-3300PF,50V,10%,X7R,TMP_QCH2336K1B12   I121 @T6G_MB_LIB.T6G(SCH_1):PAGE475

P0V9_RETIMER_CPU0_SENSE_SH_N @T6G_MB_LIB.T6G(SCH_1):P0V9_RETIMER_CPU0_SENSE_SH_N
PR6532    1      A Q_RES_0402LF-49.9,1%,1/16W,CHIP,CS04992FB07    I32 @T6G_MB_LIB.T6G(SCH_1):PAGE475
PU6502   22  RGND0 ISL69260IRAZT-ISL69260IRAZ-T,SMLF,IC,AL069260000    I42 @T6G_MB_LIB.T6G(SCH_1):PAGE475
PC6540    2      B Q_CAP_0402-3300PF,50V,10%,X7R,TMP_QCH2336K1B12   I121 @T6G_MB_LIB.T6G(SCH_1):PAGE475
PJ09_P0_N    2      2 Q_SHORT_SM-EMPTY,SHORT16   I215 @T6G_MB_LIB.T6G(SCH_1):PAGE475

P0V9_RETIMER_CPU0_SENSE_SH_P @T6G_MB_LIB.T6G(SCH_1):P0V9_RETIMER_CPU0_SENSE_SH_P
PR6530    1      A Q_RES_0402LF-49.9,1%,1/16W,CHIP,CS04992FB07    I34 @T6G_MB_LIB.T6G(SCH_1):PAGE475
PR6531    1      A Q_RES_0402LF-0,5%,1/16W,CHIP,CS00002JB13   I105 @T6G_MB_LIB.T6G(SCH_1):PAGE475
PJ09_P0_P    2      2 Q_SHORT_SM-EMPTY,SHORT16   I214 @T6G_MB_LIB.T6G(SCH_1):PAGE475

P0V9_RETIMER_CPU0_SVID_CLK @T6G_MB_LIB.T6G(SCH_1):P0V9_RETIMER_CPU0_SVID_CLK
PU6502   17  SVCLK ISL69260IRAZT-ISL69260IRAZ-T,SMLF,IC,AL069260000    I42 @T6G_MB_LIB.T6G(SCH_1):PAGE475
PR6810    1      A Q_RES_0402LF-0,5%,1/16W,CHIP,CS00002JB13   I165 @T6G_MB_LIB.T6G(SCH_1):PAGE475
PR6805    2      B Q_RES_0402LF-1K,1%,1/16W,EMPTY,CS21002FB06   I166 @T6G_MB_LIB.T6G(SCH_1):PAGE475

P0V9_RETIMER_CPU0_SVID_SDA @T6G_MB_LIB.T6G(SCH_1):P0V9_RETIMER_CPU0_SVID_SDA
PU6502   18 SVDATA ISL69260IRAZT-ISL69260IRAZ-T,SMLF,IC,AL069260000    I42 @T6G_MB_LIB.T6G(SCH_1):PAGE475
PR6803    2      B Q_RES_0402LF-1K,1%,1/16W,EMPTY,CS21002FB06   I167 @T6G_MB_LIB.T6G(SCH_1):PAGE475
PR6819    1      A Q_RES_0402LF-0,5%,1/16W,CHIP,CS00002JB13   I168 @T6G_MB_LIB.T6G(SCH_1):PAGE475

P0V9_RETIMER_CPU0_TEMP0 @T6G_MB_LIB.T6G(SCH_1):P0V9_RETIMER_CPU0_TEMP0
PU6502   35  TEMP0 ISL69260IRAZT-ISL69260IRAZ-T,SMLF,IC,AL069260000    I42 @T6G_MB_LIB.T6G(SCH_1):PAGE475
PR6814    1      A Q_RES_0402LF-10K,1%,1/16W,EMPTY,CS31002FB08   I138 @T6G_MB_LIB.T6G(SCH_1):PAGE475
PC6607    1      A Q_CAP_0402-470PF,50V,10%,X7R,TMP_QCH14706KB18   I148 @T6G_MB_LIB.T6G(SCH_1):PAGE475
PU6503   36 TOUT_FLT ISL99390FRZTR5935-ISL99390FRZ-TR5935,SMLF,IC,AL099A    I53 @T6G_MB_LIB.T6G(SCH_1):PAGE476
PU6504   36 TOUT_FLT ISL99390FRZTR5935-ISL99390FRZ-TR5935,SMLF,IC,AL099A   I270 @T6G_MB_LIB.T6G(SCH_1):PAGE476

P0V9_RETIMER_CPU0_TEMP1_R @T6G_MB_LIB.T6G(SCH_1):P0V9_RETIMER_CPU0_TEMP1_R
PU6502   36 TEMP1||ISYS ISL69260IRAZT-ISL69260IRAZ-T,SMLF,IC,AL069260000    I42 @T6G_MB_LIB.T6G(SCH_1):PAGE475
PR6618    1      A Q_RES_0402LF-0,5%,1/16W,CHIP,CS00002JB13   I204 @T6G_MB_LIB.T6G(SCH_1):PAGE475

P0V9_RETIMER_CPU0_VCC @T6G_MB_LIB.T6G(SCH_1):P0V9_RETIMER_CPU0_VCC
PU6502   39    VCC ISL69260IRAZT-ISL69260IRAZ-T,SMLF,IC,AL069260000    I42 @T6G_MB_LIB.T6G(SCH_1):PAGE475
PR6608    1      A Q_RES_0402LF-1,1%,1/16W,CHIP,CS-1002FB04   I131 @T6G_MB_LIB.T6G(SCH_1):PAGE475
PC6604    1      A Q_CAP_C0402-1UF,16V,10%,X6S,CH5103KEB01   I132 @T6G_MB_LIB.T6G(SCH_1):PAGE475
PC6603    1      A Q_CAP_C0402-100NF,50V,10%,X7R,CH4106K1B01   I144 @T6G_MB_LIB.T6G(SCH_1):PAGE475

P0V9_RETIMER_CPU0_VCC1 @T6G_MB_LIB.T6G(SCH_1):P0V9_RETIMER_CPU0_VCC1
PC6552    1      A Q_CAP_C0402-2.2UF,10V,10%,X6S,CH5222KEB01    I48 @T6G_MB_LIB.T6G(SCH_1):PAGE476
PU6503   35     EN ISL99390FRZTR5935-ISL99390FRZ-TR5935,SMLF,IC,AL099A    I53 @T6G_MB_LIB.T6G(SCH_1):PAGE476
PU6503    3    VCC ISL99390FRZTR5935-ISL99390FRZ-TR5935,SMLF,IC,AL099A    I53 @T6G_MB_LIB.T6G(SCH_1):PAGE476
PR6552    2      B Q_RES_0402LF-2.2,5%,1/16W,CHIP,TMP_QCS-2202JB25    I58 @T6G_MB_LIB.T6G(SCH_1):PAGE476

P0V9_RETIMER_CPU0_VCC2 @T6G_MB_LIB.T6G(SCH_1):P0V9_RETIMER_CPU0_VCC2
PR6560    2      B Q_RES_0402LF-2.2,5%,1/16W,CHIP,TMP_QCS-2202JB25   I269 @T6G_MB_LIB.T6G(SCH_1):PAGE476
PU6504   35     EN ISL99390FRZTR5935-ISL99390FRZ-TR5935,SMLF,IC,AL099A   I270 @T6G_MB_LIB.T6G(SCH_1):PAGE476
PU6504    3    VCC ISL99390FRZTR5935-ISL99390FRZ-TR5935,SMLF,IC,AL099A   I270 @T6G_MB_LIB.T6G(SCH_1):PAGE476
PC6575    1      A Q_CAP_C0402-2.2UF,10V,10%,X6S,CH5222KEB01   I271 @T6G_MB_LIB.T6G(SCH_1):PAGE476

P0V9_RETIMER_CPU0_VINSEN @T6G_MB_LIB.T6G(SCH_1):P0V9_RETIMER_CPU0_VINSEN
PU6502   38 VINSEN||VSYS ISL69260IRAZT-ISL69260IRAZ-T,SMLF,IC,AL069260000    I42 @T6G_MB_LIB.T6G(SCH_1):PAGE475
PC6602    1      A Q_CAP_0402-0.1UF,25V,10%,X7R,CH4104K1B00   I123 @T6G_MB_LIB.T6G(SCH_1):PAGE475
PR6607    1      A Q_RES_0402LF-1K,1%,1/16W,EMPTY,CS21002FB06   I125 @T6G_MB_LIB.T6G(SCH_1):PAGE475
PR6606    2      B Q_RES_0402LF-0,5%,1/16W,CHIP,CS00002JB13   I160 @T6G_MB_LIB.T6G(SCH_1):PAGE475

P0V9_RETIMER_CPU0_VMON @T6G_MB_LIB.T6G(SCH_1):P0V9_RETIMER_CPU0_VMON
PU6502   37 VMON||IINSEN||VSYS||ISYS ISL69260IRAZT-ISL69260IRAZ-T,SMLF,IC,AL069260000    I42 @T6G_MB_LIB.T6G(SCH_1):PAGE475
PR6605    1      A Q_RES_0402LF-0,5%,1/16W,CHIP,CS00002JB13   I150 @T6G_MB_LIB.T6G(SCH_1):PAGE475
PC6601    1      A Q_CAP_0402-0.1UF,25V,10%,EMPTY,CH4104K1B00   I151 @T6G_MB_LIB.T6G(SCH_1):PAGE475
PR6807    2      B Q_RES_0402LF-0,5%,1/16W,EMPTY,CS00002JB13   I158 @T6G_MB_LIB.T6G(SCH_1):PAGE475
PR6604    2      B Q_RES_0402LF-5.36K,1%,1/16W,EMPTY,CS25362FB02   I178 @T6G_MB_LIB.T6G(SCH_1):PAGE475

P0V9_RETIMER_CPU0_VOS1 @T6G_MB_LIB.T6G(SCH_1):P0V9_RETIMER_CPU0_VOS1
PR6556    1      A Q_RES_0402LF-0,5%,1/16W,CHIP,CS00002JB13    I42 @T6G_MB_LIB.T6G(SCH_1):PAGE476
PU6503    1    VOS ISL99390FRZTR5935-ISL99390FRZ-TR5935,SMLF,IC,AL099A    I53 @T6G_MB_LIB.T6G(SCH_1):PAGE476

P0V9_RETIMER_CPU0_VOS2 @T6G_MB_LIB.T6G(SCH_1):P0V9_RETIMER_CPU0_VOS2
PR6564    1      A Q_RES_0402LF-0,5%,1/16W,CHIP,CS00002JB13   I263 @T6G_MB_LIB.T6G(SCH_1):PAGE476
PU6504    1    VOS ISL99390FRZTR5935-ISL99390FRZ-TR5935,SMLF,IC,AL099A   I270 @T6G_MB_LIB.T6G(SCH_1):PAGE476

P0V9_RETIMER_CPU0_VRHOT @T6G_MB_LIB.T6G(SCH_1):P0V9_RETIMER_CPU0_VRHOT
PU6502   14 NVRHOT# ISL69260IRAZT-ISL69260IRAZ-T,SMLF,IC,AL069260000    I42 @T6G_MB_LIB.T6G(SCH_1):PAGE475
PR6616    1      A Q_RES_0402LF-0,5%,1/16W,CHIP,CS00002JB13   I136 @T6G_MB_LIB.T6G(SCH_1):PAGE475

P0V9_RETIMER_CPU1_ADDR @T6G_MB_LIB.T6G(SCH_1):P0V9_RETIMER_CPU1_ADDR
PR6533    2      B Q_RES_0402LF-22.1K,1%,1/16W,CHIP,CS32212FB02    I13 @T6G_MB_LIB.T6G(SCH_1):PAGE477
PU6510   34 ADDR_CFG ISL69260IRAZT-ISL69260IRAZ-T,SMLF,IC,AL069260000    I88 @T6G_MB_LIB.T6G(SCH_1):PAGE477

P0V9_RETIMER_CPU1_CFP @T6G_MB_LIB.T6G(SCH_1):P0V9_RETIMER_CPU1_CFP
  R663    2      B Q_RES_0402LF-1K,1%,1/16W,CHIP,CS21002FB06    I15 @T6G_MB_LIB.T6G(SCH_1):PAGE477
PU6510   33    CFP ISL69260IRAZT-ISL69260IRAZ-T,SMLF,IC,AL069260000    I88 @T6G_MB_LIB.T6G(SCH_1):PAGE477

P0V9_RETIMER_CPU1_EN @T6G_MB_LIB.T6G(SCH_1):P0V9_RETIMER_CPU1_EN
  R662    1      A Q_RES_0402LF-0,5%,1/16W,CHIP,CS00002JB13    I38 @T6G_MB_LIB.T6G(SCH_1):PAGE477
 R6855    2      B Q_RES_0402LF-33,5%,1/16W,CHIP,CS03302JB10   I366 @T6G_MB_LIB.T6G(SCH_1):PAGE80

P0V9_RETIMER_CPU1_EN0_R @T6G_MB_LIB.T6G(SCH_1):P0V9_RETIMER_CPU1_EN0_R
  R662    2      B Q_RES_0402LF-0,5%,1/16W,CHIP,CS00002JB13    I38 @T6G_MB_LIB.T6G(SCH_1):PAGE477
PU6510   13    EN0 ISL69260IRAZT-ISL69260IRAZ-T,SMLF,IC,AL069260000    I88 @T6G_MB_LIB.T6G(SCH_1):PAGE477
 R6787    1      A Q_RES_0402LF-1K,1%,1/16W,CHIP,CS21002FB06    I90 @T6G_MB_LIB.T6G(SCH_1):PAGE477

P0V9_RETIMER_CPU1_EN1_R @T6G_MB_LIB.T6G(SCH_1):P0V9_RETIMER_CPU1_EN1_R
 R6800    2      B Q_RES_0402LF-0,5%,1/16W,CHIP,CS00002JB13     I2 @T6G_MB_LIB.T6G(SCH_1):PAGE477
PU6510   20    EN1 ISL69260IRAZT-ISL69260IRAZ-T,SMLF,IC,AL069260000    I88 @T6G_MB_LIB.T6G(SCH_1):PAGE477

P0V9_RETIMER_CPU1_EN_R2 @T6G_MB_LIB.T6G(SCH_1):P0V9_RETIMER_CPU1_EN_R2
   U18 AA21 PB46B||SI||SISPI LCMXO3LF9400C5BG484C-LCMXO3LF-9400C-5BG484C,SMLF,IA   I216 @T6G_MB_LIB.T6G(SCH_1):PAGE80
 R6855    1      A Q_RES_0402LF-33,5%,1/16W,CHIP,CS03302JB10   I366 @T6G_MB_LIB.T6G(SCH_1):PAGE80

P0V9_RETIMER_CPU1_IMON1 @T6G_MB_LIB.T6G(SCH_1):P0V9_RETIMER_CPU1_IMON1
PU6510   23    CS7 ISL69260IRAZT-ISL69260IRAZ-T,SMLF,IC,AL069260000    I88 @T6G_MB_LIB.T6G(SCH_1):PAGE477
PU6511   38   IOUT ISL99390FRZTR5935-ISL99390FRZ-TR5935,SMLF,IC,AL099A    I51 @T6G_MB_LIB.T6G(SCH_1):PAGE478

P0V9_RETIMER_CPU1_IMON2 @T6G_MB_LIB.T6G(SCH_1):P0V9_RETIMER_CPU1_IMON2
PU6510   24    CS6 ISL69260IRAZT-ISL69260IRAZ-T,SMLF,IC,AL069260000    I88 @T6G_MB_LIB.T6G(SCH_1):PAGE477
PU6512   38   IOUT ISL99390FRZTR5935-ISL99390FRZ-TR5935,SMLF,IC,AL099A    I12 @T6G_MB_LIB.T6G(SCH_1):PAGE478

P0V9_RETIMER_CPU1_INALERT @T6G_MB_LIB.T6G(SCH_1):P0V9_RETIMER_CPU1_INALERT
  R665    2      B Q_RES_0402LF-1K,1%,1/16W,CHIP,CS21002FB06    I14 @T6G_MB_LIB.T6G(SCH_1):PAGE477
PU6510   15 NPINALERT#||NPSYSCRIT# ISL69260IRAZT-ISL69260IRAZ-T,SMLF,IC,AL069260000    I88 @T6G_MB_LIB.T6G(SCH_1):PAGE477

P0V9_RETIMER_CPU1_LSET1 @T6G_MB_LIB.T6G(SCH_1):P0V9_RETIMER_CPU1_LSET1
PR6622    1      A Q_RES_0402LF-8.87K,1%,1/16W,EMPTY,CS28872FB01    I46 @T6G_MB_LIB.T6G(SCH_1):PAGE478
PU6511   37   LSET ISL99390FRZTR5935-ISL99390FRZ-TR5935,SMLF,IC,AL099A    I51 @T6G_MB_LIB.T6G(SCH_1):PAGE478

P0V9_RETIMER_CPU1_LSET2 @T6G_MB_LIB.T6G(SCH_1):P0V9_RETIMER_CPU1_LSET2
PR6628    1      A Q_RES_0402LF-8.87K,1%,1/16W,EMPTY,CS28872FB01     I5 @T6G_MB_LIB.T6G(SCH_1):PAGE478
PU6512   37   LSET ISL99390FRZTR5935-ISL99390FRZ-TR5935,SMLF,IC,AL099A    I12 @T6G_MB_LIB.T6G(SCH_1):PAGE478

P0V9_RETIMER_CPU1_PMSCL @T6G_MB_LIB.T6G(SCH_1):P0V9_RETIMER_CPU1_PMSCL
  R657    1      A Q_RES_0402LF-0,5%,1/16W,CHIP,CS00002JB13    I33 @T6G_MB_LIB.T6G(SCH_1):PAGE477
 R6858    2      B Q_RES_0402LF-0,5%,1/16W,CHIP,CS00002JB13   I207 @T6G_MB_LIB.T6G(SCH_1):PAGE349

P0V9_RETIMER_CPU1_PMSCL_R @T6G_MB_LIB.T6G(SCH_1):P0V9_RETIMER_CPU1_PMSCL_R
  R657    2      B Q_RES_0402LF-0,5%,1/16W,CHIP,CS00002JB13    I33 @T6G_MB_LIB.T6G(SCH_1):PAGE477
PU6510   10  PMSCL ISL69260IRAZT-ISL69260IRAZ-T,SMLF,IC,AL069260000    I88 @T6G_MB_LIB.T6G(SCH_1):PAGE477

P0V9_RETIMER_CPU1_PMSDA @T6G_MB_LIB.T6G(SCH_1):P0V9_RETIMER_CPU1_PMSDA
  R658    1      A Q_RES_0402LF-0,5%,1/16W,CHIP,CS00002JB13    I31 @T6G_MB_LIB.T6G(SCH_1):PAGE477
 R6859    2      B Q_RES_0402LF-0,5%,1/16W,CHIP,CS00002JB13   I206 @T6G_MB_LIB.T6G(SCH_1):PAGE349

P0V9_RETIMER_CPU1_PMSDA_R @T6G_MB_LIB.T6G(SCH_1):P0V9_RETIMER_CPU1_PMSDA_R
  R658    2      B Q_RES_0402LF-0,5%,1/16W,CHIP,CS00002JB13    I31 @T6G_MB_LIB.T6G(SCH_1):PAGE477
PU6510    9  PMSDA ISL69260IRAZT-ISL69260IRAZ-T,SMLF,IC,AL069260000    I88 @T6G_MB_LIB.T6G(SCH_1):PAGE477

P0V9_RETIMER_CPU1_PVCC @T6G_MB_LIB.T6G(SCH_1):P0V9_RETIMER_CPU1_PVCC
PR6627    1      A Q_RES_0402LF-2.2,5%,1/16W,CHIP,TMP_QCS-2202JB25    I11 @T6G_MB_LIB.T6G(SCH_1):PAGE478
PU6512    4   PVCC ISL99390FRZTR5935-ISL99390FRZ-TR5935,SMLF,IC,AL099A    I12 @T6G_MB_LIB.T6G(SCH_1):PAGE478
PC6644_09P1_2    1      A Q_CAP_C0402-2.2UF,10V,10%,X6S,CH5222KEB01    I14 @T6G_MB_LIB.T6G(SCH_1):PAGE478
PR6619    2      B Q_RES_0402LF-0,5%,1/16W,CHIP,CS00002JB13    I42 @T6G_MB_LIB.T6G(SCH_1):PAGE478
PU6511    4   PVCC ISL99390FRZTR5935-ISL99390FRZ-TR5935,SMLF,IC,AL099A    I51 @T6G_MB_LIB.T6G(SCH_1):PAGE478
PR6621    1      A Q_RES_0402LF-2.2,5%,1/16W,CHIP,TMP_QCS-2202JB25    I53 @T6G_MB_LIB.T6G(SCH_1):PAGE478
PC6609_09P1_1    1      A Q_CAP_C0402-2.2UF,10V,10%,X6S,CH5222KEB01    I55 @T6G_MB_LIB.T6G(SCH_1):PAGE478
PR6620    2      B Q_RES_0402LF-0,5%,1/16W,EMPTY,CS00002JB13    I56 @T6G_MB_LIB.T6G(SCH_1):PAGE478

P0V9_RETIMER_CPU1_PWM1 @T6G_MB_LIB.T6G(SCH_1):P0V9_RETIMER_CPU1_PWM1
PU6510    8   PWM7 ISL69260IRAZT-ISL69260IRAZ-T,SMLF,IC,AL069260000    I88 @T6G_MB_LIB.T6G(SCH_1):PAGE477
PU6511   34    PWM ISL99390FRZTR5935-ISL99390FRZ-TR5935,SMLF,IC,AL099A    I51 @T6G_MB_LIB.T6G(SCH_1):PAGE478

P0V9_RETIMER_CPU1_PWM2 @T6G_MB_LIB.T6G(SCH_1):P0V9_RETIMER_CPU1_PWM2
PU6510    7   PWM6 ISL69260IRAZT-ISL69260IRAZ-T,SMLF,IC,AL069260000    I88 @T6G_MB_LIB.T6G(SCH_1):PAGE477
PU6512   34    PWM ISL99390FRZTR5935-ISL99390FRZ-TR5935,SMLF,IC,AL099A    I12 @T6G_MB_LIB.T6G(SCH_1):PAGE478

P0V9_RETIMER_CPU1_SENSE_R_P @T6G_MB_LIB.T6G(SCH_1):P0V9_RETIMER_CPU1_SENSE_R_P
PR6601    2      B Q_RES_0402LF-0,5%,1/16W,CHIP,CS00002JB13    I27 @T6G_MB_LIB.T6G(SCH_1):PAGE477
PC6600    1      A Q_CAP_0402-3300PF,50V,10%,X7R,TMP_QCH2336K1B12    I28 @T6G_MB_LIB.T6G(SCH_1):PAGE477
PU6510   21  VSEN0 ISL69260IRAZT-ISL69260IRAZ-T,SMLF,IC,AL069260000    I88 @T6G_MB_LIB.T6G(SCH_1):PAGE477

P0V9_RETIMER_CPU1_SENSE_SH_N @T6G_MB_LIB.T6G(SCH_1):P0V9_RETIMER_CPU1_SENSE_SH_N
PR6602    1      A Q_RES_0402LF-49.9,1%,1/16W,CHIP,CS04992FB07    I22 @T6G_MB_LIB.T6G(SCH_1):PAGE477
PC6600    2      B Q_CAP_0402-3300PF,50V,10%,X7R,TMP_QCH2336K1B12    I28 @T6G_MB_LIB.T6G(SCH_1):PAGE477
PU6510   22  RGND0 ISL69260IRAZT-ISL69260IRAZ-T,SMLF,IC,AL069260000    I88 @T6G_MB_LIB.T6G(SCH_1):PAGE477
PJ09_P1_N    2      2 Q_SHORT_SM-EMPTY,SHORT16    I96 @T6G_MB_LIB.T6G(SCH_1):PAGE477

P0V9_RETIMER_CPU1_SENSE_SH_P @T6G_MB_LIB.T6G(SCH_1):P0V9_RETIMER_CPU1_SENSE_SH_P
PR6600    1      A Q_RES_0402LF-49.9,1%,1/16W,CHIP,CS04992FB07    I23 @T6G_MB_LIB.T6G(SCH_1):PAGE477
PR6601    1      A Q_RES_0402LF-0,5%,1/16W,CHIP,CS00002JB13    I27 @T6G_MB_LIB.T6G(SCH_1):PAGE477
PJ09_P1_P    2      2 Q_SHORT_SM-EMPTY,SHORT16    I95 @T6G_MB_LIB.T6G(SCH_1):PAGE477

P0V9_RETIMER_CPU1_SVID_CLK @T6G_MB_LIB.T6G(SCH_1):P0V9_RETIMER_CPU1_SVID_CLK
PR6806    2      B Q_RES_0402LF-1K,1%,1/16W,EMPTY,CS21002FB06    I37 @T6G_MB_LIB.T6G(SCH_1):PAGE477
PR6811    1      A Q_RES_0402LF-0,5%,1/16W,CHIP,CS00002JB13    I42 @T6G_MB_LIB.T6G(SCH_1):PAGE477
PU6510   17  SVCLK ISL69260IRAZT-ISL69260IRAZ-T,SMLF,IC,AL069260000    I88 @T6G_MB_LIB.T6G(SCH_1):PAGE477

P0V9_RETIMER_CPU1_SVID_SDA @T6G_MB_LIB.T6G(SCH_1):P0V9_RETIMER_CPU1_SVID_SDA
PR6804    2      B Q_RES_0402LF-1K,1%,1/16W,EMPTY,CS21002FB06    I36 @T6G_MB_LIB.T6G(SCH_1):PAGE477
PR6820    1      A Q_RES_0402LF-0,5%,1/16W,CHIP,CS00002JB13    I43 @T6G_MB_LIB.T6G(SCH_1):PAGE477
PU6510   18 SVDATA ISL69260IRAZT-ISL69260IRAZ-T,SMLF,IC,AL069260000    I88 @T6G_MB_LIB.T6G(SCH_1):PAGE477

P0V9_RETIMER_CPU1_TEMP0 @T6G_MB_LIB.T6G(SCH_1):P0V9_RETIMER_CPU1_TEMP0
 PC523    1      A Q_CAP_0402-470PF,50V,10%,X7R,TMP_QCH14706KB18    I51 @T6G_MB_LIB.T6G(SCH_1):PAGE477
PR6815    1      A Q_RES_0402LF-10K,1%,1/16W,EMPTY,CS31002FB08    I54 @T6G_MB_LIB.T6G(SCH_1):PAGE477
PU6510   35  TEMP0 ISL69260IRAZT-ISL69260IRAZ-T,SMLF,IC,AL069260000    I88 @T6G_MB_LIB.T6G(SCH_1):PAGE477
PU6512   36 TOUT_FLT ISL99390FRZTR5935-ISL99390FRZ-TR5935,SMLF,IC,AL099A    I12 @T6G_MB_LIB.T6G(SCH_1):PAGE478
PU6511   36 TOUT_FLT ISL99390FRZTR5935-ISL99390FRZ-TR5935,SMLF,IC,AL099A    I51 @T6G_MB_LIB.T6G(SCH_1):PAGE478

P0V9_RETIMER_CPU1_TEMP1_R @T6G_MB_LIB.T6G(SCH_1):P0V9_RETIMER_CPU1_TEMP1_R
PR6548    1      A Q_RES_0402LF-0,5%,1/16W,CHIP,CS00002JB13    I52 @T6G_MB_LIB.T6G(SCH_1):PAGE477
PU6510   36 TEMP1||ISYS ISL69260IRAZT-ISL69260IRAZ-T,SMLF,IC,AL069260000    I88 @T6G_MB_LIB.T6G(SCH_1):PAGE477

P0V9_RETIMER_CPU1_VCC @T6G_MB_LIB.T6G(SCH_1):P0V9_RETIMER_CPU1_VCC
PC6543    1      A Q_CAP_C0402-100NF,50V,10%,X7R,CH4106K1B01    I74 @T6G_MB_LIB.T6G(SCH_1):PAGE477
PC6544    1      A Q_CAP_C0402-1UF,16V,10%,X6S,CH5103KEB01    I75 @T6G_MB_LIB.T6G(SCH_1):PAGE477
PR6538    1      A Q_RES_0402LF-1,1%,1/16W,CHIP,CS-1002FB04    I83 @T6G_MB_LIB.T6G(SCH_1):PAGE477
PU6510   39    VCC ISL69260IRAZT-ISL69260IRAZ-T,SMLF,IC,AL069260000    I88 @T6G_MB_LIB.T6G(SCH_1):PAGE477

P0V9_RETIMER_CPU1_VCC1 @T6G_MB_LIB.T6G(SCH_1):P0V9_RETIMER_CPU1_VCC1
PU6511   35     EN ISL99390FRZTR5935-ISL99390FRZ-TR5935,SMLF,IC,AL099A    I51 @T6G_MB_LIB.T6G(SCH_1):PAGE478
PU6511    3    VCC ISL99390FRZTR5935-ISL99390FRZ-TR5935,SMLF,IC,AL099A    I51 @T6G_MB_LIB.T6G(SCH_1):PAGE478
PC6610    1      A Q_CAP_C0402-2.2UF,10V,10%,X6S,CH5222KEB01    I52 @T6G_MB_LIB.T6G(SCH_1):PAGE478
PR6621    2      B Q_RES_0402LF-2.2,5%,1/16W,CHIP,TMP_QCS-2202JB25    I53 @T6G_MB_LIB.T6G(SCH_1):PAGE478

P0V9_RETIMER_CPU1_VCC2 @T6G_MB_LIB.T6G(SCH_1):P0V9_RETIMER_CPU1_VCC2
PC6645    1      A Q_CAP_C0402-2.2UF,10V,10%,X6S,CH5222KEB01    I10 @T6G_MB_LIB.T6G(SCH_1):PAGE478
PR6627    2      B Q_RES_0402LF-2.2,5%,1/16W,CHIP,TMP_QCS-2202JB25    I11 @T6G_MB_LIB.T6G(SCH_1):PAGE478
PU6512   35     EN ISL99390FRZTR5935-ISL99390FRZ-TR5935,SMLF,IC,AL099A    I12 @T6G_MB_LIB.T6G(SCH_1):PAGE478
PU6512    3    VCC ISL99390FRZTR5935-ISL99390FRZ-TR5935,SMLF,IC,AL099A    I12 @T6G_MB_LIB.T6G(SCH_1):PAGE478

P0V9_RETIMER_CPU1_VINSEN @T6G_MB_LIB.T6G(SCH_1):P0V9_RETIMER_CPU1_VINSEN
PR6809    2      B Q_RES_0402LF-0,5%,1/16W,CHIP,CS00002JB13    I10 @T6G_MB_LIB.T6G(SCH_1):PAGE477
PR6813    1      A Q_RES_0402LF-1K,1%,1/16W,EMPTY,CS21002FB06    I46 @T6G_MB_LIB.T6G(SCH_1):PAGE477
 PC819    1      A Q_CAP_0402-0.1UF,25V,10%,X7R,CH4104K1B00    I48 @T6G_MB_LIB.T6G(SCH_1):PAGE477
PU6510   38 VINSEN||VSYS ISL69260IRAZT-ISL69260IRAZ-T,SMLF,IC,AL069260000    I88 @T6G_MB_LIB.T6G(SCH_1):PAGE477

P0V9_RETIMER_CPU1_VMON @T6G_MB_LIB.T6G(SCH_1):P0V9_RETIMER_CPU1_VMON
PR6821    1      A Q_RES_0402LF-0,5%,1/16W,CHIP,CS00002JB13     I3 @T6G_MB_LIB.T6G(SCH_1):PAGE477
 PC514    1      A Q_CAP_0402-0.1UF,25V,10%,EMPTY,CH4104K1B00     I5 @T6G_MB_LIB.T6G(SCH_1):PAGE477
 PR885    2      B Q_RES_0402LF-5.36K,1%,1/16W,EMPTY,CS25362FB02     I7 @T6G_MB_LIB.T6G(SCH_1):PAGE477
PR6808    2      B Q_RES_0402LF-0,5%,1/16W,EMPTY,CS00002JB13    I11 @T6G_MB_LIB.T6G(SCH_1):PAGE477
PU6510   37 VMON||IINSEN||VSYS||ISYS ISL69260IRAZT-ISL69260IRAZ-T,SMLF,IC,AL069260000    I88 @T6G_MB_LIB.T6G(SCH_1):PAGE477

P0V9_RETIMER_CPU1_VOS1 @T6G_MB_LIB.T6G(SCH_1):P0V9_RETIMER_CPU1_VOS1
PU6511    1    VOS ISL99390FRZTR5935-ISL99390FRZ-TR5935,SMLF,IC,AL099A    I51 @T6G_MB_LIB.T6G(SCH_1):PAGE478
PR6626    1      A Q_RES_0402LF-0,5%,1/16W,CHIP,CS00002JB13    I59 @T6G_MB_LIB.T6G(SCH_1):PAGE478

P0V9_RETIMER_CPU1_VOS2 @T6G_MB_LIB.T6G(SCH_1):P0V9_RETIMER_CPU1_VOS2
PU6512    1    VOS ISL99390FRZTR5935-ISL99390FRZ-TR5935,SMLF,IC,AL099A    I12 @T6G_MB_LIB.T6G(SCH_1):PAGE478
PR6631    1      A Q_RES_0402LF-0,5%,1/16W,CHIP,CS00002JB13    I16 @T6G_MB_LIB.T6G(SCH_1):PAGE478

P0V9_RETIMER_CPU1_VRHOT @T6G_MB_LIB.T6G(SCH_1):P0V9_RETIMER_CPU1_VRHOT
PR6816    1      A Q_RES_0402LF-0,5%,1/16W,CHIP,CS00002JB13    I56 @T6G_MB_LIB.T6G(SCH_1):PAGE477
PU6510   14 NVRHOT# ISL69260IRAZT-ISL69260IRAZ-T,SMLF,IC,AL069260000    I88 @T6G_MB_LIB.T6G(SCH_1):PAGE477

P12V_ALL_PWROK @T6G_MB_LIB.T6G(SCH_1):P12V_ALL_PWROK
   Q12    G   GATE MOSFET_N_GSD-NX138BK,SMLF,IC,BAM01380023    I44 @T6G_MB_LIB.T6G(SCH_1):PAGE143
  R372    2      B Q_RES_0402LF-33,5%,1/16W,CHIP,CS03302JB10   I159 @T6G_MB_LIB.T6G(SCH_1):PAGE80

P12V_ALL_PWROK_N @T6G_MB_LIB.T6G(SCH_1):P12V_ALL_PWROK_N
   D46    C      C Q_LED_SMLF-LED_BLUE,LTST-C281TBKT-5A,IC,BEBL0172Z00    I43 @T6G_MB_LIB.T6G(SCH_1):PAGE143
   Q12    D  DRAIN MOSFET_N_GSD-NX138BK,SMLF,IC,BAM01380023    I44 @T6G_MB_LIB.T6G(SCH_1):PAGE143

P12V_ALL_PWROK_R @T6G_MB_LIB.T6G(SCH_1):P12V_ALL_PWROK_R
  R372    1      A Q_RES_0402LF-33,5%,1/16W,CHIP,CS03302JB10   I159 @T6G_MB_LIB.T6G(SCH_1):PAGE80
   U18  T18  PR27B LCMXO3LF9400C5BG484C-LCMXO3LF-9400C-5BG484C,SMLF,IA   I217 @T6G_MB_LIB.T6G(SCH_1):PAGE80

P12V_AUX @T6G_MB_LIB.T6G(SCH_1):P12V_AUX
PC6002    1      A Q_CAP_0402-0.1UF,25V,10%,X7R,CH4104K1B00     I3 @T6G_MB_LIB.T6G(SCH_1):PAGE201
  PL56    2      2 Q_INDUCTOR_SMLF-100NH/16A,IND,CV+10G0MZ04    I84 @T6G_MB_LIB.T6G(SCH_1):PAGE200
  PC85    1      A Q_CAP_0402-0.1UF,25V,10%,X7R,CH4104K1B00    I87 @T6G_MB_LIB.T6G(SCH_1):PAGE176
PC6003    1      A Q_CAP_0402-0.1UF,25V,10%,X7R,CH4104K1B00    I79 @T6G_MB_LIB.T6G(SCH_1):PAGE183
 PR181    1      A Q_RES_0402LF-0,5%,1/16W,CHIP,CS00002JB13    I47 @T6G_MB_LIB.T6G(SCH_1):PAGE185
 R3117    1      A Q_RES_0402LF-510K,5%,1/16W,EMPTY,CS45102JB03     I4 @T6G_MB_LIB.T6G(SCH_1):PAGE245
   PU9    3    VIN NCP3284AMNTXG-NCP3284AMNTXG,SMLF,IC,AL003284002    I21 @T6G_MB_LIB.T6G(SCH_1):PAGE245
PC1649    1      A Q_CAP_C0402-0.1UF,25V,10%,X6S,CH4104KEB00    I23 @T6G_MB_LIB.T6G(SCH_1):PAGE245
 PU288    1  VOUT1 MP5991GLUZ-MP5991GLU-Z,SMLF,IC,AL005991A00    I16 @T6G_MB_LIB.T6G(SCH_1):PAGE301
 PU288    2  VOUT2 MP5991GLUZ-MP5991GLU-Z,SMLF,IC,AL005991A00    I16 @T6G_MB_LIB.T6G(SCH_1):PAGE301
 PU288   25  VOUT3 MP5991GLUZ-MP5991GLU-Z,SMLF,IC,AL005991A00    I16 @T6G_MB_LIB.T6G(SCH_1):PAGE301
 PU288   26  VOUT4 MP5991GLUZ-MP5991GLU-Z,SMLF,IC,AL005991A00    I16 @T6G_MB_LIB.T6G(SCH_1):PAGE301
 PU288   27  VOUT5 MP5991GLUZ-MP5991GLU-Z,SMLF,IC,AL005991A00    I16 @T6G_MB_LIB.T6G(SCH_1):PAGE301
 PU288   28  VOUT6 MP5991GLUZ-MP5991GLU-Z,SMLF,IC,AL005991A00    I16 @T6G_MB_LIB.T6G(SCH_1):PAGE301
 PU288   29  VOUT7 MP5991GLUZ-MP5991GLU-Z,SMLF,IC,AL005991A00    I16 @T6G_MB_LIB.T6G(SCH_1):PAGE301
 PU288   30  VOUT8 MP5991GLUZ-MP5991GLU-Z,SMLF,IC,AL005991A00    I16 @T6G_MB_LIB.T6G(SCH_1):PAGE301
 PU288   31  VOUT9 MP5991GLUZ-MP5991GLU-Z,SMLF,IC,AL005991A00    I16 @T6G_MB_LIB.T6G(SCH_1):PAGE301
 PU288   32 VOUT10 MP5991GLUZ-MP5991GLU-Z,SMLF,IC,AL005991A00    I16 @T6G_MB_LIB.T6G(SCH_1):PAGE301
 PU287    1  VOUT1 MP5991GLUZ-MP5991GLU-Z,SMLF,IC,AL005991A00    I35 @T6G_MB_LIB.T6G(SCH_1):PAGE301
 PU287    2  VOUT2 MP5991GLUZ-MP5991GLU-Z,SMLF,IC,AL005991A00    I35 @T6G_MB_LIB.T6G(SCH_1):PAGE301
 PU287   25  VOUT3 MP5991GLUZ-MP5991GLU-Z,SMLF,IC,AL005991A00    I35 @T6G_MB_LIB.T6G(SCH_1):PAGE301
 PU287   26  VOUT4 MP5991GLUZ-MP5991GLU-Z,SMLF,IC,AL005991A00    I35 @T6G_MB_LIB.T6G(SCH_1):PAGE301
 PU287   27  VOUT5 MP5991GLUZ-MP5991GLU-Z,SMLF,IC,AL005991A00    I35 @T6G_MB_LIB.T6G(SCH_1):PAGE301
 PU287   28  VOUT6 MP5991GLUZ-MP5991GLU-Z,SMLF,IC,AL005991A00    I35 @T6G_MB_LIB.T6G(SCH_1):PAGE301
 PU287   29  VOUT7 MP5991GLUZ-MP5991GLU-Z,SMLF,IC,AL005991A00    I35 @T6G_MB_LIB.T6G(SCH_1):PAGE301
 PU287   30  VOUT8 MP5991GLUZ-MP5991GLU-Z,SMLF,IC,AL005991A00    I35 @T6G_MB_LIB.T6G(SCH_1):PAGE301
 PU287   31  VOUT9 MP5991GLUZ-MP5991GLU-Z,SMLF,IC,AL005991A00    I35 @T6G_MB_LIB.T6G(SCH_1):PAGE301
 PU287   32 VOUT10 MP5991GLUZ-MP5991GLU-Z,SMLF,IC,AL005991A00    I35 @T6G_MB_LIB.T6G(SCH_1):PAGE301
 PU297    1  VOUT1 MP5991GLUZ-MP5991GLU-Z,SMLF,IC,AL005991A00    I17 @T6G_MB_LIB.T6G(SCH_1):PAGE325
 PU297    2  VOUT2 MP5991GLUZ-MP5991GLU-Z,SMLF,IC,AL005991A00    I17 @T6G_MB_LIB.T6G(SCH_1):PAGE325
 PU297   25  VOUT3 MP5991GLUZ-MP5991GLU-Z,SMLF,IC,AL005991A00    I17 @T6G_MB_LIB.T6G(SCH_1):PAGE325
 PU297   26  VOUT4 MP5991GLUZ-MP5991GLU-Z,SMLF,IC,AL005991A00    I17 @T6G_MB_LIB.T6G(SCH_1):PAGE325
 PU297   27  VOUT5 MP5991GLUZ-MP5991GLU-Z,SMLF,IC,AL005991A00    I17 @T6G_MB_LIB.T6G(SCH_1):PAGE325
 PU297   28  VOUT6 MP5991GLUZ-MP5991GLU-Z,SMLF,IC,AL005991A00    I17 @T6G_MB_LIB.T6G(SCH_1):PAGE325
 PU297   29  VOUT7 MP5991GLUZ-MP5991GLU-Z,SMLF,IC,AL005991A00    I17 @T6G_MB_LIB.T6G(SCH_1):PAGE325
 PU297   30  VOUT8 MP5991GLUZ-MP5991GLU-Z,SMLF,IC,AL005991A00    I17 @T6G_MB_LIB.T6G(SCH_1):PAGE325
 PU297   31  VOUT9 MP5991GLUZ-MP5991GLU-Z,SMLF,IC,AL005991A00    I17 @T6G_MB_LIB.T6G(SCH_1):PAGE325
 PU297   32 VOUT10 MP5991GLUZ-MP5991GLU-Z,SMLF,IC,AL005991A00    I17 @T6G_MB_LIB.T6G(SCH_1):PAGE325
 PU296    1  VOUT1 MP5991GLUZ-MP5991GLU-Z,SMLF,IC,AL005991A00    I35 @T6G_MB_LIB.T6G(SCH_1):PAGE325
 PU296    2  VOUT2 MP5991GLUZ-MP5991GLU-Z,SMLF,IC,AL005991A00    I35 @T6G_MB_LIB.T6G(SCH_1):PAGE325
 PU296   25  VOUT3 MP5991GLUZ-MP5991GLU-Z,SMLF,IC,AL005991A00    I35 @T6G_MB_LIB.T6G(SCH_1):PAGE325
 PU296   26  VOUT4 MP5991GLUZ-MP5991GLU-Z,SMLF,IC,AL005991A00    I35 @T6G_MB_LIB.T6G(SCH_1):PAGE325
 PU296   27  VOUT5 MP5991GLUZ-MP5991GLU-Z,SMLF,IC,AL005991A00    I35 @T6G_MB_LIB.T6G(SCH_1):PAGE325
 PU296   28  VOUT6 MP5991GLUZ-MP5991GLU-Z,SMLF,IC,AL005991A00    I35 @T6G_MB_LIB.T6G(SCH_1):PAGE325
 PU296   29  VOUT7 MP5991GLUZ-MP5991GLU-Z,SMLF,IC,AL005991A00    I35 @T6G_MB_LIB.T6G(SCH_1):PAGE325
 PU296   30  VOUT8 MP5991GLUZ-MP5991GLU-Z,SMLF,IC,AL005991A00    I35 @T6G_MB_LIB.T6G(SCH_1):PAGE325
 PU296   31  VOUT9 MP5991GLUZ-MP5991GLU-Z,SMLF,IC,AL005991A00    I35 @T6G_MB_LIB.T6G(SCH_1):PAGE325
 PU296   32 VOUT10 MP5991GLUZ-MP5991GLU-Z,SMLF,IC,AL005991A00    I35 @T6G_MB_LIB.T6G(SCH_1):PAGE325
PR3805    1      A Q_RES_0402LF-160K,1%,1/16W,CHIP,CS41602FB05    I36 @T6G_MB_LIB.T6G(SCH_1):PAGE343
 R4067    1      A Q_RES_0402LF-10K,1%,1/16W,CHIP,CS31002FB08    I43 @T6G_MB_LIB.T6G(SCH_1):PAGE343
 PD107    C      C DIODE_TVS-SMF14A,SMLF,IC,BCSMF14AZ01    I47 @T6G_MB_LIB.T6G(SCH_1):PAGE343
PC2139    1      A Q_CAP_C0402-1UF,25V,10%,X6S,CH5104KEB02    I49 @T6G_MB_LIB.T6G(SCH_1):PAGE343
 PU201   A3  IN_A3 MAX15090BEWIT-MAX15090BEWI+T,SMLF,IC,AL015080B00    I67 @T6G_MB_LIB.T6G(SCH_1):PAGE343
 PU201   A5  IN_A5 MAX15090BEWIT-MAX15090BEWI+T,SMLF,IC,AL015080B00    I67 @T6G_MB_LIB.T6G(SCH_1):PAGE343
 PU201   B3  IN_B3 MAX15090BEWIT-MAX15090BEWI+T,SMLF,IC,AL015080B00    I67 @T6G_MB_LIB.T6G(SCH_1):PAGE343
 PU201   B5  IN_B5 MAX15090BEWIT-MAX15090BEWI+T,SMLF,IC,AL015080B00    I67 @T6G_MB_LIB.T6G(SCH_1):PAGE343
 PU201   C3  IN_C3 MAX15090BEWIT-MAX15090BEWI+T,SMLF,IC,AL015080B00    I67 @T6G_MB_LIB.T6G(SCH_1):PAGE343
 PU201   C5  IN_C5 MAX15090BEWIT-MAX15090BEWI+T,SMLF,IC,AL015080B00    I67 @T6G_MB_LIB.T6G(SCH_1):PAGE343
 PU201   D5  IN_D5 MAX15090BEWIT-MAX15090BEWI+T,SMLF,IC,AL015080B00    I67 @T6G_MB_LIB.T6G(SCH_1):PAGE343
PR3830    1      A Q_RES_0402LF-10,1%,1/16W,CHIP,CS01002FB07    I84 @T6G_MB_LIB.T6G(SCH_1):PAGE343
PC2165    1      A Q_CAP_C0402-1UF,25V,10%,X6S,CH5104KEB02    I13 @T6G_MB_LIB.T6G(SCH_1):PAGE344
PR3853    1      A Q_RES_0402LF-120K,1%,1/16W,CHIP,CS41202FB05    I36 @T6G_MB_LIB.T6G(SCH_1):PAGE344
PR3857    1      A Q_RES_0603LF-49.9,1%,1/10W,CHIP,CS04993F909    I37 @T6G_MB_LIB.T6G(SCH_1):PAGE344
PC2198    1      A Q_CAP_C0402-1UF,25V,10%,X6S,CH5104KEB02    I25 @T6G_MB_LIB.T6G(SCH_1):PAGE323
PR3953    1      A Q_RES_0402LF-120K,1%,1/16W,CHIP,CS41202FB05    I52 @T6G_MB_LIB.T6G(SCH_1):PAGE323
PR3957    1      A Q_RES_0603LF-49.9,1%,1/10W,CHIP,CS04993F909    I54 @T6G_MB_LIB.T6G(SCH_1):PAGE323
 R4074    1      A Q_RES_0402LF-10K,1%,1/16W,CHIP,CS31002FB08    I25 @T6G_MB_LIB.T6G(SCH_1):PAGE324
 PD114    C      C DIODE_TVS-SMF14A,SMLF,IC,BCSMF14AZ01    I33 @T6G_MB_LIB.T6G(SCH_1):PAGE324
PC2207    1      A Q_CAP_C0402-1UF,25V,10%,X6S,CH5104KEB02    I36 @T6G_MB_LIB.T6G(SCH_1):PAGE324
PR3960    1      A Q_RES_0402LF-160K,1%,1/16W,CHIP,CS41602FB05    I37 @T6G_MB_LIB.T6G(SCH_1):PAGE324
PR3966    1      A Q_RES_0402LF-10,1%,1/16W,CHIP,CS01002FB07    I65 @T6G_MB_LIB.T6G(SCH_1):PAGE324
 PU294   A3  IN_A3 MAX15090BEWIT-MAX15090BEWI+T,SMLF,IC,AL015080B00    I66 @T6G_MB_LIB.T6G(SCH_1):PAGE324
 PU294   A5  IN_A5 MAX15090BEWIT-MAX15090BEWI+T,SMLF,IC,AL015080B00    I66 @T6G_MB_LIB.T6G(SCH_1):PAGE324
 PU294   B3  IN_B3 MAX15090BEWIT-MAX15090BEWI+T,SMLF,IC,AL015080B00    I66 @T6G_MB_LIB.T6G(SCH_1):PAGE324
 PU294   B5  IN_B5 MAX15090BEWIT-MAX15090BEWI+T,SMLF,IC,AL015080B00    I66 @T6G_MB_LIB.T6G(SCH_1):PAGE324
 PU294   C3  IN_C3 MAX15090BEWIT-MAX15090BEWI+T,SMLF,IC,AL015080B00    I66 @T6G_MB_LIB.T6G(SCH_1):PAGE324
 PU294   C5  IN_C5 MAX15090BEWIT-MAX15090BEWI+T,SMLF,IC,AL015080B00    I66 @T6G_MB_LIB.T6G(SCH_1):PAGE324
 PU294   D5  IN_D5 MAX15090BEWIT-MAX15090BEWI+T,SMLF,IC,AL015080B00    I66 @T6G_MB_LIB.T6G(SCH_1):PAGE324
 R4071    1      A Q_RES_0402LF-10K,1%,1/16W,CHIP,CS31002FB08    I25 @T6G_MB_LIB.T6G(SCH_1):PAGE350
PC2230    1      A Q_CAP_C0402-1UF,25V,10%,X6S,CH5104KEB02    I31 @T6G_MB_LIB.T6G(SCH_1):PAGE350
PC2231    1      A Q_CAP_C0402-1UF,25V,10%,X6S,CH5104KEB02    I37 @T6G_MB_LIB.T6G(SCH_1):PAGE350
PR4010    1      A Q_RES_0402LF-120K,1%,1/16W,CHIP,CS41202FB05    I51 @T6G_MB_LIB.T6G(SCH_1):PAGE350
PR4000    1      A Q_RES_0402LF-160K,1%,1/16W,CHIP,CS41602FB05    I65 @T6G_MB_LIB.T6G(SCH_1):PAGE350
  R336    1      A Q_RES_0402LF-100K,1%,1/16W,CHIP,CS41002FB09    I10 @T6G_MB_LIB.T6G(SCH_1):PAGE273
 R2528    1      A Q_RES_0402LF-100K,1%,1/16W,CHIP,CS41002FB09     I8 @T6G_MB_LIB.T6G(SCH_1):PAGE365
 R2530    1      A Q_RES_0402LF-4.7K,5%,1/16W,CHIP,CS24702JB10    I10 @T6G_MB_LIB.T6G(SCH_1):PAGE365
 R4068    1      A Q_RES_0402LF-10K,1%,1/16W,CHIP,CS31002FB08    I17 @T6G_MB_LIB.T6G(SCH_1):PAGE338
PR3786    1      A Q_RES_0402LF-160K,1%,1/16W,CHIP,CS41602FB05    I43 @T6G_MB_LIB.T6G(SCH_1):PAGE338
PC2079    1      A Q_CAP_C0402-1UF,25V,10%,X6S,CH5104KEB02    I45 @T6G_MB_LIB.T6G(SCH_1):PAGE338
 PU203   A3  IN_A3 MAX15090BEWIT-MAX15090BEWI+T,SMLF,IC,AL015080B00    I50 @T6G_MB_LIB.T6G(SCH_1):PAGE338
 PU203   A5  IN_A5 MAX15090BEWIT-MAX15090BEWI+T,SMLF,IC,AL015080B00    I50 @T6G_MB_LIB.T6G(SCH_1):PAGE338
 PU203   B3  IN_B3 MAX15090BEWIT-MAX15090BEWI+T,SMLF,IC,AL015080B00    I50 @T6G_MB_LIB.T6G(SCH_1):PAGE338
 PU203   B5  IN_B5 MAX15090BEWIT-MAX15090BEWI+T,SMLF,IC,AL015080B00    I50 @T6G_MB_LIB.T6G(SCH_1):PAGE338
 PU203   C3  IN_C3 MAX15090BEWIT-MAX15090BEWI+T,SMLF,IC,AL015080B00    I50 @T6G_MB_LIB.T6G(SCH_1):PAGE338
 PU203   C5  IN_C5 MAX15090BEWIT-MAX15090BEWI+T,SMLF,IC,AL015080B00    I50 @T6G_MB_LIB.T6G(SCH_1):PAGE338
 PU203   D5  IN_D5 MAX15090BEWIT-MAX15090BEWI+T,SMLF,IC,AL015080B00    I50 @T6G_MB_LIB.T6G(SCH_1):PAGE338
PR3792    1      A Q_RES_0402LF-10,1%,1/16W,CHIP,CS01002FB07    I56 @T6G_MB_LIB.T6G(SCH_1):PAGE338
 R4070    1      A Q_RES_0402LF-10K,1%,1/16W,CHIP,CS31002FB08    I59 @T6G_MB_LIB.T6G(SCH_1):PAGE338
 PD101    C      C DIODE_TVS-SMF14A,SMLF,IC,BCSMF14AZ01   I115 @T6G_MB_LIB.T6G(SCH_1):PAGE338
 R4072    1      A Q_RES_0402LF-10K,1%,1/16W,CHIP,CS31002FB08     I8 @T6G_MB_LIB.T6G(SCH_1):PAGE324
PC2154    1      A Q_CAP_C0402-1UF,25V,10%,X6S,CH5104KEB02    I68 @T6G_MB_LIB.T6G(SCH_1):PAGE339
PR3841    1      A Q_RES_0402LF-120K,1%,1/16W,CHIP,CS41202FB05    I82 @T6G_MB_LIB.T6G(SCH_1):PAGE339
PR3843    1      A Q_RES_0603LF-49.9,1%,1/10W,CHIP,CS04993F909    I88 @T6G_MB_LIB.T6G(SCH_1):PAGE339
  R335    1      A Q_RES_0402LF-10K,1%,1/16W,CHIP,CS31002FB08    I15 @T6G_MB_LIB.T6G(SCH_1):PAGE273
PC1648    1      A Q_CAP_C0402-0.1UF,25V,10%,X6S,CH4104KEB00     I2 @T6G_MB_LIB.T6G(SCH_1):PAGE244
PL8064    1      1 Q_INDUCTOR_SMLF-BLM18SN220TN1D/8000MA,IND,CX220TN1A     I5 @T6G_MB_LIB.T6G(SCH_1):PAGE244
PL8045    1      1 Q_INDUCTOR_SMLF-100NH/16A,IND,CV+10G0MZ04    I24 @T6G_MB_LIB.T6G(SCH_1):PAGE245
PC8008    1      A Q_CAP_0603-1UF,16V,10%,X7R,TMP_QCH5103K1900    I44 @T6G_MB_LIB.T6G(SCH_1):PAGE245
PC6000    1      A Q_CAP_C0402-0.1UF,25V,10%,X6S,CH4104KEB00     I8 @T6G_MB_LIB.T6G(SCH_1):PAGE167
  PL71    1      1 Q_INDUCTOR_SMLF-BLM18SN220TN1D/8000MA,IND,CX220TN1A    I10 @T6G_MB_LIB.T6G(SCH_1):PAGE167
 PR314    1      A Q_RES_0402LF-0,5%,1/16W,CHIP,CS00002JB13    I48 @T6G_MB_LIB.T6G(SCH_1):PAGE168
  PL53    2      2 Q_INDUCTOR_SMLF-50NH/86A,IND,CVA50^0MZ09    I82 @T6G_MB_LIB.T6G(SCH_1):PAGE169
 PC479    1      A Q_CAP_0402-0.1UF,25V,10%,X7R,CH4104K1B00    I85 @T6G_MB_LIB.T6G(SCH_1):PAGE169
  PL65    2      2 Q_INDUCTOR_SMLF-50NH/86A,IND,CVA50^0MZ09    I74 @T6G_MB_LIB.T6G(SCH_1):PAGE173
 PC583    1      A Q_CAP_0402-0.1UF,25V,10%,X7R,CH4104K1B00    I77 @T6G_MB_LIB.T6G(SCH_1):PAGE173
  PR74    1      A Q_RES_0402LF-0,5%,1/16W,CHIP,CS00002JB13    I51 @T6G_MB_LIB.T6G(SCH_1):PAGE175
  PL12    2      2 Q_INDUCTOR_SMLF-50NH/86A,IND,CVA50^0MZ09    I83 @T6G_MB_LIB.T6G(SCH_1):PAGE176
  PL19    2      2 Q_INDUCTOR_SMLF-50NH/86A,IND,CVA50^0MZ09    I69 @T6G_MB_LIB.T6G(SCH_1):PAGE180
 PC148    1      A Q_CAP_0402-0.1UF,25V,10%,X7R,CH4104K1B00    I72 @T6G_MB_LIB.T6G(SCH_1):PAGE180
 PR125    1      A Q_RES_0402LF-0,5%,1/16W,CHIP,CS00002JB13    I16 @T6G_MB_LIB.T6G(SCH_1):PAGE182
  PL24    2      2 Q_INDUCTOR_SMLF-100NH/16A,IND,CV+10G0MZ04    I78 @T6G_MB_LIB.T6G(SCH_1):PAGE183
PC6001    1      A Q_CAP_C0402-0.1UF,25V,10%,X6S,CH4104KEB00     I5 @T6G_MB_LIB.T6G(SCH_1):PAGE184
  PL77    1      1 Q_INDUCTOR_SMLF-BLM18SN220TN1D/8000MA,IND,CX220TN1A     I7 @T6G_MB_LIB.T6G(SCH_1):PAGE184
  PL30    2      2 Q_INDUCTOR_SMLF-50NH/86A,IND,CVA50^0MZ09    I73 @T6G_MB_LIB.T6G(SCH_1):PAGE186
PC6004    1      A Q_CAP_0402-0.1UF,25V,10%,X7R,CH4104K1B00    I74 @T6G_MB_LIB.T6G(SCH_1):PAGE186
  PL37    2      2 Q_INDUCTOR_SMLF-50NH/86A,IND,CVA50^0MZ09    I74 @T6G_MB_LIB.T6G(SCH_1):PAGE190
PC6007    1      A Q_CAP_0402-0.1UF,25V,10%,X7R,CH4104K1B00    I77 @T6G_MB_LIB.T6G(SCH_1):PAGE190
 PR251    1      A Q_RES_0402LF-0,5%,1/16W,CHIP,CS00002JB13    I49 @T6G_MB_LIB.T6G(SCH_1):PAGE192
  PL42    2      2 Q_INDUCTOR_SMLF-50NH/86A,IND,CVA50^0MZ09    I79 @T6G_MB_LIB.T6G(SCH_1):PAGE193
 PC375    1      A Q_CAP_0402-0.1UF,25V,10%,X7R,CH4104K1B00    I83 @T6G_MB_LIB.T6G(SCH_1):PAGE193
  PL49    2      2 Q_INDUCTOR_SMLF-50NH/86A,IND,CVA50^0MZ09    I72 @T6G_MB_LIB.T6G(SCH_1):PAGE197
 PC438    1      A Q_CAP_0402-0.1UF,25V,10%,X7R,CH4104K1B00    I74 @T6G_MB_LIB.T6G(SCH_1):PAGE197
 PR388    1      A Q_RES_0402LF-0,5%,1/16W,CHIP,CS00002JB13    I18 @T6G_MB_LIB.T6G(SCH_1):PAGE199
 PC511    1      A Q_CAP_0402-0.1UF,25V,10%,X7R,CH4104K1B00    I85 @T6G_MB_LIB.T6G(SCH_1):PAGE200
  PL26    1      1 Q_INDUCTOR_SMLF-BLM18SN220TN1D/8000MA,IND,CX220TN1A     I4 @T6G_MB_LIB.T6G(SCH_1):PAGE201
 PD115    C      C DIODE_TVS-SMF14A,SMLF,IC,BCSMF14AZ01    I28 @T6G_MB_LIB.T6G(SCH_1):PAGE350
 PU300   A3  IN_A3 MAX15090BEWIT-MAX15090BEWI+T,SMLF,IC,AL015080B00    I86 @T6G_MB_LIB.T6G(SCH_1):PAGE350
 PU300   A5  IN_A5 MAX15090BEWIT-MAX15090BEWI+T,SMLF,IC,AL015080B00    I86 @T6G_MB_LIB.T6G(SCH_1):PAGE350
 PU300   B3  IN_B3 MAX15090BEWIT-MAX15090BEWI+T,SMLF,IC,AL015080B00    I86 @T6G_MB_LIB.T6G(SCH_1):PAGE350
 PU300   B5  IN_B5 MAX15090BEWIT-MAX15090BEWI+T,SMLF,IC,AL015080B00    I86 @T6G_MB_LIB.T6G(SCH_1):PAGE350
 PU300   C3  IN_C3 MAX15090BEWIT-MAX15090BEWI+T,SMLF,IC,AL015080B00    I86 @T6G_MB_LIB.T6G(SCH_1):PAGE350
 PU300   C5  IN_C5 MAX15090BEWIT-MAX15090BEWI+T,SMLF,IC,AL015080B00    I86 @T6G_MB_LIB.T6G(SCH_1):PAGE350
 PU300   D5  IN_D5 MAX15090BEWIT-MAX15090BEWI+T,SMLF,IC,AL015080B00    I86 @T6G_MB_LIB.T6G(SCH_1):PAGE350
PR4014    1      A Q_RES_0603LF-49.9,1%,1/10W,CHIP,CS04993F909    I53 @T6G_MB_LIB.T6G(SCH_1):PAGE350
PR4003    1      A Q_RES_0402LF-10,1%,1/16W,CHIP,CS01002FB07    I68 @T6G_MB_LIB.T6G(SCH_1):PAGE350
 R4065    1      A Q_RES_0402LF-10K,1%,1/16W,CHIP,CS31002FB08    I17 @T6G_MB_LIB.T6G(SCH_1):PAGE343
 R1799    1      A Q_RES_0402LF-7.87K,1%,1/16W,CHIP,CS27872FB02     I6 @T6G_MB_LIB.T6G(SCH_1):PAGE369
 PU289   27  VOUT1 MP5990GMA1111Z-MP5990GMA-1111-Z,SMLF,IC,AR0F0TP4023    I58 @T6G_MB_LIB.T6G(SCH_1):PAGE267
 PU289   28  VOUT2 MP5990GMA1111Z-MP5990GMA-1111-Z,SMLF,IC,AR0F0TP4023    I58 @T6G_MB_LIB.T6G(SCH_1):PAGE267
 PU289   29  VOUT3 MP5990GMA1111Z-MP5990GMA-1111-Z,SMLF,IC,AR0F0TP4023    I58 @T6G_MB_LIB.T6G(SCH_1):PAGE267
 PU289   30  VOUT4 MP5990GMA1111Z-MP5990GMA-1111-Z,SMLF,IC,AR0F0TP4023    I58 @T6G_MB_LIB.T6G(SCH_1):PAGE267
 PU289   31  VOUT5 MP5990GMA1111Z-MP5990GMA-1111-Z,SMLF,IC,AR0F0TP4023    I58 @T6G_MB_LIB.T6G(SCH_1):PAGE267
 PU289   32  VOUT6 MP5990GMA1111Z-MP5990GMA-1111-Z,SMLF,IC,AR0F0TP4023    I58 @T6G_MB_LIB.T6G(SCH_1):PAGE267
 PU289   33  VOUT7 MP5990GMA1111Z-MP5990GMA-1111-Z,SMLF,IC,AR0F0TP4023    I58 @T6G_MB_LIB.T6G(SCH_1):PAGE267
 PU289   34  VOUT8 MP5990GMA1111Z-MP5990GMA-1111-Z,SMLF,IC,AR0F0TP4023    I58 @T6G_MB_LIB.T6G(SCH_1):PAGE267
 PU289   35  VOUT9 MP5990GMA1111Z-MP5990GMA-1111-Z,SMLF,IC,AR0F0TP4023    I58 @T6G_MB_LIB.T6G(SCH_1):PAGE267
 PU289   36 VOUT10 MP5990GMA1111Z-MP5990GMA-1111-Z,SMLF,IC,AR0F0TP4023    I58 @T6G_MB_LIB.T6G(SCH_1):PAGE267
 R3933    1      A Q_RES_0402LF-16.9K,1%,1/16W,CHIP,CS31692FB03    I63 @T6G_MB_LIB.T6G(SCH_1):PAGE267
PR3931    1      A Q_RES_0402LF-75K,0.1%,1/16W,CHIP,CS37502BB01    I71 @T6G_MB_LIB.T6G(SCH_1):PAGE267
 PD111    K CATHODE SS15P3SM386A-SS15P3S-M3/86A,SMLF,IC,BC015P3SZ00    I89 @T6G_MB_LIB.T6G(SCH_1):PAGE267
  PPQ5    1      1 MOSFET_NCH_1D3S-PSMNR58-30YLH,SMLF,IC,BAMNR580000    I29 @T6G_MB_LIB.T6G(SCH_1):PAGE302
  PPQ5    2      2 MOSFET_NCH_1D3S-PSMNR58-30YLH,SMLF,IC,BAMNR580000    I29 @T6G_MB_LIB.T6G(SCH_1):PAGE302
  PPQ5    3      3 MOSFET_NCH_1D3S-PSMNR58-30YLH,SMLF,IC,BAMNR580000    I29 @T6G_MB_LIB.T6G(SCH_1):PAGE302
  PPQ6    1      1 MOSFET_NCH_1D3S-PSMNR58-30YLH,SMLF,IC,BAMNR580000    I46 @T6G_MB_LIB.T6G(SCH_1):PAGE302
  PPQ6    2      2 MOSFET_NCH_1D3S-PSMNR58-30YLH,SMLF,IC,BAMNR580000    I46 @T6G_MB_LIB.T6G(SCH_1):PAGE302
  PPQ6    3      3 MOSFET_NCH_1D3S-PSMNR58-30YLH,SMLF,IC,BAMNR580000    I46 @T6G_MB_LIB.T6G(SCH_1):PAGE302
  PPQ1    1      1 MOSFET_NCH_1D3S-PSMNR58-30YLH,SMLF,IC,BAMNR580000    I61 @T6G_MB_LIB.T6G(SCH_1):PAGE302
  PPQ1    2      2 MOSFET_NCH_1D3S-PSMNR58-30YLH,SMLF,IC,BAMNR580000    I61 @T6G_MB_LIB.T6G(SCH_1):PAGE302
  PPQ1    3      3 MOSFET_NCH_1D3S-PSMNR58-30YLH,SMLF,IC,BAMNR580000    I61 @T6G_MB_LIB.T6G(SCH_1):PAGE302
PC1750    1      A Q_CAP_C0402-33NF,25V,10%,EMPTY,CH3334K1B00    I63 @T6G_MB_LIB.T6G(SCH_1):PAGE302
  PPQ2    1      1 MOSFET_NCH_1D3S-PSMNR58-30YLH,SMLF,IC,BAMNR580000    I64 @T6G_MB_LIB.T6G(SCH_1):PAGE302
  PPQ2    2      2 MOSFET_NCH_1D3S-PSMNR58-30YLH,SMLF,IC,BAMNR580000    I64 @T6G_MB_LIB.T6G(SCH_1):PAGE302
  PPQ2    3      3 MOSFET_NCH_1D3S-PSMNR58-30YLH,SMLF,IC,BAMNR580000    I64 @T6G_MB_LIB.T6G(SCH_1):PAGE302
PR2537    1      A Q_RES_0402LF-10,1%,1/16W,EMPTY,CS01002FB07    I71 @T6G_MB_LIB.T6G(SCH_1):PAGE302
  PD17    K CATHODE SS15P3SM386A-SS15P3S-M3/86A,SMLF,IC,BC015P3SZ00    I72 @T6G_MB_LIB.T6G(SCH_1):PAGE302
  PPQ9    1      1 MOSFET_NCH_1D3S-PSMNR58-30YLH,SMLF,IC,BAMNR580000    I75 @T6G_MB_LIB.T6G(SCH_1):PAGE302
  PPQ9    2      2 MOSFET_NCH_1D3S-PSMNR58-30YLH,SMLF,IC,BAMNR580000    I75 @T6G_MB_LIB.T6G(SCH_1):PAGE302
  PPQ9    3      3 MOSFET_NCH_1D3S-PSMNR58-30YLH,SMLF,IC,BAMNR580000    I75 @T6G_MB_LIB.T6G(SCH_1):PAGE302
  PPQ8    1      1 MOSFET_NCH_1D3S-PSMNR58-30YLH,SMLF,IC,BAMNR580000    I79 @T6G_MB_LIB.T6G(SCH_1):PAGE302
  PPQ8    2      2 MOSFET_NCH_1D3S-PSMNR58-30YLH,SMLF,IC,BAMNR580000    I79 @T6G_MB_LIB.T6G(SCH_1):PAGE302
  PPQ8    3      3 MOSFET_NCH_1D3S-PSMNR58-30YLH,SMLF,IC,BAMNR580000    I79 @T6G_MB_LIB.T6G(SCH_1):PAGE302
  PPQ7    1      1 MOSFET_NCH_1D3S-PSMNR58-30YLH,SMLF,IC,BAMNR580000    I80 @T6G_MB_LIB.T6G(SCH_1):PAGE302
  PPQ7    2      2 MOSFET_NCH_1D3S-PSMNR58-30YLH,SMLF,IC,BAMNR580000    I80 @T6G_MB_LIB.T6G(SCH_1):PAGE302
  PPQ7    3      3 MOSFET_NCH_1D3S-PSMNR58-30YLH,SMLF,IC,BAMNR580000    I80 @T6G_MB_LIB.T6G(SCH_1):PAGE302
PC1789    1      A Q_CAP_0402-0.1UF,25V,10%,X7R,CH4104K1B00    I28 @T6G_MB_LIB.T6G(SCH_1):PAGE371
  PJ38   10     10 SCONN21_9193031121LF-SCONN21_91930-31121LF,SMLF,IOA    I42 @T6G_MB_LIB.T6G(SCH_1):PAGE371
PC6020    1      A Q_CAP_C0402-100NF,50V,10%,X7R,CH4106K1B01     I5 @T6G_MB_LIB.T6G(SCH_1):PAGE315
PL6002    1      1 Q_INDUCTOR_SMLF-BLM18SN220TN1D/8000MA,IND,CX220TN1A     I7 @T6G_MB_LIB.T6G(SCH_1):PAGE315
PL6003    1      1 Q_INDUCTOR_SMLF-BLM18SN220TN1D/8000MA,IND,CX220TN1A     I2 @T6G_MB_LIB.T6G(SCH_1):PAGE380
PC6023    1      A Q_CAP_C0402-100NF,50V,10%,X7R,CH4106K1B01    I35 @T6G_MB_LIB.T6G(SCH_1):PAGE380
 R2219    1      A Q_RES_0402LF-267K,1%,1/16W,EMPTY,CS42672FB03    I30 @T6G_MB_LIB.T6G(SCH_1):PAGE372
 R2221    1      A Q_RES_0402LF-26.7K,1%,1/16W,EMPTY,CS32672FB03    I35 @T6G_MB_LIB.T6G(SCH_1):PAGE372
  R554    1      A Q_RES_0402LF-100K,1%,1/16W,CHIP,CS41002FB09   I111 @T6G_MB_LIB.T6G(SCH_1):PAGE273
  R568    1      A Q_RES_0402LF-10K,1%,1/16W,CHIP,CS31002FB08   I114 @T6G_MB_LIB.T6G(SCH_1):PAGE273
 R8024    2      B Q_RES_0402LF-560,1%,1/16W,CHIP,CS15602FB03    I46 @T6G_MB_LIB.T6G(SCH_1):PAGE375
 C8016    1      A Q_CAP_C0402-100NF,50V,10%,EMPTY,CH4106K1B01    I95 @T6G_MB_LIB.T6G(SCH_1):PAGE371
 U8006    5    VCC AP331AWG7-AP331AWG-7,SMLF,EMPTY,AL000331011   I104 @T6G_MB_LIB.T6G(SCH_1):PAGE371
 R8114    1      A Q_RES_0402LF-17.8K,1%,1/16W,CHIP,CS31782FB04    I56 @T6G_MB_LIB.T6G(SCH_1):PAGE372
 C8019    1      A Q_CAP_C0402-100NF,50V,10%,X7R,CH4106K1B01    I66 @T6G_MB_LIB.T6G(SCH_1):PAGE372
 U8008    5    VCC AP331AWG7-AP331AWG-7,SMLF,IC,AL000331011    I71 @T6G_MB_LIB.T6G(SCH_1):PAGE372
 R8121    1      A Q_RES_0402LF-17.8K,1%,1/16W,CHIP,CS31782FB04    I76 @T6G_MB_LIB.T6G(SCH_1):PAGE372
 U8010    5    VCC AP331AWG7-AP331AWG-7,SMLF,IC,AL000331011    I80 @T6G_MB_LIB.T6G(SCH_1):PAGE372
 C8022    1      A Q_CAP_C0402-100NF,50V,10%,X7R,CH4106K1B01    I84 @T6G_MB_LIB.T6G(SCH_1):PAGE372
PC6500    1      A Q_CAP_C0402-0.1UF,25V,10%,X6S,CH4104KEB00     I4 @T6G_MB_LIB.T6G(SCH_1):PAGE469
PL6500    1      1 Q_INDUCTOR_SMLF-100NH/16A,IND,CV+10G0MZ04     I9 @T6G_MB_LIB.T6G(SCH_1):PAGE469
PC6519    1      A Q_CAP_C0402-0.1UF,25V,10%,X6S,CH4104KEB00     I3 @T6G_MB_LIB.T6G(SCH_1):PAGE470
PL6503    1      1 Q_INDUCTOR_SMLF-100NH/16A,IND,CV+10G0MZ04     I9 @T6G_MB_LIB.T6G(SCH_1):PAGE470
PR6807    1      A Q_RES_0402LF-0,5%,1/16W,EMPTY,CS00002JB13   I158 @T6G_MB_LIB.T6G(SCH_1):PAGE475
PR6606    1      A Q_RES_0402LF-0,5%,1/16W,CHIP,CS00002JB13   I160 @T6G_MB_LIB.T6G(SCH_1):PAGE475
PL6504    2      2 Q_INDUCTOR_SMLF-100NH/16A,IND,CV+10G0MZ04   I182 @T6G_MB_LIB.T6G(SCH_1):PAGE476
PC6562    1      A Q_CAP_0402-0.1UF,25V,10%,X7R,CH4104K1B00   I291 @T6G_MB_LIB.T6G(SCH_1):PAGE476
PR6809    1      A Q_RES_0402LF-0,5%,1/16W,CHIP,CS00002JB13    I10 @T6G_MB_LIB.T6G(SCH_1):PAGE477
PR6808    1      A Q_RES_0402LF-0,5%,1/16W,EMPTY,CS00002JB13    I11 @T6G_MB_LIB.T6G(SCH_1):PAGE477
PL6510    2      2 Q_INDUCTOR_SMLF-100NH/16A,IND,CV+10G0MZ04   I104 @T6G_MB_LIB.T6G(SCH_1):PAGE478
PC6620    1      A Q_CAP_0402-0.1UF,25V,10%,X7R,CH4104K1B00   I114 @T6G_MB_LIB.T6G(SCH_1):PAGE478
 R9021    1      A Q_RES_0402LF-1K,1%,1/16W,EMPTY,CS21002FB06    I97 @T6G_MB_LIB.T6G(SCH_1):PAGE372
 R1837    1      1 Q_RES_4P_12-0.001,1%,3W,SMLF,CHIP,SP_CS+001DFR10    I54 @T6G_MB_LIB.T6G(SCH_1):PAGE264
 R1838    1      1 Q_RES_4P_12-0.001,1%,3W,SMLF,CHIP,SP_CS+001DFR10    I58 @T6G_MB_LIB.T6G(SCH_1):PAGE264
  R700    1      A Q_RES_0402LF-30K,1%,1/16W,EMPTY,CS33002FB02     I2 @T6G_MB_LIB.T6G(SCH_1):PAGE146
 R1007    1      A Q_RES_0402LF-2K,1%,1/16W,EMPTY,CS22002FB07    I11 @T6G_MB_LIB.T6G(SCH_1):PAGE146
 R1480    1      A Q_RES_2512LF-10,1%,2W,EMPTY,CS0100AFR00    I19 @T6G_MB_LIB.T6G(SCH_1):PAGE146
  R896    1      A Q_RES_0402LF-30K,1%,1/16W,EMPTY,CS33002FB02    I35 @T6G_MB_LIB.T6G(SCH_1):PAGE146
 PU299 21_22 VIN_21_22 RS31312R-RS31312R,SMLF,IC,AL031312000    I95 @T6G_MB_LIB.T6G(SCH_1):PAGE350
 PU299   23 VIN_23 RS31312R-RS31312R,SMLF,IC,AL031312000    I95 @T6G_MB_LIB.T6G(SCH_1):PAGE350
 PU299   24 VIN_24 RS31312R-RS31312R,SMLF,IC,AL031312000    I95 @T6G_MB_LIB.T6G(SCH_1):PAGE350
 PU299   25 VIN_25 RS31312R-RS31312R,SMLF,IC,AL031312000    I95 @T6G_MB_LIB.T6G(SCH_1):PAGE350
 PU299   26 VIN_26 RS31312R-RS31312R,SMLF,IC,AL031312000    I95 @T6G_MB_LIB.T6G(SCH_1):PAGE350
 PU204 21_22 VIN_21_22 RS31312R-RS31312R,SMLF,IC,AL031312000   I137 @T6G_MB_LIB.T6G(SCH_1):PAGE339
 PU204   23 VIN_23 RS31312R-RS31312R,SMLF,IC,AL031312000   I137 @T6G_MB_LIB.T6G(SCH_1):PAGE339
 PU204   24 VIN_24 RS31312R-RS31312R,SMLF,IC,AL031312000   I137 @T6G_MB_LIB.T6G(SCH_1):PAGE339
 PU204   25 VIN_25 RS31312R-RS31312R,SMLF,IC,AL031312000   I137 @T6G_MB_LIB.T6G(SCH_1):PAGE339
 PU204   26 VIN_26 RS31312R-RS31312R,SMLF,IC,AL031312000   I137 @T6G_MB_LIB.T6G(SCH_1):PAGE339
 PU206 21_22 VIN_21_22 RS31312R-RS31312R,SMLF,IC,AL031312000    I82 @T6G_MB_LIB.T6G(SCH_1):PAGE344
 PU206   23 VIN_23 RS31312R-RS31312R,SMLF,IC,AL031312000    I82 @T6G_MB_LIB.T6G(SCH_1):PAGE344
 PU206   24 VIN_24 RS31312R-RS31312R,SMLF,IC,AL031312000    I82 @T6G_MB_LIB.T6G(SCH_1):PAGE344
 PU206   25 VIN_25 RS31312R-RS31312R,SMLF,IC,AL031312000    I82 @T6G_MB_LIB.T6G(SCH_1):PAGE344
 PU206   26 VIN_26 RS31312R-RS31312R,SMLF,IC,AL031312000    I82 @T6G_MB_LIB.T6G(SCH_1):PAGE344
 PU292 21_22 VIN_21_22 RS31312R-RS31312R,SMLF,IC,AL031312000    I76 @T6G_MB_LIB.T6G(SCH_1):PAGE323
 PU292   23 VIN_23 RS31312R-RS31312R,SMLF,IC,AL031312000    I76 @T6G_MB_LIB.T6G(SCH_1):PAGE323
 PU292   24 VIN_24 RS31312R-RS31312R,SMLF,IC,AL031312000    I76 @T6G_MB_LIB.T6G(SCH_1):PAGE323
 PU292   25 VIN_25 RS31312R-RS31312R,SMLF,IC,AL031312000    I76 @T6G_MB_LIB.T6G(SCH_1):PAGE323
 PU292   26 VIN_26 RS31312R-RS31312R,SMLF,IC,AL031312000    I76 @T6G_MB_LIB.T6G(SCH_1):PAGE323

P12V_AUX_ADC @T6G_MB_LIB.T6G(SCH_1):P12V_AUX_ADC
 R1799    2      B Q_RES_0402LF-7.87K,1%,1/16W,CHIP,CS27872FB02     I6 @T6G_MB_LIB.T6G(SCH_1):PAGE369
 R3680    1      A Q_RES_0402LF-0,5%,1/16W,CHIP,CS00002JB13     I9 @T6G_MB_LIB.T6G(SCH_1):PAGE369
 R3679    1      A Q_RES_0402LF-0,5%,1/16W,EMPTY,CS00002JB13    I10 @T6G_MB_LIB.T6G(SCH_1):PAGE369
 R1800    1      A Q_RES_0402LF-1.21K,1%,1/16W,CHIP,CS21212FB05   I170 @T6G_MB_LIB.T6G(SCH_1):PAGE369

P12V_AUX_ADC_MAM @T6G_MB_LIB.T6G(SCH_1):P12V_AUX_ADC_MAM
 R3679    2      B Q_RES_0402LF-0,5%,1/16W,EMPTY,CS00002JB13    I10 @T6G_MB_LIB.T6G(SCH_1):PAGE369
 C1344    1      A Q_CAP_0402-100PF,50V,5%,EMPTY,CH11006JB18    I46 @T6G_MB_LIB.T6G(SCH_1):PAGE369
  U193    5   AIN0 MAX11617EEET-MAX11617EEE+T,SMLF,EMPTY,AL011617W00   I169 @T6G_MB_LIB.T6G(SCH_1):PAGE369

P12V_AUX_ADC_TIC @T6G_MB_LIB.T6G(SCH_1):P12V_AUX_ADC_TIC
 R3680    2      B Q_RES_0402LF-0,5%,1/16W,CHIP,CS00002JB13     I9 @T6G_MB_LIB.T6G(SCH_1):PAGE369
 C2046    1      A Q_CAP_0402-0.1UF,25V,10%,X7R,CH4104K1B00    I44 @T6G_MB_LIB.T6G(SCH_1):PAGE369
  U269   16    IN0 ADC128D818CIMTXNOPB-ADC128D818CIMTX/NOPB,SMLF,IC,AA   I142 @T6G_MB_LIB.T6G(SCH_1):PAGE369

P12V_AUX_BLEEDING @T6G_MB_LIB.T6G(SCH_1):P12V_AUX_BLEEDING
 R2530    2      B Q_RES_0402LF-4.7K,5%,1/16W,CHIP,CS24702JB10    I10 @T6G_MB_LIB.T6G(SCH_1):PAGE365
   Q54    D      D MOSFET_NCH_GDS_ESD_PROTECTED-2N7002K,SMLF,IC,BAM70A    I14 @T6G_MB_LIB.T6G(SCH_1):PAGE365

P12V_AUX_DSC @T6G_MB_LIB.T6G(SCH_1):P12V_AUX_DSC
 Q7001    5      5 MOSFET_NCH_1D3S-PSMNR58-30YLH,SMLF,EMPTY,BAMNR5800A    I16 @T6G_MB_LIB.T6G(SCH_1):PAGE146
 R1480    2      B Q_RES_2512LF-10,1%,2W,EMPTY,CS0100AFR00    I19 @T6G_MB_LIB.T6G(SCH_1):PAGE146

P12V_AUX_DSC_G1 @T6G_MB_LIB.T6G(SCH_1):P12V_AUX_DSC_G1
 Q7000    G      G MOSFET_PCH_GDS_ESD_PROTECTED-DMP2035U-7,SMLF,EMPTYA    I10 @T6G_MB_LIB.T6G(SCH_1):PAGE146
 R1007    2      B Q_RES_0402LF-2K,1%,1/16W,EMPTY,CS22002FB07    I11 @T6G_MB_LIB.T6G(SCH_1):PAGE146
 R1049    1      A Q_RES_0402LF-1K,1%,1/16W,EMPTY,CS21002FB06    I12 @T6G_MB_LIB.T6G(SCH_1):PAGE146

P12V_AUX_DSC_G2 @T6G_MB_LIB.T6G(SCH_1):P12V_AUX_DSC_G2
 Q7000    D      D MOSFET_PCH_GDS_ESD_PROTECTED-DMP2035U-7,SMLF,EMPTYA    I10 @T6G_MB_LIB.T6G(SCH_1):PAGE146
 R1474    1      A Q_RES_0402LF-10K,1%,1/16W,EMPTY,CS31002FB08    I14 @T6G_MB_LIB.T6G(SCH_1):PAGE146
 Q7001    4      4 MOSFET_NCH_1D3S-PSMNR58-30YLH,SMLF,EMPTY,BAMNR5800A    I16 @T6G_MB_LIB.T6G(SCH_1):PAGE146

P12V_AUX_DSC_S1 @T6G_MB_LIB.T6G(SCH_1):P12V_AUX_DSC_S1
   U57    3      C SCHOTTKY_DUAL_12A_3C-BAT54CW,SMLF,EMPTY,BCBAT54CZ13     I5 @T6G_MB_LIB.T6G(SCH_1):PAGE146
 C1113    1      A Q_CAP_C0805-22UF,16V,20%,EMPTY,CH6223MEA00     I6 @T6G_MB_LIB.T6G(SCH_1):PAGE146
 Q7000    S      S MOSFET_PCH_GDS_ESD_PROTECTED-DMP2035U-7,SMLF,EMPTYA    I10 @T6G_MB_LIB.T6G(SCH_1):PAGE146

P12V_AUX_DSC_VOL @T6G_MB_LIB.T6G(SCH_1):P12V_AUX_DSC_VOL
  R700    2      B Q_RES_0402LF-30K,1%,1/16W,EMPTY,CS33002FB02     I2 @T6G_MB_LIB.T6G(SCH_1):PAGE146
  R855    1      A Q_RES_0402LF-11.5K,1%,1/16W,EMPTY,CS31152FB03     I3 @T6G_MB_LIB.T6G(SCH_1):PAGE146
   U57    1      B SCHOTTKY_DUAL_12A_3C-BAT54CW,SMLF,EMPTY,BCBAT54CZ13     I5 @T6G_MB_LIB.T6G(SCH_1):PAGE146

P12V_AUX_UV_ADR_TRIGGER @T6G_MB_LIB.T6G(SCH_1):P12V_AUX_UV_ADR_TRIGGER
 R8115    1      A Q_RES_0402LF-5.11K,1%,1/16W,CHIP,CS25112FB04    I55 @T6G_MB_LIB.T6G(SCH_1):PAGE372
 R8114    2      B Q_RES_0402LF-17.8K,1%,1/16W,CHIP,CS31782FB04    I56 @T6G_MB_LIB.T6G(SCH_1):PAGE372
 C8018    1      A Q_CAP_C0402-100NF,50V,10%,EMPTY,CH4106K1B01    I61 @T6G_MB_LIB.T6G(SCH_1):PAGE372
 R8117    1      A Q_RES_0402LF-1M,1%,1/16W,CHIP,CS51002FB05    I63 @T6G_MB_LIB.T6G(SCH_1):PAGE372
 U8008    3    IN+ AP331AWG7-AP331AWG-7,SMLF,IC,AL000331011    I71 @T6G_MB_LIB.T6G(SCH_1):PAGE372

P12V_AUX_UV_TRIGGER @T6G_MB_LIB.T6G(SCH_1):P12V_AUX_UV_TRIGGER
 R8122    1      A Q_RES_0402LF-5.11K,1%,1/16W,CHIP,CS25112FB04    I75 @T6G_MB_LIB.T6G(SCH_1):PAGE372
 R8121    2      B Q_RES_0402LF-17.8K,1%,1/16W,CHIP,CS31782FB04    I76 @T6G_MB_LIB.T6G(SCH_1):PAGE372
 U8010    3    IN+ AP331AWG7-AP331AWG-7,SMLF,IC,AL000331011    I80 @T6G_MB_LIB.T6G(SCH_1):PAGE372
 R8123    1      A Q_RES_0402LF-1M,1%,1/16W,CHIP,CS51002FB05    I81 @T6G_MB_LIB.T6G(SCH_1):PAGE372
 C8021    1      A Q_CAP_C0402-100NF,50V,10%,EMPTY,CH4106K1B01    I92 @T6G_MB_LIB.T6G(SCH_1):PAGE372

P12V_E1S_0 @T6G_MB_LIB.T6G(SCH_1):P12V_E1S_0
PR3950    1      A Q_RES_0402LF-100,1%,1/16W,EMPTY,CS11002FB07    I42 @T6G_MB_LIB.T6G(SCH_1):PAGE323
PR3952    1      A Q_RES_0402LF-71.5K,1%,1/16W,EMPTY,CS37152FB05    I45 @T6G_MB_LIB.T6G(SCH_1):PAGE323
PC2206    1      A Q_CAP_0402-0.1UF,25V,10%,X7R,CH4104K1B00    I56 @T6G_MB_LIB.T6G(SCH_1):PAGE323
 PU294   A4 OUT_A4 MAX15090BEWIT-MAX15090BEWI+T,SMLF,IC,AL015080B00    I66 @T6G_MB_LIB.T6G(SCH_1):PAGE324
 PU294   B4 OUT_B4 MAX15090BEWIT-MAX15090BEWI+T,SMLF,IC,AL015080B00    I66 @T6G_MB_LIB.T6G(SCH_1):PAGE324
 PU294   B6 OUT_B6 MAX15090BEWIT-MAX15090BEWI+T,SMLF,IC,AL015080B00    I66 @T6G_MB_LIB.T6G(SCH_1):PAGE324
 PU294   C4 OUT_C4 MAX15090BEWIT-MAX15090BEWI+T,SMLF,IC,AL015080B00    I66 @T6G_MB_LIB.T6G(SCH_1):PAGE324
 PU294   C6 OUT_C6 MAX15090BEWIT-MAX15090BEWI+T,SMLF,IC,AL015080B00    I66 @T6G_MB_LIB.T6G(SCH_1):PAGE324
 PU294   D4 OUT_D4 MAX15090BEWIT-MAX15090BEWI+T,SMLF,IC,AL015080B00    I66 @T6G_MB_LIB.T6G(SCH_1):PAGE324
 PU294   D6 OUT_D6 MAX15090BEWIT-MAX15090BEWI+T,SMLF,IC,AL015080B00    I66 @T6G_MB_LIB.T6G(SCH_1):PAGE324
PC2214    1      A Q_CAP_C0402-0.01UF,50V,10%,EMPTY,CH31006KB18    I72 @T6G_MB_LIB.T6G(SCH_1):PAGE324
 PD112    C      C SCHOTTKY_AC-B340A-13-F,SMLF,IC,BC000340Z30    I74 @T6G_MB_LIB.T6G(SCH_1):PAGE324
PC2217    1      A Q_CAP_0402-0.1UF,25V,10%,X7R,CH4104K1B00    I78 @T6G_MB_LIB.T6G(SCH_1):PAGE324
PC2280    1      A Q_CAP_C0805-10UF,16V,10%,X6S,CH6103KEA01    I80 @T6G_MB_LIB.T6G(SCH_1):PAGE324
PR4528    1      A Q_RES_0402LF-10M,1%,1/16W,CHIP,CS61002FB02    I73 @T6G_MB_LIB.T6G(SCH_1):PAGE324
PC2219    1      A Q_CAP_C0805-10UF,16V,10%,X6S,CH6103KEA01    I79 @T6G_MB_LIB.T6G(SCH_1):PAGE324
   U52   11   VBUS ISL28022FRZT-ISL28022FRZ-T,SMLF,IC,AL028022003    I57 @T6G_MB_LIB.T6G(SCH_1):PAGE466
 R1283    1      A Q_RES_0402LF-10,1%,1/16W,CHIP,CS01002FB07    I74 @T6G_MB_LIB.T6G(SCH_1):PAGE466
 C1107    1      A Q_CAP_0402-0.1UF,25V,10%,X7R,CH4104K1B00    I81 @T6G_MB_LIB.T6G(SCH_1):PAGE466
 R1323    2      B Q_RES_2512LF-0.002,1%,2W,CHIP,CS+002AFR06    I84 @T6G_MB_LIB.T6G(SCH_1):PAGE466
 PU292   13 VOUT_13 RS31312R-RS31312R,SMLF,IC,AL031312000    I76 @T6G_MB_LIB.T6G(SCH_1):PAGE323
 PU292   14 VOUT_14 RS31312R-RS31312R,SMLF,IC,AL031312000    I76 @T6G_MB_LIB.T6G(SCH_1):PAGE323
 PU292   15 VOUT_15 RS31312R-RS31312R,SMLF,IC,AL031312000    I76 @T6G_MB_LIB.T6G(SCH_1):PAGE323
 PU292   16 VOUT_16 RS31312R-RS31312R,SMLF,IC,AL031312000    I76 @T6G_MB_LIB.T6G(SCH_1):PAGE323
 PU292   17 VOUT_17 RS31312R-RS31312R,SMLF,IC,AL031312000    I76 @T6G_MB_LIB.T6G(SCH_1):PAGE323
 PU292   18 VOUT_18 RS31312R-RS31312R,SMLF,IC,AL031312000    I76 @T6G_MB_LIB.T6G(SCH_1):PAGE323
 PU292   19 VOUT_19 RS31312R-RS31312R,SMLF,IC,AL031312000    I76 @T6G_MB_LIB.T6G(SCH_1):PAGE323
 PU292   20 VOUT_20 RS31312R-RS31312R,SMLF,IC,AL031312000    I76 @T6G_MB_LIB.T6G(SCH_1):PAGE323

P12V_E1S_0_ADC_ALERT_R @T6G_MB_LIB.T6G(SCH_1):P12V_E1S_0_ADC_ALERT_R
   U52    3 EXT_CLK||INT ISL28022FRZT-ISL28022FRZ-T,SMLF,IC,AL028022003    I57 @T6G_MB_LIB.T6G(SCH_1):PAGE466
 R1269    1      A Q_RES_0402LF-0,5%,1/16W,CHIP,CS00002JB13    I62 @T6G_MB_LIB.T6G(SCH_1):PAGE466

P12V_E1S_0_EN @T6G_MB_LIB.T6G(SCH_1):P12V_E1S_0_EN
  R199    2      B Q_RES_0402LF-33,5%,1/16W,CHIP,CS03302JB10    I22 @T6G_MB_LIB.T6G(SCH_1):PAGE80
   U18 AA11  PB24A LCMXO3LF9400C5BG484C-LCMXO3LF-9400C-5BG484C,SMLF,IA   I216 @T6G_MB_LIB.T6G(SCH_1):PAGE80

P12V_E1S_0_EN_G @T6G_MB_LIB.T6G(SCH_1):P12V_E1S_0_EN_G
 R4074    2      B Q_RES_0402LF-10K,1%,1/16W,CHIP,CS31002FB08    I25 @T6G_MB_LIB.T6G(SCH_1):PAGE324
  Q127    5     G2 MOSFET_NCH_DUAL-PJT138K,SMLF,IC,BAM138K0003    I27 @T6G_MB_LIB.T6G(SCH_1):PAGE324
  Q127    6     D1 MOSFET_NCH_DUAL-PJT138K,SMLF,IC,BAM138K0003    I12 @T6G_MB_LIB.T6G(SCH_1):PAGE324

P12V_E1S_0_ISENSE_MAM @T6G_MB_LIB.T6G(SCH_1):P12V_E1S_0_ISENSE_MAM
   C35    1      A Q_CAP_0402-100PF,50V,5%,EMPTY,CH11006JB18    I78 @T6G_MB_LIB.T6G(SCH_1):PAGE369
 R3940    2      B Q_RES_0402LF-0,5%,1/16W,EMPTY,CS00002JB13    I79 @T6G_MB_LIB.T6G(SCH_1):PAGE369
 R3939    2      B Q_RES_0402LF-0,5%,1/16W,EMPTY,CS00002JB13    I80 @T6G_MB_LIB.T6G(SCH_1):PAGE369
  U193   12   AIN7 MAX11617EEET-MAX11617EEE+T,SMLF,EMPTY,AL011617W00   I169 @T6G_MB_LIB.T6G(SCH_1):PAGE369

P12V_E1S_0_ISENSE_MAM_MAM @T6G_MB_LIB.T6G(SCH_1):P12V_E1S_0_ISENSE_MAM_MAM
 R3974    2      B Q_RES_0402LF-0,5%,1/16W,EMPTY,CS00002JB13    I70 @T6G_MB_LIB.T6G(SCH_1):PAGE324
 R3939    1      A Q_RES_0402LF-0,5%,1/16W,EMPTY,CS00002JB13    I80 @T6G_MB_LIB.T6G(SCH_1):PAGE369

P12V_E1S_0_ISENSE_MAM_TIC @T6G_MB_LIB.T6G(SCH_1):P12V_E1S_0_ISENSE_MAM_TIC
 R3975    2      B Q_RES_0402LF-0,5%,1/16W,CHIP,CS00002JB13    I87 @T6G_MB_LIB.T6G(SCH_1):PAGE324
 R3941    1      A Q_RES_0402LF-0,5%,1/16W,CHIP,CS00002JB13    I74 @T6G_MB_LIB.T6G(SCH_1):PAGE369

P12V_E1S_0_ISENSE_MPS_MAM @T6G_MB_LIB.T6G(SCH_1):P12V_E1S_0_ISENSE_MPS_MAM
 R3955    2      B Q_RES_0402LF-0,5%,1/16W,CHIP,CS00002JB13    I48 @T6G_MB_LIB.T6G(SCH_1):PAGE323
 R3940    1      A Q_RES_0402LF-0,5%,1/16W,EMPTY,CS00002JB13    I79 @T6G_MB_LIB.T6G(SCH_1):PAGE369

P12V_E1S_0_ISENSE_MPS_TIC @T6G_MB_LIB.T6G(SCH_1):P12V_E1S_0_ISENSE_MPS_TIC
 R3956    2      B Q_RES_0402LF-0,5%,1/16W,EMPTY,CS00002JB13    I47 @T6G_MB_LIB.T6G(SCH_1):PAGE323
 R3942    1      A Q_RES_0402LF-0,5%,1/16W,EMPTY,CS00002JB13    I73 @T6G_MB_LIB.T6G(SCH_1):PAGE369

P12V_E1S_0_ISENSE_TIC @T6G_MB_LIB.T6G(SCH_1):P12V_E1S_0_ISENSE_TIC
 R3942    2      B Q_RES_0402LF-0,5%,1/16W,EMPTY,CS00002JB13    I73 @T6G_MB_LIB.T6G(SCH_1):PAGE369
 R3941    2      B Q_RES_0402LF-0,5%,1/16W,CHIP,CS00002JB13    I74 @T6G_MB_LIB.T6G(SCH_1):PAGE369
 C2194    1      A Q_CAP_0402-0.1UF,25V,10%,X7R,CH4104K1B00    I76 @T6G_MB_LIB.T6G(SCH_1):PAGE369
  U269    9    IN7 ADC128D818CIMTXNOPB-ADC128D818CIMTX/NOPB,SMLF,IC,AA   I142 @T6G_MB_LIB.T6G(SCH_1):PAGE369

P12V_E1S_0_PWRGD @T6G_MB_LIB.T6G(SCH_1):P12V_E1S_0_PWRGD
 R6048    2      B Q_RES_0402LF-0,5%,1/16W,CHIP,CS00002JB13    I28 @T6G_MB_LIB.T6G(SCH_1):PAGE80
   U18  U10  PB19D LCMXO3LF9400C5BG484C-LCMXO3LF-9400C-5BG484C,SMLF,IA   I216 @T6G_MB_LIB.T6G(SCH_1):PAGE80

P12V_E1S_0_R @T6G_MB_LIB.T6G(SCH_1):P12V_E1S_0_R
 C1276    1      A Q_CAP_C0805-22UF,16V,20%,X6S,CH6223MEA01    I66 @T6G_MB_LIB.T6G(SCH_1):PAGE297
 C1277    1      A Q_CAP_C0805-22UF,16V,20%,X6S,CH6223MEA01    I67 @T6G_MB_LIB.T6G(SCH_1):PAGE297
 C1278    1      A Q_CAP_0402-0.1UF,25V,10%,X7R,CH4104K1B00    I68 @T6G_MB_LIB.T6G(SCH_1):PAGE297
 C1279    1      A Q_CAP_0402-0.1UF,25V,10%,X7R,CH4104K1B00    I74 @T6G_MB_LIB.T6G(SCH_1):PAGE297
   J90   B1 P12V_B1 SCONN56_123276793-SCONN56_1-2327679-3,SMLF,IO,DFHSA    I90 @T6G_MB_LIB.T6G(SCH_1):PAGE297
   J90   B2 P12V_B2 SCONN56_123276793-SCONN56_1-2327679-3,SMLF,IO,DFHSA    I90 @T6G_MB_LIB.T6G(SCH_1):PAGE297
   J90   B3 P12V_B3 SCONN56_123276793-SCONN56_1-2327679-3,SMLF,IO,DFHSA    I90 @T6G_MB_LIB.T6G(SCH_1):PAGE297
   J90   B4 P12V_B4 SCONN56_123276793-SCONN56_1-2327679-3,SMLF,IO,DFHSA    I90 @T6G_MB_LIB.T6G(SCH_1):PAGE297
   J90   B5 P12V_B5 SCONN56_123276793-SCONN56_1-2327679-3,SMLF,IO,DFHSA    I90 @T6G_MB_LIB.T6G(SCH_1):PAGE297
   J90   B6 P12V_B6 SCONN56_123276793-SCONN56_1-2327679-3,SMLF,IO,DFHSA    I90 @T6G_MB_LIB.T6G(SCH_1):PAGE297
 R1292    1      A Q_RES_0402LF-10,1%,1/16W,CHIP,CS01002FB07    I75 @T6G_MB_LIB.T6G(SCH_1):PAGE466
 R1323    1      A Q_RES_2512LF-0.002,1%,2W,CHIP,CS+002AFR06    I84 @T6G_MB_LIB.T6G(SCH_1):PAGE466

P12V_E1S_AVIN_PD_0 @T6G_MB_LIB.T6G(SCH_1):P12V_E1S_AVIN_PD_0
PR3950    2      B Q_RES_0402LF-100,1%,1/16W,EMPTY,CS11002FB07    I42 @T6G_MB_LIB.T6G(SCH_1):PAGE323
PC2205    1      A Q_CAP_C0603-2.2UF,16V,20%,X7R,CH5223M1900    I51 @T6G_MB_LIB.T6G(SCH_1):PAGE323
PR3957    2      B Q_RES_0603LF-49.9,1%,1/10W,CHIP,CS04993F909    I54 @T6G_MB_LIB.T6G(SCH_1):PAGE323
 PU292   12   AVIN RS31312R-RS31312R,SMLF,IC,AL031312000    I76 @T6G_MB_LIB.T6G(SCH_1):PAGE323

P12V_E1S_CB_0 @T6G_MB_LIB.T6G(SCH_1):P12V_E1S_CB_0
PR3968    1      A Q_RES_0402LF-9.31K,1%,1/16W,CHIP,CS29312FB02    I63 @T6G_MB_LIB.T6G(SCH_1):PAGE324
 PU294   B1     CB MAX15090BEWIT-MAX15090BEWI+T,SMLF,IC,AL015080B00    I66 @T6G_MB_LIB.T6G(SCH_1):PAGE324

P12V_E1S_EN_0_R @T6G_MB_LIB.T6G(SCH_1):P12V_E1S_EN_0_R
 R4073    1      A Q_RES_0402LF-4.7K,5%,1/16W,CHIP,CS24702JB10    I11 @T6G_MB_LIB.T6G(SCH_1):PAGE324
  Q127    2     G1 MOSFET_NCH_DUAL-PJT138K,SMLF,IC,BAM138K0003    I12 @T6G_MB_LIB.T6G(SCH_1):PAGE324
 R4064    2      B Q_RES_0402LF-0,5%,1/16W,CHIP,CS00002JB13    I24 @T6G_MB_LIB.T6G(SCH_1):PAGE324

P12V_E1S_EN_0_R2 @T6G_MB_LIB.T6G(SCH_1):P12V_E1S_EN_0_R2
 R3943    2      B Q_RES_0402LF-0,5%,1/16W,CHIP,CS00002JB13    I19 @T6G_MB_LIB.T6G(SCH_1):PAGE323
 PU292    1     EN RS31312R-RS31312R,SMLF,IC,AL031312000    I76 @T6G_MB_LIB.T6G(SCH_1):PAGE323

P12V_E1S_FAULT_0 @T6G_MB_LIB.T6G(SCH_1):P12V_E1S_FAULT_0
 PU294   C7 FAULT# MAX15090BEWIT-MAX15090BEWI+T,SMLF,IC,AL015080B00    I66 @T6G_MB_LIB.T6G(SCH_1):PAGE324
 R3976    2      B Q_RES_0402LF-100K,1%,1/16W,CHIP,CS41002FB09    I76 @T6G_MB_LIB.T6G(SCH_1):PAGE324

P12V_E1S_FLTB_0 @T6G_MB_LIB.T6G(SCH_1):P12V_E1S_FLTB_0
PR3951    1      A Q_RES_0402LF-10K,1%,1/16W,CHIP,CS31002FB08    I40 @T6G_MB_LIB.T6G(SCH_1):PAGE323
 PU292    9   FLTB RS31312R-RS31312R,SMLF,IC,AL031312000    I76 @T6G_MB_LIB.T6G(SCH_1):PAGE323

P12V_E1S_GATE_0 @T6G_MB_LIB.T6G(SCH_1):P12V_E1S_GATE_0
 PU294   A6   GATE MAX15090BEWIT-MAX15090BEWI+T,SMLF,IC,AL015080B00    I66 @T6G_MB_LIB.T6G(SCH_1):PAGE324
PC2215    1      A Q_CAP_C0402-3900PF,50V,10%,X7R,CH23906KB14    I69 @T6G_MB_LIB.T6G(SCH_1):PAGE324
PC2214    2      B Q_CAP_C0402-0.01UF,50V,10%,EMPTY,CH31006KB18    I72 @T6G_MB_LIB.T6G(SCH_1):PAGE324
PR4528    2      B Q_RES_0402LF-10M,1%,1/16W,CHIP,CS61002FB02    I73 @T6G_MB_LIB.T6G(SCH_1):PAGE324

P12V_E1S_IMON_0 @T6G_MB_LIB.T6G(SCH_1):P12V_E1S_IMON_0
PR3949    1      A Q_RES_0402LF-56K,1%,1/16W,CHIP,CS35602FB00    I36 @T6G_MB_LIB.T6G(SCH_1):PAGE323
PC2202    1      A Q_CAP_C0402-100NF,50V,10%,X7R,CH4106K1B01    I39 @T6G_MB_LIB.T6G(SCH_1):PAGE323
 R3956    1      A Q_RES_0402LF-0,5%,1/16W,EMPTY,CS00002JB13    I47 @T6G_MB_LIB.T6G(SCH_1):PAGE323
 R3955    1      A Q_RES_0402LF-0,5%,1/16W,CHIP,CS00002JB13    I48 @T6G_MB_LIB.T6G(SCH_1):PAGE323
 PU292    8   IMON RS31312R-RS31312R,SMLF,IC,AL031312000    I76 @T6G_MB_LIB.T6G(SCH_1):PAGE323

P12V_E1S_ISET_0 @T6G_MB_LIB.T6G(SCH_1):P12V_E1S_ISET_0
PR3944    1      A Q_RES_0402LF-46.4K,1%,1/16W,CHIP,CS34642FB02    I15 @T6G_MB_LIB.T6G(SCH_1):PAGE323
PR4541    1      A Q_RES_0402LF-20K,1%,1/16W,CHIP,CS32002FB06    I18 @T6G_MB_LIB.T6G(SCH_1):PAGE323
 PU292    5   ISET RS31312R-RS31312R,SMLF,IC,AL031312000    I76 @T6G_MB_LIB.T6G(SCH_1):PAGE323

P12V_E1S_ISET_0_R @T6G_MB_LIB.T6G(SCH_1):P12V_E1S_ISET_0_R
PC2341    1      A Q_CAP_C0402-560PF,50V,10%,X7R,CH1566K1B09    I17 @T6G_MB_LIB.T6G(SCH_1):PAGE323
PR4541    2      B Q_RES_0402LF-20K,1%,1/16W,CHIP,CS32002FB06    I18 @T6G_MB_LIB.T6G(SCH_1):PAGE323

P12V_E1S_OV_0 @T6G_MB_LIB.T6G(SCH_1):P12V_E1S_OV_0
PR3962    1      A Q_RES_0402LF-15K,1%,1/16W,CHIP,CS31502FB05    I31 @T6G_MB_LIB.T6G(SCH_1):PAGE324
 PU294   D3     OV MAX15090BEWIT-MAX15090BEWI+T,SMLF,IC,AL015080B00    I66 @T6G_MB_LIB.T6G(SCH_1):PAGE324
PR3961    2      B Q_RES_0402LF-6.8K,1%,1/16W,CHIP,CS26802FB02    I32 @T6G_MB_LIB.T6G(SCH_1):PAGE324

P12V_E1S_OV_FB_0 @T6G_MB_LIB.T6G(SCH_1):P12V_E1S_OV_FB_0
PR3952    2      B Q_RES_0402LF-71.5K,1%,1/16W,EMPTY,CS37152FB05    I45 @T6G_MB_LIB.T6G(SCH_1):PAGE323
PR3954    1      A Q_RES_0402LF-10K,1%,1/16W,CHIP,CS31002FB08    I49 @T6G_MB_LIB.T6G(SCH_1):PAGE323
PR3953    2      B Q_RES_0402LF-120K,1%,1/16W,CHIP,CS41202FB05    I52 @T6G_MB_LIB.T6G(SCH_1):PAGE323
 PU292   11     OV RS31312R-RS31312R,SMLF,IC,AL031312000    I76 @T6G_MB_LIB.T6G(SCH_1):PAGE323

P12V_E1S_PWRGD_0 @T6G_MB_LIB.T6G(SCH_1):P12V_E1S_PWRGD_0
 PU294   D7     PG MAX15090BEWIT-MAX15090BEWI+T,SMLF,IC,AL015080B00    I66 @T6G_MB_LIB.T6G(SCH_1):PAGE324
 R3972    1      A Q_RES_0402LF-0,5%,1/16W,CHIP,CS00002JB13    I71 @T6G_MB_LIB.T6G(SCH_1):PAGE324

P12V_E1S_REG_0 @T6G_MB_LIB.T6G(SCH_1):P12V_E1S_REG_0
PC2211    2      B Q_CAP_C0402-1UF,25V,10%,X6S,CH5104KEB02    I61 @T6G_MB_LIB.T6G(SCH_1):PAGE324
 PU294   D1    REG MAX15090BEWIT-MAX15090BEWI+T,SMLF,IC,AL015080B00    I66 @T6G_MB_LIB.T6G(SCH_1):PAGE324

P12V_E1S_SENSE_0 @T6G_MB_LIB.T6G(SCH_1):P12V_E1S_SENSE_0
 PU294   A1 ISENSE MAX15090BEWIT-MAX15090BEWI+T,SMLF,IC,AL015080B00    I66 @T6G_MB_LIB.T6G(SCH_1):PAGE324
PR3970    1      A Q_RES_0402LF-2.67K,1%,1/16W,CHIP,CS22672FB03    I68 @T6G_MB_LIB.T6G(SCH_1):PAGE324
 R3974    1      A Q_RES_0402LF-0,5%,1/16W,EMPTY,CS00002JB13    I70 @T6G_MB_LIB.T6G(SCH_1):PAGE324
 R3975    1      A Q_RES_0402LF-0,5%,1/16W,CHIP,CS00002JB13    I87 @T6G_MB_LIB.T6G(SCH_1):PAGE324

P12V_E1S_SS_0 @T6G_MB_LIB.T6G(SCH_1):P12V_E1S_SS_0
PC2281    1      A Q_CAP_C0402-0.047UF,25V,10%,X7R,CH3474K1B04    I22 @T6G_MB_LIB.T6G(SCH_1):PAGE323
 PU292    6     SS RS31312R-RS31312R,SMLF,IC,AL031312000    I76 @T6G_MB_LIB.T6G(SCH_1):PAGE323

P12V_E1S_TIMER_0 @T6G_MB_LIB.T6G(SCH_1):P12V_E1S_TIMER_0
PC2196    1      A Q_CAP_0402-0.22UF,16V,10%,X7R,CH4223K1B00    I13 @T6G_MB_LIB.T6G(SCH_1):PAGE323
 PU292    4  TIMER RS31312R-RS31312R,SMLF,IC,AL031312000    I76 @T6G_MB_LIB.T6G(SCH_1):PAGE323

P12V_E1S_UV_0 @T6G_MB_LIB.T6G(SCH_1):P12V_E1S_UV_0
 R3958    2      B Q_RES_0402LF-0,5%,1/16W,CHIP,CS00002JB13    I29 @T6G_MB_LIB.T6G(SCH_1):PAGE324
PR3960    2      B Q_RES_0402LF-160K,1%,1/16W,CHIP,CS41602FB05    I37 @T6G_MB_LIB.T6G(SCH_1):PAGE324
 PU294   D2     UV MAX15090BEWIT-MAX15090BEWI+T,SMLF,IC,AL015080B00    I66 @T6G_MB_LIB.T6G(SCH_1):PAGE324
PR3961    1      A Q_RES_0402LF-6.8K,1%,1/16W,CHIP,CS26802FB02    I32 @T6G_MB_LIB.T6G(SCH_1):PAGE324

P12V_E1S_UV_0_R @T6G_MB_LIB.T6G(SCH_1):P12V_E1S_UV_0_R
  Q127    3     D2 MOSFET_NCH_DUAL-PJT138K,SMLF,IC,BAM138K0003    I27 @T6G_MB_LIB.T6G(SCH_1):PAGE324
 R3958    1      A Q_RES_0402LF-0,5%,1/16W,CHIP,CS00002JB13    I29 @T6G_MB_LIB.T6G(SCH_1):PAGE324

P12V_E1S_VCC_0 @T6G_MB_LIB.T6G(SCH_1):P12V_E1S_VCC_0
PR3966    2      B Q_RES_0402LF-10,1%,1/16W,CHIP,CS01002FB07    I65 @T6G_MB_LIB.T6G(SCH_1):PAGE324
 PU294   A2    VCC MAX15090BEWIT-MAX15090BEWI+T,SMLF,IC,AL015080B00    I66 @T6G_MB_LIB.T6G(SCH_1):PAGE324
PC2209    1      A Q_CAP_C0402-1UF,25V,10%,X6S,CH5104KEB02    I64 @T6G_MB_LIB.T6G(SCH_1):PAGE324

P12V_HSC_ADC_N @T6G_MB_LIB.T6G(SCH_1):P12V_HSC_ADC_N
  PJ38    6      6 SCONN21_9193031121LF-SCONN21_91930-31121LF,SMLF,IOA    I42 @T6G_MB_LIB.T6G(SCH_1):PAGE371
PR2515    1      A Q_RES_0402LF-10,1%,1/16W,CHIP,CS01002FB07    I83 @T6G_MB_LIB.T6G(SCH_1):PAGE302
PR2516    1      A Q_RES_0402LF-10,1%,1/16W,CHIP,CS01002FB07    I84 @T6G_MB_LIB.T6G(SCH_1):PAGE302
PR2517    1      A Q_RES_0402LF-10,1%,1/16W,CHIP,CS01002FB07    I85 @T6G_MB_LIB.T6G(SCH_1):PAGE302
PR2518    1      A Q_RES_0402LF-10,1%,1/16W,CHIP,CS01002FB07    I86 @T6G_MB_LIB.T6G(SCH_1):PAGE302
PR2519    1      A Q_RES_0402LF-100,1%,1/16W,CHIP,CS11002FB07    I87 @T6G_MB_LIB.T6G(SCH_1):PAGE302

P12V_HSC_ADC_P @T6G_MB_LIB.T6G(SCH_1):P12V_HSC_ADC_P
PR2513    1      A Q_RES_0402LF-1,1%,1/16W,CHIP,CS-1002FB04    I15 @T6G_MB_LIB.T6G(SCH_1):PAGE302
PR2512    1      A Q_RES_0402LF-1,1%,1/16W,CHIP,CS-1002FB04    I16 @T6G_MB_LIB.T6G(SCH_1):PAGE302
PR2511    1      A Q_RES_0402LF-1,1%,1/16W,CHIP,CS-1002FB04    I17 @T6G_MB_LIB.T6G(SCH_1):PAGE302
PR2510    1      A Q_RES_0402LF-1,1%,1/16W,CHIP,CS-1002FB04    I18 @T6G_MB_LIB.T6G(SCH_1):PAGE302
  PJ38    7      7 SCONN21_9193031121LF-SCONN21_91930-31121LF,SMLF,IOA    I42 @T6G_MB_LIB.T6G(SCH_1):PAGE371
PR2514    1      A Q_RES_0402LF-10,1%,1/16W,CHIP,CS01002FB07    I82 @T6G_MB_LIB.T6G(SCH_1):PAGE302

P12V_HSC_GATE1 @T6G_MB_LIB.T6G(SCH_1):P12V_HSC_GATE1
PR2538    2      B Q_RES_0402LF-10,1%,1/16W,CHIP,CS01002FB07    I74 @T6G_MB_LIB.T6G(SCH_1):PAGE302
  PJ38    8      8 SCONN21_9193031121LF-SCONN21_91930-31121LF,SMLF,IOA    I42 @T6G_MB_LIB.T6G(SCH_1):PAGE371

P12V_HSC_GATE2 @T6G_MB_LIB.T6G(SCH_1):P12V_HSC_GATE2
PR2528    2      B Q_RES_0402LF-10,1%,1/16W,CHIP,CS01002FB07    I27 @T6G_MB_LIB.T6G(SCH_1):PAGE302
PR2529    2      B Q_RES_0402LF-10,1%,1/16W,CHIP,CS01002FB07    I28 @T6G_MB_LIB.T6G(SCH_1):PAGE302
PR2530    2      B Q_RES_0402LF-10,1%,1/16W,CHIP,CS01002FB07    I45 @T6G_MB_LIB.T6G(SCH_1):PAGE302
PR2531    2      B Q_RES_0402LF-10,1%,1/16W,CHIP,CS01002FB07    I47 @T6G_MB_LIB.T6G(SCH_1):PAGE302
PR2535    2      B Q_RES_0402LF-10,1%,1/16W,CHIP,CS01002FB07    I60 @T6G_MB_LIB.T6G(SCH_1):PAGE302
PR2536    2      B Q_RES_0402LF-10,1%,1/16W,CHIP,CS01002FB07    I62 @T6G_MB_LIB.T6G(SCH_1):PAGE302
PC1750    2      B Q_CAP_C0402-33NF,25V,10%,EMPTY,CH3334K1B00    I63 @T6G_MB_LIB.T6G(SCH_1):PAGE302
PC1751    2      B Q_CAP_0402-1NF,50V,10%,EMPTY,CH21006KB16    I70 @T6G_MB_LIB.T6G(SCH_1):PAGE302
  PJ38    9      9 SCONN21_9193031121LF-SCONN21_91930-31121LF,SMLF,IOA    I42 @T6G_MB_LIB.T6G(SCH_1):PAGE371

P12V_HSC_GATE_G1 @T6G_MB_LIB.T6G(SCH_1):P12V_HSC_GATE_G1
PR2528    1      A Q_RES_0402LF-10,1%,1/16W,CHIP,CS01002FB07    I27 @T6G_MB_LIB.T6G(SCH_1):PAGE302
  PPQ5    4      4 MOSFET_NCH_1D3S-PSMNR58-30YLH,SMLF,IC,BAMNR580000    I29 @T6G_MB_LIB.T6G(SCH_1):PAGE302

P12V_HSC_GATE_G2 @T6G_MB_LIB.T6G(SCH_1):P12V_HSC_GATE_G2
PR2529    1      A Q_RES_0402LF-10,1%,1/16W,CHIP,CS01002FB07    I28 @T6G_MB_LIB.T6G(SCH_1):PAGE302
  PPQ6    4      4 MOSFET_NCH_1D3S-PSMNR58-30YLH,SMLF,IC,BAMNR580000    I46 @T6G_MB_LIB.T6G(SCH_1):PAGE302

P12V_HSC_GATE_G3 @T6G_MB_LIB.T6G(SCH_1):P12V_HSC_GATE_G3
PR2530    1      A Q_RES_0402LF-10,1%,1/16W,CHIP,CS01002FB07    I45 @T6G_MB_LIB.T6G(SCH_1):PAGE302
  PPQ7    4      4 MOSFET_NCH_1D3S-PSMNR58-30YLH,SMLF,IC,BAMNR580000    I80 @T6G_MB_LIB.T6G(SCH_1):PAGE302

P12V_HSC_GATE_G4 @T6G_MB_LIB.T6G(SCH_1):P12V_HSC_GATE_G4
PR2531    1      A Q_RES_0402LF-10,1%,1/16W,CHIP,CS01002FB07    I47 @T6G_MB_LIB.T6G(SCH_1):PAGE302
  PPQ8    4      4 MOSFET_NCH_1D3S-PSMNR58-30YLH,SMLF,IC,BAMNR580000    I79 @T6G_MB_LIB.T6G(SCH_1):PAGE302

P12V_HSC_GATE_G5 @T6G_MB_LIB.T6G(SCH_1):P12V_HSC_GATE_G5
PR2535    1      A Q_RES_0402LF-10,1%,1/16W,CHIP,CS01002FB07    I60 @T6G_MB_LIB.T6G(SCH_1):PAGE302
  PPQ1    4      4 MOSFET_NCH_1D3S-PSMNR58-30YLH,SMLF,IC,BAMNR580000    I61 @T6G_MB_LIB.T6G(SCH_1):PAGE302

P12V_HSC_GATE_G6 @T6G_MB_LIB.T6G(SCH_1):P12V_HSC_GATE_G6
PR2536    1      A Q_RES_0402LF-10,1%,1/16W,CHIP,CS01002FB07    I62 @T6G_MB_LIB.T6G(SCH_1):PAGE302
  PPQ2    4      4 MOSFET_NCH_1D3S-PSMNR58-30YLH,SMLF,IC,BAMNR580000    I64 @T6G_MB_LIB.T6G(SCH_1):PAGE302

P12V_HSC_GATE_RC @T6G_MB_LIB.T6G(SCH_1):P12V_HSC_GATE_RC
PC1751    1      A Q_CAP_0402-1NF,50V,10%,EMPTY,CH21006KB16    I70 @T6G_MB_LIB.T6G(SCH_1):PAGE302
PR2537    2      B Q_RES_0402LF-10,1%,1/16W,EMPTY,CS01002FB07    I71 @T6G_MB_LIB.T6G(SCH_1):PAGE302

P12V_HSC_SENSE1_N @T6G_MB_LIB.T6G(SCH_1):P12V_HSC_SENSE1_N
  PJ38    3      3 SCONN21_9193031121LF-SCONN21_91930-31121LF,SMLF,IOA    I42 @T6G_MB_LIB.T6G(SCH_1):PAGE371
PR6002   2B     2B Q_SP_RES4P-0.003,1%,2W,SMLF,CHIP,SP_CS+003AFR00_1    I81 @T6G_MB_LIB.T6G(SCH_1):PAGE302
PR2519    2      B Q_RES_0402LF-100,1%,1/16W,CHIP,CS11002FB07    I87 @T6G_MB_LIB.T6G(SCH_1):PAGE302

P12V_HSC_SENSE1_P @T6G_MB_LIB.T6G(SCH_1):P12V_HSC_SENSE1_P
  PJ38    2      2 SCONN21_9193031121LF-SCONN21_91930-31121LF,SMLF,IOA    I42 @T6G_MB_LIB.T6G(SCH_1):PAGE371
PR6002   1B     1B Q_SP_RES4P-0.003,1%,2W,SMLF,CHIP,SP_CS+003AFR00_1    I81 @T6G_MB_LIB.T6G(SCH_1):PAGE302
PR2514    2      B Q_RES_0402LF-10,1%,1/16W,CHIP,CS01002FB07    I82 @T6G_MB_LIB.T6G(SCH_1):PAGE302

P12V_HSC_SENSE2_N @T6G_MB_LIB.T6G(SCH_1):P12V_HSC_SENSE2_N
  PJ38    5      5 SCONN21_9193031121LF-SCONN21_91930-31121LF,SMLF,IOA    I42 @T6G_MB_LIB.T6G(SCH_1):PAGE371
PR2524    1      A Q_RES_0402LF-10,1%,1/16W,CHIP,CS01002FB07    I88 @T6G_MB_LIB.T6G(SCH_1):PAGE302
PR2525    1      A Q_RES_0402LF-10,1%,1/16W,CHIP,CS01002FB07    I89 @T6G_MB_LIB.T6G(SCH_1):PAGE302
PR2526    1      A Q_RES_0402LF-10,1%,1/16W,CHIP,CS01002FB07    I90 @T6G_MB_LIB.T6G(SCH_1):PAGE302
PR2527    1      A Q_RES_0402LF-10,1%,1/16W,CHIP,CS01002FB07    I91 @T6G_MB_LIB.T6G(SCH_1):PAGE302

P12V_HSC_SENSE2_P @T6G_MB_LIB.T6G(SCH_1):P12V_HSC_SENSE2_P
PR2523    1      A Q_RES_0402LF-1,1%,1/16W,CHIP,CS-1002FB04     I5 @T6G_MB_LIB.T6G(SCH_1):PAGE302
PR2521    1      A Q_RES_0402LF-1,1%,1/16W,CHIP,CS-1002FB04     I6 @T6G_MB_LIB.T6G(SCH_1):PAGE302
PR2522    1      A Q_RES_0402LF-1,1%,1/16W,CHIP,CS-1002FB04     I7 @T6G_MB_LIB.T6G(SCH_1):PAGE302
PR2520    1      A Q_RES_0402LF-1,1%,1/16W,CHIP,CS-1002FB04     I8 @T6G_MB_LIB.T6G(SCH_1):PAGE302
  PJ38    4      4 SCONN21_9193031121LF-SCONN21_91930-31121LF,SMLF,IOA    I42 @T6G_MB_LIB.T6G(SCH_1):PAGE371

P12V_HSC_SENSE2_R1_N @T6G_MB_LIB.T6G(SCH_1):P12V_HSC_SENSE2_R1_N
PR6001   2B     2B Q_SP_RES4P-0.0003,1%,4W,SMLF,CHIP,SP_CS0000FFT09    I55 @T6G_MB_LIB.T6G(SCH_1):PAGE302
PR2515    2      B Q_RES_0402LF-10,1%,1/16W,CHIP,CS01002FB07    I83 @T6G_MB_LIB.T6G(SCH_1):PAGE302
PR2524    2      B Q_RES_0402LF-10,1%,1/16W,CHIP,CS01002FB07    I88 @T6G_MB_LIB.T6G(SCH_1):PAGE302

P12V_HSC_SENSE2_R1_P @T6G_MB_LIB.T6G(SCH_1):P12V_HSC_SENSE2_R1_P
PR2520    2      B Q_RES_0402LF-1,1%,1/16W,CHIP,CS-1002FB04     I8 @T6G_MB_LIB.T6G(SCH_1):PAGE302
PR2510    2      B Q_RES_0402LF-1,1%,1/16W,CHIP,CS-1002FB04    I18 @T6G_MB_LIB.T6G(SCH_1):PAGE302
PR6001   1B     1B Q_SP_RES4P-0.0003,1%,4W,SMLF,CHIP,SP_CS0000FFT09    I55 @T6G_MB_LIB.T6G(SCH_1):PAGE302

P12V_HSC_SENSE2_R2_N @T6G_MB_LIB.T6G(SCH_1):P12V_HSC_SENSE2_R2_N
PR2532   2B     2B Q_SP_RES4P-0.0003,1%,4W,SMLF,CHIP,SP_CS0000FFT09    I54 @T6G_MB_LIB.T6G(SCH_1):PAGE302
PR2516    2      B Q_RES_0402LF-10,1%,1/16W,CHIP,CS01002FB07    I84 @T6G_MB_LIB.T6G(SCH_1):PAGE302
PR2525    2      B Q_RES_0402LF-10,1%,1/16W,CHIP,CS01002FB07    I89 @T6G_MB_LIB.T6G(SCH_1):PAGE302

P12V_HSC_SENSE2_R2_P @T6G_MB_LIB.T6G(SCH_1):P12V_HSC_SENSE2_R2_P
PR2521    2      B Q_RES_0402LF-1,1%,1/16W,CHIP,CS-1002FB04     I6 @T6G_MB_LIB.T6G(SCH_1):PAGE302
PR2511    2      B Q_RES_0402LF-1,1%,1/16W,CHIP,CS-1002FB04    I17 @T6G_MB_LIB.T6G(SCH_1):PAGE302
PR2532   1B     1B Q_SP_RES4P-0.0003,1%,4W,SMLF,CHIP,SP_CS0000FFT09    I54 @T6G_MB_LIB.T6G(SCH_1):PAGE302

P12V_HSC_SENSE2_R3_N @T6G_MB_LIB.T6G(SCH_1):P12V_HSC_SENSE2_R3_N
PR2533   2B     2B Q_SP_RES4P-0.0003,1%,4W,SMLF,CHIP,SP_CS0000FFT09    I53 @T6G_MB_LIB.T6G(SCH_1):PAGE302
PR2517    2      B Q_RES_0402LF-10,1%,1/16W,CHIP,CS01002FB07    I85 @T6G_MB_LIB.T6G(SCH_1):PAGE302
PR2526    2      B Q_RES_0402LF-10,1%,1/16W,CHIP,CS01002FB07    I90 @T6G_MB_LIB.T6G(SCH_1):PAGE302

P12V_HSC_SENSE2_R3_P @T6G_MB_LIB.T6G(SCH_1):P12V_HSC_SENSE2_R3_P
PR2522    2      B Q_RES_0402LF-1,1%,1/16W,CHIP,CS-1002FB04     I7 @T6G_MB_LIB.T6G(SCH_1):PAGE302
PR2512    2      B Q_RES_0402LF-1,1%,1/16W,CHIP,CS-1002FB04    I16 @T6G_MB_LIB.T6G(SCH_1):PAGE302
PR2533   1B     1B Q_SP_RES4P-0.0003,1%,4W,SMLF,CHIP,SP_CS0000FFT09    I53 @T6G_MB_LIB.T6G(SCH_1):PAGE302

P12V_HSC_SENSE2_R4_N @T6G_MB_LIB.T6G(SCH_1):P12V_HSC_SENSE2_R4_N
PR2534   2B     2B Q_SP_RES4P-0.0003,1%,4W,SMLF,CHIP,SP_CS0000FFT09    I52 @T6G_MB_LIB.T6G(SCH_1):PAGE302
PR2518    2      B Q_RES_0402LF-10,1%,1/16W,CHIP,CS01002FB07    I86 @T6G_MB_LIB.T6G(SCH_1):PAGE302
PR2527    2      B Q_RES_0402LF-10,1%,1/16W,CHIP,CS01002FB07    I91 @T6G_MB_LIB.T6G(SCH_1):PAGE302

P12V_HSC_SENSE2_R4_P @T6G_MB_LIB.T6G(SCH_1):P12V_HSC_SENSE2_R4_P
PR2523    2      B Q_RES_0402LF-1,1%,1/16W,CHIP,CS-1002FB04     I5 @T6G_MB_LIB.T6G(SCH_1):PAGE302
PR2513    2      B Q_RES_0402LF-1,1%,1/16W,CHIP,CS-1002FB04    I15 @T6G_MB_LIB.T6G(SCH_1):PAGE302
PR2534   1B     1B Q_SP_RES4P-0.0003,1%,4W,SMLF,CHIP,SP_CS0000FFT09    I52 @T6G_MB_LIB.T6G(SCH_1):PAGE302

P12V_HSC_TEMP_ALERT_N @T6G_MB_LIB.T6G(SCH_1):P12V_HSC_TEMP_ALERT_N
  U143    6 ALERT# NCT7718W-NCT7718W,SMLF,IC,AL007718001     I8 @T6G_MB_LIB.T6G(SCH_1):PAGE371
 R2628    1      A Q_RES_0402LF-0,5%,1/16W,CHIP,CS00002JB13    I10 @T6G_MB_LIB.T6G(SCH_1):PAGE371

P12V_HSC_TEMP_ALERT_R_N @T6G_MB_LIB.T6G(SCH_1):P12V_HSC_TEMP_ALERT_R_N
   U18   N7  PL20D LCMXO3LF9400C5BG484C-LCMXO3LF-9400C-5BG484C,SMLF,IA   I143 @T6G_MB_LIB.T6G(SCH_1):PAGE81
 R2628    2      B Q_RES_0402LF-0,5%,1/16W,CHIP,CS00002JB13    I10 @T6G_MB_LIB.T6G(SCH_1):PAGE371
  R355    2      B Q_RES_0402LF-10.5K,1%,1/16W,CHIP,CS31052FB03    I79 @T6G_MB_LIB.T6G(SCH_1):PAGE371

P12V_HSC_TEMP_D+ @T6G_MB_LIB.T6G(SCH_1):P12V_HSC_TEMP_D+
 R2625    2      B Q_RES_0402LF-49.9,1%,1/16W,CHIP,CS04992FB07     I3 @T6G_MB_LIB.T6G(SCH_1):PAGE371
 C1786    1      A Q_CAP_0603-1000PF,50V,10%,X7R,TMP_QCH21006K917     I4 @T6G_MB_LIB.T6G(SCH_1):PAGE371
  U143    2     D+ NCT7718W-NCT7718W,SMLF,IC,AL007718001     I8 @T6G_MB_LIB.T6G(SCH_1):PAGE371

P12V_HSC_TEMP_D- @T6G_MB_LIB.T6G(SCH_1):P12V_HSC_TEMP_D-
 R2624    2      B Q_RES_0402LF-49.9,1%,1/16W,CHIP,CS04992FB07     I2 @T6G_MB_LIB.T6G(SCH_1):PAGE371
 C1786    2      B Q_CAP_0603-1000PF,50V,10%,X7R,TMP_QCH21006K917     I4 @T6G_MB_LIB.T6G(SCH_1):PAGE371
  U143    3     D- NCT7718W-NCT7718W,SMLF,IC,AL007718001     I8 @T6G_MB_LIB.T6G(SCH_1):PAGE371

P12V_HSC_TEMP_E @T6G_MB_LIB.T6G(SCH_1):P12V_HSC_TEMP_E
 Q6001    E      2 METR3904G-METR3904-G,SMLF,IC,BA039040020     I1 @T6G_MB_LIB.T6G(SCH_1):PAGE371
 R2624    1      A Q_RES_0402LF-49.9,1%,1/16W,CHIP,CS04992FB07     I2 @T6G_MB_LIB.T6G(SCH_1):PAGE371

P12V_HSC_TEMP_R @T6G_MB_LIB.T6G(SCH_1):P12V_HSC_TEMP_R
 Q6001    B      1 METR3904G-METR3904-G,SMLF,IC,BA039040020     I1 @T6G_MB_LIB.T6G(SCH_1):PAGE371
 Q6001    C      3 METR3904G-METR3904-G,SMLF,IC,BA039040020     I1 @T6G_MB_LIB.T6G(SCH_1):PAGE371
 R2625    1      A Q_RES_0402LF-49.9,1%,1/16W,CHIP,CS04992FB07     I3 @T6G_MB_LIB.T6G(SCH_1):PAGE371

P12V_HSC_T_CRIT_N @T6G_MB_LIB.T6G(SCH_1):P12V_HSC_T_CRIT_N
  U143    4 T_CRIT# NCT7718W-NCT7718W,SMLF,IC,AL007718001     I8 @T6G_MB_LIB.T6G(SCH_1):PAGE371
  R353    1      A Q_RES_0402LF-0,5%,1/16W,CHIP,CS00002JB13    I74 @T6G_MB_LIB.T6G(SCH_1):PAGE371

P12V_HSC_T_CRIT_R_N @T6G_MB_LIB.T6G(SCH_1):P12V_HSC_T_CRIT_R_N
   U18   K4  PL13C LCMXO3LF9400C5BG484C-LCMXO3LF-9400C-5BG484C,SMLF,IA   I143 @T6G_MB_LIB.T6G(SCH_1):PAGE81
  R353    2      B Q_RES_0402LF-0,5%,1/16W,CHIP,CS00002JB13    I74 @T6G_MB_LIB.T6G(SCH_1):PAGE371
  R354    2      B Q_RES_0402LF-10.5K,1%,1/16W,CHIP,CS31052FB03    I76 @T6G_MB_LIB.T6G(SCH_1):PAGE371

P12V_MAIN_R @T6G_MB_LIB.T6G(SCH_1):P12V_MAIN_R
  PPQ5    5      5 MOSFET_NCH_1D3S-PSMNR58-30YLH,SMLF,IC,BAMNR580000    I29 @T6G_MB_LIB.T6G(SCH_1):PAGE302
  PPQ6    5      5 MOSFET_NCH_1D3S-PSMNR58-30YLH,SMLF,IC,BAMNR580000    I46 @T6G_MB_LIB.T6G(SCH_1):PAGE302
PR2534   2A     2A Q_SP_RES4P-0.0003,1%,4W,SMLF,CHIP,SP_CS0000FFT09    I52 @T6G_MB_LIB.T6G(SCH_1):PAGE302
PR2533   2A     2A Q_SP_RES4P-0.0003,1%,4W,SMLF,CHIP,SP_CS0000FFT09    I53 @T6G_MB_LIB.T6G(SCH_1):PAGE302
PR2532   2A     2A Q_SP_RES4P-0.0003,1%,4W,SMLF,CHIP,SP_CS0000FFT09    I54 @T6G_MB_LIB.T6G(SCH_1):PAGE302
PR6001   2A     2A Q_SP_RES4P-0.0003,1%,4W,SMLF,CHIP,SP_CS0000FFT09    I55 @T6G_MB_LIB.T6G(SCH_1):PAGE302
  PPQ1    5      5 MOSFET_NCH_1D3S-PSMNR58-30YLH,SMLF,IC,BAMNR580000    I61 @T6G_MB_LIB.T6G(SCH_1):PAGE302
  PPQ2    5      5 MOSFET_NCH_1D3S-PSMNR58-30YLH,SMLF,IC,BAMNR580000    I64 @T6G_MB_LIB.T6G(SCH_1):PAGE302
  PPQ8    5      5 MOSFET_NCH_1D3S-PSMNR58-30YLH,SMLF,IC,BAMNR580000    I79 @T6G_MB_LIB.T6G(SCH_1):PAGE302
  PPQ7    5      5 MOSFET_NCH_1D3S-PSMNR58-30YLH,SMLF,IC,BAMNR580000    I80 @T6G_MB_LIB.T6G(SCH_1):PAGE302

P12V_MAIN_R_0 @T6G_MB_LIB.T6G(SCH_1):P12V_MAIN_R_0
  PPQ9    5      5 MOSFET_NCH_1D3S-PSMNR58-30YLH,SMLF,IC,BAMNR580000    I75 @T6G_MB_LIB.T6G(SCH_1):PAGE302
PR6002   2A     2A Q_SP_RES4P-0.003,1%,2W,SMLF,CHIP,SP_CS+003AFR00_1    I81 @T6G_MB_LIB.T6G(SCH_1):PAGE302

P12V_MEM_CPU0 @T6G_MB_LIB.T6G(SCH_1):P12V_MEM_CPU0
   C89    1      A Q_CAP_C0805-10UF,25V,10%,X6S,CH6104KEA00   I519 @T6G_MB_LIB.T6G(SCH_1):PAGE85
  C142    1      A Q_CAP_C0805-10UF,25V,10%,X6S,CH6104KEA00   I534 @T6G_MB_LIB.T6G(SCH_1):PAGE85
   J15    1 VIN_BULK0 SCONN288_DDR506112002KQ-SCONN288_DDR506112002KQ,SMA   I352 @T6G_MB_LIB.T6G(SCH_1):PAGE86
   J15  145 VIN_BULK1 SCONN288_DDR506112002KQ-SCONN288_DDR506112002KQ,SMA   I352 @T6G_MB_LIB.T6G(SCH_1):PAGE86
   J15  146 VIN_BULK2 SCONN288_DDR506112002KQ-SCONN288_DDR506112002KQ,SMA   I352 @T6G_MB_LIB.T6G(SCH_1):PAGE86
  C143    1      A Q_CAP_C0805-10UF,25V,10%,X6S,CH6104KEA00   I369 @T6G_MB_LIB.T6G(SCH_1):PAGE86
  C145    1      A Q_CAP_C0805-10UF,25V,10%,X6S,CH6104KEA00   I370 @T6G_MB_LIB.T6G(SCH_1):PAGE86
   J17    1 VIN_BULK0 SCONN288_DDR506112002KQ-SCONN288_DDR506112002KQ,SMA   I352 @T6G_MB_LIB.T6G(SCH_1):PAGE87
   J17  145 VIN_BULK1 SCONN288_DDR506112002KQ-SCONN288_DDR506112002KQ,SMA   I352 @T6G_MB_LIB.T6G(SCH_1):PAGE87
   J17  146 VIN_BULK2 SCONN288_DDR506112002KQ-SCONN288_DDR506112002KQ,SMA   I352 @T6G_MB_LIB.T6G(SCH_1):PAGE87
  C146    1      A Q_CAP_C0805-10UF,25V,10%,X6S,CH6104KEA00   I413 @T6G_MB_LIB.T6G(SCH_1):PAGE87
  C147    1      A Q_CAP_C0805-10UF,25V,10%,X6S,CH6104KEA00   I414 @T6G_MB_LIB.T6G(SCH_1):PAGE87
   J19    1 VIN_BULK0 SCONN288_DDR506112002KQ-SCONN288_DDR506112002KQ,SMA   I352 @T6G_MB_LIB.T6G(SCH_1):PAGE88
   J19  145 VIN_BULK1 SCONN288_DDR506112002KQ-SCONN288_DDR506112002KQ,SMA   I352 @T6G_MB_LIB.T6G(SCH_1):PAGE88
   J19  146 VIN_BULK2 SCONN288_DDR506112002KQ-SCONN288_DDR506112002KQ,SMA   I352 @T6G_MB_LIB.T6G(SCH_1):PAGE88
  C149    1      A Q_CAP_C0805-10UF,25V,10%,X6S,CH6104KEA00   I417 @T6G_MB_LIB.T6G(SCH_1):PAGE88
  C150    1      A Q_CAP_C0805-10UF,25V,10%,X6S,CH6104KEA00   I418 @T6G_MB_LIB.T6G(SCH_1):PAGE88
   J21    1 VIN_BULK0 SCONN288_DDR506112002KQ-SCONN288_DDR506112002KQ,SMA   I350 @T6G_MB_LIB.T6G(SCH_1):PAGE89
   J21  145 VIN_BULK1 SCONN288_DDR506112002KQ-SCONN288_DDR506112002KQ,SMA   I350 @T6G_MB_LIB.T6G(SCH_1):PAGE89
   J21  146 VIN_BULK2 SCONN288_DDR506112002KQ-SCONN288_DDR506112002KQ,SMA   I350 @T6G_MB_LIB.T6G(SCH_1):PAGE89
  C151    1      A Q_CAP_C0805-10UF,25V,10%,X6S,CH6104KEA00   I412 @T6G_MB_LIB.T6G(SCH_1):PAGE89
  C153    1      A Q_CAP_C0805-10UF,25V,10%,X6S,CH6104KEA00   I413 @T6G_MB_LIB.T6G(SCH_1):PAGE89
   J23    1 VIN_BULK0 SCONN288_DDR506112002KQ-SCONN288_DDR506112002KQ,SMA   I352 @T6G_MB_LIB.T6G(SCH_1):PAGE90
   J23  145 VIN_BULK1 SCONN288_DDR506112002KQ-SCONN288_DDR506112002KQ,SMA   I352 @T6G_MB_LIB.T6G(SCH_1):PAGE90
   J23  146 VIN_BULK2 SCONN288_DDR506112002KQ-SCONN288_DDR506112002KQ,SMA   I352 @T6G_MB_LIB.T6G(SCH_1):PAGE90
  C154    1      A Q_CAP_C0805-10UF,25V,10%,X6S,CH6104KEA00   I414 @T6G_MB_LIB.T6G(SCH_1):PAGE90
  C155    1      A Q_CAP_C0805-10UF,25V,10%,X6S,CH6104KEA00   I415 @T6G_MB_LIB.T6G(SCH_1):PAGE90
   J16    1 VIN_BULK0 SCONN288_DDR506112002KQ-SCONN288_DDR506112002KQ,SMA   I177 @T6G_MB_LIB.T6G(SCH_1):PAGE91
   J16  145 VIN_BULK1 SCONN288_DDR506112002KQ-SCONN288_DDR506112002KQ,SMA   I177 @T6G_MB_LIB.T6G(SCH_1):PAGE91
   J16  146 VIN_BULK2 SCONN288_DDR506112002KQ-SCONN288_DDR506112002KQ,SMA   I177 @T6G_MB_LIB.T6G(SCH_1):PAGE91
  C157    1      A Q_CAP_C0805-10UF,25V,10%,X6S,CH6104KEA00   I238 @T6G_MB_LIB.T6G(SCH_1):PAGE91
  C158    1      A Q_CAP_C0805-10UF,25V,10%,X6S,CH6104KEA00   I239 @T6G_MB_LIB.T6G(SCH_1):PAGE91
   J69    1 VIN_BULK0 SCONN288_DDR506112002KQ-SCONN288_DDR506112002KQ,SMA   I177 @T6G_MB_LIB.T6G(SCH_1):PAGE92
   J69  145 VIN_BULK1 SCONN288_DDR506112002KQ-SCONN288_DDR506112002KQ,SMA   I177 @T6G_MB_LIB.T6G(SCH_1):PAGE92
   J69  146 VIN_BULK2 SCONN288_DDR506112002KQ-SCONN288_DDR506112002KQ,SMA   I177 @T6G_MB_LIB.T6G(SCH_1):PAGE92
  C159    1      A Q_CAP_C0805-10UF,25V,10%,X6S,CH6104KEA00   I239 @T6G_MB_LIB.T6G(SCH_1):PAGE92
  C161    1      A Q_CAP_C0805-10UF,25V,10%,X6S,CH6104KEA00   I240 @T6G_MB_LIB.T6G(SCH_1):PAGE92
   J18    1 VIN_BULK0 SCONN288_DDR506112002KQ-SCONN288_DDR506112002KQ,SMA   I143 @T6G_MB_LIB.T6G(SCH_1):PAGE93
   J18  145 VIN_BULK1 SCONN288_DDR506112002KQ-SCONN288_DDR506112002KQ,SMA   I143 @T6G_MB_LIB.T6G(SCH_1):PAGE93
   J18  146 VIN_BULK2 SCONN288_DDR506112002KQ-SCONN288_DDR506112002KQ,SMA   I143 @T6G_MB_LIB.T6G(SCH_1):PAGE93
  C162    1      A Q_CAP_C0805-10UF,25V,10%,X6S,CH6104KEA00   I238 @T6G_MB_LIB.T6G(SCH_1):PAGE93
  C163    1      A Q_CAP_C0805-10UF,25V,10%,X6S,CH6104KEA00   I239 @T6G_MB_LIB.T6G(SCH_1):PAGE93
   J68    1 VIN_BULK0 SCONN288_DDR506112002KQ-SCONN288_DDR506112002KQ,SMA   I177 @T6G_MB_LIB.T6G(SCH_1):PAGE94
   J68  145 VIN_BULK1 SCONN288_DDR506112002KQ-SCONN288_DDR506112002KQ,SMA   I177 @T6G_MB_LIB.T6G(SCH_1):PAGE94
   J68  146 VIN_BULK2 SCONN288_DDR506112002KQ-SCONN288_DDR506112002KQ,SMA   I177 @T6G_MB_LIB.T6G(SCH_1):PAGE94
  C165    1      A Q_CAP_C0805-10UF,25V,10%,X6S,CH6104KEA00   I238 @T6G_MB_LIB.T6G(SCH_1):PAGE94
  C166    1      A Q_CAP_C0805-10UF,25V,10%,X6S,CH6104KEA00   I239 @T6G_MB_LIB.T6G(SCH_1):PAGE94
   J20    1 VIN_BULK0 SCONN288_DDR506112002KQ-SCONN288_DDR506112002KQ,SMA   I177 @T6G_MB_LIB.T6G(SCH_1):PAGE95
   J20  145 VIN_BULK1 SCONN288_DDR506112002KQ-SCONN288_DDR506112002KQ,SMA   I177 @T6G_MB_LIB.T6G(SCH_1):PAGE95
   J20  146 VIN_BULK2 SCONN288_DDR506112002KQ-SCONN288_DDR506112002KQ,SMA   I177 @T6G_MB_LIB.T6G(SCH_1):PAGE95
  C167    1      A Q_CAP_C0805-10UF,25V,10%,X6S,CH6104KEA00   I238 @T6G_MB_LIB.T6G(SCH_1):PAGE95
  C169    1      A Q_CAP_C0805-10UF,25V,10%,X6S,CH6104KEA00   I239 @T6G_MB_LIB.T6G(SCH_1):PAGE95
   J67    1 VIN_BULK0 SCONN288_DDR506112002KQ-SCONN288_DDR506112002KQ,SMA   I140 @T6G_MB_LIB.T6G(SCH_1):PAGE96
   J67  145 VIN_BULK1 SCONN288_DDR506112002KQ-SCONN288_DDR506112002KQ,SMA   I140 @T6G_MB_LIB.T6G(SCH_1):PAGE96
   J67  146 VIN_BULK2 SCONN288_DDR506112002KQ-SCONN288_DDR506112002KQ,SMA   I140 @T6G_MB_LIB.T6G(SCH_1):PAGE96
  C170    1      A Q_CAP_C0805-10UF,25V,10%,X6S,CH6104KEA00   I238 @T6G_MB_LIB.T6G(SCH_1):PAGE96
  C171    1      A Q_CAP_C0805-10UF,25V,10%,X6S,CH6104KEA00   I239 @T6G_MB_LIB.T6G(SCH_1):PAGE96
    J1    1 VIN_BULK0 SCONN288_DDR506112002KQ-SCONN288_DDR506112002KQ,SMA   I538 @T6G_MB_LIB.T6G(SCH_1):PAGE85
    J1  145 VIN_BULK1 SCONN288_DDR506112002KQ-SCONN288_DDR506112002KQ,SMA   I538 @T6G_MB_LIB.T6G(SCH_1):PAGE85
    J1  146 VIN_BULK2 SCONN288_DDR506112002KQ-SCONN288_DDR506112002KQ,SMA   I538 @T6G_MB_LIB.T6G(SCH_1):PAGE85
 R1442    1      A Q_RES_0402LF-100K,1%,1/16W,CHIP,CS41002FB09    I30 @T6G_MB_LIB.T6G(SCH_1):PAGE264
 R1838    2      2 Q_RES_4P_12-0.001,1%,3W,SMLF,CHIP,SP_CS+001DFR10    I58 @T6G_MB_LIB.T6G(SCH_1):PAGE264

P12V_MEM_CPU1 @T6G_MB_LIB.T6G(SCH_1):P12V_MEM_CPU1
   J24    1 VIN_BULK0 SCONN288_DDR506112002KQ-SCONN288_DDR506112002KQ,SMA   I177 @T6G_MB_LIB.T6G(SCH_1):PAGE97
   J24  145 VIN_BULK1 SCONN288_DDR506112002KQ-SCONN288_DDR506112002KQ,SMA   I177 @T6G_MB_LIB.T6G(SCH_1):PAGE97
   J24  146 VIN_BULK2 SCONN288_DDR506112002KQ-SCONN288_DDR506112002KQ,SMA   I177 @T6G_MB_LIB.T6G(SCH_1):PAGE97
  C173    1      A Q_CAP_C0805-10UF,25V,10%,X6S,CH6104KEA00   I240 @T6G_MB_LIB.T6G(SCH_1):PAGE97
  C174    1      A Q_CAP_C0805-10UF,25V,10%,X6S,CH6104KEA00   I241 @T6G_MB_LIB.T6G(SCH_1):PAGE97
   J26    1 VIN_BULK0 SCONN288_DDR506112002KQ-SCONN288_DDR506112002KQ,SMA   I160 @T6G_MB_LIB.T6G(SCH_1):PAGE98
   J26  145 VIN_BULK1 SCONN288_DDR506112002KQ-SCONN288_DDR506112002KQ,SMA   I160 @T6G_MB_LIB.T6G(SCH_1):PAGE98
   J26  146 VIN_BULK2 SCONN288_DDR506112002KQ-SCONN288_DDR506112002KQ,SMA   I160 @T6G_MB_LIB.T6G(SCH_1):PAGE98
  C175    1      A Q_CAP_C0805-10UF,25V,10%,X6S,CH6104KEA00   I238 @T6G_MB_LIB.T6G(SCH_1):PAGE98
  C177    1      A Q_CAP_C0805-10UF,25V,10%,X6S,CH6104KEA00   I239 @T6G_MB_LIB.T6G(SCH_1):PAGE98
   J28    1 VIN_BULK0 SCONN288_DDR506112002KQ-SCONN288_DDR506112002KQ,SMA   I155 @T6G_MB_LIB.T6G(SCH_1):PAGE99
   J28  145 VIN_BULK1 SCONN288_DDR506112002KQ-SCONN288_DDR506112002KQ,SMA   I155 @T6G_MB_LIB.T6G(SCH_1):PAGE99
   J28  146 VIN_BULK2 SCONN288_DDR506112002KQ-SCONN288_DDR506112002KQ,SMA   I155 @T6G_MB_LIB.T6G(SCH_1):PAGE99
  C178    1      A Q_CAP_C0805-10UF,25V,10%,X6S,CH6104KEA00   I238 @T6G_MB_LIB.T6G(SCH_1):PAGE99
  C179    1      A Q_CAP_C0805-10UF,25V,10%,X6S,CH6104KEA00   I239 @T6G_MB_LIB.T6G(SCH_1):PAGE99
   J30    1 VIN_BULK0 SCONN288_DDR506112002KQ-SCONN288_DDR506112002KQ,SMA   I161 @T6G_MB_LIB.T6G(SCH_1):PAGE100
   J30  145 VIN_BULK1 SCONN288_DDR506112002KQ-SCONN288_DDR506112002KQ,SMA   I161 @T6G_MB_LIB.T6G(SCH_1):PAGE100
   J30  146 VIN_BULK2 SCONN288_DDR506112002KQ-SCONN288_DDR506112002KQ,SMA   I161 @T6G_MB_LIB.T6G(SCH_1):PAGE100
  C181    1      A Q_CAP_C0805-10UF,25V,10%,X6S,CH6104KEA00   I238 @T6G_MB_LIB.T6G(SCH_1):PAGE100
  C182    1      A Q_CAP_C0805-10UF,25V,10%,X6S,CH6104KEA00   I239 @T6G_MB_LIB.T6G(SCH_1):PAGE100
   J32    1 VIN_BULK0 SCONN288_DDR506112002KQ-SCONN288_DDR506112002KQ,SMA   I175 @T6G_MB_LIB.T6G(SCH_1):PAGE101
   J32  145 VIN_BULK1 SCONN288_DDR506112002KQ-SCONN288_DDR506112002KQ,SMA   I175 @T6G_MB_LIB.T6G(SCH_1):PAGE101
   J32  146 VIN_BULK2 SCONN288_DDR506112002KQ-SCONN288_DDR506112002KQ,SMA   I175 @T6G_MB_LIB.T6G(SCH_1):PAGE101
  C183    1      A Q_CAP_C0805-10UF,25V,10%,X6S,CH6104KEA00   I238 @T6G_MB_LIB.T6G(SCH_1):PAGE101
  C509    1      A Q_CAP_C0805-10UF,25V,10%,X6S,CH6104KEA00   I239 @T6G_MB_LIB.T6G(SCH_1):PAGE101
   J33    1 VIN_BULK0 SCONN288_DDR506112002KQ-SCONN288_DDR506112002KQ,SMA   I142 @T6G_MB_LIB.T6G(SCH_1):PAGE102
   J33  145 VIN_BULK1 SCONN288_DDR506112002KQ-SCONN288_DDR506112002KQ,SMA   I142 @T6G_MB_LIB.T6G(SCH_1):PAGE102
   J33  146 VIN_BULK2 SCONN288_DDR506112002KQ-SCONN288_DDR506112002KQ,SMA   I142 @T6G_MB_LIB.T6G(SCH_1):PAGE102
  C518    1      A Q_CAP_C0805-10UF,25V,10%,X6S,CH6104KEA00   I238 @T6G_MB_LIB.T6G(SCH_1):PAGE102
  C527    1      A Q_CAP_C0805-10UF,25V,10%,X6S,CH6104KEA00   I239 @T6G_MB_LIB.T6G(SCH_1):PAGE102
  J102    1 VIN_BULK0 SCONN288_DDR506112002KQ-SCONN288_DDR506112002KQ,SMA   I142 @T6G_MB_LIB.T6G(SCH_1):PAGE103
  J102  145 VIN_BULK1 SCONN288_DDR506112002KQ-SCONN288_DDR506112002KQ,SMA   I142 @T6G_MB_LIB.T6G(SCH_1):PAGE103
  J102  146 VIN_BULK2 SCONN288_DDR506112002KQ-SCONN288_DDR506112002KQ,SMA   I142 @T6G_MB_LIB.T6G(SCH_1):PAGE103
  C530    1      A Q_CAP_C0805-10UF,25V,10%,X6S,CH6104KEA00   I240 @T6G_MB_LIB.T6G(SCH_1):PAGE103
  C531    1      A Q_CAP_C0805-10UF,25V,10%,X6S,CH6104KEA00   I241 @T6G_MB_LIB.T6G(SCH_1):PAGE103
   J27    1 VIN_BULK0 SCONN288_DDR506112002KQ-SCONN288_DDR506112002KQ,SMA   I174 @T6G_MB_LIB.T6G(SCH_1):PAGE104
   J27  145 VIN_BULK1 SCONN288_DDR506112002KQ-SCONN288_DDR506112002KQ,SMA   I174 @T6G_MB_LIB.T6G(SCH_1):PAGE104
   J27  146 VIN_BULK2 SCONN288_DDR506112002KQ-SCONN288_DDR506112002KQ,SMA   I174 @T6G_MB_LIB.T6G(SCH_1):PAGE104
  C532    1      A Q_CAP_C0805-10UF,25V,10%,X6S,CH6104KEA00   I240 @T6G_MB_LIB.T6G(SCH_1):PAGE104
  C533    1      A Q_CAP_C0805-10UF,25V,10%,X6S,CH6104KEA00   I241 @T6G_MB_LIB.T6G(SCH_1):PAGE104
  J100    1 VIN_BULK0 SCONN288_DDR506112002KQ-SCONN288_DDR506112002KQ,SMA   I176 @T6G_MB_LIB.T6G(SCH_1):PAGE105
  J100  145 VIN_BULK1 SCONN288_DDR506112002KQ-SCONN288_DDR506112002KQ,SMA   I176 @T6G_MB_LIB.T6G(SCH_1):PAGE105
  J100  146 VIN_BULK2 SCONN288_DDR506112002KQ-SCONN288_DDR506112002KQ,SMA   I176 @T6G_MB_LIB.T6G(SCH_1):PAGE105
  C534    1      A Q_CAP_C0805-10UF,25V,10%,X6S,CH6104KEA00   I238 @T6G_MB_LIB.T6G(SCH_1):PAGE105
  C535    1      A Q_CAP_C0805-10UF,25V,10%,X6S,CH6104KEA00   I239 @T6G_MB_LIB.T6G(SCH_1):PAGE105
   J29    1 VIN_BULK0 SCONN288_DDR506112002KQ-SCONN288_DDR506112002KQ,SMA   I143 @T6G_MB_LIB.T6G(SCH_1):PAGE106
   J29  145 VIN_BULK1 SCONN288_DDR506112002KQ-SCONN288_DDR506112002KQ,SMA   I143 @T6G_MB_LIB.T6G(SCH_1):PAGE106
   J29  146 VIN_BULK2 SCONN288_DDR506112002KQ-SCONN288_DDR506112002KQ,SMA   I143 @T6G_MB_LIB.T6G(SCH_1):PAGE106
  C536    1      A Q_CAP_C0805-10UF,25V,10%,X6S,CH6104KEA00   I238 @T6G_MB_LIB.T6G(SCH_1):PAGE106
  C537    1      A Q_CAP_C0805-10UF,25V,10%,X6S,CH6104KEA00   I239 @T6G_MB_LIB.T6G(SCH_1):PAGE106
   J99    1 VIN_BULK0 SCONN288_DDR506112002KQ-SCONN288_DDR506112002KQ,SMA   I139 @T6G_MB_LIB.T6G(SCH_1):PAGE107
   J99  145 VIN_BULK1 SCONN288_DDR506112002KQ-SCONN288_DDR506112002KQ,SMA   I139 @T6G_MB_LIB.T6G(SCH_1):PAGE107
   J99  146 VIN_BULK2 SCONN288_DDR506112002KQ-SCONN288_DDR506112002KQ,SMA   I139 @T6G_MB_LIB.T6G(SCH_1):PAGE107
  C546    1      A Q_CAP_C0805-10UF,25V,10%,X6S,CH6104KEA00   I237 @T6G_MB_LIB.T6G(SCH_1):PAGE107
  C547    1      A Q_CAP_C0805-10UF,25V,10%,X6S,CH6104KEA00   I238 @T6G_MB_LIB.T6G(SCH_1):PAGE107
   J37    1 VIN_BULK0 SCONN288_DDR506112002KQ-SCONN288_DDR506112002KQ,SMA   I138 @T6G_MB_LIB.T6G(SCH_1):PAGE108
   J37  145 VIN_BULK1 SCONN288_DDR506112002KQ-SCONN288_DDR506112002KQ,SMA   I138 @T6G_MB_LIB.T6G(SCH_1):PAGE108
   J37  146 VIN_BULK2 SCONN288_DDR506112002KQ-SCONN288_DDR506112002KQ,SMA   I138 @T6G_MB_LIB.T6G(SCH_1):PAGE108
  C548    1      A Q_CAP_C0805-10UF,25V,10%,X6S,CH6104KEA00   I237 @T6G_MB_LIB.T6G(SCH_1):PAGE108
  C549    1      A Q_CAP_C0805-10UF,25V,10%,X6S,CH6104KEA00   I238 @T6G_MB_LIB.T6G(SCH_1):PAGE108
 R1440    1      A Q_RES_0402LF-100K,1%,1/16W,CHIP,CS41002FB09    I25 @T6G_MB_LIB.T6G(SCH_1):PAGE264
 R1837    2      2 Q_RES_4P_12-0.001,1%,3W,SMLF,CHIP,SP_CS+001DFR10    I54 @T6G_MB_LIB.T6G(SCH_1):PAGE264

P12V_OCP_1_EN_G @T6G_MB_LIB.T6G(SCH_1):P12V_OCP_1_EN_G
  Q123    6     D1 MOSFET_NCH_DUAL-PJT138K,SMLF,IC,BAM138K0003    I11 @T6G_MB_LIB.T6G(SCH_1):PAGE338
 R4068    2      B Q_RES_0402LF-10K,1%,1/16W,CHIP,CS31002FB08    I17 @T6G_MB_LIB.T6G(SCH_1):PAGE338
  Q123    5     G2 MOSFET_NCH_DUAL-PJT138K,SMLF,IC,BAM138K0003    I19 @T6G_MB_LIB.T6G(SCH_1):PAGE338

P12V_OCP_2_EN_G @T6G_MB_LIB.T6G(SCH_1):P12V_OCP_2_EN_G
  Q118    6     D1 MOSFET_NCH_DUAL-PJT138K,SMLF,IC,BAM138K0003    I10 @T6G_MB_LIB.T6G(SCH_1):PAGE343
  Q118    5     G2 MOSFET_NCH_DUAL-PJT138K,SMLF,IC,BAM138K0003    I19 @T6G_MB_LIB.T6G(SCH_1):PAGE343
 R4065    2      B Q_RES_0402LF-10K,1%,1/16W,CHIP,CS31002FB08    I17 @T6G_MB_LIB.T6G(SCH_1):PAGE343

P12V_OCP_AVIN_PD_1 @T6G_MB_LIB.T6G(SCH_1):P12V_OCP_AVIN_PD_1
PR3838    2      B Q_RES_0402LF-100,1%,1/16W,EMPTY,CS11002FB07    I76 @T6G_MB_LIB.T6G(SCH_1):PAGE339
PC2158    1      A Q_CAP_C0603-2.2UF,16V,20%,X7R,CH5223M1900    I86 @T6G_MB_LIB.T6G(SCH_1):PAGE339
PR3843    2      B Q_RES_0603LF-49.9,1%,1/10W,CHIP,CS04993F909    I88 @T6G_MB_LIB.T6G(SCH_1):PAGE339
 PU204   12   AVIN RS31312R-RS31312R,SMLF,IC,AL031312000   I137 @T6G_MB_LIB.T6G(SCH_1):PAGE339

P12V_OCP_AVIN_PD_2 @T6G_MB_LIB.T6G(SCH_1):P12V_OCP_AVIN_PD_2
PC1320    1      A Q_CAP_C0603-2.2UF,16V,20%,X7R,CH5223M1900    I24 @T6G_MB_LIB.T6G(SCH_1):PAGE344
PR3850    2      B Q_RES_0402LF-100,1%,1/16W,EMPTY,CS11002FB07    I30 @T6G_MB_LIB.T6G(SCH_1):PAGE344
PR3857    2      B Q_RES_0603LF-49.9,1%,1/10W,CHIP,CS04993F909    I37 @T6G_MB_LIB.T6G(SCH_1):PAGE344
 PU206   12   AVIN RS31312R-RS31312R,SMLF,IC,AL031312000    I82 @T6G_MB_LIB.T6G(SCH_1):PAGE344

P12V_OCP_CB_1 @T6G_MB_LIB.T6G(SCH_1):P12V_OCP_CB_1
PR5484    1      A Q_RES_0402LF-30.1K,1%,1/16W,CHIP,CS33012FB03    I48 @T6G_MB_LIB.T6G(SCH_1):PAGE338
 PU203   B1     CB MAX15090BEWIT-MAX15090BEWI+T,SMLF,IC,AL015080B00    I50 @T6G_MB_LIB.T6G(SCH_1):PAGE338

P12V_OCP_CB_2 @T6G_MB_LIB.T6G(SCH_1):P12V_OCP_CB_2
PR3821    1      A Q_RES_0402LF-30.1K,1%,1/16W,CHIP,CS33012FB03    I63 @T6G_MB_LIB.T6G(SCH_1):PAGE343
 PU201   B1     CB MAX15090BEWIT-MAX15090BEWI+T,SMLF,IC,AL015080B00    I67 @T6G_MB_LIB.T6G(SCH_1):PAGE343

P12V_OCP_EN_1_R @T6G_MB_LIB.T6G(SCH_1):P12V_OCP_EN_1_R
  Q123    2     G1 MOSFET_NCH_DUAL-PJT138K,SMLF,IC,BAM138K0003    I11 @T6G_MB_LIB.T6G(SCH_1):PAGE338
 R4061    2      B Q_RES_0402LF-0,5%,1/16W,EMPTY,CS00002JB13   I123 @T6G_MB_LIB.T6G(SCH_1):PAGE338
  R561    2      B Q_RES_0402LF-0,5%,1/16W,CHIP,CS00002JB13   I125 @T6G_MB_LIB.T6G(SCH_1):PAGE338
 R6045    1      A Q_RES_0402LF-4.7K,5%,1/16W,EMPTY,CS24702JB10   I130 @T6G_MB_LIB.T6G(SCH_1):PAGE338

P12V_OCP_EN_1_R2 @T6G_MB_LIB.T6G(SCH_1):P12V_OCP_EN_1_R2
 R3834    2      B Q_RES_0402LF-0,5%,1/16W,EMPTY,CS00002JB13   I128 @T6G_MB_LIB.T6G(SCH_1):PAGE339
  R591    2      B Q_RES_0402LF-0,5%,1/16W,CHIP,CS00002JB13   I130 @T6G_MB_LIB.T6G(SCH_1):PAGE339
 PU204    1     EN RS31312R-RS31312R,SMLF,IC,AL031312000   I137 @T6G_MB_LIB.T6G(SCH_1):PAGE339

P12V_OCP_EN_2_R @T6G_MB_LIB.T6G(SCH_1):P12V_OCP_EN_2_R
  Q118    2     G1 MOSFET_NCH_DUAL-PJT138K,SMLF,IC,BAM138K0003    I10 @T6G_MB_LIB.T6G(SCH_1):PAGE343
 R4059    2      B Q_RES_0402LF-0,5%,1/16W,EMPTY,CS00002JB13   I119 @T6G_MB_LIB.T6G(SCH_1):PAGE343
 R6060    1      A Q_RES_0402LF-4.7K,5%,1/16W,EMPTY,CS24702JB10   I120 @T6G_MB_LIB.T6G(SCH_1):PAGE343
 R1181    2      B Q_RES_0402LF-0,5%,1/16W,CHIP,CS00002JB13   I123 @T6G_MB_LIB.T6G(SCH_1):PAGE343

P12V_OCP_FAULT_1 @T6G_MB_LIB.T6G(SCH_1):P12V_OCP_FAULT_1
 PU203   C7 FAULT# MAX15090BEWIT-MAX15090BEWI+T,SMLF,IC,AL015080B00    I50 @T6G_MB_LIB.T6G(SCH_1):PAGE338
 R3799    2      B Q_RES_0402LF-100K,1%,1/16W,CHIP,CS41002FB09    I83 @T6G_MB_LIB.T6G(SCH_1):PAGE338

P12V_OCP_FAULT_2 @T6G_MB_LIB.T6G(SCH_1):P12V_OCP_FAULT_2
 PU201   C7 FAULT# MAX15090BEWIT-MAX15090BEWI+T,SMLF,IC,AL015080B00    I67 @T6G_MB_LIB.T6G(SCH_1):PAGE343
 R3816    2      B Q_RES_0402LF-100K,1%,1/16W,CHIP,CS41002FB09    I79 @T6G_MB_LIB.T6G(SCH_1):PAGE343

P12V_OCP_FLTB_1 @T6G_MB_LIB.T6G(SCH_1):P12V_OCP_FLTB_1
PR3839    1      A Q_RES_0402LF-10K,1%,1/16W,CHIP,CS31002FB08    I74 @T6G_MB_LIB.T6G(SCH_1):PAGE339
 PU204    9   FLTB RS31312R-RS31312R,SMLF,IC,AL031312000   I137 @T6G_MB_LIB.T6G(SCH_1):PAGE339

P12V_OCP_FLTB_2 @T6G_MB_LIB.T6G(SCH_1):P12V_OCP_FLTB_2
PR3851    1      A Q_RES_0402LF-10K,1%,1/16W,CHIP,CS31002FB08    I18 @T6G_MB_LIB.T6G(SCH_1):PAGE344
 PU206    9   FLTB RS31312R-RS31312R,SMLF,IC,AL031312000    I82 @T6G_MB_LIB.T6G(SCH_1):PAGE344

P12V_OCP_GATE_1 @T6G_MB_LIB.T6G(SCH_1):P12V_OCP_GATE_1
 PU203   A6   GATE MAX15090BEWIT-MAX15090BEWI+T,SMLF,IC,AL015080B00    I50 @T6G_MB_LIB.T6G(SCH_1):PAGE338
PC2088    2      B Q_CAP_C0402-0.01UF,50V,10%,EMPTY,CH31006KB18    I74 @T6G_MB_LIB.T6G(SCH_1):PAGE338
PR4524    2      B Q_RES_0402LF-10M,1%,1/16W,CHIP,CS61002FB02    I76 @T6G_MB_LIB.T6G(SCH_1):PAGE338
PC4056    1      A Q_CAP_C0402-3900PF,50V,10%,X7R,CH23906KB14    I77 @T6G_MB_LIB.T6G(SCH_1):PAGE338

P12V_OCP_GATE_2 @T6G_MB_LIB.T6G(SCH_1):P12V_OCP_GATE_2
 PU201   A6   GATE MAX15090BEWIT-MAX15090BEWI+T,SMLF,IC,AL015080B00    I67 @T6G_MB_LIB.T6G(SCH_1):PAGE343
   C40    2      B Q_CAP_C0402-0.01UF,50V,10%,EMPTY,CH31006KB18    I72 @T6G_MB_LIB.T6G(SCH_1):PAGE343
PC2150    1      A Q_CAP_C0402-3900PF,50V,10%,X7R,CH23906KB14    I75 @T6G_MB_LIB.T6G(SCH_1):PAGE343
PR4522    2      B Q_RES_0402LF-10M,1%,1/16W,CHIP,CS61002FB02    I76 @T6G_MB_LIB.T6G(SCH_1):PAGE343

P12V_OCP_IMON_1 @T6G_MB_LIB.T6G(SCH_1):P12V_OCP_IMON_1
PR3837    1      A Q_RES_0402LF-17.4K,1%,1/16W,CHIP,CS31742FB04    I71 @T6G_MB_LIB.T6G(SCH_1):PAGE339
PC2156    1      A Q_CAP_C0402-100NF,50V,10%,X7R,CH4106K1B01    I73 @T6G_MB_LIB.T6G(SCH_1):PAGE339
 R3872    1      A Q_RES_0402LF-0,5%,1/16W,EMPTY,CS00002JB13    I84 @T6G_MB_LIB.T6G(SCH_1):PAGE339
 R3871    1      A Q_RES_0402LF-0,5%,1/16W,CHIP,CS00002JB13    I85 @T6G_MB_LIB.T6G(SCH_1):PAGE339
 PU204    8   IMON RS31312R-RS31312R,SMLF,IC,AL031312000   I137 @T6G_MB_LIB.T6G(SCH_1):PAGE339

P12V_OCP_IMON_2 @T6G_MB_LIB.T6G(SCH_1):P12V_OCP_IMON_2
PR3849    1      A Q_RES_0402LF-17.4K,1%,1/16W,CHIP,CS31742FB04    I15 @T6G_MB_LIB.T6G(SCH_1):PAGE344
 R3874    1      A Q_RES_0402LF-0,5%,1/16W,EMPTY,CS00002JB13    I22 @T6G_MB_LIB.T6G(SCH_1):PAGE344
 R3873    1      A Q_RES_0402LF-0,5%,1/16W,CHIP,CS00002JB13    I23 @T6G_MB_LIB.T6G(SCH_1):PAGE344
PC2167    1      A Q_CAP_0402-100PF,50V,5%,NPO,CH11006JB00    I58 @T6G_MB_LIB.T6G(SCH_1):PAGE344
 PU206    8   IMON RS31312R-RS31312R,SMLF,IC,AL031312000    I82 @T6G_MB_LIB.T6G(SCH_1):PAGE344

P12V_OCP_ISET_1 @T6G_MB_LIB.T6G(SCH_1):P12V_OCP_ISET_1
PR3835    1      A Q_RES_0402LF-14.3K,1%,1/16W,CHIP,CS31432FB02    I63 @T6G_MB_LIB.T6G(SCH_1):PAGE339
 PU204    5   ISET RS31312R-RS31312R,SMLF,IC,AL031312000   I137 @T6G_MB_LIB.T6G(SCH_1):PAGE339

P12V_OCP_ISET_2 @T6G_MB_LIB.T6G(SCH_1):P12V_OCP_ISET_2
PR3847    1      A Q_RES_0402LF-14.3K,1%,1/16W,CHIP,CS31432FB02     I4 @T6G_MB_LIB.T6G(SCH_1):PAGE344
 PU206    5   ISET RS31312R-RS31312R,SMLF,IC,AL031312000    I82 @T6G_MB_LIB.T6G(SCH_1):PAGE344

P12V_OCP_OV_1 @T6G_MB_LIB.T6G(SCH_1):P12V_OCP_OV_1
PR3788    1      A Q_RES_0402LF-15K,1%,1/16W,CHIP,CS31502FB05    I36 @T6G_MB_LIB.T6G(SCH_1):PAGE338
PR3787    2      B Q_RES_0402LF-6.8K,1%,1/16W,CHIP,CS26802FB02    I42 @T6G_MB_LIB.T6G(SCH_1):PAGE338
 PU203   D3     OV MAX15090BEWIT-MAX15090BEWI+T,SMLF,IC,AL015080B00    I50 @T6G_MB_LIB.T6G(SCH_1):PAGE338

P12V_OCP_OV_2 @T6G_MB_LIB.T6G(SCH_1):P12V_OCP_OV_2
PR3806    2      B Q_RES_0402LF-6.8K,1%,1/16W,CHIP,CS26802FB02    I35 @T6G_MB_LIB.T6G(SCH_1):PAGE343
 PU201   D3     OV MAX15090BEWIT-MAX15090BEWI+T,SMLF,IC,AL015080B00    I67 @T6G_MB_LIB.T6G(SCH_1):PAGE343
PR3828    1      A Q_RES_0402LF-15K,1%,1/16W,CHIP,CS31502FB05    I31 @T6G_MB_LIB.T6G(SCH_1):PAGE343

P12V_OCP_OV_FB_1 @T6G_MB_LIB.T6G(SCH_1):P12V_OCP_OV_FB_1
PR3842    1      A Q_RES_0402LF-10K,1%,1/16W,CHIP,CS31002FB08    I80 @T6G_MB_LIB.T6G(SCH_1):PAGE339
PR3840    2      B Q_RES_0402LF-71.5K,1%,1/16W,EMPTY,CS37152FB05    I81 @T6G_MB_LIB.T6G(SCH_1):PAGE339
PR3841    2      B Q_RES_0402LF-120K,1%,1/16W,CHIP,CS41202FB05    I82 @T6G_MB_LIB.T6G(SCH_1):PAGE339
 PU204   11     OV RS31312R-RS31312R,SMLF,IC,AL031312000   I137 @T6G_MB_LIB.T6G(SCH_1):PAGE339

P12V_OCP_OV_FB_2 @T6G_MB_LIB.T6G(SCH_1):P12V_OCP_OV_FB_2
PR3854    1      A Q_RES_0402LF-10K,1%,1/16W,CHIP,CS31002FB08    I20 @T6G_MB_LIB.T6G(SCH_1):PAGE344
PR3852    2      B Q_RES_0402LF-71.5K,1%,1/16W,EMPTY,CS37152FB05    I31 @T6G_MB_LIB.T6G(SCH_1):PAGE344
PR3853    2      B Q_RES_0402LF-120K,1%,1/16W,CHIP,CS41202FB05    I36 @T6G_MB_LIB.T6G(SCH_1):PAGE344
 PU206   11     OV RS31312R-RS31312R,SMLF,IC,AL031312000    I82 @T6G_MB_LIB.T6G(SCH_1):PAGE344

P12V_OCP_PWRGD_1 @T6G_MB_LIB.T6G(SCH_1):P12V_OCP_PWRGD_1
 PU203   D7     PG MAX15090BEWIT-MAX15090BEWI+T,SMLF,IC,AL015080B00    I50 @T6G_MB_LIB.T6G(SCH_1):PAGE338
 R3144    1      A Q_RES_0402LF-0,5%,1/16W,CHIP,CS00002JB13    I75 @T6G_MB_LIB.T6G(SCH_1):PAGE338

P12V_OCP_PWRGD_2 @T6G_MB_LIB.T6G(SCH_1):P12V_OCP_PWRGD_2
 PU201   D7     PG MAX15090BEWIT-MAX15090BEWI+T,SMLF,IC,AL015080B00    I67 @T6G_MB_LIB.T6G(SCH_1):PAGE343
 R3831    1      A Q_RES_0402LF-0,5%,1/16W,CHIP,CS00002JB13    I77 @T6G_MB_LIB.T6G(SCH_1):PAGE343

P12V_OCP_REG_1 @T6G_MB_LIB.T6G(SCH_1):P12V_OCP_REG_1
 PU203   D1    REG MAX15090BEWIT-MAX15090BEWI+T,SMLF,IC,AL015080B00    I50 @T6G_MB_LIB.T6G(SCH_1):PAGE338
PC2087    2      B Q_CAP_C0402-1UF,25V,10%,X6S,CH5104KEB02    I54 @T6G_MB_LIB.T6G(SCH_1):PAGE338

P12V_OCP_REG_2 @T6G_MB_LIB.T6G(SCH_1):P12V_OCP_REG_2
PC2146    2      B Q_CAP_C0402-1UF,25V,10%,X6S,CH5104KEB02    I66 @T6G_MB_LIB.T6G(SCH_1):PAGE343
 PU201   D1    REG MAX15090BEWIT-MAX15090BEWI+T,SMLF,IC,AL015080B00    I67 @T6G_MB_LIB.T6G(SCH_1):PAGE343

P12V_OCP_SENSE_1 @T6G_MB_LIB.T6G(SCH_1):P12V_OCP_SENSE_1
 PU203   A1 ISENSE MAX15090BEWIT-MAX15090BEWI+T,SMLF,IC,AL015080B00    I50 @T6G_MB_LIB.T6G(SCH_1):PAGE338
PR3781    1      A Q_RES_0402LF-845,1%,1/16W,CHIP,CS18452FB01    I73 @T6G_MB_LIB.T6G(SCH_1):PAGE338
 R3870    1      A Q_RES_0402LF-0,5%,1/16W,CHIP,CS00002JB13    I80 @T6G_MB_LIB.T6G(SCH_1):PAGE338
 R3869    1      A Q_RES_0402LF-0,5%,1/16W,EMPTY,CS00002JB13    I82 @T6G_MB_LIB.T6G(SCH_1):PAGE338

P12V_OCP_SENSE_2 @T6G_MB_LIB.T6G(SCH_1):P12V_OCP_SENSE_2
 PU201   A1 ISENSE MAX15090BEWIT-MAX15090BEWI+T,SMLF,IC,AL015080B00    I67 @T6G_MB_LIB.T6G(SCH_1):PAGE343
PR3823    1      A Q_RES_0402LF-845,1%,1/16W,CHIP,CS18452FB01    I71 @T6G_MB_LIB.T6G(SCH_1):PAGE343
 R3868    1      A Q_RES_0402LF-0,5%,1/16W,CHIP,CS00002JB13    I73 @T6G_MB_LIB.T6G(SCH_1):PAGE343
 R3867    1      A Q_RES_0402LF-0,5%,1/16W,EMPTY,CS00002JB13    I74 @T6G_MB_LIB.T6G(SCH_1):PAGE343

P12V_OCP_SFF @T6G_MB_LIB.T6G(SCH_1):P12V_OCP_SFF
 PU203   A4 OUT_A4 MAX15090BEWIT-MAX15090BEWI+T,SMLF,IC,AL015080B00    I50 @T6G_MB_LIB.T6G(SCH_1):PAGE338
 PU203   B4 OUT_B4 MAX15090BEWIT-MAX15090BEWI+T,SMLF,IC,AL015080B00    I50 @T6G_MB_LIB.T6G(SCH_1):PAGE338
 PU203   B6 OUT_B6 MAX15090BEWIT-MAX15090BEWI+T,SMLF,IC,AL015080B00    I50 @T6G_MB_LIB.T6G(SCH_1):PAGE338
 PU203   C4 OUT_C4 MAX15090BEWIT-MAX15090BEWI+T,SMLF,IC,AL015080B00    I50 @T6G_MB_LIB.T6G(SCH_1):PAGE338
 PU203   C6 OUT_C6 MAX15090BEWIT-MAX15090BEWI+T,SMLF,IC,AL015080B00    I50 @T6G_MB_LIB.T6G(SCH_1):PAGE338
 PU203   D4 OUT_D4 MAX15090BEWIT-MAX15090BEWI+T,SMLF,IC,AL015080B00    I50 @T6G_MB_LIB.T6G(SCH_1):PAGE338
 PU203   D6 OUT_D6 MAX15090BEWIT-MAX15090BEWI+T,SMLF,IC,AL015080B00    I50 @T6G_MB_LIB.T6G(SCH_1):PAGE338
PC2088    1      A Q_CAP_C0402-0.01UF,50V,10%,EMPTY,CH31006KB18    I74 @T6G_MB_LIB.T6G(SCH_1):PAGE338
PR4524    1      A Q_RES_0402LF-10M,1%,1/16W,CHIP,CS61002FB02    I76 @T6G_MB_LIB.T6G(SCH_1):PAGE338
 PD102    C      C SCHOTTKY_AC-B340A-13-F,SMLF,IC,BC000340Z30    I79 @T6G_MB_LIB.T6G(SCH_1):PAGE338
PC2092    1      A Q_CAP_0402-0.1UF,25V,10%,X7R,CH4104K1B00    I86 @T6G_MB_LIB.T6G(SCH_1):PAGE338
PC2080    1      A Q_CAP_C0805-22UF,16V,20%,X6S,CH6223MEA01    I87 @T6G_MB_LIB.T6G(SCH_1):PAGE338
PC2082    1      A Q_CAP_C0805-10UF,16V,10%,X6S,CH6103KEA01    I89 @T6G_MB_LIB.T6G(SCH_1):PAGE338
PR3838    1      A Q_RES_0402LF-100,1%,1/16W,EMPTY,CS11002FB07    I76 @T6G_MB_LIB.T6G(SCH_1):PAGE339
PR3840    1      A Q_RES_0402LF-71.5K,1%,1/16W,EMPTY,CS37152FB05    I81 @T6G_MB_LIB.T6G(SCH_1):PAGE339
PC2160    1      A Q_CAP_0402-0.1UF,25V,10%,X7R,CH4104K1B00    I91 @T6G_MB_LIB.T6G(SCH_1):PAGE339
 R1324    2      B Q_RES_2512LF-0.002,1%,2W,CHIP,CS+002AFR06     I2 @T6G_MB_LIB.T6G(SCH_1):PAGE466
 C1108    1      A Q_CAP_0402-0.1UF,25V,10%,X7R,CH4104K1B00     I5 @T6G_MB_LIB.T6G(SCH_1):PAGE466
 R1284    1      A Q_RES_0402LF-10,1%,1/16W,CHIP,CS01002FB07    I10 @T6G_MB_LIB.T6G(SCH_1):PAGE466
   U55   11   VBUS ISL28022FRZT-ISL28022FRZ-T,SMLF,IC,AL028022003    I28 @T6G_MB_LIB.T6G(SCH_1):PAGE466
 PU204   13 VOUT_13 RS31312R-RS31312R,SMLF,IC,AL031312000   I137 @T6G_MB_LIB.T6G(SCH_1):PAGE339
 PU204   14 VOUT_14 RS31312R-RS31312R,SMLF,IC,AL031312000   I137 @T6G_MB_LIB.T6G(SCH_1):PAGE339
 PU204   15 VOUT_15 RS31312R-RS31312R,SMLF,IC,AL031312000   I137 @T6G_MB_LIB.T6G(SCH_1):PAGE339
 PU204   16 VOUT_16 RS31312R-RS31312R,SMLF,IC,AL031312000   I137 @T6G_MB_LIB.T6G(SCH_1):PAGE339
 PU204   17 VOUT_17 RS31312R-RS31312R,SMLF,IC,AL031312000   I137 @T6G_MB_LIB.T6G(SCH_1):PAGE339
 PU204   18 VOUT_18 RS31312R-RS31312R,SMLF,IC,AL031312000   I137 @T6G_MB_LIB.T6G(SCH_1):PAGE339
 PU204   19 VOUT_19 RS31312R-RS31312R,SMLF,IC,AL031312000   I137 @T6G_MB_LIB.T6G(SCH_1):PAGE339
 PU204   20 VOUT_20 RS31312R-RS31312R,SMLF,IC,AL031312000   I137 @T6G_MB_LIB.T6G(SCH_1):PAGE339

P12V_OCP_SFF_ADC_ALERT_R @T6G_MB_LIB.T6G(SCH_1):P12V_OCP_SFF_ADC_ALERT_R
 R1270    1      A Q_RES_0402LF-0,5%,1/16W,CHIP,CS00002JB13    I23 @T6G_MB_LIB.T6G(SCH_1):PAGE466
   U55    3 EXT_CLK||INT ISL28022FRZT-ISL28022FRZ-T,SMLF,IC,AL028022003    I28 @T6G_MB_LIB.T6G(SCH_1):PAGE466

P12V_OCP_SFF_BUF_EN @T6G_MB_LIB.T6G(SCH_1):P12V_OCP_SFF_BUF_EN
   U23    4      Y 74LVC1G08W57-74LVC1G08W5-7,SMLF,IC,AL1G0008020    I36 @T6G_MB_LIB.T6G(SCH_1):PAGE340
 R1134    1      A Q_RES_0402LF-0,5%,1/16W,CHIP,CS00002JB13    I47 @T6G_MB_LIB.T6G(SCH_1):PAGE340

P12V_OCP_SFF_BUF_EN_R @T6G_MB_LIB.T6G(SCH_1):P12V_OCP_SFF_BUF_EN_R
 R1134    2      B Q_RES_0402LF-0,5%,1/16W,CHIP,CS00002JB13    I47 @T6G_MB_LIB.T6G(SCH_1):PAGE340
  R561    1      A Q_RES_0402LF-0,5%,1/16W,CHIP,CS00002JB13   I125 @T6G_MB_LIB.T6G(SCH_1):PAGE338
  R591    1      A Q_RES_0402LF-0,5%,1/16W,CHIP,CS00002JB13   I130 @T6G_MB_LIB.T6G(SCH_1):PAGE339
 R1500    2      B Q_RES_0402LF-0,5%,1/16W,CHIP,CS00002JB13    I43 @T6G_MB_LIB.T6G(SCH_1):PAGE248
 R1486    1      A Q_RES_0402LF-0,5%,1/16W,CHIP,CS00002JB13   I135 @T6G_MB_LIB.T6G(SCH_1):PAGE338
 R1487    1      A Q_RES_0402LF-0,5%,1/16W,CHIP,CS00002JB13   I134 @T6G_MB_LIB.T6G(SCH_1):PAGE339

P12V_OCP_SFF_EN @T6G_MB_LIB.T6G(SCH_1):P12V_OCP_SFF_EN
   U18   F9  PT21C LCMXO3LF9400C5BG484C-LCMXO3LF-9400C-5BG484C,SMLF,IA    I94 @T6G_MB_LIB.T6G(SCH_1):PAGE79
  R152    1      A Q_RES_0402LF-33,5%,1/16W,CHIP,CS03302JB10   I153 @T6G_MB_LIB.T6G(SCH_1):PAGE79

P12V_OCP_SFF_EN_R @T6G_MB_LIB.T6G(SCH_1):P12V_OCP_SFF_EN_R
 R1195    1      A Q_RES_0402LF-4.7K,5%,1/16W,EMPTY,CS24702JB10    I36 @T6G_MB_LIB.T6G(SCH_1):PAGE82
  R152    2      B Q_RES_0402LF-33,5%,1/16W,CHIP,CS03302JB10   I153 @T6G_MB_LIB.T6G(SCH_1):PAGE79
 R4061    1      A Q_RES_0402LF-0,5%,1/16W,EMPTY,CS00002JB13   I123 @T6G_MB_LIB.T6G(SCH_1):PAGE338
 R3834    1      A Q_RES_0402LF-0,5%,1/16W,EMPTY,CS00002JB13   I128 @T6G_MB_LIB.T6G(SCH_1):PAGE339
 R1130    1      A Q_RES_0402LF-0,5%,1/16W,EMPTY,CS00002JB13    I49 @T6G_MB_LIB.T6G(SCH_1):PAGE340

P12V_OCP_SFF_EN_R3 @T6G_MB_LIB.T6G(SCH_1):P12V_OCP_SFF_EN_R3
   U23    1      A 74LVC1G08W57-74LVC1G08W5-7,SMLF,IC,AL1G0008020    I36 @T6G_MB_LIB.T6G(SCH_1):PAGE340
 R1131    2      B Q_RES_0402LF-1K,1%,1/16W,CHIP,CS21002FB06    I44 @T6G_MB_LIB.T6G(SCH_1):PAGE340
 R1130    2      B Q_RES_0402LF-0,5%,1/16W,EMPTY,CS00002JB13    I49 @T6G_MB_LIB.T6G(SCH_1):PAGE340

P12V_OCP_SFF_ISENSE_MAM @T6G_MB_LIB.T6G(SCH_1):P12V_OCP_SFF_ISENSE_MAM
 R3864    2      B Q_RES_0402LF-0,5%,1/16W,EMPTY,CS00002JB13   I110 @T6G_MB_LIB.T6G(SCH_1):PAGE369
 C2176    1      A Q_CAP_0402-100PF,50V,5%,EMPTY,CH11006JB18   I114 @T6G_MB_LIB.T6G(SCH_1):PAGE369
 R3863    2      B Q_RES_0402LF-0,5%,1/16W,EMPTY,CS00002JB13   I115 @T6G_MB_LIB.T6G(SCH_1):PAGE369
  U193    6   AIN1 MAX11617EEET-MAX11617EEE+T,SMLF,EMPTY,AL011617W00   I169 @T6G_MB_LIB.T6G(SCH_1):PAGE369

P12V_OCP_SFF_ISENSE_MAM_MAM @T6G_MB_LIB.T6G(SCH_1):P12V_OCP_SFF_ISENSE_MAM_MAM
 R3869    2      B Q_RES_0402LF-0,5%,1/16W,EMPTY,CS00002JB13    I82 @T6G_MB_LIB.T6G(SCH_1):PAGE338
 R3863    1      A Q_RES_0402LF-0,5%,1/16W,EMPTY,CS00002JB13   I115 @T6G_MB_LIB.T6G(SCH_1):PAGE369

P12V_OCP_SFF_ISENSE_MAM_TIC @T6G_MB_LIB.T6G(SCH_1):P12V_OCP_SFF_ISENSE_MAM_TIC
 R3870    2      B Q_RES_0402LF-0,5%,1/16W,CHIP,CS00002JB13    I80 @T6G_MB_LIB.T6G(SCH_1):PAGE338
 R3865    1      A Q_RES_0402LF-0,5%,1/16W,CHIP,CS00002JB13   I109 @T6G_MB_LIB.T6G(SCH_1):PAGE369

P12V_OCP_SFF_ISENSE_MPS_MAM @T6G_MB_LIB.T6G(SCH_1):P12V_OCP_SFF_ISENSE_MPS_MAM
 R3871    2      B Q_RES_0402LF-0,5%,1/16W,CHIP,CS00002JB13    I85 @T6G_MB_LIB.T6G(SCH_1):PAGE339
 R3864    1      A Q_RES_0402LF-0,5%,1/16W,EMPTY,CS00002JB13   I110 @T6G_MB_LIB.T6G(SCH_1):PAGE369

P12V_OCP_SFF_ISENSE_MPS_TIC @T6G_MB_LIB.T6G(SCH_1):P12V_OCP_SFF_ISENSE_MPS_TIC
 R3872    2      B Q_RES_0402LF-0,5%,1/16W,EMPTY,CS00002JB13    I84 @T6G_MB_LIB.T6G(SCH_1):PAGE339
 R3866    1      A Q_RES_0402LF-0,5%,1/16W,EMPTY,CS00002JB13   I108 @T6G_MB_LIB.T6G(SCH_1):PAGE369

P12V_OCP_SFF_ISENSE_TIC @T6G_MB_LIB.T6G(SCH_1):P12V_OCP_SFF_ISENSE_TIC
 R3866    2      B Q_RES_0402LF-0,5%,1/16W,EMPTY,CS00002JB13   I108 @T6G_MB_LIB.T6G(SCH_1):PAGE369
 R3865    2      B Q_RES_0402LF-0,5%,1/16W,CHIP,CS00002JB13   I109 @T6G_MB_LIB.T6G(SCH_1):PAGE369
   C37    1      A Q_CAP_0402-0.1UF,25V,10%,X7R,CH4104K1B00   I112 @T6G_MB_LIB.T6G(SCH_1):PAGE369
  U269   15    IN1 ADC128D818CIMTXNOPB-ADC128D818CIMTX/NOPB,SMLF,IC,AA   I142 @T6G_MB_LIB.T6G(SCH_1):PAGE369

P12V_OCP_SFF_R @T6G_MB_LIB.T6G(SCH_1):P12V_OCP_SFF_R
   C21    1      A Q_CAP_0402-0.1UF,25V,10%,X7R,CH4104K1B00    I89 @T6G_MB_LIB.T6G(SCH_1):PAGE335
 C1235    1      A Q_CAP_0402-0.1UF,25V,10%,X7R,CH4104K1B00    I90 @T6G_MB_LIB.T6G(SCH_1):PAGE335
   J38   B1 +12V_EDGE_B1 SCONN168_ME1016810202011-SCONN168_ME1016810202011,A   I168 @T6G_MB_LIB.T6G(SCH_1):PAGE335
   J38   B2 +12V_EDGE_B2 SCONN168_ME1016810202011-SCONN168_ME1016810202011,A   I168 @T6G_MB_LIB.T6G(SCH_1):PAGE335
   J38   B3 +12V_EDGE_B3 SCONN168_ME1016810202011-SCONN168_ME1016810202011,A   I168 @T6G_MB_LIB.T6G(SCH_1):PAGE335
   J38   B4 +12V_EDGE_B4 SCONN168_ME1016810202011-SCONN168_ME1016810202011,A   I168 @T6G_MB_LIB.T6G(SCH_1):PAGE335
   J38   B5 +12V_EDGE_B5 SCONN168_ME1016810202011-SCONN168_ME1016810202011,A   I168 @T6G_MB_LIB.T6G(SCH_1):PAGE335
   J38   B6 +12V_EDGE_B6 SCONN168_ME1016810202011-SCONN168_ME1016810202011,A   I168 @T6G_MB_LIB.T6G(SCH_1):PAGE335
 C1213    1      A Q_CAP_C0805-22UF,16V,20%,X6S,CH6223MEA00    I87 @T6G_MB_LIB.T6G(SCH_1):PAGE335
   C34    1      A Q_CAP_C0805-22UF,16V,20%,X6S,CH6223MEA00    I88 @T6G_MB_LIB.T6G(SCH_1):PAGE335
   C27    1      A Q_CAP_0402-0.1UF,25V,10%,X7R,CH4104K1B00   I163 @T6G_MB_LIB.T6G(SCH_1):PAGE335
 C1236    1      A Q_CAP_0402-0.1UF,25V,10%,X7R,CH4104K1B00   I164 @T6G_MB_LIB.T6G(SCH_1):PAGE335
 R1324    1      A Q_RES_2512LF-0.002,1%,2W,CHIP,CS+002AFR06     I2 @T6G_MB_LIB.T6G(SCH_1):PAGE466
 R1301    1      A Q_RES_0402LF-10,1%,1/16W,CHIP,CS01002FB07    I11 @T6G_MB_LIB.T6G(SCH_1):PAGE466

P12V_OCP_SS_1 @T6G_MB_LIB.T6G(SCH_1):P12V_OCP_SS_1
PC2155    1      A Q_CAP_C0402-0.047UF,25V,10%,X7R,CH3474K1B04    I64 @T6G_MB_LIB.T6G(SCH_1):PAGE339
 PU204    6     SS RS31312R-RS31312R,SMLF,IC,AL031312000   I137 @T6G_MB_LIB.T6G(SCH_1):PAGE339

P12V_OCP_SS_2 @T6G_MB_LIB.T6G(SCH_1):P12V_OCP_SS_2
PC2166    1      A Q_CAP_C0402-0.047UF,25V,10%,X7R,CH3474K1B04     I6 @T6G_MB_LIB.T6G(SCH_1):PAGE344
 PU206    6     SS RS31312R-RS31312R,SMLF,IC,AL031312000    I82 @T6G_MB_LIB.T6G(SCH_1):PAGE344

P12V_OCP_TIMER_1 @T6G_MB_LIB.T6G(SCH_1):P12V_OCP_TIMER_1
PC2153    1      A Q_CAP_0402-0.22UF,16V,10%,X7R,CH4223K1B00    I60 @T6G_MB_LIB.T6G(SCH_1):PAGE339
 PU204    4  TIMER RS31312R-RS31312R,SMLF,IC,AL031312000   I137 @T6G_MB_LIB.T6G(SCH_1):PAGE339

P12V_OCP_TIMER_2 @T6G_MB_LIB.T6G(SCH_1):P12V_OCP_TIMER_2
PC2164    1      A Q_CAP_0402-0.22UF,16V,10%,X7R,CH4223K1B00     I2 @T6G_MB_LIB.T6G(SCH_1):PAGE344
 PU206    4  TIMER RS31312R-RS31312R,SMLF,IC,AL031312000    I82 @T6G_MB_LIB.T6G(SCH_1):PAGE344

P12V_OCP_UV_1 @T6G_MB_LIB.T6G(SCH_1):P12V_OCP_UV_1
 R3784    2      B Q_RES_0402LF-0,5%,1/16W,CHIP,CS00002JB13    I40 @T6G_MB_LIB.T6G(SCH_1):PAGE338
PR3787    1      A Q_RES_0402LF-6.8K,1%,1/16W,CHIP,CS26802FB02    I42 @T6G_MB_LIB.T6G(SCH_1):PAGE338
PR3786    2      B Q_RES_0402LF-160K,1%,1/16W,CHIP,CS41602FB05    I43 @T6G_MB_LIB.T6G(SCH_1):PAGE338
 PU203   D2     UV MAX15090BEWIT-MAX15090BEWI+T,SMLF,IC,AL015080B00    I50 @T6G_MB_LIB.T6G(SCH_1):PAGE338

P12V_OCP_UV_1_R @T6G_MB_LIB.T6G(SCH_1):P12V_OCP_UV_1_R
  Q123    3     D2 MOSFET_NCH_DUAL-PJT138K,SMLF,IC,BAM138K0003    I19 @T6G_MB_LIB.T6G(SCH_1):PAGE338
 R3784    1      A Q_RES_0402LF-0,5%,1/16W,CHIP,CS00002JB13    I40 @T6G_MB_LIB.T6G(SCH_1):PAGE338

P12V_OCP_UV_2 @T6G_MB_LIB.T6G(SCH_1):P12V_OCP_UV_2
 R3827    2      B Q_RES_0402LF-0,5%,1/16W,CHIP,CS00002JB13    I33 @T6G_MB_LIB.T6G(SCH_1):PAGE343
PR3806    1      A Q_RES_0402LF-6.8K,1%,1/16W,CHIP,CS26802FB02    I35 @T6G_MB_LIB.T6G(SCH_1):PAGE343
PR3805    2      B Q_RES_0402LF-160K,1%,1/16W,CHIP,CS41602FB05    I36 @T6G_MB_LIB.T6G(SCH_1):PAGE343
 PU201   D2     UV MAX15090BEWIT-MAX15090BEWI+T,SMLF,IC,AL015080B00    I67 @T6G_MB_LIB.T6G(SCH_1):PAGE343

P12V_OCP_UV_2_R @T6G_MB_LIB.T6G(SCH_1):P12V_OCP_UV_2_R
  Q118    3     D2 MOSFET_NCH_DUAL-PJT138K,SMLF,IC,BAM138K0003    I19 @T6G_MB_LIB.T6G(SCH_1):PAGE343
 R3827    1      A Q_RES_0402LF-0,5%,1/16W,CHIP,CS00002JB13    I33 @T6G_MB_LIB.T6G(SCH_1):PAGE343

P12V_OCP_V3_1_PLD_PWRGD @T6G_MB_LIB.T6G(SCH_1):P12V_OCP_V3_1_PLD_PWRGD
 R6051    2      B Q_RES_0402LF-0,5%,1/16W,CHIP,CS00002JB13   I102 @T6G_MB_LIB.T6G(SCH_1):PAGE81
 R1132    2      B Q_RES_0402LF-0,5%,1/16W,CHIP,CS00002JB13    I58 @T6G_MB_LIB.T6G(SCH_1):PAGE340
 R1133    2      B Q_RES_0402LF-1K,1%,1/16W,CHIP,CS21002FB06    I61 @T6G_MB_LIB.T6G(SCH_1):PAGE340

P12V_OCP_V3_1_PLD_R_PWRGD @T6G_MB_LIB.T6G(SCH_1):P12V_OCP_V3_1_PLD_R_PWRGD
   U28    4      Y SN74LVC1G07DBVR_SMLF-SN74LVC1G07DBVR,IC,AL1G0007024    I51 @T6G_MB_LIB.T6G(SCH_1):PAGE340
 R1132    1      A Q_RES_0402LF-0,5%,1/16W,CHIP,CS00002JB13    I58 @T6G_MB_LIB.T6G(SCH_1):PAGE340

P12V_OCP_V3_1_PWRGD @T6G_MB_LIB.T6G(SCH_1):P12V_OCP_V3_1_PWRGD
 R6051    1      A Q_RES_0402LF-0,5%,1/16W,CHIP,CS00002JB13   I102 @T6G_MB_LIB.T6G(SCH_1):PAGE81
   U18   W2  PL28B LCMXO3LF9400C5BG484C-LCMXO3LF-9400C-5BG484C,SMLF,IA   I143 @T6G_MB_LIB.T6G(SCH_1):PAGE81

P12V_OCP_V3_2 @T6G_MB_LIB.T6G(SCH_1):P12V_OCP_V3_2
 PU201   A4 OUT_A4 MAX15090BEWIT-MAX15090BEWI+T,SMLF,IC,AL015080B00    I67 @T6G_MB_LIB.T6G(SCH_1):PAGE343
 PU201   B4 OUT_B4 MAX15090BEWIT-MAX15090BEWI+T,SMLF,IC,AL015080B00    I67 @T6G_MB_LIB.T6G(SCH_1):PAGE343
 PU201   B6 OUT_B6 MAX15090BEWIT-MAX15090BEWI+T,SMLF,IC,AL015080B00    I67 @T6G_MB_LIB.T6G(SCH_1):PAGE343
 PU201   C4 OUT_C4 MAX15090BEWIT-MAX15090BEWI+T,SMLF,IC,AL015080B00    I67 @T6G_MB_LIB.T6G(SCH_1):PAGE343
 PU201   C6 OUT_C6 MAX15090BEWIT-MAX15090BEWI+T,SMLF,IC,AL015080B00    I67 @T6G_MB_LIB.T6G(SCH_1):PAGE343
 PU201   D4 OUT_D4 MAX15090BEWIT-MAX15090BEWI+T,SMLF,IC,AL015080B00    I67 @T6G_MB_LIB.T6G(SCH_1):PAGE343
 PU201   D6 OUT_D6 MAX15090BEWIT-MAX15090BEWI+T,SMLF,IC,AL015080B00    I67 @T6G_MB_LIB.T6G(SCH_1):PAGE343
 PD108    C      C SCHOTTKY_AC-B340A-13-F,SMLF,IC,BC000340Z30    I92 @T6G_MB_LIB.T6G(SCH_1):PAGE343
PC2152    1      A Q_CAP_0402-0.1UF,25V,10%,X7R,CH4104K1B00    I97 @T6G_MB_LIB.T6G(SCH_1):PAGE343
PC2141    1      A Q_CAP_C0805-22UF,16V,20%,X6S,CH6223MEA01    I99 @T6G_MB_LIB.T6G(SCH_1):PAGE343
PC2143    1      A Q_CAP_C0805-10UF,16V,10%,X6S,CH6103KEA01   I101 @T6G_MB_LIB.T6G(SCH_1):PAGE343
PR3850    1      A Q_RES_0402LF-100,1%,1/16W,EMPTY,CS11002FB07    I30 @T6G_MB_LIB.T6G(SCH_1):PAGE344
PR3852    1      A Q_RES_0402LF-71.5K,1%,1/16W,EMPTY,CS37152FB05    I31 @T6G_MB_LIB.T6G(SCH_1):PAGE344
PC2174    1      A Q_CAP_0402-0.1UF,25V,10%,X7R,CH4104K1B00    I40 @T6G_MB_LIB.T6G(SCH_1):PAGE344
   C40    1      A Q_CAP_C0402-0.01UF,50V,10%,EMPTY,CH31006KB18    I72 @T6G_MB_LIB.T6G(SCH_1):PAGE343
PR4522    1      A Q_RES_0402LF-10M,1%,1/16W,CHIP,CS61002FB02    I76 @T6G_MB_LIB.T6G(SCH_1):PAGE343
   U56   11   VBUS ISL28022FRZT-ISL28022FRZ-T,SMLF,IC,AL028022003    I29 @T6G_MB_LIB.T6G(SCH_1):PAGE466
 R1291    1      A Q_RES_0402LF-10,1%,1/16W,CHIP,CS01002FB07    I43 @T6G_MB_LIB.T6G(SCH_1):PAGE466
 C1109    1      A Q_CAP_0402-0.1UF,25V,10%,X7R,CH4104K1B00    I51 @T6G_MB_LIB.T6G(SCH_1):PAGE466
 R1325    2      B Q_RES_2512LF-0.002,1%,2W,CHIP,CS+002AFR06    I53 @T6G_MB_LIB.T6G(SCH_1):PAGE466
 PU206   13 VOUT_13 RS31312R-RS31312R,SMLF,IC,AL031312000    I82 @T6G_MB_LIB.T6G(SCH_1):PAGE344
 PU206   14 VOUT_14 RS31312R-RS31312R,SMLF,IC,AL031312000    I82 @T6G_MB_LIB.T6G(SCH_1):PAGE344
 PU206   15 VOUT_15 RS31312R-RS31312R,SMLF,IC,AL031312000    I82 @T6G_MB_LIB.T6G(SCH_1):PAGE344
 PU206   16 VOUT_16 RS31312R-RS31312R,SMLF,IC,AL031312000    I82 @T6G_MB_LIB.T6G(SCH_1):PAGE344
 PU206   17 VOUT_17 RS31312R-RS31312R,SMLF,IC,AL031312000    I82 @T6G_MB_LIB.T6G(SCH_1):PAGE344
 PU206   18 VOUT_18 RS31312R-RS31312R,SMLF,IC,AL031312000    I82 @T6G_MB_LIB.T6G(SCH_1):PAGE344
 PU206   19 VOUT_19 RS31312R-RS31312R,SMLF,IC,AL031312000    I82 @T6G_MB_LIB.T6G(SCH_1):PAGE344
 PU206   20 VOUT_20 RS31312R-RS31312R,SMLF,IC,AL031312000    I82 @T6G_MB_LIB.T6G(SCH_1):PAGE344

P12V_OCP_V3_2_ADC_ALERT_R @T6G_MB_LIB.T6G(SCH_1):P12V_OCP_V3_2_ADC_ALERT_R
   U56    3 EXT_CLK||INT ISL28022FRZT-ISL28022FRZ-T,SMLF,IC,AL028022003    I29 @T6G_MB_LIB.T6G(SCH_1):PAGE466
 R1271    1      A Q_RES_0402LF-0,5%,1/16W,CHIP,CS00002JB13    I33 @T6G_MB_LIB.T6G(SCH_1):PAGE466

P12V_OCP_V3_2_BUF_EN @T6G_MB_LIB.T6G(SCH_1):P12V_OCP_V3_2_BUF_EN
   U31    4      Y 74LVC1G08W57-74LVC1G08W5-7,SMLF,IC,AL1G0008020    I31 @T6G_MB_LIB.T6G(SCH_1):PAGE257
 R1168    1      A Q_RES_0402LF-0,5%,1/16W,CHIP,CS00002JB13    I57 @T6G_MB_LIB.T6G(SCH_1):PAGE257

P12V_OCP_V3_2_BUF_EN_R @T6G_MB_LIB.T6G(SCH_1):P12V_OCP_V3_2_BUF_EN_R
 R1168    2      B Q_RES_0402LF-0,5%,1/16W,CHIP,CS00002JB13    I57 @T6G_MB_LIB.T6G(SCH_1):PAGE257
 R1181    1      A Q_RES_0402LF-0,5%,1/16W,CHIP,CS00002JB13   I123 @T6G_MB_LIB.T6G(SCH_1):PAGE343
 R1193    1      A Q_RES_0402LF-0,5%,1/16W,CHIP,CS00002JB13    I76 @T6G_MB_LIB.T6G(SCH_1):PAGE344
 R1522    2      B Q_RES_0402LF-0,5%,1/16W,CHIP,CS00002JB13    I44 @T6G_MB_LIB.T6G(SCH_1):PAGE248
 R1520    1      A Q_RES_0402LF-0,5%,1/16W,CHIP,CS00002JB13   I130 @T6G_MB_LIB.T6G(SCH_1):PAGE343
 R1521    1      A Q_RES_0402LF-0,5%,1/16W,CHIP,CS00002JB13    I80 @T6G_MB_LIB.T6G(SCH_1):PAGE344

P12V_OCP_V3_2_EN_2_R3 @T6G_MB_LIB.T6G(SCH_1):P12V_OCP_V3_2_EN_2_R3
 R3630    2      B Q_RES_0402LF-0,5%,1/16W,EMPTY,CS00002JB13    I73 @T6G_MB_LIB.T6G(SCH_1):PAGE344
 R1193    2      B Q_RES_0402LF-0,5%,1/16W,CHIP,CS00002JB13    I76 @T6G_MB_LIB.T6G(SCH_1):PAGE344
 PU206    1     EN RS31312R-RS31312R,SMLF,IC,AL031312000    I82 @T6G_MB_LIB.T6G(SCH_1):PAGE344

P12V_OCP_V3_2_EN_R @T6G_MB_LIB.T6G(SCH_1):P12V_OCP_V3_2_EN_R
 R6061    1      A Q_RES_0402LF-4.7K,5%,1/16W,EMPTY,CS24702JB10    I39 @T6G_MB_LIB.T6G(SCH_1):PAGE82
   U18 AA20  PB44B LCMXO3LF9400C5BG484C-LCMXO3LF-9400C-5BG484C,SMLF,IA   I216 @T6G_MB_LIB.T6G(SCH_1):PAGE80
 R1164    1      A Q_RES_0402LF-0,5%,1/16W,EMPTY,CS00002JB13    I28 @T6G_MB_LIB.T6G(SCH_1):PAGE257
 R4059    1      A Q_RES_0402LF-0,5%,1/16W,EMPTY,CS00002JB13   I119 @T6G_MB_LIB.T6G(SCH_1):PAGE343
 R3630    1      A Q_RES_0402LF-0,5%,1/16W,EMPTY,CS00002JB13    I73 @T6G_MB_LIB.T6G(SCH_1):PAGE344

P12V_OCP_V3_2_EN_R3 @T6G_MB_LIB.T6G(SCH_1):P12V_OCP_V3_2_EN_R3
 R1164    2      B Q_RES_0402LF-0,5%,1/16W,EMPTY,CS00002JB13    I28 @T6G_MB_LIB.T6G(SCH_1):PAGE257
   U31    1      A 74LVC1G08W57-74LVC1G08W5-7,SMLF,IC,AL1G0008020    I31 @T6G_MB_LIB.T6G(SCH_1):PAGE257
 R1165    2      B Q_RES_0402LF-1K,1%,1/16W,CHIP,CS21002FB06    I32 @T6G_MB_LIB.T6G(SCH_1):PAGE257

P12V_OCP_V3_2_ISENSE_MAM @T6G_MB_LIB.T6G(SCH_1):P12V_OCP_V3_2_ISENSE_MAM
 R3860    2      B Q_RES_0402LF-0,5%,1/16W,EMPTY,CS00002JB13    I83 @T6G_MB_LIB.T6G(SCH_1):PAGE369
   C59    1      A Q_CAP_0402-100PF,50V,5%,EMPTY,CH11006JB18    I87 @T6G_MB_LIB.T6G(SCH_1):PAGE369
 R3859    2      B Q_RES_0402LF-0,5%,1/16W,EMPTY,CS00002JB13   I107 @T6G_MB_LIB.T6G(SCH_1):PAGE369
  U193    7   AIN2 MAX11617EEET-MAX11617EEE+T,SMLF,EMPTY,AL011617W00   I169 @T6G_MB_LIB.T6G(SCH_1):PAGE369

P12V_OCP_V3_2_ISENSE_MAM_MAM @T6G_MB_LIB.T6G(SCH_1):P12V_OCP_V3_2_ISENSE_MAM_MAM
 R3867    2      B Q_RES_0402LF-0,5%,1/16W,EMPTY,CS00002JB13    I74 @T6G_MB_LIB.T6G(SCH_1):PAGE343
 R3859    1      A Q_RES_0402LF-0,5%,1/16W,EMPTY,CS00002JB13   I107 @T6G_MB_LIB.T6G(SCH_1):PAGE369

P12V_OCP_V3_2_ISENSE_MAM_TIC @T6G_MB_LIB.T6G(SCH_1):P12V_OCP_V3_2_ISENSE_MAM_TIC
 R3868    2      B Q_RES_0402LF-0,5%,1/16W,CHIP,CS00002JB13    I73 @T6G_MB_LIB.T6G(SCH_1):PAGE343
 R3861    1      A Q_RES_0402LF-0,5%,1/16W,CHIP,CS00002JB13    I82 @T6G_MB_LIB.T6G(SCH_1):PAGE369

P12V_OCP_V3_2_ISENSE_MPS_MAM @T6G_MB_LIB.T6G(SCH_1):P12V_OCP_V3_2_ISENSE_MPS_MAM
 R3873    2      B Q_RES_0402LF-0,5%,1/16W,CHIP,CS00002JB13    I23 @T6G_MB_LIB.T6G(SCH_1):PAGE344
 R3860    1      A Q_RES_0402LF-0,5%,1/16W,EMPTY,CS00002JB13    I83 @T6G_MB_LIB.T6G(SCH_1):PAGE369

P12V_OCP_V3_2_ISENSE_MPS_TIC @T6G_MB_LIB.T6G(SCH_1):P12V_OCP_V3_2_ISENSE_MPS_TIC
 R3874    2      B Q_RES_0402LF-0,5%,1/16W,EMPTY,CS00002JB13    I22 @T6G_MB_LIB.T6G(SCH_1):PAGE344
 R3862    1      A Q_RES_0402LF-0,5%,1/16W,EMPTY,CS00002JB13    I81 @T6G_MB_LIB.T6G(SCH_1):PAGE369

P12V_OCP_V3_2_ISENSE_TIC @T6G_MB_LIB.T6G(SCH_1):P12V_OCP_V3_2_ISENSE_TIC
 R3862    2      B Q_RES_0402LF-0,5%,1/16W,EMPTY,CS00002JB13    I81 @T6G_MB_LIB.T6G(SCH_1):PAGE369
 R3861    2      B Q_RES_0402LF-0,5%,1/16W,CHIP,CS00002JB13    I82 @T6G_MB_LIB.T6G(SCH_1):PAGE369
   C33    1      A Q_CAP_0402-0.1UF,25V,10%,X7R,CH4104K1B00    I84 @T6G_MB_LIB.T6G(SCH_1):PAGE369
  U269   14    IN2 ADC128D818CIMTXNOPB-ADC128D818CIMTX/NOPB,SMLF,IC,AA   I142 @T6G_MB_LIB.T6G(SCH_1):PAGE369

P12V_OCP_V3_2_PLD_PWRGD @T6G_MB_LIB.T6G(SCH_1):P12V_OCP_V3_2_PLD_PWRGD
  R407    1      A Q_RES_0402LF-0,5%,1/16W,CHIP,CS00002JB13   I139 @T6G_MB_LIB.T6G(SCH_1):PAGE79
 R1166    2      B Q_RES_0402LF-0,5%,1/16W,CHIP,CS00002JB13    I18 @T6G_MB_LIB.T6G(SCH_1):PAGE257
 R1167    2      B Q_RES_0402LF-1K,1%,1/16W,CHIP,CS21002FB06    I19 @T6G_MB_LIB.T6G(SCH_1):PAGE257

P12V_OCP_V3_2_PLD_R_PWRGD @T6G_MB_LIB.T6G(SCH_1):P12V_OCP_V3_2_PLD_R_PWRGD
 R1166    1      A Q_RES_0402LF-0,5%,1/16W,CHIP,CS00002JB13    I18 @T6G_MB_LIB.T6G(SCH_1):PAGE257
   U33    4      Y SN74LVC1G07DBVR_SMLF-SN74LVC1G07DBVR,IC,AL1G0007024    I64 @T6G_MB_LIB.T6G(SCH_1):PAGE257

P12V_OCP_V3_2_R @T6G_MB_LIB.T6G(SCH_1):P12V_OCP_V3_2_R
 C1834    1      A Q_CAP_0402-0.1UF,25V,10%,X7R,CH4104K1B00    I20 @T6G_MB_LIB.T6G(SCH_1):PAGE341
   J35   B1 +12V_EDGE_B1 SCONN168_ME1016810202011-SCONN168_ME1016810202011,A   I168 @T6G_MB_LIB.T6G(SCH_1):PAGE341
   J35   B2 +12V_EDGE_B2 SCONN168_ME1016810202011-SCONN168_ME1016810202011,A   I168 @T6G_MB_LIB.T6G(SCH_1):PAGE341
   J35   B3 +12V_EDGE_B3 SCONN168_ME1016810202011-SCONN168_ME1016810202011,A   I168 @T6G_MB_LIB.T6G(SCH_1):PAGE341
   J35   B4 +12V_EDGE_B4 SCONN168_ME1016810202011-SCONN168_ME1016810202011,A   I168 @T6G_MB_LIB.T6G(SCH_1):PAGE341
   J35   B5 +12V_EDGE_B5 SCONN168_ME1016810202011-SCONN168_ME1016810202011,A   I168 @T6G_MB_LIB.T6G(SCH_1):PAGE341
   J35   B6 +12V_EDGE_B6 SCONN168_ME1016810202011-SCONN168_ME1016810202011,A   I168 @T6G_MB_LIB.T6G(SCH_1):PAGE341
 C1829    1      A Q_CAP_C0805-22UF,16V,20%,X6S,CH6223MEA00    I13 @T6G_MB_LIB.T6G(SCH_1):PAGE341
 C1830    1      A Q_CAP_C0805-22UF,16V,20%,X6S,CH6223MEA00    I14 @T6G_MB_LIB.T6G(SCH_1):PAGE341
 C1831    1      A Q_CAP_0402-0.1UF,25V,10%,X7R,CH4104K1B00    I15 @T6G_MB_LIB.T6G(SCH_1):PAGE341
 C1832    1      A Q_CAP_0402-0.1UF,25V,10%,X7R,CH4104K1B00    I16 @T6G_MB_LIB.T6G(SCH_1):PAGE341
 C1833    1      A Q_CAP_0402-0.1UF,25V,10%,X7R,CH4104K1B00    I17 @T6G_MB_LIB.T6G(SCH_1):PAGE341
 C1839    1      A Q_CAP_0402-0.1UF,25V,10%,X7R,CH4104K1B00    I18 @T6G_MB_LIB.T6G(SCH_1):PAGE341
 R1325    1      A Q_RES_2512LF-0.002,1%,2W,CHIP,CS+002AFR06    I53 @T6G_MB_LIB.T6G(SCH_1):PAGE466
 R1302    1      A Q_RES_0402LF-10,1%,1/16W,CHIP,CS01002FB07    I55 @T6G_MB_LIB.T6G(SCH_1):PAGE466

P12V_OCP_VCC_1 @T6G_MB_LIB.T6G(SCH_1):P12V_OCP_VCC_1
 PU203   A2    VCC MAX15090BEWIT-MAX15090BEWI+T,SMLF,IC,AL015080B00    I50 @T6G_MB_LIB.T6G(SCH_1):PAGE338
PC2085    1      A Q_CAP_C0402-1UF,25V,10%,X6S,CH5104KEB02    I55 @T6G_MB_LIB.T6G(SCH_1):PAGE338
PR3792    2      B Q_RES_0402LF-10,1%,1/16W,CHIP,CS01002FB07    I56 @T6G_MB_LIB.T6G(SCH_1):PAGE338

P12V_OCP_VCC_2 @T6G_MB_LIB.T6G(SCH_1):P12V_OCP_VCC_2
PC2098    1      A Q_CAP_C0402-1UF,25V,10%,X6S,CH5104KEB02    I65 @T6G_MB_LIB.T6G(SCH_1):PAGE343
 PU201   A2    VCC MAX15090BEWIT-MAX15090BEWI+T,SMLF,IC,AL015080B00    I67 @T6G_MB_LIB.T6G(SCH_1):PAGE343
PR3830    2      B Q_RES_0402LF-10,1%,1/16W,CHIP,CS01002FB07    I84 @T6G_MB_LIB.T6G(SCH_1):PAGE343

P12V_PSU @T6G_MB_LIB.T6G(SCH_1):P12V_PSU
 PU288    9   VIN1 MP5991GLUZ-MP5991GLU-Z,SMLF,IC,AL005991A00    I16 @T6G_MB_LIB.T6G(SCH_1):PAGE301
 PU288   10   VIN2 MP5991GLUZ-MP5991GLU-Z,SMLF,IC,AL005991A00    I16 @T6G_MB_LIB.T6G(SCH_1):PAGE301
 PU288   11   VIN3 MP5991GLUZ-MP5991GLU-Z,SMLF,IC,AL005991A00    I16 @T6G_MB_LIB.T6G(SCH_1):PAGE301
 PU288   12   VIN4 MP5991GLUZ-MP5991GLU-Z,SMLF,IC,AL005991A00    I16 @T6G_MB_LIB.T6G(SCH_1):PAGE301
 PU288   13   VIN5 MP5991GLUZ-MP5991GLU-Z,SMLF,IC,AL005991A00    I16 @T6G_MB_LIB.T6G(SCH_1):PAGE301
 PU288   14   VIN6 MP5991GLUZ-MP5991GLU-Z,SMLF,IC,AL005991A00    I16 @T6G_MB_LIB.T6G(SCH_1):PAGE301
 PU288   15   VIN7 MP5991GLUZ-MP5991GLU-Z,SMLF,IC,AL005991A00    I16 @T6G_MB_LIB.T6G(SCH_1):PAGE301
 PU288   16   VIN8 MP5991GLUZ-MP5991GLU-Z,SMLF,IC,AL005991A00    I16 @T6G_MB_LIB.T6G(SCH_1):PAGE301
 PU288   33   VIN9 MP5991GLUZ-MP5991GLU-Z,SMLF,IC,AL005991A00    I16 @T6G_MB_LIB.T6G(SCH_1):PAGE301
 PU287    9   VIN1 MP5991GLUZ-MP5991GLU-Z,SMLF,IC,AL005991A00    I35 @T6G_MB_LIB.T6G(SCH_1):PAGE301
 PU287   10   VIN2 MP5991GLUZ-MP5991GLU-Z,SMLF,IC,AL005991A00    I35 @T6G_MB_LIB.T6G(SCH_1):PAGE301
 PU287   11   VIN3 MP5991GLUZ-MP5991GLU-Z,SMLF,IC,AL005991A00    I35 @T6G_MB_LIB.T6G(SCH_1):PAGE301
 PU287   12   VIN4 MP5991GLUZ-MP5991GLU-Z,SMLF,IC,AL005991A00    I35 @T6G_MB_LIB.T6G(SCH_1):PAGE301
 PU287   13   VIN5 MP5991GLUZ-MP5991GLU-Z,SMLF,IC,AL005991A00    I35 @T6G_MB_LIB.T6G(SCH_1):PAGE301
 PU287   14   VIN6 MP5991GLUZ-MP5991GLU-Z,SMLF,IC,AL005991A00    I35 @T6G_MB_LIB.T6G(SCH_1):PAGE301
 PU287   15   VIN7 MP5991GLUZ-MP5991GLU-Z,SMLF,IC,AL005991A00    I35 @T6G_MB_LIB.T6G(SCH_1):PAGE301
 PU287   16   VIN8 MP5991GLUZ-MP5991GLU-Z,SMLF,IC,AL005991A00    I35 @T6G_MB_LIB.T6G(SCH_1):PAGE301
 PU287   33   VIN9 MP5991GLUZ-MP5991GLU-Z,SMLF,IC,AL005991A00    I35 @T6G_MB_LIB.T6G(SCH_1):PAGE301
 PU297    9   VIN1 MP5991GLUZ-MP5991GLU-Z,SMLF,IC,AL005991A00    I17 @T6G_MB_LIB.T6G(SCH_1):PAGE325
 PU297   10   VIN2 MP5991GLUZ-MP5991GLU-Z,SMLF,IC,AL005991A00    I17 @T6G_MB_LIB.T6G(SCH_1):PAGE325
 PU297   11   VIN3 MP5991GLUZ-MP5991GLU-Z,SMLF,IC,AL005991A00    I17 @T6G_MB_LIB.T6G(SCH_1):PAGE325
 PU297   12   VIN4 MP5991GLUZ-MP5991GLU-Z,SMLF,IC,AL005991A00    I17 @T6G_MB_LIB.T6G(SCH_1):PAGE325
 PU297   13   VIN5 MP5991GLUZ-MP5991GLU-Z,SMLF,IC,AL005991A00    I17 @T6G_MB_LIB.T6G(SCH_1):PAGE325
 PU297   14   VIN6 MP5991GLUZ-MP5991GLU-Z,SMLF,IC,AL005991A00    I17 @T6G_MB_LIB.T6G(SCH_1):PAGE325
 PU297   15   VIN7 MP5991GLUZ-MP5991GLU-Z,SMLF,IC,AL005991A00    I17 @T6G_MB_LIB.T6G(SCH_1):PAGE325
 PU297   16   VIN8 MP5991GLUZ-MP5991GLU-Z,SMLF,IC,AL005991A00    I17 @T6G_MB_LIB.T6G(SCH_1):PAGE325
 PU297   33   VIN9 MP5991GLUZ-MP5991GLU-Z,SMLF,IC,AL005991A00    I17 @T6G_MB_LIB.T6G(SCH_1):PAGE325
 PU296    9   VIN1 MP5991GLUZ-MP5991GLU-Z,SMLF,IC,AL005991A00    I35 @T6G_MB_LIB.T6G(SCH_1):PAGE325
 PU296   10   VIN2 MP5991GLUZ-MP5991GLU-Z,SMLF,IC,AL005991A00    I35 @T6G_MB_LIB.T6G(SCH_1):PAGE325
 PU296   11   VIN3 MP5991GLUZ-MP5991GLU-Z,SMLF,IC,AL005991A00    I35 @T6G_MB_LIB.T6G(SCH_1):PAGE325
 PU296   12   VIN4 MP5991GLUZ-MP5991GLU-Z,SMLF,IC,AL005991A00    I35 @T6G_MB_LIB.T6G(SCH_1):PAGE325
 PU296   13   VIN5 MP5991GLUZ-MP5991GLU-Z,SMLF,IC,AL005991A00    I35 @T6G_MB_LIB.T6G(SCH_1):PAGE325
 PU296   14   VIN6 MP5991GLUZ-MP5991GLU-Z,SMLF,IC,AL005991A00    I35 @T6G_MB_LIB.T6G(SCH_1):PAGE325
 PU296   15   VIN7 MP5991GLUZ-MP5991GLU-Z,SMLF,IC,AL005991A00    I35 @T6G_MB_LIB.T6G(SCH_1):PAGE325
 PU296   16   VIN8 MP5991GLUZ-MP5991GLU-Z,SMLF,IC,AL005991A00    I35 @T6G_MB_LIB.T6G(SCH_1):PAGE325
 PU296   33   VIN9 MP5991GLUZ-MP5991GLU-Z,SMLF,IC,AL005991A00    I35 @T6G_MB_LIB.T6G(SCH_1):PAGE325
PC2188    1      A Q_CAP_C0402-1UF,25V,10%,X6S,CH5104KEB02    I46 @T6G_MB_LIB.T6G(SCH_1):PAGE267
PR3926    1      A Q_RES_0402LF-75K,0.1%,1/16W,CHIP,CS37502BB01    I48 @T6G_MB_LIB.T6G(SCH_1):PAGE267
 PU289    1   VIN1 MP5990GMA1111Z-MP5990GMA-1111-Z,SMLF,IC,AR0F0TP4023    I58 @T6G_MB_LIB.T6G(SCH_1):PAGE267
 PU289    2   VIN2 MP5990GMA1111Z-MP5990GMA-1111-Z,SMLF,IC,AR0F0TP4023    I58 @T6G_MB_LIB.T6G(SCH_1):PAGE267
 PU289    3   VIN3 MP5990GMA1111Z-MP5990GMA-1111-Z,SMLF,IC,AR0F0TP4023    I58 @T6G_MB_LIB.T6G(SCH_1):PAGE267
 PU289    4   VIN4 MP5990GMA1111Z-MP5990GMA-1111-Z,SMLF,IC,AR0F0TP4023    I58 @T6G_MB_LIB.T6G(SCH_1):PAGE267
 PU289    5   VIN5 MP5990GMA1111Z-MP5990GMA-1111-Z,SMLF,IC,AR0F0TP4023    I58 @T6G_MB_LIB.T6G(SCH_1):PAGE267
 PU289    6   VIN6 MP5990GMA1111Z-MP5990GMA-1111-Z,SMLF,IC,AR0F0TP4023    I58 @T6G_MB_LIB.T6G(SCH_1):PAGE267
 PU289    7   VIN7 MP5990GMA1111Z-MP5990GMA-1111-Z,SMLF,IC,AR0F0TP4023    I58 @T6G_MB_LIB.T6G(SCH_1):PAGE267
 PU289    8   VIN8 MP5990GMA1111Z-MP5990GMA-1111-Z,SMLF,IC,AR0F0TP4023    I58 @T6G_MB_LIB.T6G(SCH_1):PAGE267
 PU289   42   VIN9 MP5990GMA1111Z-MP5990GMA-1111-Z,SMLF,IC,AR0F0TP4023    I58 @T6G_MB_LIB.T6G(SCH_1):PAGE267
 PU289   43  VIN10 MP5990GMA1111Z-MP5990GMA-1111-Z,SMLF,IC,AR0F0TP4023    I58 @T6G_MB_LIB.T6G(SCH_1):PAGE267
   FS1    1      1 Q_FUSE_SMLF-20A/125V,IC,DKK00XFU000     I6 @T6G_MB_LIB.T6G(SCH_1):PAGE372
PR2534   1A     1A Q_SP_RES4P-0.0003,1%,4W,SMLF,CHIP,SP_CS0000FFT09    I52 @T6G_MB_LIB.T6G(SCH_1):PAGE302
PR2533   1A     1A Q_SP_RES4P-0.0003,1%,4W,SMLF,CHIP,SP_CS0000FFT09    I53 @T6G_MB_LIB.T6G(SCH_1):PAGE302
PR2532   1A     1A Q_SP_RES4P-0.0003,1%,4W,SMLF,CHIP,SP_CS0000FFT09    I54 @T6G_MB_LIB.T6G(SCH_1):PAGE302
PR6001   1A     1A Q_SP_RES4P-0.0003,1%,4W,SMLF,CHIP,SP_CS0000FFT09    I55 @T6G_MB_LIB.T6G(SCH_1):PAGE302
  PJ38    1      1 SCONN21_9193031121LF-SCONN21_91930-31121LF,SMLF,IOA    I42 @T6G_MB_LIB.T6G(SCH_1):PAGE371
PR6002   1A     1A Q_SP_RES4P-0.003,1%,2W,SMLF,CHIP,SP_CS+003AFR00_1    I81 @T6G_MB_LIB.T6G(SCH_1):PAGE302
   J45 P4_1   P4_1 CONN60_101062636003K02LF-CONN60_10106263-6003K02LFA   I466 @T6G_MB_LIB.T6G(SCH_1):PAGE363
   J45 P4_2   P4_2 CONN60_101062636003K02LF-CONN60_10106263-6003K02LFA   I466 @T6G_MB_LIB.T6G(SCH_1):PAGE363
   J45 P4_3   P4_3 CONN60_101062636003K02LF-CONN60_10106263-6003K02LFA   I466 @T6G_MB_LIB.T6G(SCH_1):PAGE363
   J45 P4_4   P4_4 CONN60_101062636003K02LF-CONN60_10106263-6003K02LFA   I466 @T6G_MB_LIB.T6G(SCH_1):PAGE363
   J45 P4_5   P4_5 CONN60_101062636003K02LF-CONN60_10106263-6003K02LFA   I466 @T6G_MB_LIB.T6G(SCH_1):PAGE363
   J45 P4_6   P4_6 CONN60_101062636003K02LF-CONN60_10106263-6003K02LFA   I466 @T6G_MB_LIB.T6G(SCH_1):PAGE363
   J45 P4_7   P4_7 CONN60_101062636003K02LF-CONN60_10106263-6003K02LFA   I466 @T6G_MB_LIB.T6G(SCH_1):PAGE363
   J45 P4_8   P4_8 CONN60_101062636003K02LF-CONN60_10106263-6003K02LFA   I466 @T6G_MB_LIB.T6G(SCH_1):PAGE363
   J45 P5_1   P5_1 CONN60_101062636003K02LF-CONN60_10106263-6003K02LFA   I466 @T6G_MB_LIB.T6G(SCH_1):PAGE363
   J45 P5_2   P5_2 CONN60_101062636003K02LF-CONN60_10106263-6003K02LFA   I466 @T6G_MB_LIB.T6G(SCH_1):PAGE363
   J45 P5_3   P5_3 CONN60_101062636003K02LF-CONN60_10106263-6003K02LFA   I466 @T6G_MB_LIB.T6G(SCH_1):PAGE363
   J45 P5_4   P5_4 CONN60_101062636003K02LF-CONN60_10106263-6003K02LFA   I466 @T6G_MB_LIB.T6G(SCH_1):PAGE363
   J45 P5_5   P5_5 CONN60_101062636003K02LF-CONN60_10106263-6003K02LFA   I466 @T6G_MB_LIB.T6G(SCH_1):PAGE363
   J45 P5_6   P5_6 CONN60_101062636003K02LF-CONN60_10106263-6003K02LFA   I466 @T6G_MB_LIB.T6G(SCH_1):PAGE363
   J45 P5_7   P5_7 CONN60_101062636003K02LF-CONN60_10106263-6003K02LFA   I466 @T6G_MB_LIB.T6G(SCH_1):PAGE363
   J45 P5_8   P5_8 CONN60_101062636003K02LF-CONN60_10106263-6003K02LFA   I466 @T6G_MB_LIB.T6G(SCH_1):PAGE363
   J45 P6_1   P6_1 CONN60_101062636003K02LF-CONN60_10106263-6003K02LFA   I466 @T6G_MB_LIB.T6G(SCH_1):PAGE363
   J45 P6_2   P6_2 CONN60_101062636003K02LF-CONN60_10106263-6003K02LFA   I466 @T6G_MB_LIB.T6G(SCH_1):PAGE363
   J45 P6_3   P6_3 CONN60_101062636003K02LF-CONN60_10106263-6003K02LFA   I466 @T6G_MB_LIB.T6G(SCH_1):PAGE363
   J45 P6_4   P6_4 CONN60_101062636003K02LF-CONN60_10106263-6003K02LFA   I466 @T6G_MB_LIB.T6G(SCH_1):PAGE363
   J45 P6_5   P6_5 CONN60_101062636003K02LF-CONN60_10106263-6003K02LFA   I466 @T6G_MB_LIB.T6G(SCH_1):PAGE363
   J45 P6_6   P6_6 CONN60_101062636003K02LF-CONN60_10106263-6003K02LFA   I466 @T6G_MB_LIB.T6G(SCH_1):PAGE363
   J45 P6_7   P6_7 CONN60_101062636003K02LF-CONN60_10106263-6003K02LFA   I466 @T6G_MB_LIB.T6G(SCH_1):PAGE363
   J45 P6_8   P6_8 CONN60_101062636003K02LF-CONN60_10106263-6003K02LFA   I466 @T6G_MB_LIB.T6G(SCH_1):PAGE363
 R8027    2      B Q_RES_0402LF-560,1%,1/16W,CHIP,CS15602FB03    I49 @T6G_MB_LIB.T6G(SCH_1):PAGE375

P12V_PSU_FUSE @T6G_MB_LIB.T6G(SCH_1):P12V_PSU_FUSE
  PD15    C      C ZENER_AC-5.0SMDJ14A,SMLF,IC,BC0MDJ14000     I1 @T6G_MB_LIB.T6G(SCH_1):PAGE372
  PD13    C      C ZENER_AC-5.0SMDJ14A,SMLF,IC,BC0MDJ14000     I3 @T6G_MB_LIB.T6G(SCH_1):PAGE372
   FS1    2      2 Q_FUSE_SMLF-20A/125V,IC,DKK00XFU000     I6 @T6G_MB_LIB.T6G(SCH_1):PAGE372
 R3923    1      A Q_RES_0402LF-63.4K,1%,1/16W,CHIP,CS36342FB04    I16 @T6G_MB_LIB.T6G(SCH_1):PAGE372
 R4901    1      A Q_RES_0402LF-82K,1%,1/16W,CHIP,CS38202FB01    I19 @T6G_MB_LIB.T6G(SCH_1):PAGE372

P12V_SCM @T6G_MB_LIB.T6G(SCH_1):P12V_SCM
 R3579    1      A Q_RES_0402LF-10,1%,1/16W,CHIP,CS01002FB07    I56 @T6G_MB_LIB.T6G(SCH_1):PAGE360
 R3635    1      A Q_RES_2512LF-0.002,1%,2W,CHIP,CS+002AFR06    I93 @T6G_MB_LIB.T6G(SCH_1):PAGE360
   J41  OB2 MAIN_PWR_EN SCONN168_ME1016810202011-SCONN168_ME1016810202011,A   I176 @T6G_MB_LIB.T6G(SCH_1):PAGE348
   J41  OB1 NIC_PWR_GOOD SCONN168_ME1016810202011-SCONN168_ME1016810202011,A   I176 @T6G_MB_LIB.T6G(SCH_1):PAGE348
   J41  OA1 PERST2# SCONN168_ME1016810202011-SCONN168_ME1016810202011,A   I176 @T6G_MB_LIB.T6G(SCH_1):PAGE348
   J41  OA2 PERST3# SCONN168_ME1016810202011-SCONN168_ME1016810202011,A   I176 @T6G_MB_LIB.T6G(SCH_1):PAGE348

P12V_SCM_ADC_ALERT @T6G_MB_LIB.T6G(SCH_1):P12V_SCM_ADC_ALERT
 R3561    2      B Q_RES_0402LF-0,5%,1/16W,CHIP,CS00002JB13    I64 @T6G_MB_LIB.T6G(SCH_1):PAGE360
   U18   K5  PL13B LCMXO3LF9400C5BG484C-LCMXO3LF-9400C-5BG484C,SMLF,IA   I143 @T6G_MB_LIB.T6G(SCH_1):PAGE81

P12V_SCM_ADC_ALERT_R @T6G_MB_LIB.T6G(SCH_1):P12V_SCM_ADC_ALERT_R
 R3561    1      A Q_RES_0402LF-0,5%,1/16W,CHIP,CS00002JB13    I64 @T6G_MB_LIB.T6G(SCH_1):PAGE360
  U265    3 EXT_CLK||INT ISL28022FRZT-ISL28022FRZ-T,SMLF,IC,AL028022003    I69 @T6G_MB_LIB.T6G(SCH_1):PAGE360
 R4091    2      B Q_RES_0402LF-1K,1%,1/16W,CHIP,CS21002FB06   I122 @T6G_MB_LIB.T6G(SCH_1):PAGE360

P12V_SCM_AVIN_PD @T6G_MB_LIB.T6G(SCH_1):P12V_SCM_AVIN_PD
PC2239    1      A Q_CAP_C0603-2.2UF,16V,20%,X7R,CH5223M1900    I52 @T6G_MB_LIB.T6G(SCH_1):PAGE350
PR4006    2      B Q_RES_0402LF-100,1%,1/16W,EMPTY,CS11002FB07    I41 @T6G_MB_LIB.T6G(SCH_1):PAGE350
PR4014    2      B Q_RES_0603LF-49.9,1%,1/10W,CHIP,CS04993F909    I53 @T6G_MB_LIB.T6G(SCH_1):PAGE350
 PU299   12   AVIN RS31312R-RS31312R,SMLF,IC,AL031312000    I95 @T6G_MB_LIB.T6G(SCH_1):PAGE350

P12V_SCM_CB @T6G_MB_LIB.T6G(SCH_1):P12V_SCM_CB
PR4004    1      A Q_RES_0402LF-17.8K,1%,1/16W,CHIP,CS31782FB04    I62 @T6G_MB_LIB.T6G(SCH_1):PAGE350
 PU300   B1     CB MAX15090BEWIT-MAX15090BEWI+T,SMLF,IC,AL015080B00    I86 @T6G_MB_LIB.T6G(SCH_1):PAGE350

P12V_SCM_EN @T6G_MB_LIB.T6G(SCH_1):P12V_SCM_EN
 R3998    1      A Q_RES_0402LF-0,5%,1/16W,CHIP,CS00002JB13    I14 @T6G_MB_LIB.T6G(SCH_1):PAGE350
 R3996    2      B Q_RES_0402LF-0,5%,1/16W,CHIP,CS00002JB13    I17 @T6G_MB_LIB.T6G(SCH_1):PAGE350
 R1857    2      B Q_RES_0402LF-10K,1%,1/16W,CHIP,CS31002FB08    I18 @T6G_MB_LIB.T6G(SCH_1):PAGE350
 R4062    1      A Q_RES_0402LF-0,5%,1/16W,CHIP,CS00002JB13    I20 @T6G_MB_LIB.T6G(SCH_1):PAGE350
   Q39    D      D MOSFET_NCH_GDS_ESD_PROTECTED-2N7002K,SMLF,IC,BAM70A     I9 @T6G_MB_LIB.T6G(SCH_1):PAGE350

P12V_SCM_EN_G @T6G_MB_LIB.T6G(SCH_1):P12V_SCM_EN_G
 R4071    2      B Q_RES_0402LF-10K,1%,1/16W,CHIP,CS31002FB08    I25 @T6G_MB_LIB.T6G(SCH_1):PAGE350
  Q125    6     D1 MOSFET_NCH_DUAL-PJT138K,SMLF,IC,BAM138K0003    I22 @T6G_MB_LIB.T6G(SCH_1):PAGE350
  Q125    5     G2 MOSFET_NCH_DUAL-PJT138K,SMLF,IC,BAM138K0003    I24 @T6G_MB_LIB.T6G(SCH_1):PAGE350

P12V_SCM_EN_R @T6G_MB_LIB.T6G(SCH_1):P12V_SCM_EN_R
 R4062    2      B Q_RES_0402LF-0,5%,1/16W,CHIP,CS00002JB13    I20 @T6G_MB_LIB.T6G(SCH_1):PAGE350
  Q125    2     G1 MOSFET_NCH_DUAL-PJT138K,SMLF,IC,BAM138K0003    I22 @T6G_MB_LIB.T6G(SCH_1):PAGE350

P12V_SCM_EN_R2 @T6G_MB_LIB.T6G(SCH_1):P12V_SCM_EN_R2
 R3998    2      B Q_RES_0402LF-0,5%,1/16W,CHIP,CS00002JB13    I14 @T6G_MB_LIB.T6G(SCH_1):PAGE350
 PU299    1     EN RS31312R-RS31312R,SMLF,IC,AL031312000    I95 @T6G_MB_LIB.T6G(SCH_1):PAGE350

P12V_SCM_FAULT_N @T6G_MB_LIB.T6G(SCH_1):P12V_SCM_FAULT_N
 PU300   C7 FAULT# MAX15090BEWIT-MAX15090BEWI+T,SMLF,IC,AL015080B00    I86 @T6G_MB_LIB.T6G(SCH_1):PAGE350
 R8030    1      A Q_RES_0402LF-0,5%,1/16W,CHIP,CS00002JB13    I91 @T6G_MB_LIB.T6G(SCH_1):PAGE350

P12V_SCM_FAULT_R_N @T6G_MB_LIB.T6G(SCH_1):P12V_SCM_FAULT_R_N
 R4013    2      B Q_RES_0402LF-100K,1%,1/16W,CHIP,CS41002FB09    I76 @T6G_MB_LIB.T6G(SCH_1):PAGE350
 Q8001    2     G1 MOSFET_NCH_DUAL-PJT138K,SMLF,IC,BAM138K0003    I57 @T6G_MB_LIB.T6G(SCH_1):PAGE375
 R8030    2      B Q_RES_0402LF-0,5%,1/16W,CHIP,CS00002JB13    I91 @T6G_MB_LIB.T6G(SCH_1):PAGE350
 R8031    2      B Q_RES_0402LF-0,5%,1/16W,CHIP,CS00002JB13    I93 @T6G_MB_LIB.T6G(SCH_1):PAGE350

P12V_SCM_FLTB_N @T6G_MB_LIB.T6G(SCH_1):P12V_SCM_FLTB_N
PR4007    1      A Q_RES_0402LF-10K,1%,1/16W,CHIP,CS31002FB08    I40 @T6G_MB_LIB.T6G(SCH_1):PAGE350
 R8031    1      A Q_RES_0402LF-0,5%,1/16W,CHIP,CS00002JB13    I93 @T6G_MB_LIB.T6G(SCH_1):PAGE350
 PU299    9   FLTB RS31312R-RS31312R,SMLF,IC,AL031312000    I95 @T6G_MB_LIB.T6G(SCH_1):PAGE350

P12V_SCM_GATE @T6G_MB_LIB.T6G(SCH_1):P12V_SCM_GATE
PC2236    2      B Q_CAP_C0402-0.01UF,50V,10%,EMPTY,CH31006KB18    I71 @T6G_MB_LIB.T6G(SCH_1):PAGE350
PC2237    1      A Q_CAP_C0402-3900PF,50V,10%,X7R,CH23906KB14    I72 @T6G_MB_LIB.T6G(SCH_1):PAGE350
 PU300   A6   GATE MAX15090BEWIT-MAX15090BEWI+T,SMLF,IC,AL015080B00    I86 @T6G_MB_LIB.T6G(SCH_1):PAGE350
PR4526    2      B Q_RES_0402LF-10M,1%,1/16W,CHIP,CS61002FB02    I74 @T6G_MB_LIB.T6G(SCH_1):PAGE350

P12V_SCM_IMON @T6G_MB_LIB.T6G(SCH_1):P12V_SCM_IMON
PC2235    1      A Q_CAP_C0402-100NF,50V,10%,X7R,CH4106K1B01    I45 @T6G_MB_LIB.T6G(SCH_1):PAGE350
PR4005    1      A Q_RES_0402LF-30.1K,1%,1/16W,CHIP,CS33012FB03    I35 @T6G_MB_LIB.T6G(SCH_1):PAGE350
 PU299    8   IMON RS31312R-RS31312R,SMLF,IC,AL031312000    I95 @T6G_MB_LIB.T6G(SCH_1):PAGE350

P12V_SCM_ISET @T6G_MB_LIB.T6G(SCH_1):P12V_SCM_ISET
PR3999    1      A Q_RES_0402LF-24.3K,1%,1/16W,CHIP,CS32432FB03    I11 @T6G_MB_LIB.T6G(SCH_1):PAGE350
PR4540    1      A Q_RES_0402LF-20K,1%,1/16W,CHIP,CS32002FB06    I12 @T6G_MB_LIB.T6G(SCH_1):PAGE350
 PU299    5   ISET RS31312R-RS31312R,SMLF,IC,AL031312000    I95 @T6G_MB_LIB.T6G(SCH_1):PAGE350

P12V_SCM_ISET_R @T6G_MB_LIB.T6G(SCH_1):P12V_SCM_ISET_R
PR4540    2      B Q_RES_0402LF-20K,1%,1/16W,CHIP,CS32002FB06    I12 @T6G_MB_LIB.T6G(SCH_1):PAGE350
PC2340    1      A Q_CAP_C0402-560PF,50V,10%,X7R,CH1566K1B09     I6 @T6G_MB_LIB.T6G(SCH_1):PAGE350

P12V_SCM_OV @T6G_MB_LIB.T6G(SCH_1):P12V_SCM_OV
 PU300   D3     OV MAX15090BEWIT-MAX15090BEWI+T,SMLF,IC,AL015080B00    I86 @T6G_MB_LIB.T6G(SCH_1):PAGE350
PR4002    1      A Q_RES_0402LF-15K,1%,1/16W,CHIP,CS31502FB05    I60 @T6G_MB_LIB.T6G(SCH_1):PAGE350
PR4001    2      B Q_RES_0402LF-6.8K,1%,1/16W,CHIP,CS26802FB02    I63 @T6G_MB_LIB.T6G(SCH_1):PAGE350

P12V_SCM_OV_FB @T6G_MB_LIB.T6G(SCH_1):P12V_SCM_OV_FB
PR4009    2      B Q_RES_0402LF-71.5K,1%,1/16W,EMPTY,CS37152FB05    I50 @T6G_MB_LIB.T6G(SCH_1):PAGE350
PR4010    2      B Q_RES_0402LF-120K,1%,1/16W,CHIP,CS41202FB05    I51 @T6G_MB_LIB.T6G(SCH_1):PAGE350
PR4011    1      A Q_RES_0402LF-10K,1%,1/16W,CHIP,CS31002FB08    I49 @T6G_MB_LIB.T6G(SCH_1):PAGE350
 PU299   11     OV RS31312R-RS31312R,SMLF,IC,AL031312000    I95 @T6G_MB_LIB.T6G(SCH_1):PAGE350

P12V_SCM_PWRGD @T6G_MB_LIB.T6G(SCH_1):P12V_SCM_PWRGD
PR4012    1      A Q_RES_0402LF-0,5%,1/16W,CHIP,CS00002JB13    I73 @T6G_MB_LIB.T6G(SCH_1):PAGE350
 PU300   D7     PG MAX15090BEWIT-MAX15090BEWI+T,SMLF,IC,AL015080B00    I86 @T6G_MB_LIB.T6G(SCH_1):PAGE350

P12V_SCM_PWRGD_R @T6G_MB_LIB.T6G(SCH_1):P12V_SCM_PWRGD_R
 R6055    2      B Q_RES_0402LF-0,5%,1/16W,CHIP,CS00002JB13    I60 @T6G_MB_LIB.T6G(SCH_1):PAGE80
   U18   Y6  PB10D LCMXO3LF9400C5BG484C-LCMXO3LF-9400C-5BG484C,SMLF,IA   I216 @T6G_MB_LIB.T6G(SCH_1):PAGE80

P12V_SCM_R @T6G_MB_LIB.T6G(SCH_1):P12V_SCM_R
PR4009    1      A Q_RES_0402LF-71.5K,1%,1/16W,EMPTY,CS37152FB05    I50 @T6G_MB_LIB.T6G(SCH_1):PAGE350
PC2236    1      A Q_CAP_C0402-0.01UF,50V,10%,EMPTY,CH31006KB18    I71 @T6G_MB_LIB.T6G(SCH_1):PAGE350
 PD116    C      C SCHOTTKY_AC-B340A-13-F,SMLF,IC,BC000340Z30    I79 @T6G_MB_LIB.T6G(SCH_1):PAGE350
PC2238    1      A Q_CAP_0402-0.1UF,25V,10%,X7R,CH4104K1B00    I80 @T6G_MB_LIB.T6G(SCH_1):PAGE350
 C2019    1      A Q_CAP_0402-0.1UF,25V,10%,X7R,CH4104K1B00    I49 @T6G_MB_LIB.T6G(SCH_1):PAGE360
 R3578    1      A Q_RES_0402LF-10,1%,1/16W,CHIP,CS01002FB07    I58 @T6G_MB_LIB.T6G(SCH_1):PAGE360
  U265   11   VBUS ISL28022FRZT-ISL28022FRZ-T,SMLF,IC,AL028022003    I69 @T6G_MB_LIB.T6G(SCH_1):PAGE360
 R3635    2      B Q_RES_2512LF-0.002,1%,2W,CHIP,CS+002AFR06    I93 @T6G_MB_LIB.T6G(SCH_1):PAGE360
PR4006    1      A Q_RES_0402LF-100,1%,1/16W,EMPTY,CS11002FB07    I41 @T6G_MB_LIB.T6G(SCH_1):PAGE350
 PU300   A4 OUT_A4 MAX15090BEWIT-MAX15090BEWI+T,SMLF,IC,AL015080B00    I86 @T6G_MB_LIB.T6G(SCH_1):PAGE350
 PU300   B4 OUT_B4 MAX15090BEWIT-MAX15090BEWI+T,SMLF,IC,AL015080B00    I86 @T6G_MB_LIB.T6G(SCH_1):PAGE350
 PU300   B6 OUT_B6 MAX15090BEWIT-MAX15090BEWI+T,SMLF,IC,AL015080B00    I86 @T6G_MB_LIB.T6G(SCH_1):PAGE350
 PU300   C4 OUT_C4 MAX15090BEWIT-MAX15090BEWI+T,SMLF,IC,AL015080B00    I86 @T6G_MB_LIB.T6G(SCH_1):PAGE350
 PU300   C6 OUT_C6 MAX15090BEWIT-MAX15090BEWI+T,SMLF,IC,AL015080B00    I86 @T6G_MB_LIB.T6G(SCH_1):PAGE350
 PU300   D4 OUT_D4 MAX15090BEWIT-MAX15090BEWI+T,SMLF,IC,AL015080B00    I86 @T6G_MB_LIB.T6G(SCH_1):PAGE350
 PU300   D6 OUT_D6 MAX15090BEWIT-MAX15090BEWI+T,SMLF,IC,AL015080B00    I86 @T6G_MB_LIB.T6G(SCH_1):PAGE350
PC2241    1      A Q_CAP_0402-0.1UF,25V,10%,X7R,CH4104K1B00    I56 @T6G_MB_LIB.T6G(SCH_1):PAGE350
PR4526    1      A Q_RES_0402LF-10M,1%,1/16W,CHIP,CS61002FB02    I74 @T6G_MB_LIB.T6G(SCH_1):PAGE350
PC2240    1      A Q_CAP_C0805-10UF,16V,10%,X6S,CH6103KEA01    I81 @T6G_MB_LIB.T6G(SCH_1):PAGE350
PC2242    1      A Q_CAP_C0805-22UF,16V,20%,X6S,CH6223MEA01    I84 @T6G_MB_LIB.T6G(SCH_1):PAGE350
 PU299   13 VOUT_13 RS31312R-RS31312R,SMLF,IC,AL031312000    I95 @T6G_MB_LIB.T6G(SCH_1):PAGE350
 PU299   14 VOUT_14 RS31312R-RS31312R,SMLF,IC,AL031312000    I95 @T6G_MB_LIB.T6G(SCH_1):PAGE350
 PU299   15 VOUT_15 RS31312R-RS31312R,SMLF,IC,AL031312000    I95 @T6G_MB_LIB.T6G(SCH_1):PAGE350
 PU299   16 VOUT_16 RS31312R-RS31312R,SMLF,IC,AL031312000    I95 @T6G_MB_LIB.T6G(SCH_1):PAGE350
 PU299   17 VOUT_17 RS31312R-RS31312R,SMLF,IC,AL031312000    I95 @T6G_MB_LIB.T6G(SCH_1):PAGE350
 PU299   18 VOUT_18 RS31312R-RS31312R,SMLF,IC,AL031312000    I95 @T6G_MB_LIB.T6G(SCH_1):PAGE350
 PU299   19 VOUT_19 RS31312R-RS31312R,SMLF,IC,AL031312000    I95 @T6G_MB_LIB.T6G(SCH_1):PAGE350
 PU299   20 VOUT_20 RS31312R-RS31312R,SMLF,IC,AL031312000    I95 @T6G_MB_LIB.T6G(SCH_1):PAGE350

P12V_SCM_REG @T6G_MB_LIB.T6G(SCH_1):P12V_SCM_REG
PC2234    2      B Q_CAP_C0402-1UF,25V,10%,X6S,CH5104KEB02    I67 @T6G_MB_LIB.T6G(SCH_1):PAGE350
 PU300   D1    REG MAX15090BEWIT-MAX15090BEWI+T,SMLF,IC,AL015080B00    I86 @T6G_MB_LIB.T6G(SCH_1):PAGE350

P12V_SCM_SENSE @T6G_MB_LIB.T6G(SCH_1):P12V_SCM_SENSE
PR4008    1      A Q_RES_0402LF-1.33K,1%,1/16W,CHIP,CS21332FB05    I70 @T6G_MB_LIB.T6G(SCH_1):PAGE350
 PU300   A1 ISENSE MAX15090BEWIT-MAX15090BEWI+T,SMLF,IC,AL015080B00    I86 @T6G_MB_LIB.T6G(SCH_1):PAGE350

P12V_SCM_SS @T6G_MB_LIB.T6G(SCH_1):P12V_SCM_SS
PC2232    1      A Q_CAP_C0402-0.047UF,25V,10%,X7R,CH3474K1B04    I33 @T6G_MB_LIB.T6G(SCH_1):PAGE350
 PU299    6     SS RS31312R-RS31312R,SMLF,IC,AL031312000    I95 @T6G_MB_LIB.T6G(SCH_1):PAGE350

P12V_SCM_TIMER @T6G_MB_LIB.T6G(SCH_1):P12V_SCM_TIMER
PC2229    1      A Q_CAP_0402-0.22UF,16V,10%,X7R,CH4223K1B00     I8 @T6G_MB_LIB.T6G(SCH_1):PAGE350
 PU299    4  TIMER RS31312R-RS31312R,SMLF,IC,AL031312000    I95 @T6G_MB_LIB.T6G(SCH_1):PAGE350

P12V_SCM_UV @T6G_MB_LIB.T6G(SCH_1):P12V_SCM_UV
 R3997    2      B Q_RES_0402LF-0,5%,1/16W,CHIP,CS00002JB13    I27 @T6G_MB_LIB.T6G(SCH_1):PAGE350
PR4000    2      B Q_RES_0402LF-160K,1%,1/16W,CHIP,CS41602FB05    I65 @T6G_MB_LIB.T6G(SCH_1):PAGE350
 PU300   D2     UV MAX15090BEWIT-MAX15090BEWI+T,SMLF,IC,AL015080B00    I86 @T6G_MB_LIB.T6G(SCH_1):PAGE350
PR4001    1      A Q_RES_0402LF-6.8K,1%,1/16W,CHIP,CS26802FB02    I63 @T6G_MB_LIB.T6G(SCH_1):PAGE350

P12V_SCM_UV_R @T6G_MB_LIB.T6G(SCH_1):P12V_SCM_UV_R
 R3997    1      A Q_RES_0402LF-0,5%,1/16W,CHIP,CS00002JB13    I27 @T6G_MB_LIB.T6G(SCH_1):PAGE350
  Q125    3     D2 MOSFET_NCH_DUAL-PJT138K,SMLF,IC,BAM138K0003    I24 @T6G_MB_LIB.T6G(SCH_1):PAGE350

P12V_SCM_VCC @T6G_MB_LIB.T6G(SCH_1):P12V_SCM_VCC
PC2233    1      A Q_CAP_C0402-1UF,25V,10%,X6S,CH5104KEB02    I66 @T6G_MB_LIB.T6G(SCH_1):PAGE350
 PU300   A2    VCC MAX15090BEWIT-MAX15090BEWI+T,SMLF,IC,AL015080B00    I86 @T6G_MB_LIB.T6G(SCH_1):PAGE350
PR4003    2      B Q_RES_0402LF-10,1%,1/16W,CHIP,CS01002FB07    I68 @T6G_MB_LIB.T6G(SCH_1):PAGE350

P1V2_AUX @T6G_MB_LIB.T6G(SCH_1):P1V2_AUX
 U6001   10 AVDD12_1 CYUSB330468LTXI-CYUSB3304-68LTXI,SMLF,IC,AJ0330400A     I1 @T6G_MB_LIB.T6G(SCH_1):PAGE154
 U6001   16 AVDD12_2 CYUSB330468LTXI-CYUSB3304-68LTXI,SMLF,IC,AJ0330400A     I1 @T6G_MB_LIB.T6G(SCH_1):PAGE154
 U6001   34 AVDD12_3 CYUSB330468LTXI-CYUSB3304-68LTXI,SMLF,IC,AJ0330400A     I1 @T6G_MB_LIB.T6G(SCH_1):PAGE154
 U6001   46 AVDD12_4 CYUSB330468LTXI-CYUSB3304-68LTXI,SMLF,IC,AJ0330400A     I1 @T6G_MB_LIB.T6G(SCH_1):PAGE154
 U6001   52 AVDD12_5 CYUSB330468LTXI-CYUSB3304-68LTXI,SMLF,IC,AJ0330400A     I1 @T6G_MB_LIB.T6G(SCH_1):PAGE154
 U6001   53 AVDD12_6 CYUSB330468LTXI-CYUSB3304-68LTXI,SMLF,IC,AJ0330400A     I1 @T6G_MB_LIB.T6G(SCH_1):PAGE154
 U6001   49 DVDD12_4 CYUSB330468LTXI-CYUSB3304-68LTXI,SMLF,IC,AJ0330400A     I1 @T6G_MB_LIB.T6G(SCH_1):PAGE154
 U6001    7 DVDD12_5 CYUSB330468LTXI-CYUSB3304-68LTXI,SMLF,IC,AJ0330400A     I1 @T6G_MB_LIB.T6G(SCH_1):PAGE154
 U6001   13 DVDD12_6 CYUSB330468LTXI-CYUSB3304-68LTXI,SMLF,IC,AJ0330400A     I1 @T6G_MB_LIB.T6G(SCH_1):PAGE154
 U6001   37 DVDD12_7 CYUSB330468LTXI-CYUSB3304-68LTXI,SMLF,IC,AJ0330400A     I1 @T6G_MB_LIB.T6G(SCH_1):PAGE154
 U6001   43 DVDD12_8 CYUSB330468LTXI-CYUSB3304-68LTXI,SMLF,IC,AJ0330400A     I1 @T6G_MB_LIB.T6G(SCH_1):PAGE154
 L6001    1      1 Q_INDUCTOR_SMLF-BLM21PG221SN1D,IND,CX1PG221001    I26 @T6G_MB_LIB.T6G(SCH_1):PAGE154
 C6054    1      A Q_CAP_C0402-0.001UF,50V,10%,X7R,CH30106KB19    I43 @T6G_MB_LIB.T6G(SCH_1):PAGE154
 C6055    1      A Q_CAP_C0402-0.01UF,50V,10%,X7R,CH31006KB18    I44 @T6G_MB_LIB.T6G(SCH_1):PAGE154
 C6056    1      A Q_CAP_C0402-0.001UF,50V,10%,X7R,CH30106KB19    I46 @T6G_MB_LIB.T6G(SCH_1):PAGE154
 C6057    1      A Q_CAP_C0402-0.01UF,50V,10%,X7R,CH31006KB18    I47 @T6G_MB_LIB.T6G(SCH_1):PAGE154
 C6058    1      A Q_CAP_C0402-0.001UF,50V,10%,X7R,CH30106KB19    I49 @T6G_MB_LIB.T6G(SCH_1):PAGE154
 C6059    1      A Q_CAP_C0402-0.01UF,50V,10%,X7R,CH31006KB18    I50 @T6G_MB_LIB.T6G(SCH_1):PAGE154
 C6060    1      A Q_CAP_C0402-0.001UF,50V,10%,X7R,CH30106KB19    I52 @T6G_MB_LIB.T6G(SCH_1):PAGE154
 C6061    1      A Q_CAP_C0402-0.01UF,50V,10%,X7R,CH31006KB18    I53 @T6G_MB_LIB.T6G(SCH_1):PAGE154
 C6062    1      A Q_CAP_C0402-0.001UF,50V,10%,X7R,CH30106KB19    I55 @T6G_MB_LIB.T6G(SCH_1):PAGE154
 C6063    1      A Q_CAP_C0402-0.01UF,50V,10%,X7R,CH31006KB18    I56 @T6G_MB_LIB.T6G(SCH_1):PAGE154
 C6064    1      A Q_CAP_0402-0.1UF,25V,10%,X7R,CH4104K1B00    I58 @T6G_MB_LIB.T6G(SCH_1):PAGE154
 C6065    1      A Q_CAP_C0402-1UF,25V,10%,X6S,CH5104KEB02    I59 @T6G_MB_LIB.T6G(SCH_1):PAGE154
 C6066    1      A Q_CAP_C0603-22UF,6.3V,20%,X6S,CH6221ME900    I60 @T6G_MB_LIB.T6G(SCH_1):PAGE154
 C6069    1      A Q_CAP_C0402-0.001UF,50V,10%,X7R,CH30106KB19    I63 @T6G_MB_LIB.T6G(SCH_1):PAGE154
 C6079    1      A Q_CAP_C0603-22UF,6.3V,20%,X6S,CH6221ME900    I64 @T6G_MB_LIB.T6G(SCH_1):PAGE154
 C6078    1      A Q_CAP_C0402-1UF,25V,10%,X6S,CH5104KEB02    I65 @T6G_MB_LIB.T6G(SCH_1):PAGE154
 C6077    1      A Q_CAP_0402-0.1UF,25V,10%,X7R,CH4104K1B00    I66 @T6G_MB_LIB.T6G(SCH_1):PAGE154
 C6076    1      A Q_CAP_C0402-0.01UF,50V,10%,X7R,CH31006KB18    I68 @T6G_MB_LIB.T6G(SCH_1):PAGE154
 C6075    1      A Q_CAP_C0402-0.001UF,50V,10%,X7R,CH30106KB19    I69 @T6G_MB_LIB.T6G(SCH_1):PAGE154
 C6074    1      A Q_CAP_C0402-0.01UF,50V,10%,X7R,CH31006KB18    I71 @T6G_MB_LIB.T6G(SCH_1):PAGE154
 C6073    1      A Q_CAP_C0402-0.001UF,50V,10%,X7R,CH30106KB19    I73 @T6G_MB_LIB.T6G(SCH_1):PAGE154
 C6072    1      A Q_CAP_C0402-0.01UF,50V,10%,X7R,CH31006KB18    I74 @T6G_MB_LIB.T6G(SCH_1):PAGE154
 C6071    1      A Q_CAP_C0402-0.001UF,50V,10%,X7R,CH30106KB19    I75 @T6G_MB_LIB.T6G(SCH_1):PAGE154
 C6070    1      A Q_CAP_C0402-0.01UF,50V,10%,X7R,CH31006KB18    I76 @T6G_MB_LIB.T6G(SCH_1):PAGE154
 C6068    1      A Q_CAP_C0402-0.01UF,50V,10%,X7R,CH31006KB18    I78 @T6G_MB_LIB.T6G(SCH_1):PAGE154
 C6067    1      A Q_CAP_C0402-0.001UF,50V,10%,X7R,CH30106KB19    I79 @T6G_MB_LIB.T6G(SCH_1):PAGE154
 C6080    1      A Q_CAP_C0402-0.01UF,50V,10%,X7R,CH31006KB18    I81 @T6G_MB_LIB.T6G(SCH_1):PAGE154
 C6081    1      A Q_CAP_0402-0.1UF,25V,10%,X7R,CH4104K1B00    I82 @T6G_MB_LIB.T6G(SCH_1):PAGE154
 C6082    1      A Q_CAP_C0402-1UF,25V,10%,X6S,CH5104KEB02    I83 @T6G_MB_LIB.T6G(SCH_1):PAGE154
PC6022    1      A Q_CAP_C0402-100NF,50V,10%,X7R,CH4106K1B01    I23 @T6G_MB_LIB.T6G(SCH_1):PAGE380
PL6001    2      2 Q_INDUCTOR_SMLF-2.2UH,IND,CV-2280MZ15    I24 @T6G_MB_LIB.T6G(SCH_1):PAGE380
 PC852    2      B Q_CAP_0402-330PF,50V,10%,X7R,CH1336K1B02    I26 @T6G_MB_LIB.T6G(SCH_1):PAGE380
PR6008    2      B Q_RES_0402LF-10K,1%,1/16W,CHIP,CS31002FB08    I27 @T6G_MB_LIB.T6G(SCH_1):PAGE380
PC6024    1      A Q_CAP_C0805-22UF,4V,20%,X6S,CH622KMEA03    I28 @T6G_MB_LIB.T6G(SCH_1):PAGE380
PC6025    1      A Q_CAP_C0805-22UF,4V,20%,X6S,CH622KMEA03    I29 @T6G_MB_LIB.T6G(SCH_1):PAGE380
PC6026    1      A Q_CAP_C0805-22UF,4V,20%,X6S,CH622KMEA03    I32 @T6G_MB_LIB.T6G(SCH_1):PAGE380
PC6018    1      A Q_CAP_C0805-22UF,4V,20%,X6S,CH622KMEA03    I33 @T6G_MB_LIB.T6G(SCH_1):PAGE380
 L6004    1      1 Q_INDUCTOR_SMLF-BLM21PG221SN1D,IND,CX1PG221001    I20 @T6G_MB_LIB.T6G(SCH_1):PAGE157
 R1232    1      A Q_RES_0402LF-5.11K,1%,1/16W,CHIP,CS25112FB04   I179 @T6G_MB_LIB.T6G(SCH_1):PAGE263

P1V2_AUX_ADC @T6G_MB_LIB.T6G(SCH_1):P1V2_AUX_ADC
 R1245    1      A Q_RES_0402LF-0,5%,1/16W,EMPTY,CS00002JB13   I177 @T6G_MB_LIB.T6G(SCH_1):PAGE263
 R1251    1      A Q_RES_0402LF-0,5%,1/16W,CHIP,CS00002JB13   I178 @T6G_MB_LIB.T6G(SCH_1):PAGE263
 R1232    2      B Q_RES_0402LF-5.11K,1%,1/16W,CHIP,CS25112FB04   I179 @T6G_MB_LIB.T6G(SCH_1):PAGE263
 R1221    1      A Q_RES_0402LF-18K,1%,1/16W,CHIP,CS31802FB04   I243 @T6G_MB_LIB.T6G(SCH_1):PAGE263

P1V2_AUX_ADC_MAM @T6G_MB_LIB.T6G(SCH_1):P1V2_AUX_ADC_MAM
   U50    7   AIN2 MAX11617EEET-MAX11617EEE+T,SMLF,EMPTY,AL011617W00   I156 @T6G_MB_LIB.T6G(SCH_1):PAGE263
 C1078    1      A Q_CAP_0402-100PF,50V,5%,EMPTY,CH11006JB18   I173 @T6G_MB_LIB.T6G(SCH_1):PAGE263
 R1245    2      B Q_RES_0402LF-0,5%,1/16W,EMPTY,CS00002JB13   I177 @T6G_MB_LIB.T6G(SCH_1):PAGE263

P1V2_AUX_ADC_TIC @T6G_MB_LIB.T6G(SCH_1):P1V2_AUX_ADC_TIC
   U51   14    IN2 ADC128D818CIMTXNOPB-ADC128D818CIMTX/NOPB,SMLF,IC,AA   I142 @T6G_MB_LIB.T6G(SCH_1):PAGE263
 C1086    1      A Q_CAP_0402-0.1UF,25V,10%,X7R,CH4104K1B00   I175 @T6G_MB_LIB.T6G(SCH_1):PAGE263
 R1251    2      B Q_RES_0402LF-0,5%,1/16W,CHIP,CS00002JB13   I178 @T6G_MB_LIB.T6G(SCH_1):PAGE263

P1V2_AUX_CS @T6G_MB_LIB.T6G(SCH_1):P1V2_AUX_CS
PR6004    1      A Q_RES_0402LF-11.5K,1%,1/16W,CHIP,CS31152FB03     I6 @T6G_MB_LIB.T6G(SCH_1):PAGE380
PU6001    4     CS MPQ8626GDZ-MPQ8626GD-Z,SMLF,IC,AL008626000    I16 @T6G_MB_LIB.T6G(SCH_1):PAGE380

P1V2_AUX_ENABLE @T6G_MB_LIB.T6G(SCH_1):P1V2_AUX_ENABLE
PU6001    5     EN MPQ8626GDZ-MPQ8626GD-Z,SMLF,IC,AL008626000    I16 @T6G_MB_LIB.T6G(SCH_1):PAGE380
 R6240    2      B Q_RES_0402LF-0,5%,1/16W,CHIP,CS00002JB13    I40 @T6G_MB_LIB.T6G(SCH_1):PAGE380

P1V2_AUX_FB @T6G_MB_LIB.T6G(SCH_1):P1V2_AUX_FB
PU6001    6     FB MPQ8626GDZ-MPQ8626GD-Z,SMLF,IC,AL008626000    I16 @T6G_MB_LIB.T6G(SCH_1):PAGE380
PR6011    1      A Q_RES_0402LF-10K,1%,1/16W,CHIP,CS31002FB08    I21 @T6G_MB_LIB.T6G(SCH_1):PAGE380
 PC852    1      A Q_CAP_0402-330PF,50V,10%,X7R,CH1336K1B02    I26 @T6G_MB_LIB.T6G(SCH_1):PAGE380
PR6008    1      A Q_RES_0402LF-10K,1%,1/16W,CHIP,CS31002FB08    I27 @T6G_MB_LIB.T6G(SCH_1):PAGE380

P1V2_AUX_MODE @T6G_MB_LIB.T6G(SCH_1):P1V2_AUX_MODE
PR6005    2      B Q_RES_0402LF-60.4K,1%,1/16W,CHIP,CS36042FB04    I11 @T6G_MB_LIB.T6G(SCH_1):PAGE380
PU6001   12   MODE MPQ8626GDZ-MPQ8626GD-Z,SMLF,IC,AL008626000    I16 @T6G_MB_LIB.T6G(SCH_1):PAGE380

P1V2_AUX_REF @T6G_MB_LIB.T6G(SCH_1):P1V2_AUX_REF
PU6001    8 TRK_REF MPQ8626GDZ-MPQ8626GD-Z,SMLF,IC,AL008626000    I16 @T6G_MB_LIB.T6G(SCH_1):PAGE380
PC6016    1      A Q_CAP_0402-3300PF,50V,10%,X7R,TMP_QCH2336K1B12    I17 @T6G_MB_LIB.T6G(SCH_1):PAGE380

P1V2_AUX_VCC @T6G_MB_LIB.T6G(SCH_1):P1V2_AUX_VCC
PC6009    1      A Q_CAP_C0402-1UF,25V,10%,X6S,CH5104KEB02     I7 @T6G_MB_LIB.T6G(SCH_1):PAGE380
PU6001   13    VCC MPQ8626GDZ-MPQ8626GD-Z,SMLF,IC,AL008626000    I16 @T6G_MB_LIB.T6G(SCH_1):PAGE380
 R6245    2      B Q_RES_0402LF-0,5%,1/16W,CHIP,CS00002JB13    I38 @T6G_MB_LIB.T6G(SCH_1):PAGE380

P1V2_CPU0_USB2_DVDD12 @T6G_MB_LIB.T6G(SCH_1):P1V2_CPU0_USB2_DVDD12
 L6004    2      2 Q_INDUCTOR_SMLF-BLM21PG221SN1D,IND,CX1PG221001    I20 @T6G_MB_LIB.T6G(SCH_1):PAGE157
 C6105    1      A Q_CAP_C0805-10UF,25V,10%,X6S,CH6104KEA00    I36 @T6G_MB_LIB.T6G(SCH_1):PAGE157
 C6108    1      A Q_CAP_0402-0.1UF,25V,10%,X7R,CH4104K1B00    I39 @T6G_MB_LIB.T6G(SCH_1):PAGE157
 C6107    1      A Q_CAP_C0402-0.01UF,50V,10%,X7R,CH31006KB18    I40 @T6G_MB_LIB.T6G(SCH_1):PAGE157
 C6106    1      A Q_CAP_C0402-1PF,50V,0.05P,COG,CH-106T0B00    I41 @T6G_MB_LIB.T6G(SCH_1):PAGE157
 C6111    1      A Q_CAP_0402-0.1UF,25V,10%,X7R,CH4104K1B00    I42 @T6G_MB_LIB.T6G(SCH_1):PAGE157
 C6110    1      A Q_CAP_C0402-0.01UF,50V,10%,X7R,CH31006KB18    I43 @T6G_MB_LIB.T6G(SCH_1):PAGE157
 C6109    1      A Q_CAP_C0402-1PF,50V,0.05P,COG,CH-106T0B00    I44 @T6G_MB_LIB.T6G(SCH_1):PAGE157
 C6114    1      A Q_CAP_0402-0.1UF,25V,10%,X7R,CH4104K1B00    I45 @T6G_MB_LIB.T6G(SCH_1):PAGE157
 C6113    1      A Q_CAP_C0402-0.01UF,50V,10%,X7R,CH31006KB18    I46 @T6G_MB_LIB.T6G(SCH_1):PAGE157
 C6112    1      A Q_CAP_C0402-1PF,50V,0.05P,COG,CH-106T0B00    I47 @T6G_MB_LIB.T6G(SCH_1):PAGE157
 C6117    1      A Q_CAP_0402-0.1UF,25V,10%,X7R,CH4104K1B00    I48 @T6G_MB_LIB.T6G(SCH_1):PAGE157
 C6116    1      A Q_CAP_C0402-0.01UF,50V,10%,X7R,CH31006KB18    I49 @T6G_MB_LIB.T6G(SCH_1):PAGE157
 C6115    1      A Q_CAP_C0402-1PF,50V,0.05P,COG,CH-106T0B00    I50 @T6G_MB_LIB.T6G(SCH_1):PAGE157
 C6121    1      A Q_CAP_0402-0.1UF,25V,10%,X7R,CH4104K1B00    I51 @T6G_MB_LIB.T6G(SCH_1):PAGE157
 C6120    1      A Q_CAP_C0402-0.01UF,50V,10%,X7R,CH31006KB18    I52 @T6G_MB_LIB.T6G(SCH_1):PAGE157
 C6119    1      A Q_CAP_C0402-1PF,50V,0.05P,COG,CH-106T0B00    I53 @T6G_MB_LIB.T6G(SCH_1):PAGE157
 C6118    1      A Q_CAP_C0805-10UF,25V,10%,X6S,CH6104KEA00    I54 @T6G_MB_LIB.T6G(SCH_1):PAGE157
 U6002   13 VDD_13 TUSB8042AIRGCR-TUSB8042AIRGCR,SMLF,IC,AL008042000   I119 @T6G_MB_LIB.T6G(SCH_1):PAGE157
 U6002   51 VDD_51 TUSB8042AIRGCR-TUSB8042AIRGCR,SMLF,IC,AL008042000   I119 @T6G_MB_LIB.T6G(SCH_1):PAGE157
 U6002   57 VDD_57 TUSB8042AIRGCR-TUSB8042AIRGCR,SMLF,IC,AL008042000   I119 @T6G_MB_LIB.T6G(SCH_1):PAGE157
 R6267    2      B Q_RES_0402LF-0,5%,1/16W,CHIP,CS00002JB13   I122 @T6G_MB_LIB.T6G(SCH_1):PAGE157
 R6261    2      B Q_RES_0402LF-0,5%,1/16W,CHIP,CS00002JB13   I134 @T6G_MB_LIB.T6G(SCH_1):PAGE155
 R6266    2      B Q_RES_0402LF-0,5%,1/16W,CHIP,CS00002JB13   I136 @T6G_MB_LIB.T6G(SCH_1):PAGE155
 R6262    2      B Q_RES_0402LF-0,5%,1/16W,CHIP,CS00002JB13   I134 @T6G_MB_LIB.T6G(SCH_1):PAGE157
 R6268    2      B Q_RES_0402LF-0,5%,1/16W,CHIP,CS00002JB13   I149 @T6G_MB_LIB.T6G(SCH_1):PAGE155
 R6269    2      B Q_RES_0402LF-0,5%,1/16W,CHIP,CS00002JB13   I136 @T6G_MB_LIB.T6G(SCH_1):PAGE157
 R6263    2      B Q_RES_0402LF-0,5%,1/16W,CHIP,CS00002JB13   I155 @T6G_MB_LIB.T6G(SCH_1):PAGE155
 R6265    2      B Q_RES_0402LF-0,5%,1/16W,CHIP,CS00002JB13   I145 @T6G_MB_LIB.T6G(SCH_1):PAGE157
 R6259    1      A Q_RES_0402LF-0,5%,1/16W,CHIP,CS00002JB13   I166 @T6G_MB_LIB.T6G(SCH_1):PAGE155
 R6260    2      B Q_RES_0402LF-0,5%,1/16W,CHIP,CS00002JB13   I170 @T6G_MB_LIB.T6G(SCH_1):PAGE157

P1V2_CPU0_USB_DVDD12 @T6G_MB_LIB.T6G(SCH_1):P1V2_CPU0_USB_DVDD12
 U6001    1 DVDD12_1 CYUSB330468LTXI-CYUSB3304-68LTXI,SMLF,IC,AJ0330400A     I1 @T6G_MB_LIB.T6G(SCH_1):PAGE154
 U6001    3 DVDD12_2 CYUSB330468LTXI-CYUSB3304-68LTXI,SMLF,IC,AJ0330400A     I1 @T6G_MB_LIB.T6G(SCH_1):PAGE154
 U6001   27 DVDD12_3 CYUSB330468LTXI-CYUSB3304-68LTXI,SMLF,IC,AJ0330400A     I1 @T6G_MB_LIB.T6G(SCH_1):PAGE154
 U6001   19 VDD_EFUSE CYUSB330468LTXI-CYUSB3304-68LTXI,SMLF,IC,AJ0330400A     I1 @T6G_MB_LIB.T6G(SCH_1):PAGE154
 L6001    2      2 Q_INDUCTOR_SMLF-BLM21PG221SN1D,IND,CX1PG221001    I26 @T6G_MB_LIB.T6G(SCH_1):PAGE154
 C6030    1      A Q_CAP_C0603-22UF,6.3V,20%,X6S,CH6221ME900    I27 @T6G_MB_LIB.T6G(SCH_1):PAGE154
 C6031    1      A Q_CAP_C0402-1UF,25V,10%,X6S,CH5104KEB02    I29 @T6G_MB_LIB.T6G(SCH_1):PAGE154
 C6035    1      A Q_CAP_C0402-0.01UF,50V,10%,X7R,CH31006KB18    I31 @T6G_MB_LIB.T6G(SCH_1):PAGE154
 C6034    1      A Q_CAP_0402-0.1UF,25V,10%,X7R,CH4104K1B00    I32 @T6G_MB_LIB.T6G(SCH_1):PAGE154
 C6033    1      A Q_CAP_C0402-0.01UF,50V,10%,X7R,CH31006KB18    I34 @T6G_MB_LIB.T6G(SCH_1):PAGE154
 C6032    1      A Q_CAP_0402-0.1UF,25V,10%,X7R,CH4104K1B00    I35 @T6G_MB_LIB.T6G(SCH_1):PAGE154
 C6036    1      A Q_CAP_0402-0.1UF,25V,10%,X7R,CH4104K1B00    I37 @T6G_MB_LIB.T6G(SCH_1):PAGE154
 C6037    1      A Q_CAP_C0402-0.01UF,50V,10%,X7R,CH31006KB18    I38 @T6G_MB_LIB.T6G(SCH_1):PAGE154
 C6039    1      A Q_CAP_C0402-0.01UF,50V,10%,X7R,CH31006KB18    I40 @T6G_MB_LIB.T6G(SCH_1):PAGE154
 C6038    1      A Q_CAP_0402-0.1UF,25V,10%,X7R,CH4104K1B00    I41 @T6G_MB_LIB.T6G(SCH_1):PAGE154

P1V581_PDB_ADC @T6G_MB_LIB.T6G(SCH_1):P1V581_PDB_ADC
 R4568    1      A Q_RES_0402LF-4.7K,1%,1/16W,CHIP,CS24702FB06     I7 @T6G_MB_LIB.T6G(SCH_1):PAGE369
 R4567    2      B Q_RES_0402LF-5.11K,1%,1/16W,CHIP,CS25112FB04     I8 @T6G_MB_LIB.T6G(SCH_1):PAGE369
 R3688    1      A Q_RES_0402LF-0,5%,1/16W,CHIP,CS00002JB13    I41 @T6G_MB_LIB.T6G(SCH_1):PAGE369
 R3687    1      A Q_RES_0402LF-0,5%,1/16W,EMPTY,CS00002JB13    I42 @T6G_MB_LIB.T6G(SCH_1):PAGE369

P1V5_BAT @T6G_MB_LIB.T6G(SCH_1):P1V5_BAT
   U25 BN23 VDDBT_RTC_G GENOA_SP5-SOCKET6096_13568-001,SMLF,IO,DGA^6000030    I28 @T6G_MB_LIB.T6G(SCH_1):PAGE30
  R373    1      A Q_RES_0402LF-0,5%,1/16W,EMPTY,CS00002JB13    I52 @T6G_MB_LIB.T6G(SCH_1):PAGE57
 R1779    2      B Q_RES_0402LF-100,1%,1/16W,CHIP,CS11002FB07   I116 @T6G_MB_LIB.T6G(SCH_1):PAGE156
 C1567    1      A Q_CAP_C0402-1UF,25V,10%,X6S,CH5104KEB02   I125 @T6G_MB_LIB.T6G(SCH_1):PAGE156
 C5032    1      A Q_CAP_C0805-10UF,25V,10%,X6S,CH6104KEA00   I126 @T6G_MB_LIB.T6G(SCH_1):PAGE156
  JP12    2      2 CONN3_210HP1030BR1-CONN3_210-HP1-030BR1,THLF,IO,DFA   I128 @T6G_MB_LIB.T6G(SCH_1):PAGE156
 R5055    1      A Q_RES_0402LF-10K,5%,1/16W,CHIP,CS31002JB08   I427 @T6G_MB_LIB.T6G(SCH_1):PAGE27

P1V5_BAT_IN @T6G_MB_LIB.T6G(SCH_1):P1V5_BAT_IN
    U9    1     IN TPS71715DCKR-TPS71715DCKR,SMLF,EMPTY,AL071715001    I91 @T6G_MB_LIB.T6G(SCH_1):PAGE156
 R5051    2      B Q_RES_0402LF-0,5%,1/16W,EMPTY,CS00002JB13   I101 @T6G_MB_LIB.T6G(SCH_1):PAGE156
   C45    1      A Q_CAP_C0402-1UF,25V,10%,X6S,CH5104KEB02   I107 @T6G_MB_LIB.T6G(SCH_1):PAGE156
  C193    1      A Q_CAP_C0402-100NF,50V,10%,X7R,CH4106K1B01   I108 @T6G_MB_LIB.T6G(SCH_1):PAGE156
 R1777    1      A Q_RES_0402LF-1K,1%,1/16W,CHIP,CS21002FB06   I129 @T6G_MB_LIB.T6G(SCH_1):PAGE156
  U167    2    VIN NCP698SQ15T1G-NCP698SQ15T1G,SMLF,EMPTY,AL000698000   I130 @T6G_MB_LIB.T6G(SCH_1):PAGE156

P1V5_BAT_OUT @T6G_MB_LIB.T6G(SCH_1):P1V5_BAT_OUT
    U9    5    OUT TPS71715DCKR-TPS71715DCKR,SMLF,EMPTY,AL071715001    I91 @T6G_MB_LIB.T6G(SCH_1):PAGE156
 C1564    1      A Q_CAP_C0402-1UF,25V,10%,X6S,CH5104KEB02   I118 @T6G_MB_LIB.T6G(SCH_1):PAGE156
 R5053    1      A Q_RES_0402LF-1K,1%,1/16W,EMPTY,CS21002FB06   I120 @T6G_MB_LIB.T6G(SCH_1):PAGE156
  U167    3   VOUT NCP698SQ15T1G-NCP698SQ15T1G,SMLF,EMPTY,AL000698000   I130 @T6G_MB_LIB.T6G(SCH_1):PAGE156

P1V5_BAT_OUT_R @T6G_MB_LIB.T6G(SCH_1):P1V5_BAT_OUT_R
 R5053    2      B Q_RES_0402LF-1K,1%,1/16W,EMPTY,CS21002FB06   I120 @T6G_MB_LIB.T6G(SCH_1):PAGE156
 R5054    2      B Q_RES_0402LF-0,5%,1/16W,CHIP,CS00002JB13   I122 @T6G_MB_LIB.T6G(SCH_1):PAGE156
  JP12    1      1 CONN3_210HP1030BR1-CONN3_210-HP1-030BR1,THLF,IO,DFA   I128 @T6G_MB_LIB.T6G(SCH_1):PAGE156

P1V8_AUX @T6G_MB_LIB.T6G(SCH_1):P1V8_AUX
    U3    5    VCC SN74LVC1G07DBVR_SMLF-SN74LVC1G07DBVR,IC,AL1G0007024   I373 @T6G_MB_LIB.T6G(SCH_1):PAGE29
   C30    1      A Q_CAP_0402-0.1UF,25V,10%,X7R,CH4104K1B00   I379 @T6G_MB_LIB.T6G(SCH_1):PAGE29
  R943    1      A Q_RES_0402LF-4.7K,5%,1/16W,CHIP,CS24702JB10    I53 @T6G_MB_LIB.T6G(SCH_1):PAGE34
  C223    1      A Q_CAP_0402-0.1UF,25V,10%,X7R,CH4104K1B00    I11 @T6G_MB_LIB.T6G(SCH_1):PAGE77
   U29    5    VCC SN74LVC2G07DCKR_SMLF-SN74LVC2G07DCKR,IC,AL002G07006    I15 @T6G_MB_LIB.T6G(SCH_1):PAGE77
  C224    1      A Q_CAP_0402-0.1UF,25V,10%,X7R,CH4104K1B00    I19 @T6G_MB_LIB.T6G(SCH_1):PAGE77
   U40    5    VCC SN74LVC2G07DCKR_SMLF-SN74LVC2G07DCKR,IC,AL002G07006    I21 @T6G_MB_LIB.T6G(SCH_1):PAGE77
  C218    1      A Q_CAP_0402-0.1UF,25V,10%,X7R,CH4104K1B00    I24 @T6G_MB_LIB.T6G(SCH_1):PAGE143
   U82    5    VCC SN74LVC1G07DBVR_SMLF-SN74LVC1G07DBVR,IC,AL1G0007024    I26 @T6G_MB_LIB.T6G(SCH_1):PAGE143
  C219    1      A Q_CAP_0402-0.1UF,25V,10%,X7R,CH4104K1B00    I29 @T6G_MB_LIB.T6G(SCH_1):PAGE143
   U86    5    VCC SN74LVC1G07DBVR_SMLF-SN74LVC1G07DBVR,IC,AL1G0007024    I31 @T6G_MB_LIB.T6G(SCH_1):PAGE143
   U98    2  VREF1 PCA9306DP1-PCA9306DP1,SMLF,IC,AL009306K04    I27 @T6G_MB_LIB.T6G(SCH_1):PAGE346
 C1323    1      A Q_CAP_0402-0.1UF,25V,10%,X7R,CH4104K1B00    I28 @T6G_MB_LIB.T6G(SCH_1):PAGE346
 R1702    1      A Q_RES_0402LF-4.7K,5%,1/16W,CHIP,CS24702JB10    I43 @T6G_MB_LIB.T6G(SCH_1):PAGE346
 R1703    1      A Q_RES_0402LF-4.7K,5%,1/16W,CHIP,CS24702JB10    I45 @T6G_MB_LIB.T6G(SCH_1):PAGE346
 C1134    1      A Q_CAP_C0402-0.1UF,16V,10%,X7R,CH4103K1B08    I79 @T6G_MB_LIB.T6G(SCH_1):PAGE82
 C1132    1      A Q_CAP_C0402-0.1UF,16V,10%,X7R,CH4103K1B08    I80 @T6G_MB_LIB.T6G(SCH_1):PAGE82
 C1131    1      A Q_CAP_C0402-0.1UF,16V,10%,X7R,CH4103K1B08    I82 @T6G_MB_LIB.T6G(SCH_1):PAGE82
  C352    1      A Q_CAP_C0402-0.1UF,16V,10%,X7R,CH4103K1B08    I83 @T6G_MB_LIB.T6G(SCH_1):PAGE82
 C1128    1      A Q_CAP_C0402-0.1UF,16V,10%,X7R,CH4103K1B08    I84 @T6G_MB_LIB.T6G(SCH_1):PAGE82
 C1129    1      A Q_CAP_C0402-0.1UF,16V,10%,X7R,CH4103K1B08    I85 @T6G_MB_LIB.T6G(SCH_1):PAGE82
 C1126    1      A Q_CAP_C0402-0.1UF,16V,10%,X7R,CH4103K1B08    I86 @T6G_MB_LIB.T6G(SCH_1):PAGE82
 C1127    1      A Q_CAP_C0402-0.1UF,16V,10%,X7R,CH4103K1B08    I87 @T6G_MB_LIB.T6G(SCH_1):PAGE82
  R996    1      A Q_RES_0402LF-4.7K,5%,1/16W,CHIP,CS24702JB10    I22 @T6G_MB_LIB.T6G(SCH_1):PAGE83
  C552    1      A Q_CAP_0402-0.1UF,25V,10%,X7R,CH4104K1B00    I24 @T6G_MB_LIB.T6G(SCH_1):PAGE83
   U92    5    VCC SN74LVC1G07DBVR_SMLF-SN74LVC1G07DBVR,IC,AL1G0007024    I26 @T6G_MB_LIB.T6G(SCH_1):PAGE83
 R1261    1      A Q_RES_0402LF-10K,5%,1/16W,CHIP,CS31002JB08    I15 @T6G_MB_LIB.T6G(SCH_1):PAGE144
 R1262    1      A Q_RES_0402LF-10K,5%,1/16W,CHIP,CS31002JB08    I30 @T6G_MB_LIB.T6G(SCH_1):PAGE144
 R5071    1      A Q_RES_0402LF-100,1%,1/16W,CHIP,CS11002FB07    I34 @T6G_MB_LIB.T6G(SCH_1):PAGE144
 R1264    1      A Q_RES_0402LF-1K,1%,1/16W,EMPTY,CS21002FB06    I44 @T6G_MB_LIB.T6G(SCH_1):PAGE144
  R733    1      A Q_RES_0402LF-100,1%,1/16W,EMPTY,CS11002FB07    I50 @T6G_MB_LIB.T6G(SCH_1):PAGE144
   R22    1      A Q_RES_0402LF-100,1%,1/16W,CHIP,CS11002FB07    I54 @T6G_MB_LIB.T6G(SCH_1):PAGE144
 R6040    1      A Q_RES_0402LF-10K,5%,1/16W,CHIP,CS31002JB08    I70 @T6G_MB_LIB.T6G(SCH_1):PAGE144
 R1358    1      A Q_RES_0402LF-10K,5%,1/16W,EMPTY,CS31002JB08    I72 @T6G_MB_LIB.T6G(SCH_1):PAGE144
   U18  F20 VCCIO1_1 LCMXO3LF9400C5BG484C-LCMXO3LF-9400C-5BG484C,SMLF,IA   I141 @T6G_MB_LIB.T6G(SCH_1):PAGE81
   U18  J15 VCCIO1_2 LCMXO3LF9400C5BG484C-LCMXO3LF-9400C-5BG484C,SMLF,IA   I141 @T6G_MB_LIB.T6G(SCH_1):PAGE81
   U18  K15 VCCIO1_3 LCMXO3LF9400C5BG484C-LCMXO3LF-9400C-5BG484C,SMLF,IA   I141 @T6G_MB_LIB.T6G(SCH_1):PAGE81
   U18  L15 VCCIO1_4 LCMXO3LF9400C5BG484C-LCMXO3LF-9400C-5BG484C,SMLF,IA   I141 @T6G_MB_LIB.T6G(SCH_1):PAGE81
   U18  M15 VCCIO1_5 LCMXO3LF9400C5BG484C-LCMXO3LF-9400C-5BG484C,SMLF,IA   I141 @T6G_MB_LIB.T6G(SCH_1):PAGE81
   U18  M18 VCCIO1_6 LCMXO3LF9400C5BG484C-LCMXO3LF-9400C-5BG484C,SMLF,IA   I141 @T6G_MB_LIB.T6G(SCH_1):PAGE81
   U18  N15 VCCIO1_7 LCMXO3LF9400C5BG484C-LCMXO3LF-9400C-5BG484C,SMLF,IA   I141 @T6G_MB_LIB.T6G(SCH_1):PAGE81
   U18  P15 VCCIO1_8 LCMXO3LF9400C5BG484C-LCMXO3LF-9400C-5BG484C,SMLF,IA   I141 @T6G_MB_LIB.T6G(SCH_1):PAGE81
   U18  V20 VCCIO1_9 LCMXO3LF9400C5BG484C-LCMXO3LF-9400C-5BG484C,SMLF,IA   I141 @T6G_MB_LIB.T6G(SCH_1):PAGE81
   U18   F3 VCCIO5_1 LCMXO3LF9400C5BG484C-LCMXO3LF-9400C-5BG484C,SMLF,IA   I141 @T6G_MB_LIB.T6G(SCH_1):PAGE81
   U18   J8 VCCIO5_2 LCMXO3LF9400C5BG484C-LCMXO3LF-9400C-5BG484C,SMLF,IA   I141 @T6G_MB_LIB.T6G(SCH_1):PAGE81
   U18   K8 VCCIO5_3 LCMXO3LF9400C5BG484C-LCMXO3LF-9400C-5BG484C,SMLF,IA   I141 @T6G_MB_LIB.T6G(SCH_1):PAGE81
  R654    2      B Q_RES_0402LF-4.7K,5%,1/16W,CHIP,CS24702JB10    I64 @T6G_MB_LIB.T6G(SCH_1):PAGE82
 C1133    1      A Q_CAP_C0402-0.1UF,16V,10%,X7R,CH4103K1B08    I81 @T6G_MB_LIB.T6G(SCH_1):PAGE82
   U38    5    VCC SN74LVC1G11DCKR-SN74LVC1G11DCKR,SMLF,IC,ALLVC1G1000     I8 @T6G_MB_LIB.T6G(SCH_1):PAGE264
 R1457    1      A Q_RES_0402LF-10K,5%,1/16W,CHIP,CS31002JB08    I41 @T6G_MB_LIB.T6G(SCH_1):PAGE264
 R1452    1      A Q_RES_0402LF-10K,5%,1/16W,CHIP,CS31002JB08    I43 @T6G_MB_LIB.T6G(SCH_1):PAGE264
  C347    1      A Q_CAP_0402-0.1UF,25V,10%,X7R,CH4104K1B00    I47 @T6G_MB_LIB.T6G(SCH_1):PAGE264
PL6000    2      2 Q_INDUCTOR_SMLF-3.3UH/6A,IND,CV-3360MZ07    I25 @T6G_MB_LIB.T6G(SCH_1):PAGE315
PC6019    2      B Q_CAP_0402-330PF,50V,10%,X7R,CH1336K1B02    I26 @T6G_MB_LIB.T6G(SCH_1):PAGE315
PC6021    1      A Q_CAP_C0402-100NF,50V,10%,X7R,CH4106K1B01    I27 @T6G_MB_LIB.T6G(SCH_1):PAGE315
PR6007    2      B Q_RES_0402LF-20K,1%,1/16W,CHIP,CS32002FB06    I28 @T6G_MB_LIB.T6G(SCH_1):PAGE315
 PC865    1      A Q_CAP_C0805-22UF,4V,20%,X6S,CH622KMEA03    I29 @T6G_MB_LIB.T6G(SCH_1):PAGE315
 PC866    1      A Q_CAP_C0805-22UF,4V,20%,X6S,CH622KMEA03    I34 @T6G_MB_LIB.T6G(SCH_1):PAGE315
 PC867    1      A Q_CAP_C0805-22UF,4V,20%,X6S,CH622KMEA03    I36 @T6G_MB_LIB.T6G(SCH_1):PAGE315
 PC850    1      A Q_CAP_C0805-22UF,4V,20%,X6S,CH622KMEA03    I37 @T6G_MB_LIB.T6G(SCH_1):PAGE315
 R1493    1      A Q_RES_0402LF-10K,5%,1/16W,CHIP,CS31002JB08   I125 @T6G_MB_LIB.T6G(SCH_1):PAGE273
 R6504    1      A Q_RES_0402LF-10K,1%,1/16W,CHIP,CS31002FB08    I51 @T6G_MB_LIB.T6G(SCH_1):PAGE264
 R8018    1      A Q_RES_0402LF-0,5%,1/16W,CHIP,CS00002JB13    I84 @T6G_MB_LIB.T6G(SCH_1):PAGE144
 U8000    5    VCC NC7SB3157P6X-NC7SB3157P6X,SMLF,IC,ALSB3157000     I1 @T6G_MB_LIB.T6G(SCH_1):PAGE130
 C8007    1      A Q_CAP_0402-0.1UF,25V,10%,X7R,CH4104K1B00     I4 @T6G_MB_LIB.T6G(SCH_1):PAGE130
 R8035    1      A Q_RES_0402LF-4.7K,5%,1/16W,EMPTY,CS24702JB10    I11 @T6G_MB_LIB.T6G(SCH_1):PAGE130
 U6020   24    VCC TCA9548APWR-TCA9548APWR,SMLF,IC,AL009548K02     I1 @T6G_MB_LIB.T6G(SCH_1):PAGE378
 R6742    1      A Q_RES_0402LF-1K,1%,1/16W,EMPTY,CS21002FB06     I5 @T6G_MB_LIB.T6G(SCH_1):PAGE467
 R6743    1      A Q_RES_0402LF-1K,1%,1/16W,EMPTY,CS21002FB06     I6 @T6G_MB_LIB.T6G(SCH_1):PAGE467
 C7500    1      A Q_CAP_C0201-0.1UF,10V,10%,X7S,CH4102K6E00    I88 @T6G_MB_LIB.T6G(SCH_1):PAGE378
 R6770    1      A Q_RES_0201LF-4.7K,5%,1/20W,EMPTY,CS24701JE04    I96 @T6G_MB_LIB.T6G(SCH_1):PAGE378
 R6772    1      A Q_RES_0201LF-4.7K,5%,1/20W,EMPTY,CS24701JE04    I98 @T6G_MB_LIB.T6G(SCH_1):PAGE378
 R6771    1      A Q_RES_0201LF-4.7K,5%,1/20W,EMPTY,CS24701JE04   I100 @T6G_MB_LIB.T6G(SCH_1):PAGE378
  R842    1      A Q_RES_0201LF-4.7K,5%,1/20W,EMPTY,CS24701JE04     I4 @T6G_MB_LIB.T6G(SCH_1):PAGE377
  R843    1      A Q_RES_0201LF-4.7K,5%,1/20W,EMPTY,CS24701JE04     I5 @T6G_MB_LIB.T6G(SCH_1):PAGE377
  R844    1      A Q_RES_0201LF-4.7K,5%,1/20W,EMPTY,CS24701JE04     I9 @T6G_MB_LIB.T6G(SCH_1):PAGE377
  C365    1      A Q_CAP_C0201-0.1UF,10V,10%,X7S,CH4102K6E00    I55 @T6G_MB_LIB.T6G(SCH_1):PAGE377
   U22   24    VCC TCA9548APWR-TCA9548APWR,SMLF,IC,AL009548K02    I94 @T6G_MB_LIB.T6G(SCH_1):PAGE377
 R6860    1      A Q_RES_0402LF-1K,1%,1/16W,CHIP,CS21002FB06   I213 @T6G_MB_LIB.T6G(SCH_1):PAGE475
 R6861    1      A Q_RES_0402LF-1K,1%,1/16W,CHIP,CS21002FB06    I93 @T6G_MB_LIB.T6G(SCH_1):PAGE477
 R1237    1      A Q_RES_0402LF-5.11K,1%,1/16W,CHIP,CS25112FB04    I19 @T6G_MB_LIB.T6G(SCH_1):PAGE263
 R6146    1      A Q_RES_0402LF-1K,1%,1/16W,CHIP,CS21002FB06   I138 @T6G_MB_LIB.T6G(SCH_1):PAGE83
 R6147    1      A Q_RES_0402LF-1K,1%,1/16W,EMPTY,CS21002FB06   I140 @T6G_MB_LIB.T6G(SCH_1):PAGE83
 R6148    1      A Q_RES_0402LF-1K,1%,1/16W,EMPTY,CS21002FB06   I142 @T6G_MB_LIB.T6G(SCH_1):PAGE83

P1V8_AUX_ADC @T6G_MB_LIB.T6G(SCH_1):P1V8_AUX_ADC
 R1237    2      B Q_RES_0402LF-5.11K,1%,1/16W,CHIP,CS25112FB04    I19 @T6G_MB_LIB.T6G(SCH_1):PAGE263
 R1259    1      A Q_RES_0402LF-0,5%,1/16W,CHIP,CS00002JB13    I21 @T6G_MB_LIB.T6G(SCH_1):PAGE263
 R1258    1      A Q_RES_0402LF-0,5%,1/16W,EMPTY,CS00002JB13    I22 @T6G_MB_LIB.T6G(SCH_1):PAGE263
 R1229    1      A Q_RES_0402LF-18K,1%,1/16W,CHIP,CS31802FB04   I242 @T6G_MB_LIB.T6G(SCH_1):PAGE263

P1V8_AUX_ADC_MAM @T6G_MB_LIB.T6G(SCH_1):P1V8_AUX_ADC_MAM
 R1258    2      B Q_RES_0402LF-0,5%,1/16W,EMPTY,CS00002JB13    I22 @T6G_MB_LIB.T6G(SCH_1):PAGE263
 C1084    1      A Q_CAP_0402-100PF,50V,5%,EMPTY,CH11006JB18    I77 @T6G_MB_LIB.T6G(SCH_1):PAGE263
   U50    6   AIN1 MAX11617EEET-MAX11617EEE+T,SMLF,EMPTY,AL011617W00   I156 @T6G_MB_LIB.T6G(SCH_1):PAGE263

P1V8_AUX_ADC_TIC @T6G_MB_LIB.T6G(SCH_1):P1V8_AUX_ADC_TIC
 R1259    2      B Q_RES_0402LF-0,5%,1/16W,CHIP,CS00002JB13    I21 @T6G_MB_LIB.T6G(SCH_1):PAGE263
 C1092    1      A Q_CAP_0402-0.1UF,25V,10%,X7R,CH4104K1B00    I76 @T6G_MB_LIB.T6G(SCH_1):PAGE263
   U51   15    IN1 ADC128D818CIMTXNOPB-ADC128D818CIMTX/NOPB,SMLF,IC,AA   I142 @T6G_MB_LIB.T6G(SCH_1):PAGE263

P1V8_AUX_CS @T6G_MB_LIB.T6G(SCH_1):P1V8_AUX_CS
PR6003    1      A Q_RES_0402LF-10K,1%,1/16W,CHIP,CS31002FB08    I12 @T6G_MB_LIB.T6G(SCH_1):PAGE315
PU6000    4     CS MPQ8626GDZ-MPQ8626GD-Z,SMLF,IC,AL008626000    I18 @T6G_MB_LIB.T6G(SCH_1):PAGE315

P1V8_AUX_ENABLE @T6G_MB_LIB.T6G(SCH_1):P1V8_AUX_ENABLE
PU6000    5     EN MPQ8626GDZ-MPQ8626GD-Z,SMLF,IC,AL008626000    I18 @T6G_MB_LIB.T6G(SCH_1):PAGE315
 R6119    2      B Q_RES_0402LF-0,5%,1/16W,CHIP,CS00002JB13    I40 @T6G_MB_LIB.T6G(SCH_1):PAGE315
  C345    1      A Q_CAP_0402-0.1UF,25V,10%,EMPTY,CH4104K1B00    I41 @T6G_MB_LIB.T6G(SCH_1):PAGE315

P1V8_AUX_FB @T6G_MB_LIB.T6G(SCH_1):P1V8_AUX_FB
PU6000    6     FB MPQ8626GDZ-MPQ8626GD-Z,SMLF,IC,AL008626000    I18 @T6G_MB_LIB.T6G(SCH_1):PAGE315
PR6010    1      A Q_RES_0402LF-10K,1%,1/16W,CHIP,CS31002FB08    I23 @T6G_MB_LIB.T6G(SCH_1):PAGE315
PC6019    1      A Q_CAP_0402-330PF,50V,10%,X7R,CH1336K1B02    I26 @T6G_MB_LIB.T6G(SCH_1):PAGE315
PR6007    1      A Q_RES_0402LF-20K,1%,1/16W,CHIP,CS32002FB06    I28 @T6G_MB_LIB.T6G(SCH_1):PAGE315

P1V8_AUX_MODE @T6G_MB_LIB.T6G(SCH_1):P1V8_AUX_MODE
PR6006    2      B Q_RES_0402LF-60.4K,1%,1/16W,CHIP,CS36042FB04    I15 @T6G_MB_LIB.T6G(SCH_1):PAGE315
PU6000   12   MODE MPQ8626GDZ-MPQ8626GD-Z,SMLF,IC,AL008626000    I18 @T6G_MB_LIB.T6G(SCH_1):PAGE315

P1V8_AUX_REF @T6G_MB_LIB.T6G(SCH_1):P1V8_AUX_REF
PU6000    8 TRK_REF MPQ8626GDZ-MPQ8626GD-Z,SMLF,IC,AL008626000    I18 @T6G_MB_LIB.T6G(SCH_1):PAGE315
 PC384    1      A Q_CAP_0402-3300PF,50V,10%,X7R,TMP_QCH2336K1B12    I21 @T6G_MB_LIB.T6G(SCH_1):PAGE315

P1V8_AUX_VCC @T6G_MB_LIB.T6G(SCH_1):P1V8_AUX_VCC
 R6242    2      B Q_RES_0402LF-0,5%,1/16W,CHIP,CS00002JB13     I2 @T6G_MB_LIB.T6G(SCH_1):PAGE315
PC6008    1      A Q_CAP_C0402-1UF,25V,10%,X6S,CH5104KEB02    I13 @T6G_MB_LIB.T6G(SCH_1):PAGE315
PU6000   13    VCC MPQ8626GDZ-MPQ8626GD-Z,SMLF,IC,AL008626000    I18 @T6G_MB_LIB.T6G(SCH_1):PAGE315

P1V8_CPU0_RT0_1A @T6G_MB_LIB.T6G(SCH_1):P1V8_CPU0_RT0_1A
 U6010 BV20 PWR_1A_1 PT5161LRS-PT5161LRS,SMLF,IC,AJ051610U03     I3 @T6G_MB_LIB.T6G(SCH_1):PAGE386
 U6010 CE17 PWR_1A_2 PT5161LRS-PT5161LRS,SMLF,IC,AJ051610U03     I3 @T6G_MB_LIB.T6G(SCH_1):PAGE386
 U6010 CE20 PWR_1A_3 PT5161LRS-PT5161LRS,SMLF,IC,AJ051610U03     I3 @T6G_MB_LIB.T6G(SCH_1):PAGE386
 U6010 CM17 PWR_1A_4 PT5161LRS-PT5161LRS,SMLF,IC,AJ051610U03     I3 @T6G_MB_LIB.T6G(SCH_1):PAGE386
 U6010 CM20 PWR_1A_5 PT5161LRS-PT5161LRS,SMLF,IC,AJ051610U03     I3 @T6G_MB_LIB.T6G(SCH_1):PAGE386
  R952    2      B Q_RES_0402LF-0,5%,1/16W,EMPTY,CS00002JB13     I4 @T6G_MB_LIB.T6G(SCH_1):PAGE388
  R951    2      B Q_RES_0402LF-0,5%,1/16W,EMPTY,CS00002JB13     I5 @T6G_MB_LIB.T6G(SCH_1):PAGE388
   L11    2      2 Q_INDUCTOR_SMLF-BLM21SN300SN1D/5A,IND,CX300SN1000    I12 @T6G_MB_LIB.T6G(SCH_1):PAGE388
  C503    1      A Q_CAP_C0805-100UF,4V,20%,X6S,CH710KMEA01    I13 @T6G_MB_LIB.T6G(SCH_1):PAGE388
  C505    1      A Q_CAP_C0402-22UF,4V,20%,X6S,CH622KMEB02    I14 @T6G_MB_LIB.T6G(SCH_1):PAGE388
  C507    1      A Q_CAP_C0402-10UF,6.3V,20%,X6S,CH6101MEB01    I17 @T6G_MB_LIB.T6G(SCH_1):PAGE388
  C510    1      A Q_CAP_0402-4.7UF,6.3V,20%,X6S,CH5471MEB01    I18 @T6G_MB_LIB.T6G(SCH_1):PAGE388
  C512    1      A Q_CAP_0201-1UF,4V,20%,X6S,CH-10KMEE00    I19 @T6G_MB_LIB.T6G(SCH_1):PAGE388
  C514    1      A Q_CAP_0201-1UF,4V,20%,X6S,CH-10KMEE00    I22 @T6G_MB_LIB.T6G(SCH_1):PAGE388
  C515    1      A Q_CAP_C0201-0.1UF,10V,10%,X7S,CH4102K6E00    I23 @T6G_MB_LIB.T6G(SCH_1):PAGE388
  C517    1      A Q_CAP_C0201-0.1UF,10V,10%,X7S,CH4102K6E00    I27 @T6G_MB_LIB.T6G(SCH_1):PAGE388
  C519    1      A Q_CAP_C0201-0.1UF,10V,10%,X7S,CH4102K6E00    I28 @T6G_MB_LIB.T6G(SCH_1):PAGE388
  C520    1      A Q_CAP_C0201-0.1UF,10V,10%,X7S,CH4102K6E00    I29 @T6G_MB_LIB.T6G(SCH_1):PAGE388

P1V8_CPU0_RT0_1A_1D @T6G_MB_LIB.T6G(SCH_1):P1V8_CPU0_RT0_1A_1D
 U6010 BV17 PWR_1D PT5161LRS-PT5161LRS,SMLF,IC,AJ051610U03     I3 @T6G_MB_LIB.T6G(SCH_1):PAGE386
  R952    1      A Q_RES_0402LF-0,5%,1/16W,EMPTY,CS00002JB13     I4 @T6G_MB_LIB.T6G(SCH_1):PAGE388
  R951    1      A Q_RES_0402LF-0,5%,1/16W,EMPTY,CS00002JB13     I5 @T6G_MB_LIB.T6G(SCH_1):PAGE388
  C513    1      A Q_CAP_0201-1UF,4V,20%,X6S,CH-10KMEE00     I8 @T6G_MB_LIB.T6G(SCH_1):PAGE388
  C516    1      A Q_CAP_C0201-0.1UF,10V,10%,X7S,CH4102K6E00     I9 @T6G_MB_LIB.T6G(SCH_1):PAGE388
   L26    2      2 Q_INDUCTOR_SMLF-BLM15PD121SN1D/1300MA,IND,CX5PD121A    I88 @T6G_MB_LIB.T6G(SCH_1):PAGE388
  R960    2      B Q_RES_0402LF-0,5%,1/16W,EMPTY,CS00002JB13    I89 @T6G_MB_LIB.T6G(SCH_1):PAGE388

P1V8_CPU0_RT1_1A @T6G_MB_LIB.T6G(SCH_1):P1V8_CPU0_RT1_1A
 U6011 BV20 PWR_1A_1 PT5161LRS-PT5161LRS,SMLF,IC,AJ051610U03     I5 @T6G_MB_LIB.T6G(SCH_1):PAGE409
 U6011 CE17 PWR_1A_2 PT5161LRS-PT5161LRS,SMLF,IC,AJ051610U03     I5 @T6G_MB_LIB.T6G(SCH_1):PAGE409
 U6011 CE20 PWR_1A_3 PT5161LRS-PT5161LRS,SMLF,IC,AJ051610U03     I5 @T6G_MB_LIB.T6G(SCH_1):PAGE409
 U6011 CM17 PWR_1A_4 PT5161LRS-PT5161LRS,SMLF,IC,AJ051610U03     I5 @T6G_MB_LIB.T6G(SCH_1):PAGE409
 U6011 CM20 PWR_1A_5 PT5161LRS-PT5161LRS,SMLF,IC,AJ051610U03     I5 @T6G_MB_LIB.T6G(SCH_1):PAGE409
 R1003    2      B Q_RES_0402LF-0,5%,1/16W,EMPTY,CS00002JB13     I2 @T6G_MB_LIB.T6G(SCH_1):PAGE411
 R1002    2      B Q_RES_0402LF-0,5%,1/16W,EMPTY,CS00002JB13     I4 @T6G_MB_LIB.T6G(SCH_1):PAGE411
   L13    2      2 Q_INDUCTOR_SMLF-BLM21SN300SN1D/5A,IND,CX300SN1000    I11 @T6G_MB_LIB.T6G(SCH_1):PAGE411
  C588    1      A Q_CAP_C0805-100UF,4V,20%,X6S,CH710KMEA01    I12 @T6G_MB_LIB.T6G(SCH_1):PAGE411
  C590    1      A Q_CAP_C0402-22UF,4V,20%,X6S,CH622KMEB02    I15 @T6G_MB_LIB.T6G(SCH_1):PAGE411
  C595    1      A Q_CAP_C0402-10UF,6.3V,20%,X6S,CH6101MEB01    I16 @T6G_MB_LIB.T6G(SCH_1):PAGE411
  C594    1      A Q_CAP_0402-4.7UF,6.3V,20%,X6S,CH5471MEB01    I19 @T6G_MB_LIB.T6G(SCH_1):PAGE411
  C597    1      A Q_CAP_0201-1UF,4V,20%,X6S,CH-10KMEE00    I20 @T6G_MB_LIB.T6G(SCH_1):PAGE411
  C599    1      A Q_CAP_0201-1UF,4V,20%,X6S,CH-10KMEE00    I21 @T6G_MB_LIB.T6G(SCH_1):PAGE411
  C600    1      A Q_CAP_C0201-0.1UF,10V,10%,X7S,CH4102K6E00    I25 @T6G_MB_LIB.T6G(SCH_1):PAGE411
  C602    1      A Q_CAP_C0201-0.1UF,10V,10%,X7S,CH4102K6E00    I26 @T6G_MB_LIB.T6G(SCH_1):PAGE411
  C603    1      A Q_CAP_C0201-0.1UF,10V,10%,X7S,CH4102K6E00    I27 @T6G_MB_LIB.T6G(SCH_1):PAGE411
  C606    1      A Q_CAP_C0201-0.1UF,10V,10%,X7S,CH4102K6E00    I28 @T6G_MB_LIB.T6G(SCH_1):PAGE411

P1V8_CPU0_RT1_1A_1D @T6G_MB_LIB.T6G(SCH_1):P1V8_CPU0_RT1_1A_1D
 U6011 BV17 PWR_1D PT5161LRS-PT5161LRS,SMLF,IC,AJ051610U03     I5 @T6G_MB_LIB.T6G(SCH_1):PAGE409
 R1003    1      A Q_RES_0402LF-0,5%,1/16W,EMPTY,CS00002JB13     I2 @T6G_MB_LIB.T6G(SCH_1):PAGE411
 R1002    1      A Q_RES_0402LF-0,5%,1/16W,EMPTY,CS00002JB13     I4 @T6G_MB_LIB.T6G(SCH_1):PAGE411
  C598    1      A Q_CAP_0201-1UF,4V,20%,X6S,CH-10KMEE00     I5 @T6G_MB_LIB.T6G(SCH_1):PAGE411
  C601    1      A Q_CAP_C0201-0.1UF,10V,10%,X7S,CH4102K6E00     I7 @T6G_MB_LIB.T6G(SCH_1):PAGE411
   L28    2      2 Q_INDUCTOR_SMLF-BLM15PD121SN1D/1300MA,IND,CX5PD121A    I88 @T6G_MB_LIB.T6G(SCH_1):PAGE411
 R1008    2      B Q_RES_0402LF-0,5%,1/16W,EMPTY,CS00002JB13    I89 @T6G_MB_LIB.T6G(SCH_1):PAGE411

P1V8_CPU0_RT2_1A @T6G_MB_LIB.T6G(SCH_1):P1V8_CPU0_RT2_1A
 U6012 BV20 PWR_1A_1 PT5161LRS-PT5161LRS,SMLF,IC,AJ051610U03     I6 @T6G_MB_LIB.T6G(SCH_1):PAGE420
 U6012 CE17 PWR_1A_2 PT5161LRS-PT5161LRS,SMLF,IC,AJ051610U03     I6 @T6G_MB_LIB.T6G(SCH_1):PAGE420
 U6012 CE20 PWR_1A_3 PT5161LRS-PT5161LRS,SMLF,IC,AJ051610U03     I6 @T6G_MB_LIB.T6G(SCH_1):PAGE420
 U6012 CM17 PWR_1A_4 PT5161LRS-PT5161LRS,SMLF,IC,AJ051610U03     I6 @T6G_MB_LIB.T6G(SCH_1):PAGE420
 U6012 CM20 PWR_1A_5 PT5161LRS-PT5161LRS,SMLF,IC,AJ051610U03     I6 @T6G_MB_LIB.T6G(SCH_1):PAGE420
 R1046    2      B Q_RES_0402LF-0,5%,1/16W,EMPTY,CS00002JB13     I4 @T6G_MB_LIB.T6G(SCH_1):PAGE422
 R1045    2      B Q_RES_0402LF-0,5%,1/16W,EMPTY,CS00002JB13     I5 @T6G_MB_LIB.T6G(SCH_1):PAGE422
  C666    1      A Q_CAP_C0805-100UF,4V,20%,X6S,CH710KMEA01     I6 @T6G_MB_LIB.T6G(SCH_1):PAGE422
  C668    1      A Q_CAP_C0402-22UF,4V,20%,X6S,CH622KMEB02     I7 @T6G_MB_LIB.T6G(SCH_1):PAGE422
  C671    1      A Q_CAP_C0402-10UF,6.3V,20%,X6S,CH6101MEB01    I12 @T6G_MB_LIB.T6G(SCH_1):PAGE422
  C670    1      A Q_CAP_0402-4.7UF,6.3V,20%,X6S,CH5471MEB01    I13 @T6G_MB_LIB.T6G(SCH_1):PAGE422
  C673    1      A Q_CAP_0201-1UF,4V,20%,X6S,CH-10KMEE00    I15 @T6G_MB_LIB.T6G(SCH_1):PAGE422
  C677    1      A Q_CAP_0201-1UF,4V,20%,X6S,CH-10KMEE00    I16 @T6G_MB_LIB.T6G(SCH_1):PAGE422
  C774    1      A Q_CAP_C0201-0.1UF,10V,10%,X7S,CH4102K6E00    I17 @T6G_MB_LIB.T6G(SCH_1):PAGE422
  C776    1      A Q_CAP_C0201-0.1UF,10V,10%,X7S,CH4102K6E00    I18 @T6G_MB_LIB.T6G(SCH_1):PAGE422
  C777    1      A Q_CAP_C0201-0.1UF,10V,10%,X7S,CH4102K6E00    I19 @T6G_MB_LIB.T6G(SCH_1):PAGE422
  C778    1      A Q_CAP_C0201-0.1UF,10V,10%,X7S,CH4102K6E00    I20 @T6G_MB_LIB.T6G(SCH_1):PAGE422
   L18    2      2 Q_INDUCTOR_SMLF-BLM21SN300SN1D/5A,IND,CX300SN1000    I23 @T6G_MB_LIB.T6G(SCH_1):PAGE422

P1V8_CPU0_RT2_1A_1D @T6G_MB_LIB.T6G(SCH_1):P1V8_CPU0_RT2_1A_1D
 U6012 BV17 PWR_1D PT5161LRS-PT5161LRS,SMLF,IC,AJ051610U03     I6 @T6G_MB_LIB.T6G(SCH_1):PAGE420
 R1046    1      A Q_RES_0402LF-0,5%,1/16W,EMPTY,CS00002JB13     I4 @T6G_MB_LIB.T6G(SCH_1):PAGE422
 R1045    1      A Q_RES_0402LF-0,5%,1/16W,EMPTY,CS00002JB13     I5 @T6G_MB_LIB.T6G(SCH_1):PAGE422
  C676    1      A Q_CAP_0201-1UF,4V,20%,X6S,CH-10KMEE00     I9 @T6G_MB_LIB.T6G(SCH_1):PAGE422
  C775    1      A Q_CAP_C0201-0.1UF,10V,10%,X7S,CH4102K6E00    I10 @T6G_MB_LIB.T6G(SCH_1):PAGE422
   L29    2      2 Q_INDUCTOR_SMLF-BLM15PD121SN1D/1300MA,IND,CX5PD121A    I88 @T6G_MB_LIB.T6G(SCH_1):PAGE422
 R1050    2      B Q_RES_0402LF-0,5%,1/16W,EMPTY,CS00002JB13    I89 @T6G_MB_LIB.T6G(SCH_1):PAGE422

P1V8_CPU0_RT3_1A @T6G_MB_LIB.T6G(SCH_1):P1V8_CPU0_RT3_1A
 U6013 BV20 PWR_1A_1 PT5161LRS-PT5161LRS,SMLF,IC,AJ051610U03     I6 @T6G_MB_LIB.T6G(SCH_1):PAGE431
 U6013 CE17 PWR_1A_2 PT5161LRS-PT5161LRS,SMLF,IC,AJ051610U03     I6 @T6G_MB_LIB.T6G(SCH_1):PAGE431
 U6013 CE20 PWR_1A_3 PT5161LRS-PT5161LRS,SMLF,IC,AJ051610U03     I6 @T6G_MB_LIB.T6G(SCH_1):PAGE431
 U6013 CM17 PWR_1A_4 PT5161LRS-PT5161LRS,SMLF,IC,AJ051610U03     I6 @T6G_MB_LIB.T6G(SCH_1):PAGE431
 U6013 CM20 PWR_1A_5 PT5161LRS-PT5161LRS,SMLF,IC,AJ051610U03     I6 @T6G_MB_LIB.T6G(SCH_1):PAGE431
 R1087    2      B Q_RES_0402LF-0,5%,1/16W,EMPTY,CS00002JB13     I1 @T6G_MB_LIB.T6G(SCH_1):PAGE433
 R1086    2      B Q_RES_0402LF-0,5%,1/16W,EMPTY,CS00002JB13     I2 @T6G_MB_LIB.T6G(SCH_1):PAGE433
   L22    2      2 Q_INDUCTOR_SMLF-BLM21SN300SN1D/5A,IND,CX300SN1000    I10 @T6G_MB_LIB.T6G(SCH_1):PAGE433
  C991    1      A Q_CAP_C0805-100UF,4V,20%,X6S,CH710KMEA01    I12 @T6G_MB_LIB.T6G(SCH_1):PAGE433
  C993    1      A Q_CAP_C0402-22UF,4V,20%,X6S,CH622KMEB02    I13 @T6G_MB_LIB.T6G(SCH_1):PAGE433
  C995    1      A Q_CAP_C0402-10UF,6.3V,20%,X6S,CH6101MEB01    I15 @T6G_MB_LIB.T6G(SCH_1):PAGE433
  C996    1      A Q_CAP_0402-4.7UF,6.3V,20%,X6S,CH5471MEB01    I16 @T6G_MB_LIB.T6G(SCH_1):PAGE433
  C998    1      A Q_CAP_0201-1UF,4V,20%,X6S,CH-10KMEE00    I17 @T6G_MB_LIB.T6G(SCH_1):PAGE433
 C1000    1      A Q_CAP_0201-1UF,4V,20%,X6S,CH-10KMEE00    I24 @T6G_MB_LIB.T6G(SCH_1):PAGE433
 C1001    1      A Q_CAP_C0201-0.1UF,10V,10%,X7S,CH4102K6E00    I25 @T6G_MB_LIB.T6G(SCH_1):PAGE433
 C1003    1      A Q_CAP_C0201-0.1UF,10V,10%,X7S,CH4102K6E00    I26 @T6G_MB_LIB.T6G(SCH_1):PAGE433
 C1004    1      A Q_CAP_C0201-0.1UF,10V,10%,X7S,CH4102K6E00    I27 @T6G_MB_LIB.T6G(SCH_1):PAGE433
 C1005    1      A Q_CAP_C0201-0.1UF,10V,10%,X7S,CH4102K6E00    I28 @T6G_MB_LIB.T6G(SCH_1):PAGE433

P1V8_CPU0_RT3_1A_1D @T6G_MB_LIB.T6G(SCH_1):P1V8_CPU0_RT3_1A_1D
 U6013 BV17 PWR_1D PT5161LRS-PT5161LRS,SMLF,IC,AJ051610U03     I6 @T6G_MB_LIB.T6G(SCH_1):PAGE431
 R1087    1      A Q_RES_0402LF-0,5%,1/16W,EMPTY,CS00002JB13     I1 @T6G_MB_LIB.T6G(SCH_1):PAGE433
 R1086    1      A Q_RES_0402LF-0,5%,1/16W,EMPTY,CS00002JB13     I2 @T6G_MB_LIB.T6G(SCH_1):PAGE433
  C999    1      A Q_CAP_0201-1UF,4V,20%,X6S,CH-10KMEE00     I5 @T6G_MB_LIB.T6G(SCH_1):PAGE433
 C1002    1      A Q_CAP_C0201-0.1UF,10V,10%,X7S,CH4102K6E00     I6 @T6G_MB_LIB.T6G(SCH_1):PAGE433
   L30    2      2 Q_INDUCTOR_SMLF-BLM15PD121SN1D/1300MA,IND,CX5PD121A    I88 @T6G_MB_LIB.T6G(SCH_1):PAGE433
 R1093    2      B Q_RES_0402LF-0,5%,1/16W,EMPTY,CS00002JB13    I89 @T6G_MB_LIB.T6G(SCH_1):PAGE433

P1V8_CPU0_RT_1D @T6G_MB_LIB.T6G(SCH_1):P1V8_CPU0_RT_1D
 R1105    1      A Q_RES_0201LF-4.7K,5%,1/20W,EMPTY,CS24701JE04     I5 @T6G_MB_LIB.T6G(SCH_1):PAGE430
   U11    8    VCC M24M02DRMN6TP-M24M02-DRMN6TP,SMLF,IC,AKE33Z00600     I3 @T6G_MB_LIB.T6G(SCH_1):PAGE387
   U15    8    VCC M24M02DRMN6TP-M24M02-DRMN6TP,SMLF,IC,AKE33Z00600     I5 @T6G_MB_LIB.T6G(SCH_1):PAGE410
   U16    8    VCC M24M02DRMN6TP-M24M02-DRMN6TP,SMLF,IC,AKE33Z00600     I5 @T6G_MB_LIB.T6G(SCH_1):PAGE421
   U17    8    VCC M24M02DRMN6TP-M24M02-DRMN6TP,SMLF,IC,AKE33Z00600     I5 @T6G_MB_LIB.T6G(SCH_1):PAGE432
PC6515    2      B Q_CAP_0402-150PF,50V,5%,NPO,TMP_QCH11506JB08    I34 @T6G_MB_LIB.T6G(SCH_1):PAGE469
PR6505    2      B Q_RES_0402LF-20K,1%,1/16W,CHIP,CS32002FB06    I35 @T6G_MB_LIB.T6G(SCH_1):PAGE469
PL6501    2      2 Q_INDUCTOR_SMLF-1UH,IND,CV-10U0MZ01    I36 @T6G_MB_LIB.T6G(SCH_1):PAGE469
PC6508    1      A Q_CAP_C0805-22UF,4V,20%,X6S,CH622KMEA03    I38 @T6G_MB_LIB.T6G(SCH_1):PAGE469
PC6509    1      A Q_CAP_C0805-22UF,4V,20%,X6S,CH622KMEA03    I39 @T6G_MB_LIB.T6G(SCH_1):PAGE469
PC6510    1      A Q_CAP_C0805-22UF,4V,20%,X6S,CH622KMEA03    I40 @T6G_MB_LIB.T6G(SCH_1):PAGE469
PC6511    1      A Q_CAP_C0805-22UF,4V,20%,X6S,CH622KMEA03    I44 @T6G_MB_LIB.T6G(SCH_1):PAGE469
PC6513    1      A Q_CAPP_SMLF-390UF,2.5V,20%,ALUM,CC7390JMZ13    I46 @T6G_MB_LIB.T6G(SCH_1):PAGE469
PC6805    1      A Q_CAPP_SMLF-390UF,2.5V,20%,ALUM,CC7390JMZ13    I48 @T6G_MB_LIB.T6G(SCH_1):PAGE469
PC6514    1      A Q_CAP_0402-0.1UF,25V,10%,X7R,CH4104K1B00    I49 @T6G_MB_LIB.T6G(SCH_1):PAGE469
PC6512    1      A Q_CAP_C0805-22UF,4V,20%,X6S,CH622KMEA03    I52 @T6G_MB_LIB.T6G(SCH_1):PAGE469
 R6762    1      A Q_RES_0201LF-1K,1%,1/20W,CHIP,CS21001FE07    I77 @T6G_MB_LIB.T6G(SCH_1):PAGE378
 R6763    1      A Q_RES_0201LF-1K,1%,1/20W,CHIP,CS21001FE07    I78 @T6G_MB_LIB.T6G(SCH_1):PAGE378
 R6764    1      A Q_RES_0201LF-1K,1%,1/20W,CHIP,CS21001FE07    I79 @T6G_MB_LIB.T6G(SCH_1):PAGE378
 R6765    1      A Q_RES_0201LF-1K,1%,1/20W,CHIP,CS21001FE07    I80 @T6G_MB_LIB.T6G(SCH_1):PAGE378
 R6767    1      A Q_RES_0201LF-1K,1%,1/20W,CHIP,CS21001FE07    I82 @T6G_MB_LIB.T6G(SCH_1):PAGE378
 R6766    1      A Q_RES_0201LF-1K,1%,1/20W,CHIP,CS21001FE07    I83 @T6G_MB_LIB.T6G(SCH_1):PAGE378
 R6768    1      A Q_RES_0201LF-1K,1%,1/20W,CHIP,CS21001FE07    I84 @T6G_MB_LIB.T6G(SCH_1):PAGE378
 R6769    1      A Q_RES_0201LF-1K,1%,1/20W,CHIP,CS21001FE07    I85 @T6G_MB_LIB.T6G(SCH_1):PAGE378
  R841    1      A Q_RES_0201LF-1K,1%,1/20W,CHIP,CS21001FE07    I17 @T6G_MB_LIB.T6G(SCH_1):PAGE377
  R840    1      A Q_RES_0201LF-1K,1%,1/20W,CHIP,CS21001FE07    I18 @T6G_MB_LIB.T6G(SCH_1):PAGE377
  R838    1      A Q_RES_0201LF-1K,1%,1/20W,CHIP,CS21001FE07    I19 @T6G_MB_LIB.T6G(SCH_1):PAGE377
  R839    1      A Q_RES_0201LF-1K,1%,1/20W,CHIP,CS21001FE07    I20 @T6G_MB_LIB.T6G(SCH_1):PAGE377
  R837    1      A Q_RES_0201LF-1K,1%,1/20W,CHIP,CS21001FE07    I21 @T6G_MB_LIB.T6G(SCH_1):PAGE377
  R836    1      A Q_RES_0201LF-1K,1%,1/20W,CHIP,CS21001FE07    I22 @T6G_MB_LIB.T6G(SCH_1):PAGE377
  R835    1      A Q_RES_0201LF-1K,1%,1/20W,CHIP,CS21001FE07    I23 @T6G_MB_LIB.T6G(SCH_1):PAGE377
  R834    1      A Q_RES_0201LF-1K,1%,1/20W,CHIP,CS21001FE07    I24 @T6G_MB_LIB.T6G(SCH_1):PAGE377
  R972    1      A Q_RES_0201LF-4.7K,5%,1/20W,EMPTY,CS24701JE04    I25 @T6G_MB_LIB.T6G(SCH_1):PAGE385
  R978    1      A Q_RES_0201LF-4.7K,5%,1/20W,EMPTY,CS24701JE04    I30 @T6G_MB_LIB.T6G(SCH_1):PAGE385
  R981    1      A Q_RES_0201LF-4.7K,5%,1/20W,EMPTY,CS24701JE04    I31 @T6G_MB_LIB.T6G(SCH_1):PAGE385
  R983    1      A Q_RES_0201LF-4.7K,5%,1/20W,EMPTY,CS24701JE04    I61 @T6G_MB_LIB.T6G(SCH_1):PAGE385
  R985    1      A Q_RES_0201LF-4.7K,5%,1/20W,EMPTY,CS24701JE04    I62 @T6G_MB_LIB.T6G(SCH_1):PAGE385
  R975    1      A Q_RES_0201LF-4.7K,5%,1/20W,EMPTY,CS24701JE04    I63 @T6G_MB_LIB.T6G(SCH_1):PAGE385
  R998    1      A Q_RES_0201LF-4.7K,5%,1/20W,CHIP,CS24701JE04    I72 @T6G_MB_LIB.T6G(SCH_1):PAGE385
  R964    1      A Q_RES_0201LF-1K,1%,1/20W,CHIP,CS21001FE07    I88 @T6G_MB_LIB.T6G(SCH_1):PAGE385
  R966    1      A Q_RES_0201LF-1K,1%,1/20W,EMPTY,CS21001FE07    I89 @T6G_MB_LIB.T6G(SCH_1):PAGE385
  R968    1      A Q_RES_0201LF-1K,1%,1/20W,EMPTY,CS21001FE07    I91 @T6G_MB_LIB.T6G(SCH_1):PAGE385
  R974    1      A Q_RES_0201LF-4.7K,5%,1/20W,EMPTY,CS24701JE04    I98 @T6G_MB_LIB.T6G(SCH_1):PAGE385
 C7510    1      A Q_CAP_C0201-0.1UF,10V,10%,X7S,CH4102K6E00    I21 @T6G_MB_LIB.T6G(SCH_1):PAGE387
   L11    1      1 Q_INDUCTOR_SMLF-BLM21SN300SN1D/5A,IND,CX300SN1000    I12 @T6G_MB_LIB.T6G(SCH_1):PAGE388
  C502    1      A Q_CAP_C0805-100UF,4V,20%,X6S,CH710KMEA01    I16 @T6G_MB_LIB.T6G(SCH_1):PAGE388
  C504    1      A Q_CAP_C0402-22UF,4V,20%,X6S,CH622KMEB02    I24 @T6G_MB_LIB.T6G(SCH_1):PAGE388
  C506    1      A Q_CAP_C0402-10UF,6.3V,20%,X6S,CH6101MEB01    I25 @T6G_MB_LIB.T6G(SCH_1):PAGE388
  C511    1      A Q_CAP_0402-4.7UF,6.3V,20%,X6S,CH5471MEB01    I26 @T6G_MB_LIB.T6G(SCH_1):PAGE388
 R1021    1      A Q_RES_0201LF-4.7K,5%,1/20W,EMPTY,CS24701JE04     I5 @T6G_MB_LIB.T6G(SCH_1):PAGE408
 R1027    1      A Q_RES_0201LF-4.7K,5%,1/20W,EMPTY,CS24701JE04    I10 @T6G_MB_LIB.T6G(SCH_1):PAGE408
 R1030    1      A Q_RES_0201LF-4.7K,5%,1/20W,EMPTY,CS24701JE04    I11 @T6G_MB_LIB.T6G(SCH_1):PAGE408
 R1032    1      A Q_RES_0201LF-4.7K,5%,1/20W,EMPTY,CS24701JE04    I40 @T6G_MB_LIB.T6G(SCH_1):PAGE408
 R1034    1      A Q_RES_0201LF-4.7K,5%,1/20W,EMPTY,CS24701JE04    I41 @T6G_MB_LIB.T6G(SCH_1):PAGE408
 R1024    1      A Q_RES_0201LF-4.7K,5%,1/20W,EMPTY,CS24701JE04    I42 @T6G_MB_LIB.T6G(SCH_1):PAGE408
 R1039    1      A Q_RES_0201LF-4.7K,5%,1/20W,CHIP,CS24701JE04    I51 @T6G_MB_LIB.T6G(SCH_1):PAGE408
 R1013    1      A Q_RES_0201LF-1K,1%,1/20W,CHIP,CS21001FE07    I66 @T6G_MB_LIB.T6G(SCH_1):PAGE408
 R1015    1      A Q_RES_0201LF-1K,1%,1/20W,EMPTY,CS21001FE07    I67 @T6G_MB_LIB.T6G(SCH_1):PAGE408
 R1017    1      A Q_RES_0201LF-1K,1%,1/20W,EMPTY,CS21001FE07    I69 @T6G_MB_LIB.T6G(SCH_1):PAGE408
 R1023    1      A Q_RES_0201LF-4.7K,5%,1/20W,EMPTY,CS24701JE04    I78 @T6G_MB_LIB.T6G(SCH_1):PAGE408
  C664    1      A Q_CAP_C0201-0.1UF,10V,10%,X7S,CH4102K6E00    I24 @T6G_MB_LIB.T6G(SCH_1):PAGE410
   L13    1      1 Q_INDUCTOR_SMLF-BLM21SN300SN1D/5A,IND,CX300SN1000    I11 @T6G_MB_LIB.T6G(SCH_1):PAGE411
  C587    1      A Q_CAP_C0805-100UF,4V,20%,X6S,CH710KMEA01    I17 @T6G_MB_LIB.T6G(SCH_1):PAGE411
  C589    1      A Q_CAP_C0402-22UF,4V,20%,X6S,CH622KMEB02    I18 @T6G_MB_LIB.T6G(SCH_1):PAGE411
  C591    1      A Q_CAP_C0402-10UF,6.3V,20%,X6S,CH6101MEB01    I22 @T6G_MB_LIB.T6G(SCH_1):PAGE411
  C596    1      A Q_CAP_0402-4.7UF,6.3V,20%,X6S,CH5471MEB01    I24 @T6G_MB_LIB.T6G(SCH_1):PAGE411
 R1063    1      A Q_RES_0201LF-4.7K,5%,1/20W,EMPTY,CS24701JE04     I5 @T6G_MB_LIB.T6G(SCH_1):PAGE419
 R1069    1      A Q_RES_0201LF-4.7K,5%,1/20W,EMPTY,CS24701JE04    I10 @T6G_MB_LIB.T6G(SCH_1):PAGE419
 R1073    1      A Q_RES_0201LF-4.7K,5%,1/20W,EMPTY,CS24701JE04    I11 @T6G_MB_LIB.T6G(SCH_1):PAGE419
 R1075    1      A Q_RES_0201LF-4.7K,5%,1/20W,EMPTY,CS24701JE04    I40 @T6G_MB_LIB.T6G(SCH_1):PAGE419
 R1077    1      A Q_RES_0201LF-4.7K,5%,1/20W,EMPTY,CS24701JE04    I41 @T6G_MB_LIB.T6G(SCH_1):PAGE419
 R1066    1      A Q_RES_0201LF-4.7K,5%,1/20W,EMPTY,CS24701JE04    I42 @T6G_MB_LIB.T6G(SCH_1):PAGE419
 R1080    1      A Q_RES_0201LF-4.7K,5%,1/20W,CHIP,CS24701JE04    I51 @T6G_MB_LIB.T6G(SCH_1):PAGE419
 R1055    1      A Q_RES_0201LF-1K,1%,1/20W,CHIP,CS21001FE07    I67 @T6G_MB_LIB.T6G(SCH_1):PAGE419
 R1057    1      A Q_RES_0201LF-1K,1%,1/20W,EMPTY,CS21001FE07    I68 @T6G_MB_LIB.T6G(SCH_1):PAGE419
 R1059    1      A Q_RES_0201LF-1K,1%,1/20W,EMPTY,CS21001FE07    I70 @T6G_MB_LIB.T6G(SCH_1):PAGE419
 R1065    1      A Q_RES_0201LF-4.7K,5%,1/20W,EMPTY,CS24701JE04    I78 @T6G_MB_LIB.T6G(SCH_1):PAGE419
  C989    1      A Q_CAP_C0201-0.1UF,10V,10%,X7S,CH4102K6E00    I23 @T6G_MB_LIB.T6G(SCH_1):PAGE421
   L18    1      1 Q_INDUCTOR_SMLF-BLM21SN300SN1D/5A,IND,CX300SN1000    I23 @T6G_MB_LIB.T6G(SCH_1):PAGE422
  C665    1      A Q_CAP_C0805-100UF,4V,20%,X6S,CH710KMEA01    I25 @T6G_MB_LIB.T6G(SCH_1):PAGE422
  C669    1      A Q_CAP_C0402-10UF,6.3V,20%,X6S,CH6101MEB01    I26 @T6G_MB_LIB.T6G(SCH_1):PAGE422
  C667    1      A Q_CAP_C0402-22UF,4V,20%,X6S,CH622KMEB02    I27 @T6G_MB_LIB.T6G(SCH_1):PAGE422
  C672    1      A Q_CAP_0402-4.7UF,6.3V,20%,X6S,CH5471MEB01    I29 @T6G_MB_LIB.T6G(SCH_1):PAGE422
 R1111    1      A Q_RES_0201LF-4.7K,5%,1/20W,EMPTY,CS24701JE04    I10 @T6G_MB_LIB.T6G(SCH_1):PAGE430
 R1114    1      A Q_RES_0201LF-4.7K,5%,1/20W,EMPTY,CS24701JE04    I11 @T6G_MB_LIB.T6G(SCH_1):PAGE430
 R1116    1      A Q_RES_0201LF-4.7K,5%,1/20W,EMPTY,CS24701JE04    I40 @T6G_MB_LIB.T6G(SCH_1):PAGE430
 R1119    1      A Q_RES_0201LF-4.7K,5%,1/20W,EMPTY,CS24701JE04    I41 @T6G_MB_LIB.T6G(SCH_1):PAGE430
 R1108    1      A Q_RES_0201LF-4.7K,5%,1/20W,EMPTY,CS24701JE04    I42 @T6G_MB_LIB.T6G(SCH_1):PAGE430
 R1122    1      A Q_RES_0201LF-4.7K,5%,1/20W,CHIP,CS24701JE04    I51 @T6G_MB_LIB.T6G(SCH_1):PAGE430
 R1097    1      A Q_RES_0201LF-1K,1%,1/20W,CHIP,CS21001FE07    I67 @T6G_MB_LIB.T6G(SCH_1):PAGE430
 R1099    1      A Q_RES_0201LF-1K,1%,1/20W,EMPTY,CS21001FE07    I68 @T6G_MB_LIB.T6G(SCH_1):PAGE430
 R1101    1      A Q_RES_0201LF-1K,1%,1/20W,EMPTY,CS21001FE07    I70 @T6G_MB_LIB.T6G(SCH_1):PAGE430
 R1107    1      A Q_RES_0201LF-4.7K,5%,1/20W,EMPTY,CS24701JE04    I79 @T6G_MB_LIB.T6G(SCH_1):PAGE430
 C1057    1      A Q_CAP_C0201-0.1UF,10V,10%,X7S,CH4102K6E00    I23 @T6G_MB_LIB.T6G(SCH_1):PAGE432
   L22    1      1 Q_INDUCTOR_SMLF-BLM21SN300SN1D/5A,IND,CX300SN1000    I10 @T6G_MB_LIB.T6G(SCH_1):PAGE433
  C990    1      A Q_CAP_C0805-100UF,4V,20%,X6S,CH710KMEA01    I19 @T6G_MB_LIB.T6G(SCH_1):PAGE433
  C992    1      A Q_CAP_C0402-22UF,4V,20%,X6S,CH622KMEB02    I20 @T6G_MB_LIB.T6G(SCH_1):PAGE433
  C994    1      A Q_CAP_C0402-10UF,6.3V,20%,X6S,CH6101MEB01    I21 @T6G_MB_LIB.T6G(SCH_1):PAGE433
  C997    1      A Q_CAP_0402-4.7UF,6.3V,20%,X6S,CH5471MEB01    I22 @T6G_MB_LIB.T6G(SCH_1):PAGE433
 R1231    1      A Q_RES_0402LF-5.11K,1%,1/16W,CHIP,CS25112FB04   I191 @T6G_MB_LIB.T6G(SCH_1):PAGE263
 R1369    1      A Q_RES_0201LF-1K,1%,1/20W,EMPTY,CS21001FE07   I116 @T6G_MB_LIB.T6G(SCH_1):PAGE385
 R1397    1      A Q_RES_0201LF-1K,1%,1/20W,EMPTY,CS21001FE07    I99 @T6G_MB_LIB.T6G(SCH_1):PAGE408
 R1405    1      A Q_RES_0201LF-1K,1%,1/20W,EMPTY,CS21001FE07    I96 @T6G_MB_LIB.T6G(SCH_1):PAGE419
 R1413    1      A Q_RES_0201LF-1K,1%,1/20W,EMPTY,CS21001FE07    I97 @T6G_MB_LIB.T6G(SCH_1):PAGE430
 R6808    1      A Q_RES_0201LF-1K,1%,1/20W,EMPTY,CS21001FE07    I19 @T6G_MB_LIB.T6G(SCH_1):PAGE386
 R1040    1      A Q_RES_0201LF-1K,1%,1/20W,EMPTY,CS21001FE07    I19 @T6G_MB_LIB.T6G(SCH_1):PAGE409
 R1081    1      A Q_RES_0201LF-1K,1%,1/20W,EMPTY,CS21001FE07    I19 @T6G_MB_LIB.T6G(SCH_1):PAGE420
 R1123    1      A Q_RES_0201LF-1K,1%,1/20W,EMPTY,CS21001FE07    I19 @T6G_MB_LIB.T6G(SCH_1):PAGE431
 R1446    1      A Q_RES_0201LF-4.7K,5%,1/20W,EMPTY,CS24701JE04   I143 @T6G_MB_LIB.T6G(SCH_1):PAGE385
 R1445    1      A Q_RES_0201LF-1K,1%,1/20W,EMPTY,CS21001FE07   I145 @T6G_MB_LIB.T6G(SCH_1):PAGE385
 R1439    1      A Q_RES_0201LF-4.7K,5%,1/20W,EMPTY,CS24701JE04   I146 @T6G_MB_LIB.T6G(SCH_1):PAGE385
 R1438    1      A Q_RES_0201LF-4.7K,5%,1/20W,EMPTY,CS24701JE04   I147 @T6G_MB_LIB.T6G(SCH_1):PAGE385
 R1470    1      A Q_RES_0201LF-4.7K,5%,1/20W,EMPTY,CS24701JE04   I115 @T6G_MB_LIB.T6G(SCH_1):PAGE408
 R1471    1      A Q_RES_0201LF-4.7K,5%,1/20W,EMPTY,CS24701JE04   I116 @T6G_MB_LIB.T6G(SCH_1):PAGE408
 R1472    1      A Q_RES_0201LF-1K,1%,1/20W,EMPTY,CS21001FE07   I121 @T6G_MB_LIB.T6G(SCH_1):PAGE408
 R1473    1      A Q_RES_0201LF-4.7K,5%,1/20W,EMPTY,CS24701JE04   I122 @T6G_MB_LIB.T6G(SCH_1):PAGE408
 R1476    1      A Q_RES_0201LF-4.7K,5%,1/20W,EMPTY,CS24701JE04   I116 @T6G_MB_LIB.T6G(SCH_1):PAGE419
 R1477    1      A Q_RES_0201LF-4.7K,5%,1/20W,EMPTY,CS24701JE04   I117 @T6G_MB_LIB.T6G(SCH_1):PAGE419
 R1478    1      A Q_RES_0201LF-1K,1%,1/20W,EMPTY,CS21001FE07   I118 @T6G_MB_LIB.T6G(SCH_1):PAGE419
 R1479    1      A Q_RES_0201LF-4.7K,5%,1/20W,EMPTY,CS24701JE04   I121 @T6G_MB_LIB.T6G(SCH_1):PAGE419
 R1482    1      A Q_RES_0201LF-4.7K,5%,1/20W,EMPTY,CS24701JE04   I112 @T6G_MB_LIB.T6G(SCH_1):PAGE430
 R1483    1      A Q_RES_0201LF-4.7K,5%,1/20W,EMPTY,CS24701JE04   I113 @T6G_MB_LIB.T6G(SCH_1):PAGE430
 R1484    1      A Q_RES_0201LF-1K,1%,1/20W,EMPTY,CS21001FE07   I118 @T6G_MB_LIB.T6G(SCH_1):PAGE430
 R1485    1      A Q_RES_0201LF-4.7K,5%,1/20W,EMPTY,CS24701JE04   I119 @T6G_MB_LIB.T6G(SCH_1):PAGE430
 R1367    1      A Q_RES_0201LF-4.7K,5%,1/20W,CHIP,CS24701JE04   I121 @T6G_MB_LIB.T6G(SCH_1):PAGE377
 R1366    1      A Q_RES_0201LF-4.7K,5%,1/20W,CHIP,CS24701JE04   I122 @T6G_MB_LIB.T6G(SCH_1):PAGE377
 R1374    1      A Q_RES_0201LF-4.7K,5%,1/20W,CHIP,CS24701JE04   I123 @T6G_MB_LIB.T6G(SCH_1):PAGE377
 R1371    1      A Q_RES_0201LF-4.7K,5%,1/20W,CHIP,CS24701JE04   I124 @T6G_MB_LIB.T6G(SCH_1):PAGE377
 R1375    1      A Q_RES_0201LF-4.7K,5%,1/20W,CHIP,CS24701JE04   I125 @T6G_MB_LIB.T6G(SCH_1):PAGE377
 R1379    1      A Q_RES_0201LF-4.7K,5%,1/20W,CHIP,CS24701JE04   I126 @T6G_MB_LIB.T6G(SCH_1):PAGE377
 R1382    1      A Q_RES_0201LF-4.7K,5%,1/20W,CHIP,CS24701JE04   I127 @T6G_MB_LIB.T6G(SCH_1):PAGE377
 R1383    1      A Q_RES_0201LF-4.7K,5%,1/20W,CHIP,CS24701JE04   I128 @T6G_MB_LIB.T6G(SCH_1):PAGE377
 R1410    1      A Q_RES_0201LF-1K,1%,1/20W,CHIP,CS21001FE07   I164 @T6G_MB_LIB.T6G(SCH_1):PAGE377
 R1411    1      A Q_RES_0201LF-1K,1%,1/20W,CHIP,CS21001FE07   I165 @T6G_MB_LIB.T6G(SCH_1):PAGE377
 R1415    1      A Q_RES_0201LF-1K,1%,1/20W,CHIP,CS21001FE07   I166 @T6G_MB_LIB.T6G(SCH_1):PAGE377
 R1418    1      A Q_RES_0201LF-1K,1%,1/20W,CHIP,CS21001FE07   I167 @T6G_MB_LIB.T6G(SCH_1):PAGE377
 R1420    1      A Q_RES_0201LF-1K,1%,1/20W,CHIP,CS21001FE07   I168 @T6G_MB_LIB.T6G(SCH_1):PAGE377
 R1428    1      A Q_RES_0201LF-1K,1%,1/20W,CHIP,CS21001FE07   I169 @T6G_MB_LIB.T6G(SCH_1):PAGE377
 R1431    1      A Q_RES_0201LF-1K,1%,1/20W,CHIP,CS21001FE07   I170 @T6G_MB_LIB.T6G(SCH_1):PAGE377
 R1432    1      A Q_RES_0201LF-1K,1%,1/20W,CHIP,CS21001FE07   I171 @T6G_MB_LIB.T6G(SCH_1):PAGE377
   L26    1      1 Q_INDUCTOR_SMLF-BLM15PD121SN1D/1300MA,IND,CX5PD121A    I88 @T6G_MB_LIB.T6G(SCH_1):PAGE388
  R960    1      A Q_RES_0402LF-0,5%,1/16W,EMPTY,CS00002JB13    I89 @T6G_MB_LIB.T6G(SCH_1):PAGE388
   L28    1      1 Q_INDUCTOR_SMLF-BLM15PD121SN1D/1300MA,IND,CX5PD121A    I88 @T6G_MB_LIB.T6G(SCH_1):PAGE411
 R1008    1      A Q_RES_0402LF-0,5%,1/16W,EMPTY,CS00002JB13    I89 @T6G_MB_LIB.T6G(SCH_1):PAGE411
   L29    1      1 Q_INDUCTOR_SMLF-BLM15PD121SN1D/1300MA,IND,CX5PD121A    I88 @T6G_MB_LIB.T6G(SCH_1):PAGE422
 R1050    1      A Q_RES_0402LF-0,5%,1/16W,EMPTY,CS00002JB13    I89 @T6G_MB_LIB.T6G(SCH_1):PAGE422
   L30    1      1 Q_INDUCTOR_SMLF-BLM15PD121SN1D/1300MA,IND,CX5PD121A    I88 @T6G_MB_LIB.T6G(SCH_1):PAGE433
 R1093    1      A Q_RES_0402LF-0,5%,1/16W,EMPTY,CS00002JB13    I89 @T6G_MB_LIB.T6G(SCH_1):PAGE433

P1V8_CPU0_RT_1D_ADC @T6G_MB_LIB.T6G(SCH_1):P1V8_CPU0_RT_1D_ADC
 R1246    1      A Q_RES_0402LF-0,5%,1/16W,EMPTY,CS00002JB13   I189 @T6G_MB_LIB.T6G(SCH_1):PAGE263
 R1252    1      A Q_RES_0402LF-0,5%,1/16W,CHIP,CS00002JB13   I190 @T6G_MB_LIB.T6G(SCH_1):PAGE263
 R1231    2      B Q_RES_0402LF-5.11K,1%,1/16W,CHIP,CS25112FB04   I191 @T6G_MB_LIB.T6G(SCH_1):PAGE263
 R1220    1      A Q_RES_0402LF-18K,1%,1/16W,CHIP,CS31802FB04   I244 @T6G_MB_LIB.T6G(SCH_1):PAGE263

P1V8_CPU0_RT_1D_ADC_MAM @T6G_MB_LIB.T6G(SCH_1):P1V8_CPU0_RT_1D_ADC_MAM
   U50    8   AIN3 MAX11617EEET-MAX11617EEE+T,SMLF,EMPTY,AL011617W00   I156 @T6G_MB_LIB.T6G(SCH_1):PAGE263
 C1079    1      A Q_CAP_0402-100PF,50V,5%,EMPTY,CH11006JB18   I185 @T6G_MB_LIB.T6G(SCH_1):PAGE263
 R1246    2      B Q_RES_0402LF-0,5%,1/16W,EMPTY,CS00002JB13   I189 @T6G_MB_LIB.T6G(SCH_1):PAGE263

P1V8_CPU0_RT_1D_ADC_TIC @T6G_MB_LIB.T6G(SCH_1):P1V8_CPU0_RT_1D_ADC_TIC
   U51   13    IN3 ADC128D818CIMTXNOPB-ADC128D818CIMTX/NOPB,SMLF,IC,AA   I142 @T6G_MB_LIB.T6G(SCH_1):PAGE263
 C1087    1      A Q_CAP_0402-0.1UF,25V,10%,X7R,CH4104K1B00   I187 @T6G_MB_LIB.T6G(SCH_1):PAGE263
 R1252    2      B Q_RES_0402LF-0,5%,1/16W,CHIP,CS00002JB13   I190 @T6G_MB_LIB.T6G(SCH_1):PAGE263

P1V8_CPU1_RT0_1A @T6G_MB_LIB.T6G(SCH_1):P1V8_CPU1_RT0_1A
 U6014 BV20 PWR_1A_1 PT5161LRS-PT5161LRS,SMLF,IC,AJ051610U03     I1 @T6G_MB_LIB.T6G(SCH_1):PAGE400
 U6014 CE17 PWR_1A_2 PT5161LRS-PT5161LRS,SMLF,IC,AJ051610U03     I1 @T6G_MB_LIB.T6G(SCH_1):PAGE400
 U6014 CE20 PWR_1A_3 PT5161LRS-PT5161LRS,SMLF,IC,AJ051610U03     I1 @T6G_MB_LIB.T6G(SCH_1):PAGE400
 U6014 CM17 PWR_1A_4 PT5161LRS-PT5161LRS,SMLF,IC,AJ051610U03     I1 @T6G_MB_LIB.T6G(SCH_1):PAGE400
 U6014 CM20 PWR_1A_5 PT5161LRS-PT5161LRS,SMLF,IC,AJ051610U03     I1 @T6G_MB_LIB.T6G(SCH_1):PAGE400
  C114    1      A Q_CAP_C0805-100UF,4V,20%,X6S,CH710KMEA01     I4 @T6G_MB_LIB.T6G(SCH_1):PAGE398
  C117    1      A Q_CAP_C0402-22UF,4V,20%,X6S,CH622KMEB02     I5 @T6G_MB_LIB.T6G(SCH_1):PAGE398
  C121    1      A Q_CAP_0402-4.7UF,6.3V,20%,X6S,CH5471MEB01     I7 @T6G_MB_LIB.T6G(SCH_1):PAGE398
  C126    1      A Q_CAP_0201-1UF,4V,20%,X6S,CH-10KMEE00     I9 @T6G_MB_LIB.T6G(SCH_1):PAGE398
  C123    1      A Q_CAP_0201-1UF,4V,20%,X6S,CH-10KMEE00    I18 @T6G_MB_LIB.T6G(SCH_1):PAGE398
  C119    1      A Q_CAP_C0402-10UF,6.3V,20%,X6S,CH6101MEB01    I20 @T6G_MB_LIB.T6G(SCH_1):PAGE398
    L3    2      2 Q_INDUCTOR_SMLF-BLM21SN300SN1D/5A,IND,CX300SN1000    I22 @T6G_MB_LIB.T6G(SCH_1):PAGE398
  C129    1      A Q_CAP_C0201-0.1UF,10V,10%,X7S,CH4102K6E00    I23 @T6G_MB_LIB.T6G(SCH_1):PAGE398
  C131    1      A Q_CAP_C0201-0.1UF,10V,10%,X7S,CH4102K6E00    I24 @T6G_MB_LIB.T6G(SCH_1):PAGE398
  C133    1      A Q_CAP_C0201-0.1UF,10V,10%,X7S,CH4102K6E00    I25 @T6G_MB_LIB.T6G(SCH_1):PAGE398
  C134    1      A Q_CAP_C0201-0.1UF,10V,10%,X7S,CH4102K6E00    I26 @T6G_MB_LIB.T6G(SCH_1):PAGE398
 R6702    2      B Q_RES_0402LF-0,5%,1/16W,EMPTY,CS00002JB13    I32 @T6G_MB_LIB.T6G(SCH_1):PAGE398
 R6703    2      B Q_RES_0402LF-0,5%,1/16W,EMPTY,CS00002JB13    I33 @T6G_MB_LIB.T6G(SCH_1):PAGE398

P1V8_CPU1_RT0_1A_1D @T6G_MB_LIB.T6G(SCH_1):P1V8_CPU1_RT0_1A_1D
 U6014 BV17 PWR_1D PT5161LRS-PT5161LRS,SMLF,IC,AJ051610U03     I1 @T6G_MB_LIB.T6G(SCH_1):PAGE400
  C125    1      A Q_CAP_0201-1UF,4V,20%,X6S,CH-10KMEE00    I19 @T6G_MB_LIB.T6G(SCH_1):PAGE398
  C130    1      A Q_CAP_C0201-0.1UF,10V,10%,X7S,CH4102K6E00    I27 @T6G_MB_LIB.T6G(SCH_1):PAGE398
 R6702    1      A Q_RES_0402LF-0,5%,1/16W,EMPTY,CS00002JB13    I32 @T6G_MB_LIB.T6G(SCH_1):PAGE398
 R6703    1      A Q_RES_0402LF-0,5%,1/16W,EMPTY,CS00002JB13    I33 @T6G_MB_LIB.T6G(SCH_1):PAGE398
   L27    2      2 Q_INDUCTOR_SMLF-BLM15PD121SN1D/1300MA,IND,CX5PD121A    I97 @T6G_MB_LIB.T6G(SCH_1):PAGE398
 R6701    2      B Q_RES_0402LF-0,5%,1/16W,EMPTY,CS00002JB13    I98 @T6G_MB_LIB.T6G(SCH_1):PAGE398

P1V8_CPU1_RT1_1A @T6G_MB_LIB.T6G(SCH_1):P1V8_CPU1_RT1_1A
 U6015 BV20 PWR_1A_1 PT5161LRS-PT5161LRS,SMLF,IC,AJ051610U03     I5 @T6G_MB_LIB.T6G(SCH_1):PAGE391
 U6015 CE17 PWR_1A_2 PT5161LRS-PT5161LRS,SMLF,IC,AJ051610U03     I5 @T6G_MB_LIB.T6G(SCH_1):PAGE391
 U6015 CE20 PWR_1A_3 PT5161LRS-PT5161LRS,SMLF,IC,AJ051610U03     I5 @T6G_MB_LIB.T6G(SCH_1):PAGE391
 U6015 CM17 PWR_1A_4 PT5161LRS-PT5161LRS,SMLF,IC,AJ051610U03     I5 @T6G_MB_LIB.T6G(SCH_1):PAGE391
 U6015 CM20 PWR_1A_5 PT5161LRS-PT5161LRS,SMLF,IC,AJ051610U03     I5 @T6G_MB_LIB.T6G(SCH_1):PAGE391
  R664    2      B Q_RES_0402LF-0,5%,1/16W,EMPTY,CS00002JB13     I4 @T6G_MB_LIB.T6G(SCH_1):PAGE443
  R653    2      B Q_RES_0402LF-0,5%,1/16W,EMPTY,CS00002JB13     I5 @T6G_MB_LIB.T6G(SCH_1):PAGE443
    L5    2      2 Q_INDUCTOR_SMLF-BLM21SN300SN1D/5A,IND,CX300SN1000    I12 @T6G_MB_LIB.T6G(SCH_1):PAGE443
  C103    1      A Q_CAP_C0805-100UF,4V,20%,X6S,CH710KMEA01    I13 @T6G_MB_LIB.T6G(SCH_1):PAGE443
  C111    1      A Q_CAP_C0402-22UF,4V,20%,X6S,CH622KMEB02    I14 @T6G_MB_LIB.T6G(SCH_1):PAGE443
  C199    1      A Q_CAP_C0402-10UF,6.3V,20%,X6S,CH6101MEB01    I17 @T6G_MB_LIB.T6G(SCH_1):PAGE443
  C195    1      A Q_CAP_0402-4.7UF,6.3V,20%,X6S,CH5471MEB01    I18 @T6G_MB_LIB.T6G(SCH_1):PAGE443
  C202    1      A Q_CAP_0201-1UF,4V,20%,X6S,CH-10KMEE00    I20 @T6G_MB_LIB.T6G(SCH_1):PAGE443
  C204    1      A Q_CAP_0201-1UF,4V,20%,X6S,CH-10KMEE00    I22 @T6G_MB_LIB.T6G(SCH_1):PAGE443
  C205    1      A Q_CAP_C0201-0.1UF,10V,10%,X7S,CH4102K6E00    I23 @T6G_MB_LIB.T6G(SCH_1):PAGE443
  C217    1      A Q_CAP_C0201-0.1UF,10V,10%,X7S,CH4102K6E00    I27 @T6G_MB_LIB.T6G(SCH_1):PAGE443
  C287    1      A Q_CAP_C0201-0.1UF,10V,10%,X7S,CH4102K6E00    I28 @T6G_MB_LIB.T6G(SCH_1):PAGE443
  C288    1      A Q_CAP_C0201-0.1UF,10V,10%,X7S,CH4102K6E00    I29 @T6G_MB_LIB.T6G(SCH_1):PAGE443

P1V8_CPU1_RT1_1A_1D @T6G_MB_LIB.T6G(SCH_1):P1V8_CPU1_RT1_1A_1D
 U6015 BV17 PWR_1D PT5161LRS-PT5161LRS,SMLF,IC,AJ051610U03     I5 @T6G_MB_LIB.T6G(SCH_1):PAGE391
  R664    1      A Q_RES_0402LF-0,5%,1/16W,EMPTY,CS00002JB13     I4 @T6G_MB_LIB.T6G(SCH_1):PAGE443
  R653    1      A Q_RES_0402LF-0,5%,1/16W,EMPTY,CS00002JB13     I5 @T6G_MB_LIB.T6G(SCH_1):PAGE443
  C203    1      A Q_CAP_0201-1UF,4V,20%,X6S,CH-10KMEE00     I8 @T6G_MB_LIB.T6G(SCH_1):PAGE443
  C206    1      A Q_CAP_C0201-0.1UF,10V,10%,X7S,CH4102K6E00     I9 @T6G_MB_LIB.T6G(SCH_1):PAGE443
   L31    2      2 Q_INDUCTOR_SMLF-BLM15PD121SN1D/1300MA,IND,CX5PD121A    I88 @T6G_MB_LIB.T6G(SCH_1):PAGE443
  R704    2      B Q_RES_0402LF-0,5%,1/16W,EMPTY,CS00002JB13    I89 @T6G_MB_LIB.T6G(SCH_1):PAGE443

P1V8_CPU1_RT2_1A @T6G_MB_LIB.T6G(SCH_1):P1V8_CPU1_RT2_1A
 U6016 BV20 PWR_1A_1 PT5161LRS-PT5161LRS,SMLF,IC,AJ051610U03     I7 @T6G_MB_LIB.T6G(SCH_1):PAGE452
 U6016 CE17 PWR_1A_2 PT5161LRS-PT5161LRS,SMLF,IC,AJ051610U03     I7 @T6G_MB_LIB.T6G(SCH_1):PAGE452
 U6016 CE20 PWR_1A_3 PT5161LRS-PT5161LRS,SMLF,IC,AJ051610U03     I7 @T6G_MB_LIB.T6G(SCH_1):PAGE452
 U6016 CM17 PWR_1A_4 PT5161LRS-PT5161LRS,SMLF,IC,AJ051610U03     I7 @T6G_MB_LIB.T6G(SCH_1):PAGE452
 U6016 CM20 PWR_1A_5 PT5161LRS-PT5161LRS,SMLF,IC,AJ051610U03     I7 @T6G_MB_LIB.T6G(SCH_1):PAGE452
  R852    2      B Q_RES_0402LF-0,5%,1/16W,EMPTY,CS00002JB13     I2 @T6G_MB_LIB.T6G(SCH_1):PAGE454
  R853    2      B Q_RES_0402LF-0,5%,1/16W,EMPTY,CS00002JB13     I3 @T6G_MB_LIB.T6G(SCH_1):PAGE454
  C367    1      A Q_CAP_C0805-100UF,4V,20%,X6S,CH710KMEA01     I5 @T6G_MB_LIB.T6G(SCH_1):PAGE454
  C369    1      A Q_CAP_C0402-22UF,4V,20%,X6S,CH622KMEB02    I10 @T6G_MB_LIB.T6G(SCH_1):PAGE454
  C372    1      A Q_CAP_C0402-10UF,6.3V,20%,X6S,CH6101MEB01    I11 @T6G_MB_LIB.T6G(SCH_1):PAGE454
  C371    1      A Q_CAP_0402-4.7UF,6.3V,20%,X6S,CH5471MEB01    I12 @T6G_MB_LIB.T6G(SCH_1):PAGE454
  C374    1      A Q_CAP_0201-1UF,4V,20%,X6S,CH-10KMEE00    I13 @T6G_MB_LIB.T6G(SCH_1):PAGE454
  C376    1      A Q_CAP_0201-1UF,4V,20%,X6S,CH-10KMEE00    I15 @T6G_MB_LIB.T6G(SCH_1):PAGE454
  C377    1      A Q_CAP_C0201-0.1UF,10V,10%,X7S,CH4102K6E00    I16 @T6G_MB_LIB.T6G(SCH_1):PAGE454
  C379    1      A Q_CAP_C0201-0.1UF,10V,10%,X7S,CH4102K6E00    I17 @T6G_MB_LIB.T6G(SCH_1):PAGE454
  C380    1      A Q_CAP_C0201-0.1UF,10V,10%,X7S,CH4102K6E00    I18 @T6G_MB_LIB.T6G(SCH_1):PAGE454
  C381    1      A Q_CAP_C0201-0.1UF,10V,10%,X7S,CH4102K6E00    I19 @T6G_MB_LIB.T6G(SCH_1):PAGE454
    L7    2      2 Q_INDUCTOR_SMLF-BLM21SN300SN1D/5A,IND,CX300SN1000    I21 @T6G_MB_LIB.T6G(SCH_1):PAGE454

P1V8_CPU1_RT2_1A_1D @T6G_MB_LIB.T6G(SCH_1):P1V8_CPU1_RT2_1A_1D
 U6016 BV17 PWR_1D PT5161LRS-PT5161LRS,SMLF,IC,AJ051610U03     I7 @T6G_MB_LIB.T6G(SCH_1):PAGE452
  R852    1      A Q_RES_0402LF-0,5%,1/16W,EMPTY,CS00002JB13     I2 @T6G_MB_LIB.T6G(SCH_1):PAGE454
  R853    1      A Q_RES_0402LF-0,5%,1/16W,EMPTY,CS00002JB13     I3 @T6G_MB_LIB.T6G(SCH_1):PAGE454
  C375    1      A Q_CAP_0201-1UF,4V,20%,X6S,CH-10KMEE00     I6 @T6G_MB_LIB.T6G(SCH_1):PAGE454
  C378    1      A Q_CAP_C0201-0.1UF,10V,10%,X7S,CH4102K6E00     I8 @T6G_MB_LIB.T6G(SCH_1):PAGE454
   L32    2      2 Q_INDUCTOR_SMLF-BLM15PD121SN1D/1300MA,IND,CX5PD121A    I88 @T6G_MB_LIB.T6G(SCH_1):PAGE454
  R857    2      B Q_RES_0402LF-0,5%,1/16W,EMPTY,CS00002JB13    I89 @T6G_MB_LIB.T6G(SCH_1):PAGE454

P1V8_CPU1_RT3_1A @T6G_MB_LIB.T6G(SCH_1):P1V8_CPU1_RT3_1A
 U6017 BV20 PWR_1A_1 PT5161LRS-PT5161LRS,SMLF,IC,AJ051610U03     I5 @T6G_MB_LIB.T6G(SCH_1):PAGE463
 U6017 CE17 PWR_1A_2 PT5161LRS-PT5161LRS,SMLF,IC,AJ051610U03     I5 @T6G_MB_LIB.T6G(SCH_1):PAGE463
 U6017 CE20 PWR_1A_3 PT5161LRS-PT5161LRS,SMLF,IC,AJ051610U03     I5 @T6G_MB_LIB.T6G(SCH_1):PAGE463
 U6017 CM17 PWR_1A_4 PT5161LRS-PT5161LRS,SMLF,IC,AJ051610U03     I5 @T6G_MB_LIB.T6G(SCH_1):PAGE463
 U6017 CM20 PWR_1A_5 PT5161LRS-PT5161LRS,SMLF,IC,AJ051610U03     I5 @T6G_MB_LIB.T6G(SCH_1):PAGE463
  R894    2      B Q_RES_0402LF-0,5%,1/16W,EMPTY,CS00002JB13     I1 @T6G_MB_LIB.T6G(SCH_1):PAGE465
  R893    2      B Q_RES_0402LF-0,5%,1/16W,EMPTY,CS00002JB13     I2 @T6G_MB_LIB.T6G(SCH_1):PAGE465
    L9    2      2 Q_INDUCTOR_SMLF-BLM21SN300SN1D/5A,IND,CX300SN1000    I11 @T6G_MB_LIB.T6G(SCH_1):PAGE465
  C433    1      A Q_CAP_C0805-100UF,4V,20%,X6S,CH710KMEA01    I14 @T6G_MB_LIB.T6G(SCH_1):PAGE465
  C435    1      A Q_CAP_C0402-22UF,4V,20%,X6S,CH622KMEB02    I15 @T6G_MB_LIB.T6G(SCH_1):PAGE465
  C437    1      A Q_CAP_C0402-10UF,6.3V,20%,X6S,CH6101MEB01    I16 @T6G_MB_LIB.T6G(SCH_1):PAGE465
  C438    1      A Q_CAP_0402-4.7UF,6.3V,20%,X6S,CH5471MEB01    I19 @T6G_MB_LIB.T6G(SCH_1):PAGE465
  C440    1      A Q_CAP_0201-1UF,4V,20%,X6S,CH-10KMEE00    I20 @T6G_MB_LIB.T6G(SCH_1):PAGE465
  C442    1      A Q_CAP_0201-1UF,4V,20%,X6S,CH-10KMEE00    I24 @T6G_MB_LIB.T6G(SCH_1):PAGE465
  C443    1      A Q_CAP_C0201-0.1UF,10V,10%,X7S,CH4102K6E00    I25 @T6G_MB_LIB.T6G(SCH_1):PAGE465
  C445    1      A Q_CAP_C0201-0.1UF,10V,10%,X7S,CH4102K6E00    I26 @T6G_MB_LIB.T6G(SCH_1):PAGE465
  C446    1      A Q_CAP_C0201-0.1UF,10V,10%,X7S,CH4102K6E00    I27 @T6G_MB_LIB.T6G(SCH_1):PAGE465
  C447    1      A Q_CAP_C0201-0.1UF,10V,10%,X7S,CH4102K6E00    I28 @T6G_MB_LIB.T6G(SCH_1):PAGE465

P1V8_CPU1_RT3_1A_1D @T6G_MB_LIB.T6G(SCH_1):P1V8_CPU1_RT3_1A_1D
 U6017 BV17 PWR_1D PT5161LRS-PT5161LRS,SMLF,IC,AJ051610U03     I5 @T6G_MB_LIB.T6G(SCH_1):PAGE463
  R894    1      A Q_RES_0402LF-0,5%,1/16W,EMPTY,CS00002JB13     I1 @T6G_MB_LIB.T6G(SCH_1):PAGE465
  R893    1      A Q_RES_0402LF-0,5%,1/16W,EMPTY,CS00002JB13     I2 @T6G_MB_LIB.T6G(SCH_1):PAGE465
  C441    1      A Q_CAP_0201-1UF,4V,20%,X6S,CH-10KMEE00     I4 @T6G_MB_LIB.T6G(SCH_1):PAGE465
  C444    1      A Q_CAP_C0201-0.1UF,10V,10%,X7S,CH4102K6E00     I6 @T6G_MB_LIB.T6G(SCH_1):PAGE465
   L33    2      2 Q_INDUCTOR_SMLF-BLM15PD121SN1D/1300MA,IND,CX5PD121A    I88 @T6G_MB_LIB.T6G(SCH_1):PAGE465
  R897    2      B Q_RES_0402LF-0,5%,1/16W,EMPTY,CS00002JB13    I89 @T6G_MB_LIB.T6G(SCH_1):PAGE465

P1V8_CPU1_RT_1D @T6G_MB_LIB.T6G(SCH_1):P1V8_CPU1_RT_1D
   U12    8    VCC M24M02DRMN6TP-M24M02-DRMN6TP,SMLF,IC,AKE33Z00600     I5 @T6G_MB_LIB.T6G(SCH_1):PAGE399
   U19    8    VCC M24M02DRMN6TP-M24M02-DRMN6TP,SMLF,IC,AKE33Z00600     I5 @T6G_MB_LIB.T6G(SCH_1):PAGE442
   U20    8    VCC M24M02DRMN6TP-M24M02-DRMN6TP,SMLF,IC,AKE33Z00600     I5 @T6G_MB_LIB.T6G(SCH_1):PAGE453
   U21    8    VCC M24M02DRMN6TP-M24M02-DRMN6TP,SMLF,IC,AKE33Z00600     I5 @T6G_MB_LIB.T6G(SCH_1):PAGE464
  C113    1      A Q_CAP_C0805-100UF,4V,20%,X6S,CH710KMEA01    I12 @T6G_MB_LIB.T6G(SCH_1):PAGE398
  C118    1      A Q_CAP_C0402-10UF,6.3V,20%,X6S,CH6101MEB01    I14 @T6G_MB_LIB.T6G(SCH_1):PAGE398
  C122    1      A Q_CAP_0402-4.7UF,6.3V,20%,X6S,CH5471MEB01    I15 @T6G_MB_LIB.T6G(SCH_1):PAGE398
PC6534    2      B Q_CAP_0402-150PF,50V,5%,NPO,TMP_QCH11506JB08    I33 @T6G_MB_LIB.T6G(SCH_1):PAGE470
PR6524    2      B Q_RES_0402LF-20K,1%,1/16W,CHIP,CS32002FB06    I34 @T6G_MB_LIB.T6G(SCH_1):PAGE470
PL6502    2      2 Q_INDUCTOR_SMLF-1UH,IND,CV-10U0MZ01    I37 @T6G_MB_LIB.T6G(SCH_1):PAGE470
PC6527    1      A Q_CAP_C0805-22UF,4V,20%,X6S,CH622KMEA03    I38 @T6G_MB_LIB.T6G(SCH_1):PAGE470
PC6528    1      A Q_CAP_C0805-22UF,4V,20%,X6S,CH622KMEA03    I41 @T6G_MB_LIB.T6G(SCH_1):PAGE470
PC6529    1      A Q_CAP_C0805-22UF,4V,20%,X6S,CH622KMEA03    I42 @T6G_MB_LIB.T6G(SCH_1):PAGE470
PC6530    1      A Q_CAP_C0805-22UF,4V,20%,X6S,CH622KMEA03    I44 @T6G_MB_LIB.T6G(SCH_1):PAGE470
PC6531    1      A Q_CAP_C0805-22UF,4V,20%,X6S,CH622KMEA03    I45 @T6G_MB_LIB.T6G(SCH_1):PAGE470
PC6532    1      A Q_CAPP_SMLF-390UF,2.5V,20%,ALUM,CC7390JMZ13    I46 @T6G_MB_LIB.T6G(SCH_1):PAGE470
PC6804    1      A Q_CAPP_SMLF-390UF,2.5V,20%,ALUM,CC7390JMZ13    I47 @T6G_MB_LIB.T6G(SCH_1):PAGE470
PC6533    1      A Q_CAP_0402-0.1UF,25V,10%,X7R,CH4104K1B00    I49 @T6G_MB_LIB.T6G(SCH_1):PAGE470
  C115    1      A Q_CAP_C0402-22UF,4V,20%,X6S,CH622KMEB02    I21 @T6G_MB_LIB.T6G(SCH_1):PAGE398
    L3    1      1 Q_INDUCTOR_SMLF-BLM21SN300SN1D/5A,IND,CX300SN1000    I22 @T6G_MB_LIB.T6G(SCH_1):PAGE398
  R724    1      A Q_RES_0201LF-4.7K,5%,1/20W,EMPTY,CS24701JE04    I25 @T6G_MB_LIB.T6G(SCH_1):PAGE401
  R720    1      A Q_RES_0201LF-4.7K,5%,1/20W,EMPTY,CS24701JE04    I26 @T6G_MB_LIB.T6G(SCH_1):PAGE401
  R716    1      A Q_RES_0201LF-4.7K,5%,1/20W,EMPTY,CS24701JE04    I27 @T6G_MB_LIB.T6G(SCH_1):PAGE401
  R706    1      A Q_RES_0201LF-4.7K,5%,1/20W,EMPTY,CS24701JE04    I29 @T6G_MB_LIB.T6G(SCH_1):PAGE401
  R727    1      A Q_RES_0201LF-4.7K,5%,1/20W,CHIP,CS24701JE04    I54 @T6G_MB_LIB.T6G(SCH_1):PAGE401
 R6718    1      A Q_RES_0201LF-1K,1%,1/20W,CHIP,CS21001FE07     I9 @T6G_MB_LIB.T6G(SCH_1):PAGE378
 R6719    1      A Q_RES_0201LF-1K,1%,1/20W,CHIP,CS21001FE07    I11 @T6G_MB_LIB.T6G(SCH_1):PAGE378
 R6722    1      A Q_RES_0201LF-4.7K,5%,1/20W,EMPTY,CS24701JE04    I85 @T6G_MB_LIB.T6G(SCH_1):PAGE401
 R6725    1      A Q_RES_0201LF-4.7K,5%,1/20W,EMPTY,CS24701JE04    I91 @T6G_MB_LIB.T6G(SCH_1):PAGE401
 R6724    1      A Q_RES_0201LF-4.7K,5%,1/20W,EMPTY,CS24701JE04   I101 @T6G_MB_LIB.T6G(SCH_1):PAGE401
    L5    1      1 Q_INDUCTOR_SMLF-BLM21SN300SN1D/5A,IND,CX300SN1000    I12 @T6G_MB_LIB.T6G(SCH_1):PAGE443
  C102    1      A Q_CAP_C0805-100UF,4V,20%,X6S,CH710KMEA01    I16 @T6G_MB_LIB.T6G(SCH_1):PAGE443
  C110    1      A Q_CAP_C0402-22UF,4V,20%,X6S,CH622KMEB02    I24 @T6G_MB_LIB.T6G(SCH_1):PAGE443
  C127    1      A Q_CAP_C0402-10UF,6.3V,20%,X6S,CH6101MEB01    I25 @T6G_MB_LIB.T6G(SCH_1):PAGE443
  C200    1      A Q_CAP_0402-4.7UF,6.3V,20%,X6S,CH5471MEB01    I26 @T6G_MB_LIB.T6G(SCH_1):PAGE443
  R755    1      A Q_RES_0201LF-4.7K,5%,1/20W,EMPTY,CS24701JE04    I19 @T6G_MB_LIB.T6G(SCH_1):PAGE392
  R781    1      A Q_RES_0201LF-4.7K,5%,1/20W,EMPTY,CS24701JE04    I24 @T6G_MB_LIB.T6G(SCH_1):PAGE392
  R784    1      A Q_RES_0201LF-4.7K,5%,1/20W,EMPTY,CS24701JE04    I25 @T6G_MB_LIB.T6G(SCH_1):PAGE392
  R786    1      A Q_RES_0201LF-4.7K,5%,1/20W,EMPTY,CS24701JE04    I55 @T6G_MB_LIB.T6G(SCH_1):PAGE392
  R788    1      A Q_RES_0201LF-4.7K,5%,1/20W,EMPTY,CS24701JE04    I56 @T6G_MB_LIB.T6G(SCH_1):PAGE392
  R759    1      A Q_RES_0201LF-4.7K,5%,1/20W,EMPTY,CS24701JE04    I57 @T6G_MB_LIB.T6G(SCH_1):PAGE392
  R793    1      A Q_RES_0201LF-4.7K,5%,1/20W,CHIP,CS24701JE04    I66 @T6G_MB_LIB.T6G(SCH_1):PAGE392
  R758    1      A Q_RES_0201LF-4.7K,5%,1/20W,EMPTY,CS24701JE04    I94 @T6G_MB_LIB.T6G(SCH_1):PAGE392
 R6738    1      A Q_RES_0201LF-1K,1%,1/20W,CHIP,CS21001FE07    I17 @T6G_MB_LIB.T6G(SCH_1):PAGE378
 R6739    1      A Q_RES_0201LF-1K,1%,1/20W,CHIP,CS21001FE07    I18 @T6G_MB_LIB.T6G(SCH_1):PAGE378
 R6750    1      A Q_RES_0201LF-1K,1%,1/20W,CHIP,CS21001FE07    I31 @T6G_MB_LIB.T6G(SCH_1):PAGE378
 R6751    1      A Q_RES_0201LF-1K,1%,1/20W,CHIP,CS21001FE07    I32 @T6G_MB_LIB.T6G(SCH_1):PAGE378
 R6752    1      A Q_RES_0201LF-1K,1%,1/20W,CHIP,CS21001FE07    I35 @T6G_MB_LIB.T6G(SCH_1):PAGE378
 R6753    1      A Q_RES_0201LF-1K,1%,1/20W,CHIP,CS21001FE07    I36 @T6G_MB_LIB.T6G(SCH_1):PAGE378
  R827    1      A Q_RES_0201LF-1K,1%,1/20W,CHIP,CS21001FE07    I58 @T6G_MB_LIB.T6G(SCH_1):PAGE377
  R826    1      A Q_RES_0201LF-1K,1%,1/20W,CHIP,CS21001FE07    I59 @T6G_MB_LIB.T6G(SCH_1):PAGE377
  R812    1      A Q_RES_0201LF-1K,1%,1/20W,CHIP,CS21001FE07    I60 @T6G_MB_LIB.T6G(SCH_1):PAGE377
  R810    1      A Q_RES_0201LF-1K,1%,1/20W,CHIP,CS21001FE07    I61 @T6G_MB_LIB.T6G(SCH_1):PAGE377
 R6734    1      A Q_RES_0201LF-1K,1%,1/20W,CHIP,CS21001FE07    I62 @T6G_MB_LIB.T6G(SCH_1):PAGE377
 R6735    1      A Q_RES_0201LF-1K,1%,1/20W,CHIP,CS21001FE07    I63 @T6G_MB_LIB.T6G(SCH_1):PAGE377
 R6707    1      A Q_RES_0201LF-1K,1%,1/20W,CHIP,CS21001FE07    I64 @T6G_MB_LIB.T6G(SCH_1):PAGE377
 R6706    1      A Q_RES_0201LF-1K,1%,1/20W,CHIP,CS21001FE07    I65 @T6G_MB_LIB.T6G(SCH_1):PAGE377
 R6712    1      A Q_RES_0201LF-1K,1%,1/20W,CHIP,CS21001FE07   I102 @T6G_MB_LIB.T6G(SCH_1):PAGE401
 R6714    1      A Q_RES_0201LF-1K,1%,1/20W,EMPTY,CS21001FE07   I104 @T6G_MB_LIB.T6G(SCH_1):PAGE401
 R6716    1      A Q_RES_0201LF-1K,1%,1/20W,EMPTY,CS21001FE07   I107 @T6G_MB_LIB.T6G(SCH_1):PAGE401
  R735    1      A Q_RES_0201LF-1K,1%,1/20W,CHIP,CS21001FE07   I103 @T6G_MB_LIB.T6G(SCH_1):PAGE392
  R745    1      A Q_RES_0201LF-1K,1%,1/20W,EMPTY,CS21001FE07   I104 @T6G_MB_LIB.T6G(SCH_1):PAGE392
  R795    1      A Q_RES_0201LF-1K,1%,1/20W,EMPTY,CS21001FE07   I110 @T6G_MB_LIB.T6G(SCH_1):PAGE392
 C7501    1      A Q_CAP_C0201-0.1UF,10V,10%,X7S,CH4102K6E00    I11 @T6G_MB_LIB.T6G(SCH_1):PAGE399
 C7502    1      A Q_CAP_C0201-0.1UF,10V,10%,X7S,CH4102K6E00    I22 @T6G_MB_LIB.T6G(SCH_1):PAGE442
 C7503    1      A Q_CAP_C0201-0.1UF,10V,10%,X7S,CH4102K6E00    I23 @T6G_MB_LIB.T6G(SCH_1):PAGE453
 C7504    1      A Q_CAP_C0201-0.1UF,10V,10%,X7S,CH4102K6E00    I19 @T6G_MB_LIB.T6G(SCH_1):PAGE464
  R868    1      A Q_RES_0201LF-4.7K,5%,1/20W,EMPTY,CS24701JE04    I17 @T6G_MB_LIB.T6G(SCH_1):PAGE451
  R874    1      A Q_RES_0201LF-4.7K,5%,1/20W,EMPTY,CS24701JE04    I21 @T6G_MB_LIB.T6G(SCH_1):PAGE451
  R878    1      A Q_RES_0201LF-4.7K,5%,1/20W,EMPTY,CS24701JE04    I47 @T6G_MB_LIB.T6G(SCH_1):PAGE451
  R880    1      A Q_RES_0201LF-4.7K,5%,1/20W,EMPTY,CS24701JE04    I48 @T6G_MB_LIB.T6G(SCH_1):PAGE451
  R882    1      A Q_RES_0201LF-4.7K,5%,1/20W,EMPTY,CS24701JE04    I49 @T6G_MB_LIB.T6G(SCH_1):PAGE451
  R871    1      A Q_RES_0201LF-4.7K,5%,1/20W,EMPTY,CS24701JE04    I50 @T6G_MB_LIB.T6G(SCH_1):PAGE451
  R885    1      A Q_RES_0201LF-4.7K,5%,1/20W,CHIP,CS24701JE04    I59 @T6G_MB_LIB.T6G(SCH_1):PAGE451
  R861    1      A Q_RES_0201LF-1K,1%,1/20W,CHIP,CS21001FE07    I74 @T6G_MB_LIB.T6G(SCH_1):PAGE451
  R864    1      A Q_RES_0201LF-1K,1%,1/20W,EMPTY,CS21001FE07    I75 @T6G_MB_LIB.T6G(SCH_1):PAGE451
  R887    1      A Q_RES_0201LF-1K,1%,1/20W,EMPTY,CS21001FE07    I77 @T6G_MB_LIB.T6G(SCH_1):PAGE451
  R870    1      A Q_RES_0201LF-4.7K,5%,1/20W,EMPTY,CS24701JE04    I86 @T6G_MB_LIB.T6G(SCH_1):PAGE451
    L7    1      1 Q_INDUCTOR_SMLF-BLM21SN300SN1D/5A,IND,CX300SN1000    I21 @T6G_MB_LIB.T6G(SCH_1):PAGE454
  C366    1      A Q_CAP_C0805-100UF,4V,20%,X6S,CH710KMEA01    I24 @T6G_MB_LIB.T6G(SCH_1):PAGE454
  C368    1      A Q_CAP_C0402-22UF,4V,20%,X6S,CH622KMEB02    I25 @T6G_MB_LIB.T6G(SCH_1):PAGE454
  C370    1      A Q_CAP_C0402-10UF,6.3V,20%,X6S,CH6101MEB01    I27 @T6G_MB_LIB.T6G(SCH_1):PAGE454
  C373    1      A Q_CAP_0402-4.7UF,6.3V,20%,X6S,CH5471MEB01    I28 @T6G_MB_LIB.T6G(SCH_1):PAGE454
  R909    1      A Q_RES_0201LF-4.7K,5%,1/20W,EMPTY,CS24701JE04    I17 @T6G_MB_LIB.T6G(SCH_1):PAGE462
  R915    1      A Q_RES_0201LF-4.7K,5%,1/20W,EMPTY,CS24701JE04    I22 @T6G_MB_LIB.T6G(SCH_1):PAGE462
  R918    1      A Q_RES_0201LF-4.7K,5%,1/20W,EMPTY,CS24701JE04    I23 @T6G_MB_LIB.T6G(SCH_1):PAGE462
  R920    1      A Q_RES_0201LF-4.7K,5%,1/20W,EMPTY,CS24701JE04    I54 @T6G_MB_LIB.T6G(SCH_1):PAGE462
  R922    1      A Q_RES_0201LF-4.7K,5%,1/20W,EMPTY,CS24701JE04    I55 @T6G_MB_LIB.T6G(SCH_1):PAGE462
  R912    1      A Q_RES_0201LF-4.7K,5%,1/20W,EMPTY,CS24701JE04    I56 @T6G_MB_LIB.T6G(SCH_1):PAGE462
  R925    1      A Q_RES_0201LF-4.7K,5%,1/20W,CHIP,CS24701JE04    I65 @T6G_MB_LIB.T6G(SCH_1):PAGE462
  R902    1      A Q_RES_0201LF-1K,1%,1/20W,CHIP,CS21001FE07    I80 @T6G_MB_LIB.T6G(SCH_1):PAGE462
  R904    1      A Q_RES_0201LF-1K,1%,1/20W,EMPTY,CS21001FE07    I82 @T6G_MB_LIB.T6G(SCH_1):PAGE462
  R927    1      A Q_RES_0201LF-1K,1%,1/20W,EMPTY,CS21001FE07    I84 @T6G_MB_LIB.T6G(SCH_1):PAGE462
  R911    1      A Q_RES_0201LF-4.7K,5%,1/20W,EMPTY,CS24701JE04    I93 @T6G_MB_LIB.T6G(SCH_1):PAGE462
    L9    1      1 Q_INDUCTOR_SMLF-BLM21SN300SN1D/5A,IND,CX300SN1000    I11 @T6G_MB_LIB.T6G(SCH_1):PAGE465
  C432    1      A Q_CAP_C0805-100UF,4V,20%,X6S,CH710KMEA01    I17 @T6G_MB_LIB.T6G(SCH_1):PAGE465
  C434    1      A Q_CAP_C0402-22UF,4V,20%,X6S,CH622KMEB02    I18 @T6G_MB_LIB.T6G(SCH_1):PAGE465
  C436    1      A Q_CAP_C0402-10UF,6.3V,20%,X6S,CH6101MEB01    I21 @T6G_MB_LIB.T6G(SCH_1):PAGE465
  C439    1      A Q_CAP_0402-4.7UF,6.3V,20%,X6S,CH5471MEB01    I23 @T6G_MB_LIB.T6G(SCH_1):PAGE465
 R1234    1      A Q_RES_0402LF-5.11K,1%,1/16W,CHIP,CS25112FB04   I194 @T6G_MB_LIB.T6G(SCH_1):PAGE263
 R1388    1      A Q_RES_0201LF-1K,1%,1/20W,EMPTY,CS21001FE07   I125 @T6G_MB_LIB.T6G(SCH_1):PAGE401
 R1377    1      A Q_RES_0201LF-1K,1%,1/20W,EMPTY,CS21001FE07   I125 @T6G_MB_LIB.T6G(SCH_1):PAGE392
 R1426    1      A Q_RES_0201LF-1K,1%,1/20W,EMPTY,CS21001FE07   I114 @T6G_MB_LIB.T6G(SCH_1):PAGE451
 R1434    1      A Q_RES_0201LF-1K,1%,1/20W,EMPTY,CS21001FE07   I115 @T6G_MB_LIB.T6G(SCH_1):PAGE462
  R699    1      A Q_RES_0201LF-1K,1%,1/20W,EMPTY,CS21001FE07   I106 @T6G_MB_LIB.T6G(SCH_1):PAGE400
 R6730    1      A Q_RES_0201LF-1K,1%,1/20W,EMPTY,CS21001FE07    I21 @T6G_MB_LIB.T6G(SCH_1):PAGE391
 R6794    1      A Q_RES_0201LF-1K,1%,1/20W,EMPTY,CS21001FE07    I21 @T6G_MB_LIB.T6G(SCH_1):PAGE452
 R6900    1      A Q_RES_0201LF-1K,1%,1/20W,EMPTY,CS21001FE07    I19 @T6G_MB_LIB.T6G(SCH_1):PAGE463
 R1465    1      A Q_RES_0201LF-4.7K,5%,1/20W,EMPTY,CS24701JE04   I145 @T6G_MB_LIB.T6G(SCH_1):PAGE401
 R1466    1      A Q_RES_0201LF-1K,1%,1/20W,EMPTY,CS21001FE07   I146 @T6G_MB_LIB.T6G(SCH_1):PAGE401
 R1467    1      A Q_RES_0201LF-4.7K,5%,1/20W,EMPTY,CS24701JE04   I147 @T6G_MB_LIB.T6G(SCH_1):PAGE401
 R1464    1      A Q_RES_0201LF-4.7K,5%,1/20W,EMPTY,CS24701JE04   I149 @T6G_MB_LIB.T6G(SCH_1):PAGE401
 R1454    1      A Q_RES_0201LF-4.7K,5%,1/20W,EMPTY,CS24701JE04   I145 @T6G_MB_LIB.T6G(SCH_1):PAGE392
 R1455    1      A Q_RES_0201LF-4.7K,5%,1/20W,EMPTY,CS24701JE04   I146 @T6G_MB_LIB.T6G(SCH_1):PAGE392
 R1461    1      A Q_RES_0201LF-4.7K,5%,1/20W,EMPTY,CS24701JE04   I151 @T6G_MB_LIB.T6G(SCH_1):PAGE392
 R1456    1      A Q_RES_0201LF-1K,1%,1/20W,EMPTY,CS21001FE07   I153 @T6G_MB_LIB.T6G(SCH_1):PAGE392
 R1488    1      A Q_RES_0201LF-4.7K,5%,1/20W,EMPTY,CS24701JE04   I132 @T6G_MB_LIB.T6G(SCH_1):PAGE451
 R1499    1      A Q_RES_0201LF-4.7K,5%,1/20W,EMPTY,CS24701JE04   I137 @T6G_MB_LIB.T6G(SCH_1):PAGE451
 R1490    1      A Q_RES_0201LF-1K,1%,1/20W,EMPTY,CS21001FE07   I139 @T6G_MB_LIB.T6G(SCH_1):PAGE451
 R1489    1      A Q_RES_0201LF-4.7K,5%,1/20W,EMPTY,CS24701JE04   I140 @T6G_MB_LIB.T6G(SCH_1):PAGE451
 R1511    1      A Q_RES_0201LF-4.7K,5%,1/20W,EMPTY,CS24701JE04   I132 @T6G_MB_LIB.T6G(SCH_1):PAGE462
 R1513    1      A Q_RES_0201LF-4.7K,5%,1/20W,EMPTY,CS24701JE04   I137 @T6G_MB_LIB.T6G(SCH_1):PAGE462
 R1510    1      A Q_RES_0201LF-4.7K,5%,1/20W,EMPTY,CS24701JE04   I139 @T6G_MB_LIB.T6G(SCH_1):PAGE462
 R1512    1      A Q_RES_0201LF-1K,1%,1/20W,EMPTY,CS21001FE07   I140 @T6G_MB_LIB.T6G(SCH_1):PAGE462
 R1361    1      A Q_RES_0201LF-4.7K,5%,1/20W,CHIP,CS24701JE04   I104 @T6G_MB_LIB.T6G(SCH_1):PAGE377
 R1390    1      A Q_RES_0201LF-4.7K,5%,1/20W,CHIP,CS24701JE04   I105 @T6G_MB_LIB.T6G(SCH_1):PAGE377
 R1393    1      A Q_RES_0201LF-4.7K,5%,1/20W,CHIP,CS24701JE04   I106 @T6G_MB_LIB.T6G(SCH_1):PAGE377
 R1394    1      A Q_RES_0201LF-4.7K,5%,1/20W,CHIP,CS24701JE04   I107 @T6G_MB_LIB.T6G(SCH_1):PAGE377
 R1399    1      A Q_RES_0201LF-4.7K,5%,1/20W,CHIP,CS24701JE04   I108 @T6G_MB_LIB.T6G(SCH_1):PAGE377
 R1402    1      A Q_RES_0201LF-4.7K,5%,1/20W,CHIP,CS24701JE04   I109 @T6G_MB_LIB.T6G(SCH_1):PAGE377
 R1403    1      A Q_RES_0201LF-4.7K,5%,1/20W,CHIP,CS24701JE04   I110 @T6G_MB_LIB.T6G(SCH_1):PAGE377
 R1407    1      A Q_RES_0201LF-4.7K,5%,1/20W,CHIP,CS24701JE04   I111 @T6G_MB_LIB.T6G(SCH_1):PAGE377
 R1437    1      A Q_RES_0201LF-1K,1%,1/20W,CHIP,CS21001FE07   I172 @T6G_MB_LIB.T6G(SCH_1):PAGE377
 R1436    1      A Q_RES_0201LF-1K,1%,1/20W,CHIP,CS21001FE07   I173 @T6G_MB_LIB.T6G(SCH_1):PAGE377
 R1448    1      A Q_RES_0201LF-1K,1%,1/20W,CHIP,CS21001FE07   I174 @T6G_MB_LIB.T6G(SCH_1):PAGE377
 R1451    1      A Q_RES_0201LF-1K,1%,1/20W,CHIP,CS21001FE07   I175 @T6G_MB_LIB.T6G(SCH_1):PAGE377
 R1462    1      A Q_RES_0201LF-1K,1%,1/20W,CHIP,CS21001FE07   I176 @T6G_MB_LIB.T6G(SCH_1):PAGE377
 R1463    1      A Q_RES_0201LF-1K,1%,1/20W,CHIP,CS21001FE07   I177 @T6G_MB_LIB.T6G(SCH_1):PAGE377
 R1468    1      A Q_RES_0201LF-1K,1%,1/20W,CHIP,CS21001FE07   I178 @T6G_MB_LIB.T6G(SCH_1):PAGE377
 R1469    1      A Q_RES_0201LF-1K,1%,1/20W,CHIP,CS21001FE07   I179 @T6G_MB_LIB.T6G(SCH_1):PAGE377
   L27    1      1 Q_INDUCTOR_SMLF-BLM15PD121SN1D/1300MA,IND,CX5PD121A    I97 @T6G_MB_LIB.T6G(SCH_1):PAGE398
 R6701    1      A Q_RES_0402LF-0,5%,1/16W,EMPTY,CS00002JB13    I98 @T6G_MB_LIB.T6G(SCH_1):PAGE398
   L31    1      1 Q_INDUCTOR_SMLF-BLM15PD121SN1D/1300MA,IND,CX5PD121A    I88 @T6G_MB_LIB.T6G(SCH_1):PAGE443
  R704    1      A Q_RES_0402LF-0,5%,1/16W,EMPTY,CS00002JB13    I89 @T6G_MB_LIB.T6G(SCH_1):PAGE443
   L32    1      1 Q_INDUCTOR_SMLF-BLM15PD121SN1D/1300MA,IND,CX5PD121A    I88 @T6G_MB_LIB.T6G(SCH_1):PAGE454
  R857    1      A Q_RES_0402LF-0,5%,1/16W,EMPTY,CS00002JB13    I89 @T6G_MB_LIB.T6G(SCH_1):PAGE454
   L33    1      1 Q_INDUCTOR_SMLF-BLM15PD121SN1D/1300MA,IND,CX5PD121A    I88 @T6G_MB_LIB.T6G(SCH_1):PAGE465
  R897    1      A Q_RES_0402LF-0,5%,1/16W,EMPTY,CS00002JB13    I89 @T6G_MB_LIB.T6G(SCH_1):PAGE465

P1V8_CPU1_RT_1D_ADC @T6G_MB_LIB.T6G(SCH_1):P1V8_CPU1_RT_1D_ADC
 R1234    2      B Q_RES_0402LF-5.11K,1%,1/16W,CHIP,CS25112FB04   I194 @T6G_MB_LIB.T6G(SCH_1):PAGE263
 R1250    1      A Q_RES_0402LF-0,5%,1/16W,EMPTY,CS00002JB13   I202 @T6G_MB_LIB.T6G(SCH_1):PAGE263
 R1257    1      A Q_RES_0402LF-0,5%,1/16W,CHIP,CS00002JB13   I203 @T6G_MB_LIB.T6G(SCH_1):PAGE263
 R1223    1      A Q_RES_0402LF-18K,1%,1/16W,CHIP,CS31802FB04   I245 @T6G_MB_LIB.T6G(SCH_1):PAGE263

P1V8_CPU1_RT_1D_ADC_MAM @T6G_MB_LIB.T6G(SCH_1):P1V8_CPU1_RT_1D_ADC_MAM
   U50    9   AIN4 MAX11617EEET-MAX11617EEE+T,SMLF,EMPTY,AL011617W00   I156 @T6G_MB_LIB.T6G(SCH_1):PAGE263
 C1083    1      A Q_CAP_0402-100PF,50V,5%,EMPTY,CH11006JB18   I198 @T6G_MB_LIB.T6G(SCH_1):PAGE263
 R1250    2      B Q_RES_0402LF-0,5%,1/16W,EMPTY,CS00002JB13   I202 @T6G_MB_LIB.T6G(SCH_1):PAGE263

P1V8_CPU1_RT_1D_ADC_TIC @T6G_MB_LIB.T6G(SCH_1):P1V8_CPU1_RT_1D_ADC_TIC
   U51   12    IN4 ADC128D818CIMTXNOPB-ADC128D818CIMTX/NOPB,SMLF,IC,AA   I142 @T6G_MB_LIB.T6G(SCH_1):PAGE263
 C1091    1      A Q_CAP_0402-0.1UF,25V,10%,X7R,CH4104K1B00   I200 @T6G_MB_LIB.T6G(SCH_1):PAGE263
 R1257    2      B Q_RES_0402LF-0,5%,1/16W,CHIP,CS00002JB13   I203 @T6G_MB_LIB.T6G(SCH_1):PAGE263

P1V8_RETIMER_CPU0_CS @T6G_MB_LIB.T6G(SCH_1):P1V8_RETIMER_CPU0_CS
PR6502    1      A Q_RES_0402LF-7.15K,1%,1/16W,CHIP,CS27152FB03    I20 @T6G_MB_LIB.T6G(SCH_1):PAGE469
PU6500    3     CS MPQ8633BGLEC838Z-MPQ8633BGLE-C838-Z,SMLF,IC,AL0086A    I51 @T6G_MB_LIB.T6G(SCH_1):PAGE469

P1V8_RETIMER_CPU0_EN @T6G_MB_LIB.T6G(SCH_1):P1V8_RETIMER_CPU0_EN
 C6757    1      A Q_CAP_0402-0.1UF,25V,10%,EMPTY,CH4104K1B00     I5 @T6G_MB_LIB.T6G(SCH_1):PAGE469
PU6500    8     EN MPQ8633BGLEC838Z-MPQ8633BGLE-C838-Z,SMLF,IC,AL0086A    I51 @T6G_MB_LIB.T6G(SCH_1):PAGE469
 R6850    1      A Q_RES_0402LF-33,5%,1/16W,CHIP,CS03302JB10   I146 @T6G_MB_LIB.T6G(SCH_1):PAGE79

P1V8_RETIMER_CPU0_FB @T6G_MB_LIB.T6G(SCH_1):P1V8_RETIMER_CPU0_FB
PR6507    1      A Q_RES_0402LF-10K,1%,1/16W,CHIP,CS31002FB08    I33 @T6G_MB_LIB.T6G(SCH_1):PAGE469
PC6515    1      A Q_CAP_0402-150PF,50V,5%,NPO,TMP_QCH11506JB08    I34 @T6G_MB_LIB.T6G(SCH_1):PAGE469
PR6505    1      A Q_RES_0402LF-20K,1%,1/16W,CHIP,CS32002FB06    I35 @T6G_MB_LIB.T6G(SCH_1):PAGE469
PU6500    7     FB MPQ8633BGLEC838Z-MPQ8633BGLE-C838-Z,SMLF,IC,AL0086A    I51 @T6G_MB_LIB.T6G(SCH_1):PAGE469

P1V8_RETIMER_CPU0_MODE @T6G_MB_LIB.T6G(SCH_1):P1V8_RETIMER_CPU0_MODE
PR6500    2      B Q_RES_0402LF-0,5%,1/16W,CHIP,CS00002JB13    I21 @T6G_MB_LIB.T6G(SCH_1):PAGE469
PU6500    4   MODE MPQ8633BGLEC838Z-MPQ8633BGLE-C838-Z,SMLF,IC,AL0086A    I51 @T6G_MB_LIB.T6G(SCH_1):PAGE469

P1V8_RETIMER_CPU0_REF @T6G_MB_LIB.T6G(SCH_1):P1V8_RETIMER_CPU0_REF
PC6518    1      A Q_CAP_0402-0.1UF,25V,10%,X7R,CH4104K1B00    I26 @T6G_MB_LIB.T6G(SCH_1):PAGE469
PU6500    5 TRK_REF MPQ8633BGLEC838Z-MPQ8633BGLE-C838-Z,SMLF,IC,AL0086A    I51 @T6G_MB_LIB.T6G(SCH_1):PAGE469

P1V8_RETIMER_CPU0_R_EN @T6G_MB_LIB.T6G(SCH_1):P1V8_RETIMER_CPU0_R_EN
   U18  B15  PT38B LCMXO3LF9400C5BG484C-LCMXO3LF-9400C-5BG484C,SMLF,IA    I94 @T6G_MB_LIB.T6G(SCH_1):PAGE79
 R6850    2      B Q_RES_0402LF-33,5%,1/16W,CHIP,CS03302JB10   I146 @T6G_MB_LIB.T6G(SCH_1):PAGE79

P1V8_RETIMER_CPU0_VCC @T6G_MB_LIB.T6G(SCH_1):P1V8_RETIMER_CPU0_VCC
PC6506    1      A Q_CAP_C0402-1UF,25V,10%,X6S,CH5104KEB02    I12 @T6G_MB_LIB.T6G(SCH_1):PAGE469
PR6501    2      B Q_RES_0402LF-0,5%,1/16W,CHIP,CS00002JB13    I13 @T6G_MB_LIB.T6G(SCH_1):PAGE469
PU6500   19    VCC MPQ8633BGLEC838Z-MPQ8633BGLE-C838-Z,SMLF,IC,AL0086A    I51 @T6G_MB_LIB.T6G(SCH_1):PAGE469

P1V8_RETIMER_CPU1_CS @T6G_MB_LIB.T6G(SCH_1):P1V8_RETIMER_CPU1_CS
PR6522    1      A Q_RES_0402LF-7.15K,1%,1/16W,CHIP,CS27152FB03    I20 @T6G_MB_LIB.T6G(SCH_1):PAGE470
PU6501    3     CS MPQ8633BGLEC838Z-MPQ8633BGLE-C838-Z,SMLF,IC,AL0086A    I51 @T6G_MB_LIB.T6G(SCH_1):PAGE470

P1V8_RETIMER_CPU1_EN @T6G_MB_LIB.T6G(SCH_1):P1V8_RETIMER_CPU1_EN
  C105    1      A Q_CAP_0402-0.1UF,25V,10%,EMPTY,CH4104K1B00     I5 @T6G_MB_LIB.T6G(SCH_1):PAGE470
PU6501    8     EN MPQ8633BGLEC838Z-MPQ8633BGLE-C838-Z,SMLF,IC,AL0086A    I51 @T6G_MB_LIB.T6G(SCH_1):PAGE470
 R6851    1      A Q_RES_0402LF-33,5%,1/16W,CHIP,CS03302JB10   I147 @T6G_MB_LIB.T6G(SCH_1):PAGE79

P1V8_RETIMER_CPU1_FB @T6G_MB_LIB.T6G(SCH_1):P1V8_RETIMER_CPU1_FB
PR6526    1      A Q_RES_0402LF-10K,1%,1/16W,CHIP,CS31002FB08    I32 @T6G_MB_LIB.T6G(SCH_1):PAGE470
PC6534    1      A Q_CAP_0402-150PF,50V,5%,NPO,TMP_QCH11506JB08    I33 @T6G_MB_LIB.T6G(SCH_1):PAGE470
PR6524    1      A Q_RES_0402LF-20K,1%,1/16W,CHIP,CS32002FB06    I34 @T6G_MB_LIB.T6G(SCH_1):PAGE470
PU6501    7     FB MPQ8633BGLEC838Z-MPQ8633BGLE-C838-Z,SMLF,IC,AL0086A    I51 @T6G_MB_LIB.T6G(SCH_1):PAGE470

P1V8_RETIMER_CPU1_MODE @T6G_MB_LIB.T6G(SCH_1):P1V8_RETIMER_CPU1_MODE
PR6520    2      B Q_RES_0402LF-0,5%,1/16W,CHIP,CS00002JB13    I21 @T6G_MB_LIB.T6G(SCH_1):PAGE470
PU6501    4   MODE MPQ8633BGLEC838Z-MPQ8633BGLE-C838-Z,SMLF,IC,AL0086A    I51 @T6G_MB_LIB.T6G(SCH_1):PAGE470

P1V8_RETIMER_CPU1_REF @T6G_MB_LIB.T6G(SCH_1):P1V8_RETIMER_CPU1_REF
PC6537    1      A Q_CAP_0402-0.1UF,25V,10%,X7R,CH4104K1B00    I25 @T6G_MB_LIB.T6G(SCH_1):PAGE470
PU6501    5 TRK_REF MPQ8633BGLEC838Z-MPQ8633BGLE-C838-Z,SMLF,IC,AL0086A    I51 @T6G_MB_LIB.T6G(SCH_1):PAGE470

P1V8_RETIMER_CPU1_R_EN @T6G_MB_LIB.T6G(SCH_1):P1V8_RETIMER_CPU1_R_EN
   U18  A20 PT43A||R_GPLLT LCMXO3LF9400C5BG484C-LCMXO3LF-9400C-5BG484C,SMLF,IA    I94 @T6G_MB_LIB.T6G(SCH_1):PAGE79
 R6851    2      B Q_RES_0402LF-33,5%,1/16W,CHIP,CS03302JB10   I147 @T6G_MB_LIB.T6G(SCH_1):PAGE79

P1V8_RETIMER_CPU1_VCC @T6G_MB_LIB.T6G(SCH_1):P1V8_RETIMER_CPU1_VCC
PC6525    1      A Q_CAP_C0402-1UF,25V,10%,X6S,CH5104KEB02    I12 @T6G_MB_LIB.T6G(SCH_1):PAGE470
PR6521    2      B Q_RES_0402LF-0,5%,1/16W,CHIP,CS00002JB13    I13 @T6G_MB_LIB.T6G(SCH_1):PAGE470
PU6501   19    VCC MPQ8633BGLEC838Z-MPQ8633BGLE-C838-Z,SMLF,IC,AL0086A    I51 @T6G_MB_LIB.T6G(SCH_1):PAGE470

P2E_CPU0_P5_RX_DN @T6G_MB_LIB.T6G(SCH_1):P2E_CPU0_P5_RX_DN
   U25  E44 P5_RXN2 GENOA_SP5-SOCKET6096_13568-001,SMLF,IO,DGA^6000030    I59 @T6G_MB_LIB.T6G(SCH_1):PAGE26
   J41  A21  PERP1 SCONN168_ME1016810202011-SCONN168_ME1016810202011,A   I176 @T6G_MB_LIB.T6G(SCH_1):PAGE348

P2E_CPU0_P5_RX_DP @T6G_MB_LIB.T6G(SCH_1):P2E_CPU0_P5_RX_DP
   U25  E43 P5_RXP2 GENOA_SP5-SOCKET6096_13568-001,SMLF,IO,DGA^6000030    I59 @T6G_MB_LIB.T6G(SCH_1):PAGE26
   J41  A20  PERN1 SCONN168_ME1016810202011-SCONN168_ME1016810202011,A   I176 @T6G_MB_LIB.T6G(SCH_1):PAGE348

P2E_CPU0_P5_TX_C_DN @T6G_MB_LIB.T6G(SCH_1):P2E_CPU0_P5_TX_C_DN
   J41  A18  PERP0 SCONN168_ME1016810202011-SCONN168_ME1016810202011,A   I176 @T6G_MB_LIB.T6G(SCH_1):PAGE348
 C2078    2      2 Q_CAP_DIFFBUS_C0201-DIFF BUS_0.22UF,6.3V,20%,X6S,SA   I157 @T6G_MB_LIB.T6G(SCH_1):PAGE26

P2E_CPU0_P5_TX_C_DP @T6G_MB_LIB.T6G(SCH_1):P2E_CPU0_P5_TX_C_DP
   J41  A17  PERN0 SCONN168_ME1016810202011-SCONN168_ME1016810202011,A   I176 @T6G_MB_LIB.T6G(SCH_1):PAGE348
 C2077    2      2 Q_CAP_DIFFBUS_C0201-DIFF BUS_0.22UF,6.3V,20%,X6S,SA   I156 @T6G_MB_LIB.T6G(SCH_1):PAGE26

P2E_CPU0_P5_TX_DN @T6G_MB_LIB.T6G(SCH_1):P2E_CPU0_P5_TX_DN
   U25  C45 P5_TXN2 GENOA_SP5-SOCKET6096_13568-001,SMLF,IO,DGA^6000030    I59 @T6G_MB_LIB.T6G(SCH_1):PAGE26
 C2078    1      1 Q_CAP_DIFFBUS_C0201-DIFF BUS_0.22UF,6.3V,20%,X6S,SA   I157 @T6G_MB_LIB.T6G(SCH_1):PAGE26

P2E_CPU0_P5_TX_DP @T6G_MB_LIB.T6G(SCH_1):P2E_CPU0_P5_TX_DP
   U25  C44 P5_TXP2 GENOA_SP5-SOCKET6096_13568-001,SMLF,IO,DGA^6000030    I59 @T6G_MB_LIB.T6G(SCH_1):PAGE26
 C2077    1      1 Q_CAP_DIFFBUS_C0201-DIFF BUS_0.22UF,6.3V,20%,X6S,SA   I156 @T6G_MB_LIB.T6G(SCH_1):PAGE26

P2E_MB_BMC_RX_BUF2_C_DN<0> @T6G_MB_LIB.T6G(SCH_1):P2E_MB_BMC_RX_BUF2_C_DN(0)
 U6000   19  OUTB- DS125BR111RTWR-DS125BR111RTWR,SMLF,IC,AL000125003     I1 @T6G_MB_LIB.T6G(SCH_1):PAGE111
 C6008    1      A Q_CAP_0402-0.1UF,25V,10%,X7R,CH4104K1B00    I44 @T6G_MB_LIB.T6G(SCH_1):PAGE112

P2E_MB_BMC_RX_BUF2_C_DP<0> @T6G_MB_LIB.T6G(SCH_1):P2E_MB_BMC_RX_BUF2_C_DP(0)
 U6000   20  OUTB+ DS125BR111RTWR-DS125BR111RTWR,SMLF,IC,AL000125003     I1 @T6G_MB_LIB.T6G(SCH_1):PAGE111
 C6007    1      A Q_CAP_0402-0.1UF,25V,10%,X7R,CH4104K1B00    I43 @T6G_MB_LIB.T6G(SCH_1):PAGE112

P2E_MB_BMC_RX_BUF_C_DN<0> @T6G_MB_LIB.T6G(SCH_1):P2E_MB_BMC_RX_BUF_C_DN(0)
  U237    8    BON PI3EQX12902AZLEX-PI3EQX12902AZLEX,SMLF,IC,AL012902A    I63 @T6G_MB_LIB.T6G(SCH_1):PAGE110
 C1869    1      A Q_CAP_0402-0.1UF,25V,10%,X7R,CH4104K1B00    I12 @T6G_MB_LIB.T6G(SCH_1):PAGE112

P2E_MB_BMC_RX_BUF_C_DP<0> @T6G_MB_LIB.T6G(SCH_1):P2E_MB_BMC_RX_BUF_C_DP(0)
  U237    9    BOP PI3EQX12902AZLEX-PI3EQX12902AZLEX,SMLF,IC,AL012902A    I63 @T6G_MB_LIB.T6G(SCH_1):PAGE110
 C1868    1      A Q_CAP_0402-0.1UF,25V,10%,X7R,CH4104K1B00    I11 @T6G_MB_LIB.T6G(SCH_1):PAGE112

P2E_MB_BMC_RX_BUF_DN<0> @T6G_MB_LIB.T6G(SCH_1):P2E_MB_BMC_RX_BUF_DN(0)
   J41  A66 PERP15 SCONN168_ME1016810202011-SCONN168_ME1016810202011,A   I176 @T6G_MB_LIB.T6G(SCH_1):PAGE348
 C1869    2      B Q_CAP_0402-0.1UF,25V,10%,X7R,CH4104K1B00    I12 @T6G_MB_LIB.T6G(SCH_1):PAGE112
 C6008    2      B Q_CAP_0402-0.1UF,25V,10%,X7R,CH4104K1B00    I44 @T6G_MB_LIB.T6G(SCH_1):PAGE112

P2E_MB_BMC_RX_BUF_DP<0> @T6G_MB_LIB.T6G(SCH_1):P2E_MB_BMC_RX_BUF_DP(0)
   J41  A65 PERN15 SCONN168_ME1016810202011-SCONN168_ME1016810202011,A   I176 @T6G_MB_LIB.T6G(SCH_1):PAGE348
 C1868    2      B Q_CAP_0402-0.1UF,25V,10%,X7R,CH4104K1B00    I11 @T6G_MB_LIB.T6G(SCH_1):PAGE112
 C6007    2      B Q_CAP_0402-0.1UF,25V,10%,X7R,CH4104K1B00    I43 @T6G_MB_LIB.T6G(SCH_1):PAGE112

P2E_MB_BMC_RX_DN<0> @T6G_MB_LIB.T6G(SCH_1):P2E_MB_BMC_RX_DN(0)
 R6157    1      A Q_RES_0201LF-0,5%,1/20W,CHIP,CS00001JE10    I22 @T6G_MB_LIB.T6G(SCH_1):PAGE112
 R6159    1      A Q_RES_0201LF-0,5%,1/20W,CHIP,CS00001JE10    I23 @T6G_MB_LIB.T6G(SCH_1):PAGE112
  J112   O6     O6 CONN160_10131762101LF-CONN160_10131762-101LF,THLF,A     I7 @T6G_MB_LIB.T6G(SCH_1):PAGE329

P2E_MB_BMC_RX_DP<0> @T6G_MB_LIB.T6G(SCH_1):P2E_MB_BMC_RX_DP(0)
 R6156    1      A Q_RES_0201LF-0,5%,1/20W,CHIP,CS00001JE10    I21 @T6G_MB_LIB.T6G(SCH_1):PAGE112
 R6158    1      A Q_RES_0201LF-0,5%,1/20W,CHIP,CS00001JE10    I24 @T6G_MB_LIB.T6G(SCH_1):PAGE112
  J112   N6     N6 CONN160_10131762101LF-CONN160_10131762-101LF,THLF,A     I7 @T6G_MB_LIB.T6G(SCH_1):PAGE329

P2E_MB_BMC_RX_R1_DN<0> @T6G_MB_LIB.T6G(SCH_1):P2E_MB_BMC_RX_R1_DN(0)
  U237   18    BIN PI3EQX12902AZLEX-PI3EQX12902AZLEX,SMLF,IC,AL012902A    I63 @T6G_MB_LIB.T6G(SCH_1):PAGE110
 R6157    2      B Q_RES_0201LF-0,5%,1/20W,CHIP,CS00001JE10    I22 @T6G_MB_LIB.T6G(SCH_1):PAGE112

P2E_MB_BMC_RX_R1_DP<0> @T6G_MB_LIB.T6G(SCH_1):P2E_MB_BMC_RX_R1_DP(0)
  U237   17    BIP PI3EQX12902AZLEX-PI3EQX12902AZLEX,SMLF,IC,AL012902A    I63 @T6G_MB_LIB.T6G(SCH_1):PAGE110
 R6156    2      B Q_RES_0201LF-0,5%,1/20W,CHIP,CS00001JE10    I21 @T6G_MB_LIB.T6G(SCH_1):PAGE112

P2E_MB_BMC_RX_R2_DN<0> @T6G_MB_LIB.T6G(SCH_1):P2E_MB_BMC_RX_R2_DN(0)
 U6000   12   INB- DS125BR111RTWR-DS125BR111RTWR,SMLF,IC,AL000125003     I1 @T6G_MB_LIB.T6G(SCH_1):PAGE111
 R6159    2      B Q_RES_0201LF-0,5%,1/20W,CHIP,CS00001JE10    I23 @T6G_MB_LIB.T6G(SCH_1):PAGE112

P2E_MB_BMC_RX_R2_DP<0> @T6G_MB_LIB.T6G(SCH_1):P2E_MB_BMC_RX_R2_DP(0)
 U6000   11   INB+ DS125BR111RTWR-DS125BR111RTWR,SMLF,IC,AL000125003     I1 @T6G_MB_LIB.T6G(SCH_1):PAGE111
 R6158    2      B Q_RES_0201LF-0,5%,1/20W,CHIP,CS00001JE10    I24 @T6G_MB_LIB.T6G(SCH_1):PAGE112

P2E_MB_BMC_TX_BUF2_DN<0> @T6G_MB_LIB.T6G(SCH_1):P2E_MB_BMC_TX_BUF2_DN(0)
 U6000    8  OUTA- DS125BR111RTWR-DS125BR111RTWR,SMLF,IC,AL000125003     I1 @T6G_MB_LIB.T6G(SCH_1):PAGE111
 C6006    1      A Q_CAP_0402-0.1UF,25V,10%,X7R,CH4104K1B00    I35 @T6G_MB_LIB.T6G(SCH_1):PAGE112

P2E_MB_BMC_TX_BUF2_DP<0> @T6G_MB_LIB.T6G(SCH_1):P2E_MB_BMC_TX_BUF2_DP(0)
 U6000    7  OUTA+ DS125BR111RTWR-DS125BR111RTWR,SMLF,IC,AL000125003     I1 @T6G_MB_LIB.T6G(SCH_1):PAGE111
 C6005    1      A Q_CAP_0402-0.1UF,25V,10%,X7R,CH4104K1B00    I36 @T6G_MB_LIB.T6G(SCH_1):PAGE112

P2E_MB_BMC_TX_BUF_C_DN<0> @T6G_MB_LIB.T6G(SCH_1):P2E_MB_BMC_TX_BUF_C_DN(0)
 C1871    2      B Q_CAP_0402-0.1UF,25V,10%,X7R,CH4104K1B00    I14 @T6G_MB_LIB.T6G(SCH_1):PAGE112
 C6006    2      B Q_CAP_0402-0.1UF,25V,10%,X7R,CH4104K1B00    I35 @T6G_MB_LIB.T6G(SCH_1):PAGE112
  J112   R6     R6 CONN160_10131762101LF-CONN160_10131762-101LF,THLF,A     I7 @T6G_MB_LIB.T6G(SCH_1):PAGE329

P2E_MB_BMC_TX_BUF_C_DP<0> @T6G_MB_LIB.T6G(SCH_1):P2E_MB_BMC_TX_BUF_C_DP(0)
 C1870    2      B Q_CAP_0402-0.1UF,25V,10%,X7R,CH4104K1B00    I13 @T6G_MB_LIB.T6G(SCH_1):PAGE112
 C6005    2      B Q_CAP_0402-0.1UF,25V,10%,X7R,CH4104K1B00    I36 @T6G_MB_LIB.T6G(SCH_1):PAGE112
  J112   Q6     Q6 CONN160_10131762101LF-CONN160_10131762-101LF,THLF,A     I7 @T6G_MB_LIB.T6G(SCH_1):PAGE329

P2E_MB_BMC_TX_BUF_DN<0> @T6G_MB_LIB.T6G(SCH_1):P2E_MB_BMC_TX_BUF_DN(0)
  U237   23    AON PI3EQX12902AZLEX-PI3EQX12902AZLEX,SMLF,IC,AL012902A    I63 @T6G_MB_LIB.T6G(SCH_1):PAGE110
 C1871    1      A Q_CAP_0402-0.1UF,25V,10%,X7R,CH4104K1B00    I14 @T6G_MB_LIB.T6G(SCH_1):PAGE112

P2E_MB_BMC_TX_BUF_DP<0> @T6G_MB_LIB.T6G(SCH_1):P2E_MB_BMC_TX_BUF_DP(0)
  U237   24    AOP PI3EQX12902AZLEX-PI3EQX12902AZLEX,SMLF,IC,AL012902A    I63 @T6G_MB_LIB.T6G(SCH_1):PAGE110
 C1870    1      A Q_CAP_0402-0.1UF,25V,10%,X7R,CH4104K1B00    I13 @T6G_MB_LIB.T6G(SCH_1):PAGE112

P2E_MB_BMC_TX_C_DN<0> @T6G_MB_LIB.T6G(SCH_1):P2E_MB_BMC_TX_C_DN(0)
   J41  B66 PETP15 SCONN168_ME1016810202011-SCONN168_ME1016810202011,A   I176 @T6G_MB_LIB.T6G(SCH_1):PAGE348
 R6155    1      A Q_RES_0201LF-0,5%,1/20W,CHIP,CS00001JE10     I2 @T6G_MB_LIB.T6G(SCH_1):PAGE112
 R6153    1      A Q_RES_0201LF-0,5%,1/20W,CHIP,CS00001JE10     I3 @T6G_MB_LIB.T6G(SCH_1):PAGE112

P2E_MB_BMC_TX_C_DP<0> @T6G_MB_LIB.T6G(SCH_1):P2E_MB_BMC_TX_C_DP(0)
   J41  B65 PETN15 SCONN168_ME1016810202011-SCONN168_ME1016810202011,A   I176 @T6G_MB_LIB.T6G(SCH_1):PAGE348
 R6154    1      A Q_RES_0201LF-0,5%,1/20W,CHIP,CS00001JE10     I1 @T6G_MB_LIB.T6G(SCH_1):PAGE112
 R6152    1      A Q_RES_0201LF-0,5%,1/20W,CHIP,CS00001JE10     I8 @T6G_MB_LIB.T6G(SCH_1):PAGE112

P2E_MB_BMC_TX_C_R1_DN<0> @T6G_MB_LIB.T6G(SCH_1):P2E_MB_BMC_TX_C_R1_DN(0)
  U237    3    AIN PI3EQX12902AZLEX-PI3EQX12902AZLEX,SMLF,IC,AL012902A    I63 @T6G_MB_LIB.T6G(SCH_1):PAGE110
 R6153    2      B Q_RES_0201LF-0,5%,1/20W,CHIP,CS00001JE10     I3 @T6G_MB_LIB.T6G(SCH_1):PAGE112

P2E_MB_BMC_TX_C_R1_DP<0> @T6G_MB_LIB.T6G(SCH_1):P2E_MB_BMC_TX_C_R1_DP(0)
  U237    2    AIP PI3EQX12902AZLEX-PI3EQX12902AZLEX,SMLF,IC,AL012902A    I63 @T6G_MB_LIB.T6G(SCH_1):PAGE110
 R6152    2      B Q_RES_0201LF-0,5%,1/20W,CHIP,CS00001JE10     I8 @T6G_MB_LIB.T6G(SCH_1):PAGE112

P2E_MB_BMC_TX_C_R2_DN<0> @T6G_MB_LIB.T6G(SCH_1):P2E_MB_BMC_TX_C_R2_DN(0)
 U6000   23   INA- DS125BR111RTWR-DS125BR111RTWR,SMLF,IC,AL000125003     I1 @T6G_MB_LIB.T6G(SCH_1):PAGE111
 R6155    2      B Q_RES_0201LF-0,5%,1/20W,CHIP,CS00001JE10     I2 @T6G_MB_LIB.T6G(SCH_1):PAGE112

P2E_MB_BMC_TX_C_R2_DP<0> @T6G_MB_LIB.T6G(SCH_1):P2E_MB_BMC_TX_C_R2_DP(0)
 U6000   24   INA+ DS125BR111RTWR-DS125BR111RTWR,SMLF,IC,AL000125003     I1 @T6G_MB_LIB.T6G(SCH_1):PAGE111
 R6154    2      B Q_RES_0201LF-0,5%,1/20W,CHIP,CS00001JE10     I1 @T6G_MB_LIB.T6G(SCH_1):PAGE112

P3E_CPU0_P4_RX_DN<0> @T6G_MB_LIB.T6G(SCH_1):P3E_CPU0_P4_RX_DN(0)
   U25 DG53 P4_RXN0 GENOA_SP5-SOCKET6096_13568-001,SMLF,IO,DGA^6000030    I59 @T6G_MB_LIB.T6G(SCH_1):PAGE26
   J90  A18 PER_P0 SCONN56_123276793-SCONN56_1-2327679-3,SMLF,IO,DFHSA    I90 @T6G_MB_LIB.T6G(SCH_1):PAGE297

P3E_CPU0_P4_RX_DN<1> @T6G_MB_LIB.T6G(SCH_1):P3E_CPU0_P4_RX_DN(1)
   U25 DG50 P4_RXN1 GENOA_SP5-SOCKET6096_13568-001,SMLF,IO,DGA^6000030    I59 @T6G_MB_LIB.T6G(SCH_1):PAGE26
   J90  A21 PER_P1 SCONN56_123276793-SCONN56_1-2327679-3,SMLF,IO,DFHSA    I90 @T6G_MB_LIB.T6G(SCH_1):PAGE297

P3E_CPU0_P4_RX_DN<2> @T6G_MB_LIB.T6G(SCH_1):P3E_CPU0_P4_RX_DN(2)
   U25 DG47 P4_RXN2 GENOA_SP5-SOCKET6096_13568-001,SMLF,IO,DGA^6000030    I59 @T6G_MB_LIB.T6G(SCH_1):PAGE26
   J90  A24 PER_P2 SCONN56_123276793-SCONN56_1-2327679-3,SMLF,IO,DFHSA    I90 @T6G_MB_LIB.T6G(SCH_1):PAGE297

P3E_CPU0_P4_RX_DN<3> @T6G_MB_LIB.T6G(SCH_1):P3E_CPU0_P4_RX_DN(3)
   U25 DG44 P4_RXN3 GENOA_SP5-SOCKET6096_13568-001,SMLF,IO,DGA^6000030    I59 @T6G_MB_LIB.T6G(SCH_1):PAGE26
   J90  A27 PER_P3 SCONN56_123276793-SCONN56_1-2327679-3,SMLF,IO,DFHSA    I90 @T6G_MB_LIB.T6G(SCH_1):PAGE297

P3E_CPU0_P4_RX_DP<0> @T6G_MB_LIB.T6G(SCH_1):P3E_CPU0_P4_RX_DP(0)
   U25 DG54 P4_RXP0 GENOA_SP5-SOCKET6096_13568-001,SMLF,IO,DGA^6000030    I59 @T6G_MB_LIB.T6G(SCH_1):PAGE26
   J90  A17 PER_N0 SCONN56_123276793-SCONN56_1-2327679-3,SMLF,IO,DFHSA    I90 @T6G_MB_LIB.T6G(SCH_1):PAGE297

P3E_CPU0_P4_RX_DP<1> @T6G_MB_LIB.T6G(SCH_1):P3E_CPU0_P4_RX_DP(1)
   U25 DG51 P4_RXP1 GENOA_SP5-SOCKET6096_13568-001,SMLF,IO,DGA^6000030    I59 @T6G_MB_LIB.T6G(SCH_1):PAGE26
   J90  A20 PER_N1 SCONN56_123276793-SCONN56_1-2327679-3,SMLF,IO,DFHSA    I90 @T6G_MB_LIB.T6G(SCH_1):PAGE297

P3E_CPU0_P4_RX_DP<2> @T6G_MB_LIB.T6G(SCH_1):P3E_CPU0_P4_RX_DP(2)
   U25 DG48 P4_RXP2 GENOA_SP5-SOCKET6096_13568-001,SMLF,IO,DGA^6000030    I59 @T6G_MB_LIB.T6G(SCH_1):PAGE26
   J90  A23 PER_N2 SCONN56_123276793-SCONN56_1-2327679-3,SMLF,IO,DFHSA    I90 @T6G_MB_LIB.T6G(SCH_1):PAGE297

P3E_CPU0_P4_RX_DP<3> @T6G_MB_LIB.T6G(SCH_1):P3E_CPU0_P4_RX_DP(3)
   U25 DG45 P4_RXP3 GENOA_SP5-SOCKET6096_13568-001,SMLF,IO,DGA^6000030    I59 @T6G_MB_LIB.T6G(SCH_1):PAGE26
   J90  A26 PER_N3 SCONN56_123276793-SCONN56_1-2327679-3,SMLF,IO,DFHSA    I90 @T6G_MB_LIB.T6G(SCH_1):PAGE297

P3E_CPU0_P4_TX_C_DN<0> @T6G_MB_LIB.T6G(SCH_1):P3E_CPU0_P4_TX_C_DN(0)
 C1996    1      1 Q_CAP_DIFFBUS_C0201-DIFF BUS_0.22UF,6.3V,20%,X6S,SA    I51 @T6G_MB_LIB.T6G(SCH_1):PAGE355
   J90  B18 PET_P0 SCONN56_123276793-SCONN56_1-2327679-3,SMLF,IO,DFHSA    I90 @T6G_MB_LIB.T6G(SCH_1):PAGE297

P3E_CPU0_P4_TX_C_DN<1> @T6G_MB_LIB.T6G(SCH_1):P3E_CPU0_P4_TX_C_DN(1)
 C1994    1      1 Q_CAP_DIFFBUS_C0201-DIFF BUS_0.22UF,6.3V,20%,X6S,SA    I11 @T6G_MB_LIB.T6G(SCH_1):PAGE355
   J90  B21 PET_P1 SCONN56_123276793-SCONN56_1-2327679-3,SMLF,IO,DFHSA    I90 @T6G_MB_LIB.T6G(SCH_1):PAGE297

P3E_CPU0_P4_TX_C_DN<2> @T6G_MB_LIB.T6G(SCH_1):P3E_CPU0_P4_TX_C_DN(2)
 C1992    1      1 Q_CAP_DIFFBUS_C0201-DIFF BUS_0.22UF,6.3V,20%,X6S,SA     I9 @T6G_MB_LIB.T6G(SCH_1):PAGE355
   J90  B24 PET_P2 SCONN56_123276793-SCONN56_1-2327679-3,SMLF,IO,DFHSA    I90 @T6G_MB_LIB.T6G(SCH_1):PAGE297

P3E_CPU0_P4_TX_C_DN<3> @T6G_MB_LIB.T6G(SCH_1):P3E_CPU0_P4_TX_C_DN(3)
 C1990    1      1 Q_CAP_DIFFBUS_C0201-DIFF BUS_0.22UF,6.3V,20%,X6S,SA     I7 @T6G_MB_LIB.T6G(SCH_1):PAGE355
   J90  B26 PET_N3 SCONN56_123276793-SCONN56_1-2327679-3,SMLF,IO,DFHSA    I90 @T6G_MB_LIB.T6G(SCH_1):PAGE297

P3E_CPU0_P4_TX_C_DP<0> @T6G_MB_LIB.T6G(SCH_1):P3E_CPU0_P4_TX_C_DP(0)
 C1995    1      1 Q_CAP_DIFFBUS_C0201-DIFF BUS_0.22UF,6.3V,20%,X6S,SA    I52 @T6G_MB_LIB.T6G(SCH_1):PAGE355
   J90  B17 PET_N0 SCONN56_123276793-SCONN56_1-2327679-3,SMLF,IO,DFHSA    I90 @T6G_MB_LIB.T6G(SCH_1):PAGE297

P3E_CPU0_P4_TX_C_DP<1> @T6G_MB_LIB.T6G(SCH_1):P3E_CPU0_P4_TX_C_DP(1)
 C1993    1      1 Q_CAP_DIFFBUS_C0201-DIFF BUS_0.22UF,6.3V,20%,X6S,SA    I12 @T6G_MB_LIB.T6G(SCH_1):PAGE355
   J90  B20 PET_N1 SCONN56_123276793-SCONN56_1-2327679-3,SMLF,IO,DFHSA    I90 @T6G_MB_LIB.T6G(SCH_1):PAGE297

P3E_CPU0_P4_TX_C_DP<2> @T6G_MB_LIB.T6G(SCH_1):P3E_CPU0_P4_TX_C_DP(2)
 C1991    1      1 Q_CAP_DIFFBUS_C0201-DIFF BUS_0.22UF,6.3V,20%,X6S,SA    I10 @T6G_MB_LIB.T6G(SCH_1):PAGE355
   J90  B23 PET_N2 SCONN56_123276793-SCONN56_1-2327679-3,SMLF,IO,DFHSA    I90 @T6G_MB_LIB.T6G(SCH_1):PAGE297

P3E_CPU0_P4_TX_C_DP<3> @T6G_MB_LIB.T6G(SCH_1):P3E_CPU0_P4_TX_C_DP(3)
 C1989    1      1 Q_CAP_DIFFBUS_C0201-DIFF BUS_0.22UF,6.3V,20%,X6S,SA     I8 @T6G_MB_LIB.T6G(SCH_1):PAGE355
   J90  B27 PET_P3 SCONN56_123276793-SCONN56_1-2327679-3,SMLF,IO,DFHSA    I90 @T6G_MB_LIB.T6G(SCH_1):PAGE297

P3E_CPU0_P4_TX_DN<0> @T6G_MB_LIB.T6G(SCH_1):P3E_CPU0_P4_TX_DN(0)
   U25 DE52 P4_TXN0 GENOA_SP5-SOCKET6096_13568-001,SMLF,IO,DGA^6000030    I59 @T6G_MB_LIB.T6G(SCH_1):PAGE26
 C1996    2      2 Q_CAP_DIFFBUS_C0201-DIFF BUS_0.22UF,6.3V,20%,X6S,SA    I51 @T6G_MB_LIB.T6G(SCH_1):PAGE355

P3E_CPU0_P4_TX_DN<1> @T6G_MB_LIB.T6G(SCH_1):P3E_CPU0_P4_TX_DN(1)
   U25 DE49 P4_TXN1 GENOA_SP5-SOCKET6096_13568-001,SMLF,IO,DGA^6000030    I59 @T6G_MB_LIB.T6G(SCH_1):PAGE26
 C1994    2      2 Q_CAP_DIFFBUS_C0201-DIFF BUS_0.22UF,6.3V,20%,X6S,SA    I11 @T6G_MB_LIB.T6G(SCH_1):PAGE355

P3E_CPU0_P4_TX_DN<2> @T6G_MB_LIB.T6G(SCH_1):P3E_CPU0_P4_TX_DN(2)
   U25 DE46 P4_TXN2 GENOA_SP5-SOCKET6096_13568-001,SMLF,IO,DGA^6000030    I59 @T6G_MB_LIB.T6G(SCH_1):PAGE26
 C1992    2      2 Q_CAP_DIFFBUS_C0201-DIFF BUS_0.22UF,6.3V,20%,X6S,SA     I9 @T6G_MB_LIB.T6G(SCH_1):PAGE355

P3E_CPU0_P4_TX_DN<3> @T6G_MB_LIB.T6G(SCH_1):P3E_CPU0_P4_TX_DN(3)
   U25 DE43 P4_TXN3 GENOA_SP5-SOCKET6096_13568-001,SMLF,IO,DGA^6000030    I59 @T6G_MB_LIB.T6G(SCH_1):PAGE26
 C1990    2      2 Q_CAP_DIFFBUS_C0201-DIFF BUS_0.22UF,6.3V,20%,X6S,SA     I7 @T6G_MB_LIB.T6G(SCH_1):PAGE355

P3E_CPU0_P4_TX_DP<0> @T6G_MB_LIB.T6G(SCH_1):P3E_CPU0_P4_TX_DP(0)
   U25 DE53 P4_TXP0 GENOA_SP5-SOCKET6096_13568-001,SMLF,IO,DGA^6000030    I59 @T6G_MB_LIB.T6G(SCH_1):PAGE26
 C1995    2      2 Q_CAP_DIFFBUS_C0201-DIFF BUS_0.22UF,6.3V,20%,X6S,SA    I52 @T6G_MB_LIB.T6G(SCH_1):PAGE355

P3E_CPU0_P4_TX_DP<1> @T6G_MB_LIB.T6G(SCH_1):P3E_CPU0_P4_TX_DP(1)
   U25 DE50 P4_TXP1 GENOA_SP5-SOCKET6096_13568-001,SMLF,IO,DGA^6000030    I59 @T6G_MB_LIB.T6G(SCH_1):PAGE26
 C1993    2      2 Q_CAP_DIFFBUS_C0201-DIFF BUS_0.22UF,6.3V,20%,X6S,SA    I12 @T6G_MB_LIB.T6G(SCH_1):PAGE355

P3E_CPU0_P4_TX_DP<2> @T6G_MB_LIB.T6G(SCH_1):P3E_CPU0_P4_TX_DP(2)
   U25 DE47 P4_TXP2 GENOA_SP5-SOCKET6096_13568-001,SMLF,IO,DGA^6000030    I59 @T6G_MB_LIB.T6G(SCH_1):PAGE26
 C1991    2      2 Q_CAP_DIFFBUS_C0201-DIFF BUS_0.22UF,6.3V,20%,X6S,SA    I10 @T6G_MB_LIB.T6G(SCH_1):PAGE355

P3E_CPU0_P4_TX_DP<3> @T6G_MB_LIB.T6G(SCH_1):P3E_CPU0_P4_TX_DP(3)
   U25 DE44 P4_TXP3 GENOA_SP5-SOCKET6096_13568-001,SMLF,IO,DGA^6000030    I59 @T6G_MB_LIB.T6G(SCH_1):PAGE26
 C1989    2      2 Q_CAP_DIFFBUS_C0201-DIFF BUS_0.22UF,6.3V,20%,X6S,SA     I8 @T6G_MB_LIB.T6G(SCH_1):PAGE355

P3E_CPU1_P4_RX_DN<0> @T6G_MB_LIB.T6G(SCH_1):P3E_CPU1_P4_RX_DN(0)
   J59   41 PERN0||SATA-B+ SCONN75K_APCI0155P004A-SCONN75K_APCI0155-P004A,SMLA    I88 @T6G_MB_LIB.T6G(SCH_1):PAGE345
   U26 DG53 P4_RXN0 GENOA_SP5-SOCKET6096_13568-001,SMLF,IO,DGA^6000030   I145 @T6G_MB_LIB.T6G(SCH_1):PAGE53

P3E_CPU1_P4_RX_DN<1> @T6G_MB_LIB.T6G(SCH_1):P3E_CPU1_P4_RX_DN(1)
   J59   29  PERN1 SCONN75K_APCI0155P004A-SCONN75K_APCI0155-P004A,SMLA    I88 @T6G_MB_LIB.T6G(SCH_1):PAGE345
   U26 DG50 P4_RXN1 GENOA_SP5-SOCKET6096_13568-001,SMLF,IO,DGA^6000030   I145 @T6G_MB_LIB.T6G(SCH_1):PAGE53

P3E_CPU1_P4_RX_DN<2> @T6G_MB_LIB.T6G(SCH_1):P3E_CPU1_P4_RX_DN(2)
   J59   17  PERN2 SCONN75K_APCI0155P004A-SCONN75K_APCI0155-P004A,SMLA    I88 @T6G_MB_LIB.T6G(SCH_1):PAGE345
   U26 DG47 P4_RXN2 GENOA_SP5-SOCKET6096_13568-001,SMLF,IO,DGA^6000030   I145 @T6G_MB_LIB.T6G(SCH_1):PAGE53

P3E_CPU1_P4_RX_DN<3> @T6G_MB_LIB.T6G(SCH_1):P3E_CPU1_P4_RX_DN(3)
   J59    5  PERN3 SCONN75K_APCI0155P004A-SCONN75K_APCI0155-P004A,SMLA    I88 @T6G_MB_LIB.T6G(SCH_1):PAGE345
   U26 DG44 P4_RXN3 GENOA_SP5-SOCKET6096_13568-001,SMLF,IO,DGA^6000030   I145 @T6G_MB_LIB.T6G(SCH_1):PAGE53

P3E_CPU1_P4_RX_DP<0> @T6G_MB_LIB.T6G(SCH_1):P3E_CPU1_P4_RX_DP(0)
   J59   43 PERP0||SATA-B- SCONN75K_APCI0155P004A-SCONN75K_APCI0155-P004A,SMLA    I88 @T6G_MB_LIB.T6G(SCH_1):PAGE345
   U26 DG54 P4_RXP0 GENOA_SP5-SOCKET6096_13568-001,SMLF,IO,DGA^6000030   I145 @T6G_MB_LIB.T6G(SCH_1):PAGE53

P3E_CPU1_P4_RX_DP<1> @T6G_MB_LIB.T6G(SCH_1):P3E_CPU1_P4_RX_DP(1)
   J59   31  PERP1 SCONN75K_APCI0155P004A-SCONN75K_APCI0155-P004A,SMLA    I88 @T6G_MB_LIB.T6G(SCH_1):PAGE345
   U26 DG51 P4_RXP1 GENOA_SP5-SOCKET6096_13568-001,SMLF,IO,DGA^6000030   I145 @T6G_MB_LIB.T6G(SCH_1):PAGE53

P3E_CPU1_P4_RX_DP<2> @T6G_MB_LIB.T6G(SCH_1):P3E_CPU1_P4_RX_DP(2)
   J59   19  PERP2 SCONN75K_APCI0155P004A-SCONN75K_APCI0155-P004A,SMLA    I88 @T6G_MB_LIB.T6G(SCH_1):PAGE345
   U26 DG48 P4_RXP2 GENOA_SP5-SOCKET6096_13568-001,SMLF,IO,DGA^6000030   I145 @T6G_MB_LIB.T6G(SCH_1):PAGE53

P3E_CPU1_P4_RX_DP<3> @T6G_MB_LIB.T6G(SCH_1):P3E_CPU1_P4_RX_DP(3)
   J59    7  PERP3 SCONN75K_APCI0155P004A-SCONN75K_APCI0155-P004A,SMLA    I88 @T6G_MB_LIB.T6G(SCH_1):PAGE345
   U26 DG45 P4_RXP3 GENOA_SP5-SOCKET6096_13568-001,SMLF,IO,DGA^6000030   I145 @T6G_MB_LIB.T6G(SCH_1):PAGE53

P3E_CPU1_P4_TX_C_DN<0> @T6G_MB_LIB.T6G(SCH_1):P3E_CPU1_P4_TX_C_DN(0)
   J59   47 PETN0||SATA-A- SCONN75K_APCI0155P004A-SCONN75K_APCI0155-P004A,SMLA    I88 @T6G_MB_LIB.T6G(SCH_1):PAGE345
 C9105    1      1 Q_CAP_DIFFBUS_C0201-DIFF BUS_0.22UF,6.3V,20%,X6S,SA   I161 @T6G_MB_LIB.T6G(SCH_1):PAGE355

P3E_CPU1_P4_TX_C_DN<1> @T6G_MB_LIB.T6G(SCH_1):P3E_CPU1_P4_TX_C_DN(1)
   J59   35  PETN1 SCONN75K_APCI0155P004A-SCONN75K_APCI0155-P004A,SMLA    I88 @T6G_MB_LIB.T6G(SCH_1):PAGE345
 C9103    1      1 Q_CAP_DIFFBUS_C0201-DIFF BUS_0.22UF,6.3V,20%,X6S,SA   I137 @T6G_MB_LIB.T6G(SCH_1):PAGE355

P3E_CPU1_P4_TX_C_DN<2> @T6G_MB_LIB.T6G(SCH_1):P3E_CPU1_P4_TX_C_DN(2)
   J59   23  PETN2 SCONN75K_APCI0155P004A-SCONN75K_APCI0155-P004A,SMLA    I88 @T6G_MB_LIB.T6G(SCH_1):PAGE345
 C1101    1      1 Q_CAP_DIFFBUS_C0201-DIFF BUS_0.22UF,6.3V,20%,X6S,SA   I135 @T6G_MB_LIB.T6G(SCH_1):PAGE355

P3E_CPU1_P4_TX_C_DN<3> @T6G_MB_LIB.T6G(SCH_1):P3E_CPU1_P4_TX_C_DN(3)
   J59   11  PETN3 SCONN75K_APCI0155P004A-SCONN75K_APCI0155-P004A,SMLA    I88 @T6G_MB_LIB.T6G(SCH_1):PAGE345
 C1099    1      1 Q_CAP_DIFFBUS_C0201-DIFF BUS_0.22UF,6.3V,20%,X6S,SA   I133 @T6G_MB_LIB.T6G(SCH_1):PAGE355

P3E_CPU1_P4_TX_C_DP<0> @T6G_MB_LIB.T6G(SCH_1):P3E_CPU1_P4_TX_C_DP(0)
   J59   49 PETP0||SATA-A+ SCONN75K_APCI0155P004A-SCONN75K_APCI0155-P004A,SMLA    I88 @T6G_MB_LIB.T6G(SCH_1):PAGE345
 C9104    1      1 Q_CAP_DIFFBUS_C0201-DIFF BUS_0.22UF,6.3V,20%,X6S,SA   I162 @T6G_MB_LIB.T6G(SCH_1):PAGE355

P3E_CPU1_P4_TX_C_DP<1> @T6G_MB_LIB.T6G(SCH_1):P3E_CPU1_P4_TX_C_DP(1)
   J59   37  PETP1 SCONN75K_APCI0155P004A-SCONN75K_APCI0155-P004A,SMLA    I88 @T6G_MB_LIB.T6G(SCH_1):PAGE345
 C9102    1      1 Q_CAP_DIFFBUS_C0201-DIFF BUS_0.22UF,6.3V,20%,X6S,SA   I138 @T6G_MB_LIB.T6G(SCH_1):PAGE355

P3E_CPU1_P4_TX_C_DP<2> @T6G_MB_LIB.T6G(SCH_1):P3E_CPU1_P4_TX_C_DP(2)
   J59   25  PETP2 SCONN75K_APCI0155P004A-SCONN75K_APCI0155-P004A,SMLA    I88 @T6G_MB_LIB.T6G(SCH_1):PAGE345
 C1100    1      1 Q_CAP_DIFFBUS_C0201-DIFF BUS_0.22UF,6.3V,20%,X6S,SA   I136 @T6G_MB_LIB.T6G(SCH_1):PAGE355

P3E_CPU1_P4_TX_C_DP<3> @T6G_MB_LIB.T6G(SCH_1):P3E_CPU1_P4_TX_C_DP(3)
   J59   13  PETP3 SCONN75K_APCI0155P004A-SCONN75K_APCI0155-P004A,SMLA    I88 @T6G_MB_LIB.T6G(SCH_1):PAGE345
 C1098    1      1 Q_CAP_DIFFBUS_C0201-DIFF BUS_0.22UF,6.3V,20%,X6S,SA   I134 @T6G_MB_LIB.T6G(SCH_1):PAGE355

P3E_CPU1_P4_TX_DN<0> @T6G_MB_LIB.T6G(SCH_1):P3E_CPU1_P4_TX_DN(0)
 C9105    2      2 Q_CAP_DIFFBUS_C0201-DIFF BUS_0.22UF,6.3V,20%,X6S,SA   I161 @T6G_MB_LIB.T6G(SCH_1):PAGE355
   U26 DE52 P4_TXN0 GENOA_SP5-SOCKET6096_13568-001,SMLF,IO,DGA^6000030   I145 @T6G_MB_LIB.T6G(SCH_1):PAGE53

P3E_CPU1_P4_TX_DN<1> @T6G_MB_LIB.T6G(SCH_1):P3E_CPU1_P4_TX_DN(1)
 C9103    2      2 Q_CAP_DIFFBUS_C0201-DIFF BUS_0.22UF,6.3V,20%,X6S,SA   I137 @T6G_MB_LIB.T6G(SCH_1):PAGE355
   U26 DE49 P4_TXN1 GENOA_SP5-SOCKET6096_13568-001,SMLF,IO,DGA^6000030   I145 @T6G_MB_LIB.T6G(SCH_1):PAGE53

P3E_CPU1_P4_TX_DN<2> @T6G_MB_LIB.T6G(SCH_1):P3E_CPU1_P4_TX_DN(2)
 C1101    2      2 Q_CAP_DIFFBUS_C0201-DIFF BUS_0.22UF,6.3V,20%,X6S,SA   I135 @T6G_MB_LIB.T6G(SCH_1):PAGE355
   U26 DE46 P4_TXN2 GENOA_SP5-SOCKET6096_13568-001,SMLF,IO,DGA^6000030   I145 @T6G_MB_LIB.T6G(SCH_1):PAGE53

P3E_CPU1_P4_TX_DN<3> @T6G_MB_LIB.T6G(SCH_1):P3E_CPU1_P4_TX_DN(3)
 C1099    2      2 Q_CAP_DIFFBUS_C0201-DIFF BUS_0.22UF,6.3V,20%,X6S,SA   I133 @T6G_MB_LIB.T6G(SCH_1):PAGE355
   U26 DE43 P4_TXN3 GENOA_SP5-SOCKET6096_13568-001,SMLF,IO,DGA^6000030   I145 @T6G_MB_LIB.T6G(SCH_1):PAGE53

P3E_CPU1_P4_TX_DP<0> @T6G_MB_LIB.T6G(SCH_1):P3E_CPU1_P4_TX_DP(0)
 C9104    2      2 Q_CAP_DIFFBUS_C0201-DIFF BUS_0.22UF,6.3V,20%,X6S,SA   I162 @T6G_MB_LIB.T6G(SCH_1):PAGE355
   U26 DE53 P4_TXP0 GENOA_SP5-SOCKET6096_13568-001,SMLF,IO,DGA^6000030   I145 @T6G_MB_LIB.T6G(SCH_1):PAGE53

P3E_CPU1_P4_TX_DP<1> @T6G_MB_LIB.T6G(SCH_1):P3E_CPU1_P4_TX_DP(1)
 C9102    2      2 Q_CAP_DIFFBUS_C0201-DIFF BUS_0.22UF,6.3V,20%,X6S,SA   I138 @T6G_MB_LIB.T6G(SCH_1):PAGE355
   U26 DE50 P4_TXP1 GENOA_SP5-SOCKET6096_13568-001,SMLF,IO,DGA^6000030   I145 @T6G_MB_LIB.T6G(SCH_1):PAGE53

P3E_CPU1_P4_TX_DP<2> @T6G_MB_LIB.T6G(SCH_1):P3E_CPU1_P4_TX_DP(2)
 C1100    2      2 Q_CAP_DIFFBUS_C0201-DIFF BUS_0.22UF,6.3V,20%,X6S,SA   I136 @T6G_MB_LIB.T6G(SCH_1):PAGE355
   U26 DE47 P4_TXP2 GENOA_SP5-SOCKET6096_13568-001,SMLF,IO,DGA^6000030   I145 @T6G_MB_LIB.T6G(SCH_1):PAGE53

P3E_CPU1_P4_TX_DP<3> @T6G_MB_LIB.T6G(SCH_1):P3E_CPU1_P4_TX_DP(3)
 C1098    2      2 Q_CAP_DIFFBUS_C0201-DIFF BUS_0.22UF,6.3V,20%,X6S,SA   I134 @T6G_MB_LIB.T6G(SCH_1):PAGE355
   U26 DE44 P4_TXP3 GENOA_SP5-SOCKET6096_13568-001,SMLF,IO,DGA^6000030   I145 @T6G_MB_LIB.T6G(SCH_1):PAGE53

P3E_CPU1_P5_RX_DN<0> @T6G_MB_LIB.T6G(SCH_1):P3E_CPU1_P5_RX_DN(0)
   U26  E43 P5_RXP2 GENOA_SP5-SOCKET6096_13568-001,SMLF,IO,DGA^6000030   I145 @T6G_MB_LIB.T6G(SCH_1):PAGE53
  J112   N8     N8 CONN160_10131762101LF-CONN160_10131762-101LF,THLF,A     I7 @T6G_MB_LIB.T6G(SCH_1):PAGE329

P3E_CPU1_P5_RX_DN<1> @T6G_MB_LIB.T6G(SCH_1):P3E_CPU1_P5_RX_DN(1)
   U26  E40 P5_RXP3 GENOA_SP5-SOCKET6096_13568-001,SMLF,IO,DGA^6000030   I145 @T6G_MB_LIB.T6G(SCH_1):PAGE53
  J112   O7     O7 CONN160_10131762101LF-CONN160_10131762-101LF,THLF,A     I7 @T6G_MB_LIB.T6G(SCH_1):PAGE329

P3E_CPU1_P5_RX_DP<0> @T6G_MB_LIB.T6G(SCH_1):P3E_CPU1_P5_RX_DP(0)
   U26  E44 P5_RXN2 GENOA_SP5-SOCKET6096_13568-001,SMLF,IO,DGA^6000030   I145 @T6G_MB_LIB.T6G(SCH_1):PAGE53
  J112   O8     O8 CONN160_10131762101LF-CONN160_10131762-101LF,THLF,A     I7 @T6G_MB_LIB.T6G(SCH_1):PAGE329

P3E_CPU1_P5_RX_DP<1> @T6G_MB_LIB.T6G(SCH_1):P3E_CPU1_P5_RX_DP(1)
   U26  E41 P5_RXN3 GENOA_SP5-SOCKET6096_13568-001,SMLF,IO,DGA^6000030   I145 @T6G_MB_LIB.T6G(SCH_1):PAGE53
  J112   P7     P7 CONN160_10131762101LF-CONN160_10131762-101LF,THLF,A     I7 @T6G_MB_LIB.T6G(SCH_1):PAGE329

P3E_CPU1_P5_TX_C_DN<0> @T6G_MB_LIB.T6G(SCH_1):P3E_CPU1_P5_TX_C_DN(0)
 C2076    1      1 Q_CAP_DIFFBUS_C0201-DIFF BUS_0.22UF,6.3V,20%,X6S,SA   I134 @T6G_MB_LIB.T6G(SCH_1):PAGE53
  J112   Q8     Q8 CONN160_10131762101LF-CONN160_10131762-101LF,THLF,A     I7 @T6G_MB_LIB.T6G(SCH_1):PAGE329

P3E_CPU1_P5_TX_C_DN<1> @T6G_MB_LIB.T6G(SCH_1):P3E_CPU1_P5_TX_C_DN(1)
 C2074    1      1 Q_CAP_DIFFBUS_C0201-DIFF BUS_0.22UF,6.3V,20%,X6S,SA   I133 @T6G_MB_LIB.T6G(SCH_1):PAGE53
  J112   S7     S7 CONN160_10131762101LF-CONN160_10131762-101LF,THLF,A     I7 @T6G_MB_LIB.T6G(SCH_1):PAGE329

P3E_CPU1_P5_TX_C_DP<0> @T6G_MB_LIB.T6G(SCH_1):P3E_CPU1_P5_TX_C_DP(0)
 C2075    1      1 Q_CAP_DIFFBUS_C0201-DIFF BUS_0.22UF,6.3V,20%,X6S,SA   I135 @T6G_MB_LIB.T6G(SCH_1):PAGE53
  J112   R8     R8 CONN160_10131762101LF-CONN160_10131762-101LF,THLF,A     I7 @T6G_MB_LIB.T6G(SCH_1):PAGE329

P3E_CPU1_P5_TX_C_DP<1> @T6G_MB_LIB.T6G(SCH_1):P3E_CPU1_P5_TX_C_DP(1)
 C2073    1      1 Q_CAP_DIFFBUS_C0201-DIFF BUS_0.22UF,6.3V,20%,X6S,SA   I132 @T6G_MB_LIB.T6G(SCH_1):PAGE53
  J112   R7     R7 CONN160_10131762101LF-CONN160_10131762-101LF,THLF,A     I7 @T6G_MB_LIB.T6G(SCH_1):PAGE329

P3E_CPU1_P5_TX_DN<0> @T6G_MB_LIB.T6G(SCH_1):P3E_CPU1_P5_TX_DN(0)
 C2076    2      2 Q_CAP_DIFFBUS_C0201-DIFF BUS_0.22UF,6.3V,20%,X6S,SA   I134 @T6G_MB_LIB.T6G(SCH_1):PAGE53
   U26  C45 P5_TXN2 GENOA_SP5-SOCKET6096_13568-001,SMLF,IO,DGA^6000030   I145 @T6G_MB_LIB.T6G(SCH_1):PAGE53

P3E_CPU1_P5_TX_DN<1> @T6G_MB_LIB.T6G(SCH_1):P3E_CPU1_P5_TX_DN(1)
 C2074    2      2 Q_CAP_DIFFBUS_C0201-DIFF BUS_0.22UF,6.3V,20%,X6S,SA   I133 @T6G_MB_LIB.T6G(SCH_1):PAGE53
   U26  C42 P5_TXN3 GENOA_SP5-SOCKET6096_13568-001,SMLF,IO,DGA^6000030   I145 @T6G_MB_LIB.T6G(SCH_1):PAGE53

P3E_CPU1_P5_TX_DP<0> @T6G_MB_LIB.T6G(SCH_1):P3E_CPU1_P5_TX_DP(0)
 C2075    2      2 Q_CAP_DIFFBUS_C0201-DIFF BUS_0.22UF,6.3V,20%,X6S,SA   I135 @T6G_MB_LIB.T6G(SCH_1):PAGE53
   U26  C44 P5_TXP2 GENOA_SP5-SOCKET6096_13568-001,SMLF,IO,DGA^6000030   I145 @T6G_MB_LIB.T6G(SCH_1):PAGE53

P3E_CPU1_P5_TX_DP<1> @T6G_MB_LIB.T6G(SCH_1):P3E_CPU1_P5_TX_DP(1)
 C2073    2      2 Q_CAP_DIFFBUS_C0201-DIFF BUS_0.22UF,6.3V,20%,X6S,SA   I132 @T6G_MB_LIB.T6G(SCH_1):PAGE53
   U26  C41 P5_TXP3 GENOA_SP5-SOCKET6096_13568-001,SMLF,IO,DGA^6000030   I145 @T6G_MB_LIB.T6G(SCH_1):PAGE53

P3V3 @T6G_MB_LIB.T6G(SCH_1):P3V3
   R88    1      A Q_RES_0402LF-1K,1%,1/16W,EMPTY,CS21002FB06   I526 @T6G_MB_LIB.T6G(SCH_1):PAGE85
   R89    1      A Q_RES_0402LF-1K,1%,1/16W,EMPTY,CS21002FB06   I528 @T6G_MB_LIB.T6G(SCH_1):PAGE85
   R90    1      A Q_RES_0402LF-1K,1%,1/16W,EMPTY,CS21002FB06   I365 @T6G_MB_LIB.T6G(SCH_1):PAGE86
   R91    1      A Q_RES_0402LF-1K,1%,1/16W,EMPTY,CS21002FB06   I365 @T6G_MB_LIB.T6G(SCH_1):PAGE87
   R92    1      A Q_RES_0402LF-1K,1%,1/16W,EMPTY,CS21002FB06   I367 @T6G_MB_LIB.T6G(SCH_1):PAGE88
   R93    1      A Q_RES_0402LF-1K,1%,1/16W,EMPTY,CS21002FB06   I364 @T6G_MB_LIB.T6G(SCH_1):PAGE89
   R94    1      A Q_RES_0402LF-1K,1%,1/16W,EMPTY,CS21002FB06   I365 @T6G_MB_LIB.T6G(SCH_1):PAGE90
   R96    1      A Q_RES_0402LF-1K,1%,1/16W,EMPTY,CS21002FB06   I187 @T6G_MB_LIB.T6G(SCH_1):PAGE91
   R95    1      A Q_RES_0402LF-1K,1%,1/16W,EMPTY,CS21002FB06   I190 @T6G_MB_LIB.T6G(SCH_1):PAGE91
   R97    1      A Q_RES_0402LF-1K,1%,1/16W,EMPTY,CS21002FB06   I191 @T6G_MB_LIB.T6G(SCH_1):PAGE92
   R98    1      A Q_RES_0402LF-1K,1%,1/16W,EMPTY,CS21002FB06   I189 @T6G_MB_LIB.T6G(SCH_1):PAGE93
   R99    1      A Q_RES_0402LF-1K,1%,1/16W,EMPTY,CS21002FB06   I189 @T6G_MB_LIB.T6G(SCH_1):PAGE94
  R100    1      A Q_RES_0402LF-1K,1%,1/16W,EMPTY,CS21002FB06   I189 @T6G_MB_LIB.T6G(SCH_1):PAGE95
  R101    1      A Q_RES_0402LF-1K,1%,1/16W,EMPTY,CS21002FB06   I189 @T6G_MB_LIB.T6G(SCH_1):PAGE96
  R102    1      A Q_RES_0402LF-1K,1%,1/16W,EMPTY,CS21002FB06   I189 @T6G_MB_LIB.T6G(SCH_1):PAGE97
  R103    1      A Q_RES_0402LF-1K,1%,1/16W,EMPTY,CS21002FB06   I191 @T6G_MB_LIB.T6G(SCH_1):PAGE97
  R104    1      A Q_RES_0402LF-1K,1%,1/16W,EMPTY,CS21002FB06   I190 @T6G_MB_LIB.T6G(SCH_1):PAGE98
  R105    1      A Q_RES_0402LF-1K,1%,1/16W,EMPTY,CS21002FB06   I190 @T6G_MB_LIB.T6G(SCH_1):PAGE99
  R106    1      A Q_RES_0402LF-1K,1%,1/16W,EMPTY,CS21002FB06   I190 @T6G_MB_LIB.T6G(SCH_1):PAGE100
  R107    1      A Q_RES_0402LF-1K,1%,1/16W,EMPTY,CS21002FB06   I190 @T6G_MB_LIB.T6G(SCH_1):PAGE101
  R108    1      A Q_RES_0402LF-1K,1%,1/16W,EMPTY,CS21002FB06   I190 @T6G_MB_LIB.T6G(SCH_1):PAGE102
  R109    1      A Q_RES_0402LF-1K,1%,1/16W,EMPTY,CS21002FB06   I189 @T6G_MB_LIB.T6G(SCH_1):PAGE103
  R110    1      A Q_RES_0402LF-1K,1%,1/16W,EMPTY,CS21002FB06   I192 @T6G_MB_LIB.T6G(SCH_1):PAGE103
  R111    1      A Q_RES_0402LF-1K,1%,1/16W,EMPTY,CS21002FB06   I190 @T6G_MB_LIB.T6G(SCH_1):PAGE104
  R112    1      A Q_RES_0402LF-1K,1%,1/16W,EMPTY,CS21002FB06   I190 @T6G_MB_LIB.T6G(SCH_1):PAGE105
  R113    1      A Q_RES_0402LF-1K,1%,1/16W,EMPTY,CS21002FB06   I190 @T6G_MB_LIB.T6G(SCH_1):PAGE106
  R114    1      A Q_RES_0402LF-1K,1%,1/16W,EMPTY,CS21002FB06   I190 @T6G_MB_LIB.T6G(SCH_1):PAGE107
  R115    1      A Q_RES_0402LF-1K,1%,1/16W,EMPTY,CS21002FB06   I190 @T6G_MB_LIB.T6G(SCH_1):PAGE108
    D1    1      1 BAT547F-BAT547F,SMLF,IC,BC0BAT54Z53    I27 @T6G_MB_LIB.T6G(SCH_1):PAGE273
   Q56    1      1 MOSFET_NCH_1D3S-PSMNR58-30YLH,SMLF,IC,BAMNR580000    I50 @T6G_MB_LIB.T6G(SCH_1):PAGE273
   Q56    2      2 MOSFET_NCH_1D3S-PSMNR58-30YLH,SMLF,IC,BAMNR580000    I50 @T6G_MB_LIB.T6G(SCH_1):PAGE273
   Q56    3      3 MOSFET_NCH_1D3S-PSMNR58-30YLH,SMLF,IC,BAMNR580000    I50 @T6G_MB_LIB.T6G(SCH_1):PAGE273
 C1340    1      A Q_CAP_C0805-10UF,16V,10%,X6S,CH6103KEA00    I61 @T6G_MB_LIB.T6G(SCH_1):PAGE273
 C2018    1      A Q_CAP_0402-0.1UF,25V,10%,X7R,CH4104K1B00    I26 @T6G_MB_LIB.T6G(SCH_1):PAGE360
 R3574    1      A Q_RES_0402LF-10,1%,1/16W,CHIP,CS01002FB07    I35 @T6G_MB_LIB.T6G(SCH_1):PAGE360
  U264   11   VBUS ISL28022FRZT-ISL28022FRZ-T,SMLF,IC,AL028022003    I46 @T6G_MB_LIB.T6G(SCH_1):PAGE360
 R3634    2      B Q_RES_2512LF-0.002,1%,2W,CHIP,CS+002AFR06    I92 @T6G_MB_LIB.T6G(SCH_1):PAGE360
   C26    1      A Q_CAP_0402-0.1UF,25V,10%,X7R,CH4104K1B00    I29 @T6G_MB_LIB.T6G(SCH_1):PAGE137
   R78    1      A Q_RES_0402LF-4.7K,5%,1/16W,EMPTY,CS24702JB10    I31 @T6G_MB_LIB.T6G(SCH_1):PAGE137
  R361    1      A Q_RES_0402LF-4.7K,5%,1/16W,EMPTY,CS24702JB10    I40 @T6G_MB_LIB.T6G(SCH_1):PAGE137
  R365    1      A Q_RES_0402LF-4.7K,5%,1/16W,EMPTY,CS24702JB10    I41 @T6G_MB_LIB.T6G(SCH_1):PAGE137
    U5    8   VCCB PCA9617ADP-PCA9617ADP,SMLF,EMPTY,AL009617K02    I48 @T6G_MB_LIB.T6G(SCH_1):PAGE137
 R3100    2      B Q_RES_0402LF-130,1%,1/16W,CHIP,CS11302FB03     I8 @T6G_MB_LIB.T6G(SCH_1):PAGE254
   C61    1      A Q_CAP_C0402-100NF,50V,10%,X7R,CH4106K1B01    I59 @T6G_MB_LIB.T6G(SCH_1):PAGE273
 R2908    1      A Q_RES_0402LF-5.11K,1%,1/16W,CHIP,CS25112FB04    I21 @T6G_MB_LIB.T6G(SCH_1):PAGE369
 U6006    3    VCC APX80929SAG7-APX809-29SAG-7,SMLF,IC,AL080929000   I131 @T6G_MB_LIB.T6G(SCH_1):PAGE273
 C6500    1      A Q_CAP_0402-0.1UF,25V,10%,X7R,CH4104K1B00   I133 @T6G_MB_LIB.T6G(SCH_1):PAGE273
 R1491    1      A Q_RES_0402LF-10K,5%,1/16W,EMPTY,CS31002JB08   I141 @T6G_MB_LIB.T6G(SCH_1):PAGE273

P3V3_9ZXL045_P0 @T6G_MB_LIB.T6G(SCH_1):P3V3_9ZXL045_P0
 R4475    1      A Q_RES_0603LF-1,1%,1/10W,CHIP,CS-1003F900     I6 @T6G_MB_LIB.T6G(SCH_1):PAGE160
   L19    2      2 Q_INDUCTOR_SMLF-FCM2012KF-601T/0.5A,IND,CX601T05003    I26 @T6G_MB_LIB.T6G(SCH_1):PAGE160
 R4493    1      A Q_RES_0603LF-1,1%,1/10W,CHIP,CS-1003F900    I27 @T6G_MB_LIB.T6G(SCH_1):PAGE160

P3V3_9ZXL045_P0_VDD @T6G_MB_LIB.T6G(SCH_1):P3V3_9ZXL045_P0_VDD
   L20    2      2 Q_INDUCTOR_SMLF-FCM2012KF-601T/0.5A,IND,CX601T05003    I24 @T6G_MB_LIB.T6G(SCH_1):PAGE160
 C2329    1      A Q_CAP_0402-0.1UF,25V,10%,X7R,CH4104K1B00    I40 @T6G_MB_LIB.T6G(SCH_1):PAGE160
   C79    1      A Q_CAP_0402-0.1UF,25V,10%,X7R,CH4104K1B00    I41 @T6G_MB_LIB.T6G(SCH_1):PAGE160
   C80    1      A Q_CAP_0402-0.1UF,25V,10%,X7R,CH4104K1B00    I44 @T6G_MB_LIB.T6G(SCH_1):PAGE160
   C81    1      A Q_CAP_0402-0.1UF,25V,10%,X7R,CH4104K1B00    I45 @T6G_MB_LIB.T6G(SCH_1):PAGE160
 C2339    1      A Q_CAP_0402-0.1UF,25V,10%,X7R,CH4104K1B00    I47 @T6G_MB_LIB.T6G(SCH_1):PAGE160
  U314   12   VDD0 9ZXL0451EKILFT-9ZXL0451EKILFT,SMLF,IC,AL000451003    I63 @T6G_MB_LIB.T6G(SCH_1):PAGE160
  U314   16   VDD1 9ZXL0451EKILFT-9ZXL0451EKILFT,SMLF,IC,AL000451003    I63 @T6G_MB_LIB.T6G(SCH_1):PAGE160
  U314   21   VDD2 9ZXL0451EKILFT-9ZXL0451EKILFT,SMLF,IC,AL000451003    I63 @T6G_MB_LIB.T6G(SCH_1):PAGE160
  U314   25   VDD3 9ZXL0451EKILFT-9ZXL0451EKILFT,SMLF,IC,AL000451003    I63 @T6G_MB_LIB.T6G(SCH_1):PAGE160
  U314   29   VDD4 9ZXL0451EKILFT-9ZXL0451EKILFT,SMLF,IC,AL000451003    I63 @T6G_MB_LIB.T6G(SCH_1):PAGE160
 C2328    1      A Q_CAP_C0402-10UF,6.3V,20%,X6S,CH6101MEB01    I71 @T6G_MB_LIB.T6G(SCH_1):PAGE160

P3V3_9ZXL045_P0_VDDA @T6G_MB_LIB.T6G(SCH_1):P3V3_9ZXL045_P0_VDDA
 C2334    1      A Q_CAP_0402-0.1UF,25V,10%,X7R,CH4104K1B00    I20 @T6G_MB_LIB.T6G(SCH_1):PAGE160
 R4493    2      B Q_RES_0603LF-1,1%,1/10W,CHIP,CS-1003F900    I27 @T6G_MB_LIB.T6G(SCH_1):PAGE160
  U314   31   VDDA 9ZXL0451EKILFT-9ZXL0451EKILFT,SMLF,IC,AL000451003    I63 @T6G_MB_LIB.T6G(SCH_1):PAGE160
   C76    1      A Q_CAP_C0402-10UF,6.3V,20%,X6S,CH6101MEB01    I69 @T6G_MB_LIB.T6G(SCH_1):PAGE160

P3V3_9ZXL045_P0_VDDR @T6G_MB_LIB.T6G(SCH_1):P3V3_9ZXL045_P0_VDDR
 R4475    2      B Q_RES_0603LF-1,1%,1/10W,CHIP,CS-1003F900     I6 @T6G_MB_LIB.T6G(SCH_1):PAGE160
   C78    1      A Q_CAP_0402-0.1UF,25V,10%,X7R,CH4104K1B00    I18 @T6G_MB_LIB.T6G(SCH_1):PAGE160
  U314    2   VDDR 9ZXL0451EKILFT-9ZXL0451EKILFT,SMLF,IC,AL000451003    I63 @T6G_MB_LIB.T6G(SCH_1):PAGE160
   C77    1      A Q_CAP_C0402-10UF,6.3V,20%,X6S,CH6101MEB01    I70 @T6G_MB_LIB.T6G(SCH_1):PAGE160

P3V3_9ZXL045_P1 @T6G_MB_LIB.T6G(SCH_1):P3V3_9ZXL045_P1
    L1    2      2 Q_INDUCTOR_SMLF-FCM2012KF-601T/0.5A,IND,CX601T05003     I2 @T6G_MB_LIB.T6G(SCH_1):PAGE379
  R555    1      A Q_RES_0603LF-1,1%,1/10W,CHIP,CS-1003F900    I20 @T6G_MB_LIB.T6G(SCH_1):PAGE379
  R586    1      A Q_RES_0603LF-1,1%,1/10W,CHIP,CS-1003F900    I21 @T6G_MB_LIB.T6G(SCH_1):PAGE379

P3V3_9ZXL045_P1_VDD @T6G_MB_LIB.T6G(SCH_1):P3V3_9ZXL045_P1_VDD
    L2    2      2 Q_INDUCTOR_SMLF-FCM2012KF-601T/0.5A,IND,CX601T05003    I32 @T6G_MB_LIB.T6G(SCH_1):PAGE379
   C58    1      A Q_CAP_0402-0.1UF,25V,10%,X7R,CH4104K1B00    I34 @T6G_MB_LIB.T6G(SCH_1):PAGE379
   C90    1      A Q_CAP_0402-0.1UF,25V,10%,X7R,CH4104K1B00    I35 @T6G_MB_LIB.T6G(SCH_1):PAGE379
   C98    1      A Q_CAP_0402-0.1UF,25V,10%,X7R,CH4104K1B00    I36 @T6G_MB_LIB.T6G(SCH_1):PAGE379
   C99    1      A Q_CAP_0402-0.1UF,25V,10%,X7R,CH4104K1B00    I58 @T6G_MB_LIB.T6G(SCH_1):PAGE379
   C75    1      A Q_CAP_0402-0.1UF,25V,10%,X7R,CH4104K1B00    I60 @T6G_MB_LIB.T6G(SCH_1):PAGE379
   U10   12   VDD0 9ZXL0451EKILFT-9ZXL0451EKILFT,SMLF,IC,AL000451003    I63 @T6G_MB_LIB.T6G(SCH_1):PAGE379
   U10   16   VDD1 9ZXL0451EKILFT-9ZXL0451EKILFT,SMLF,IC,AL000451003    I63 @T6G_MB_LIB.T6G(SCH_1):PAGE379
   U10   21   VDD2 9ZXL0451EKILFT-9ZXL0451EKILFT,SMLF,IC,AL000451003    I63 @T6G_MB_LIB.T6G(SCH_1):PAGE379
   U10   25   VDD3 9ZXL0451EKILFT-9ZXL0451EKILFT,SMLF,IC,AL000451003    I63 @T6G_MB_LIB.T6G(SCH_1):PAGE379
   U10   29   VDD4 9ZXL0451EKILFT-9ZXL0451EKILFT,SMLF,IC,AL000451003    I63 @T6G_MB_LIB.T6G(SCH_1):PAGE379
   C28    1      A Q_CAP_C0402-10UF,6.3V,20%,X6S,CH6101MEB01    I79 @T6G_MB_LIB.T6G(SCH_1):PAGE379

P3V3_9ZXL045_P1_VDDA @T6G_MB_LIB.T6G(SCH_1):P3V3_9ZXL045_P1_VDDA
  R586    2      B Q_RES_0603LF-1,1%,1/10W,CHIP,CS-1003F900    I21 @T6G_MB_LIB.T6G(SCH_1):PAGE379
   C68    1      A Q_CAP_0402-0.1UF,25V,10%,X7R,CH4104K1B00    I24 @T6G_MB_LIB.T6G(SCH_1):PAGE379
   U10   31   VDDA 9ZXL0451EKILFT-9ZXL0451EKILFT,SMLF,IC,AL000451003    I63 @T6G_MB_LIB.T6G(SCH_1):PAGE379
   C82    1      A Q_CAP_C0402-10UF,6.3V,20%,X6S,CH6101MEB01    I77 @T6G_MB_LIB.T6G(SCH_1):PAGE379

P3V3_9ZXL045_P1_VDDR @T6G_MB_LIB.T6G(SCH_1):P3V3_9ZXL045_P1_VDDR
  R555    2      B Q_RES_0603LF-1,1%,1/10W,CHIP,CS-1003F900    I20 @T6G_MB_LIB.T6G(SCH_1):PAGE379
   C84    1      A Q_CAP_0402-0.1UF,25V,10%,X7R,CH4104K1B00    I26 @T6G_MB_LIB.T6G(SCH_1):PAGE379
   U10    2   VDDR 9ZXL0451EKILFT-9ZXL0451EKILFT,SMLF,IC,AL000451003    I63 @T6G_MB_LIB.T6G(SCH_1):PAGE379
   C83    1      A Q_CAP_C0402-10UF,6.3V,20%,X6S,CH6101MEB01    I78 @T6G_MB_LIB.T6G(SCH_1):PAGE379

P3V3_ADC @T6G_MB_LIB.T6G(SCH_1):P3V3_ADC
 R2843    1      A Q_RES_0402LF-4.7K,1%,1/16W,CHIP,CS24702FB06    I20 @T6G_MB_LIB.T6G(SCH_1):PAGE369
 R2908    2      B Q_RES_0402LF-5.11K,1%,1/16W,CHIP,CS25112FB04    I21 @T6G_MB_LIB.T6G(SCH_1):PAGE369
 R3684    1      A Q_RES_0402LF-0,5%,1/16W,CHIP,CS00002JB13    I22 @T6G_MB_LIB.T6G(SCH_1):PAGE369
 R3683    1      A Q_RES_0402LF-0,5%,1/16W,EMPTY,CS00002JB13    I23 @T6G_MB_LIB.T6G(SCH_1):PAGE369

P3V3_ADC128_2_VCC @T6G_MB_LIB.T6G(SCH_1):P3V3_ADC128_2_VCC
 C1094    1      A Q_CAP_0402-0.1UF,25V,10%,X7R,CH4104K1B00    I68 @T6G_MB_LIB.T6G(SCH_1):PAGE263
   L25    2      2 Q_INDUCTOR_SMLF-BLM18PG300SN1D ,IND,TMP_QCX8PG3000A    I69 @T6G_MB_LIB.T6G(SCH_1):PAGE263
 C1095    1      A Q_CAP_0402-0.1UF,25V,10%,X7R,CH4104K1B00   I130 @T6G_MB_LIB.T6G(SCH_1):PAGE263
 R1267    1      A Q_RES_0402LF-4.7K,1%,1/16W,EMPTY,CS24702FB06   I131 @T6G_MB_LIB.T6G(SCH_1):PAGE263
   U51    5     V+ ADC128D818CIMTXNOPB-ADC128D818CIMTX/NOPB,SMLF,IC,AA   I142 @T6G_MB_LIB.T6G(SCH_1):PAGE263

P3V3_ADC128_VCC @T6G_MB_LIB.T6G(SCH_1):P3V3_ADC128_VCC
   L16    2      2 Q_INDUCTOR_SMLF-BLM18PG300SN1D ,IND,TMP_QCX8PG3000A    I69 @T6G_MB_LIB.T6G(SCH_1):PAGE369
 C2051    1      A Q_CAP_0402-0.1UF,25V,10%,X7R,CH4104K1B00    I71 @T6G_MB_LIB.T6G(SCH_1):PAGE369
 C2052    1      A Q_CAP_0402-0.1UF,25V,10%,X7R,CH4104K1B00    I72 @T6G_MB_LIB.T6G(SCH_1):PAGE369
 R3689    1      A Q_RES_0402LF-4.7K,1%,1/16W,EMPTY,CS24702FB06   I131 @T6G_MB_LIB.T6G(SCH_1):PAGE369
  U269    5     V+ ADC128D818CIMTXNOPB-ADC128D818CIMTX/NOPB,SMLF,IC,AA   I142 @T6G_MB_LIB.T6G(SCH_1):PAGE369

P3V3_ADC_MAM @T6G_MB_LIB.T6G(SCH_1):P3V3_ADC_MAM
 R3683    2      B Q_RES_0402LF-0,5%,1/16W,EMPTY,CS00002JB13    I23 @T6G_MB_LIB.T6G(SCH_1):PAGE369
 C2043    1      A Q_CAP_0402-100PF,50V,5%,EMPTY,CH11006JB18    I55 @T6G_MB_LIB.T6G(SCH_1):PAGE369
  U193    9   AIN4 MAX11617EEET-MAX11617EEE+T,SMLF,EMPTY,AL011617W00   I169 @T6G_MB_LIB.T6G(SCH_1):PAGE369

P3V3_ADC_TIC @T6G_MB_LIB.T6G(SCH_1):P3V3_ADC_TIC
 R3684    2      B Q_RES_0402LF-0,5%,1/16W,CHIP,CS00002JB13    I22 @T6G_MB_LIB.T6G(SCH_1):PAGE369
 C2048    1      A Q_CAP_0402-0.1UF,25V,10%,X7R,CH4104K1B00    I32 @T6G_MB_LIB.T6G(SCH_1):PAGE369
  U269   12    IN4 ADC128D818CIMTXNOPB-ADC128D818CIMTX/NOPB,SMLF,IC,AA   I142 @T6G_MB_LIB.T6G(SCH_1):PAGE369

P3V3_AUX @T6G_MB_LIB.T6G(SCH_1):P3V3_AUX
  R387    1      A Q_RES_0402LF-2.2K,5%,1/16W,CHIP,CS22202JB07   I388 @T6G_MB_LIB.T6G(SCH_1):PAGE27
  R388    1      A Q_RES_0402LF-2.2K,5%,1/16W,CHIP,CS22202JB07   I389 @T6G_MB_LIB.T6G(SCH_1):PAGE27
  R390    1      A Q_RES_0402LF-2.2K,5%,1/16W,CHIP,CS22202JB07   I390 @T6G_MB_LIB.T6G(SCH_1):PAGE27
  R389    1      A Q_RES_0402LF-2.2K,5%,1/16W,CHIP,CS22202JB07   I391 @T6G_MB_LIB.T6G(SCH_1):PAGE27
  R391    1      A Q_RES_0402LF-2.2K,5%,1/16W,CHIP,CS22202JB07   I392 @T6G_MB_LIB.T6G(SCH_1):PAGE27
  R396    1      A Q_RES_0402LF-2.2K,5%,1/16W,CHIP,CS22202JB07   I393 @T6G_MB_LIB.T6G(SCH_1):PAGE27
  R397    1      A Q_RES_0402LF-2.2K,5%,1/16W,CHIP,CS22202JB07   I394 @T6G_MB_LIB.T6G(SCH_1):PAGE27
  R499    1      A Q_RES_0402LF-4.7K,5%,1/16W,CHIP,CS24702JB10     I4 @T6G_MB_LIB.T6G(SCH_1):PAGE34
  R590    1      A Q_RES_0402LF-4.7K,5%,1/16W,CHIP,CS24702JB10     I5 @T6G_MB_LIB.T6G(SCH_1):PAGE34
   U27    8   VCCB PCA9617ADP-PCA9617ADP,SMLF,IC,AL009617K02    I18 @T6G_MB_LIB.T6G(SCH_1):PAGE34
   C43    1      A Q_CAP_0402-0.1UF,25V,10%,X7R,CH4104K1B00    I47 @T6G_MB_LIB.T6G(SCH_1):PAGE34
  R517    1      A Q_RES_0402LF-2.2K,5%,1/16W,CHIP,CS22202JB07   I387 @T6G_MB_LIB.T6G(SCH_1):PAGE54
  R522    1      A Q_RES_0402LF-2.2K,5%,1/16W,CHIP,CS22202JB07   I388 @T6G_MB_LIB.T6G(SCH_1):PAGE54
  R513    1      A Q_RES_0402LF-2.2K,5%,1/16W,CHIP,CS22202JB07   I390 @T6G_MB_LIB.T6G(SCH_1):PAGE54
  R515    1      A Q_RES_0402LF-2.2K,5%,1/16W,CHIP,CS22202JB07   I391 @T6G_MB_LIB.T6G(SCH_1):PAGE54
  R512    1      A Q_RES_0402LF-2.2K,5%,1/16W,CHIP,CS22202JB07   I400 @T6G_MB_LIB.T6G(SCH_1):PAGE54
  R514    1      A Q_RES_0402LF-2.2K,5%,1/16W,CHIP,CS22202JB07   I401 @T6G_MB_LIB.T6G(SCH_1):PAGE54
  R516    1      A Q_RES_0402LF-2.2K,5%,1/16W,CHIP,CS22202JB07   I402 @T6G_MB_LIB.T6G(SCH_1):PAGE54
 C1104    1      A Q_CAP_0402-0.1UF,25V,10%,X7R,CH4104K1B00    I50 @T6G_MB_LIB.T6G(SCH_1):PAGE76
 C1105    1      A Q_CAP_0402-0.1UF,25V,10%,X7R,CH4104K1B00    I59 @T6G_MB_LIB.T6G(SCH_1):PAGE76
   U53   15   VCCB SN74AVC4T774PWR-SN74AVC4T774PWR,SMLF,IC,AL04T774K00    I63 @T6G_MB_LIB.T6G(SCH_1):PAGE76
   U54   11   VCCB PI4ULS3V304AZMAEX-PI4ULS3V304AZMAEX,SMLF,IC,AL0003A    I67 @T6G_MB_LIB.T6G(SCH_1):PAGE76
  R610    1      A Q_RES_0402LF-1K,1%,1/16W,EMPTY,CS21002FB06    I97 @T6G_MB_LIB.T6G(SCH_1):PAGE76
   C88    1      A Q_CAP_0402-0.1UF,25V,10%,X7R,CH4104K1B00   I523 @T6G_MB_LIB.T6G(SCH_1):PAGE85
   J15    3 VIN_MGMT SCONN288_DDR506112002KQ-SCONN288_DDR506112002KQ,SMA   I350 @T6G_MB_LIB.T6G(SCH_1):PAGE86
   C92    1      A Q_CAP_0402-0.1UF,25V,10%,X7R,CH4104K1B00   I362 @T6G_MB_LIB.T6G(SCH_1):PAGE86
   J17    3 VIN_MGMT SCONN288_DDR506112002KQ-SCONN288_DDR506112002KQ,SMA   I350 @T6G_MB_LIB.T6G(SCH_1):PAGE87
   C96    1      A Q_CAP_0402-0.1UF,25V,10%,X7R,CH4104K1B00   I362 @T6G_MB_LIB.T6G(SCH_1):PAGE87
   J19    3 VIN_MGMT SCONN288_DDR506112002KQ-SCONN288_DDR506112002KQ,SMA   I350 @T6G_MB_LIB.T6G(SCH_1):PAGE88
  C100    1      A Q_CAP_0402-0.1UF,25V,10%,X7R,CH4104K1B00   I362 @T6G_MB_LIB.T6G(SCH_1):PAGE88
   J21    3 VIN_MGMT SCONN288_DDR506112002KQ-SCONN288_DDR506112002KQ,SMA   I348 @T6G_MB_LIB.T6G(SCH_1):PAGE89
  C104    1      A Q_CAP_0402-0.1UF,25V,10%,X7R,CH4104K1B00   I360 @T6G_MB_LIB.T6G(SCH_1):PAGE89
   J23    3 VIN_MGMT SCONN288_DDR506112002KQ-SCONN288_DDR506112002KQ,SMA   I350 @T6G_MB_LIB.T6G(SCH_1):PAGE90
  C108    1      A Q_CAP_0402-0.1UF,25V,10%,X7R,CH4104K1B00   I361 @T6G_MB_LIB.T6G(SCH_1):PAGE90
   J16    3 VIN_MGMT SCONN288_DDR506112002KQ-SCONN288_DDR506112002KQ,SMA    I22 @T6G_MB_LIB.T6G(SCH_1):PAGE91
  C112    1      A Q_CAP_0402-0.1UF,25V,10%,X7R,CH4104K1B00   I183 @T6G_MB_LIB.T6G(SCH_1):PAGE91
   J69    3 VIN_MGMT SCONN288_DDR506112002KQ-SCONN288_DDR506112002KQ,SMA    I22 @T6G_MB_LIB.T6G(SCH_1):PAGE92
  C116    1      A Q_CAP_0402-0.1UF,25V,10%,X7R,CH4104K1B00   I186 @T6G_MB_LIB.T6G(SCH_1):PAGE92
   J18    3 VIN_MGMT SCONN288_DDR506112002KQ-SCONN288_DDR506112002KQ,SMA    I22 @T6G_MB_LIB.T6G(SCH_1):PAGE93
  C120    1      A Q_CAP_0402-0.1UF,25V,10%,X7R,CH4104K1B00   I185 @T6G_MB_LIB.T6G(SCH_1):PAGE93
   J68    3 VIN_MGMT SCONN288_DDR506112002KQ-SCONN288_DDR506112002KQ,SMA    I22 @T6G_MB_LIB.T6G(SCH_1):PAGE94
  C124    1      A Q_CAP_0402-0.1UF,25V,10%,X7R,CH4104K1B00   I185 @T6G_MB_LIB.T6G(SCH_1):PAGE94
   J20    3 VIN_MGMT SCONN288_DDR506112002KQ-SCONN288_DDR506112002KQ,SMA    I22 @T6G_MB_LIB.T6G(SCH_1):PAGE95
  C128    1      A Q_CAP_0402-0.1UF,25V,10%,X7R,CH4104K1B00   I185 @T6G_MB_LIB.T6G(SCH_1):PAGE95
   J67    3 VIN_MGMT SCONN288_DDR506112002KQ-SCONN288_DDR506112002KQ,SMA    I22 @T6G_MB_LIB.T6G(SCH_1):PAGE96
  C132    1      A Q_CAP_0402-0.1UF,25V,10%,X7R,CH4104K1B00   I185 @T6G_MB_LIB.T6G(SCH_1):PAGE96
   J24    3 VIN_MGMT SCONN288_DDR506112002KQ-SCONN288_DDR506112002KQ,SMA    I22 @T6G_MB_LIB.T6G(SCH_1):PAGE97
  C136    1      A Q_CAP_0402-0.1UF,25V,10%,X7R,CH4104K1B00   I185 @T6G_MB_LIB.T6G(SCH_1):PAGE97
   J26    3 VIN_MGMT SCONN288_DDR506112002KQ-SCONN288_DDR506112002KQ,SMA    I22 @T6G_MB_LIB.T6G(SCH_1):PAGE98
  C140    1      A Q_CAP_0402-0.1UF,25V,10%,X7R,CH4104K1B00   I185 @T6G_MB_LIB.T6G(SCH_1):PAGE98
   J28    3 VIN_MGMT SCONN288_DDR506112002KQ-SCONN288_DDR506112002KQ,SMA    I22 @T6G_MB_LIB.T6G(SCH_1):PAGE99
  C144    1      A Q_CAP_0402-0.1UF,25V,10%,X7R,CH4104K1B00   I185 @T6G_MB_LIB.T6G(SCH_1):PAGE99
   J30    3 VIN_MGMT SCONN288_DDR506112002KQ-SCONN288_DDR506112002KQ,SMA    I52 @T6G_MB_LIB.T6G(SCH_1):PAGE100
  C148    1      A Q_CAP_0402-0.1UF,25V,10%,X7R,CH4104K1B00   I185 @T6G_MB_LIB.T6G(SCH_1):PAGE100
   J32    3 VIN_MGMT SCONN288_DDR506112002KQ-SCONN288_DDR506112002KQ,SMA    I52 @T6G_MB_LIB.T6G(SCH_1):PAGE101
  C152    1      A Q_CAP_0402-0.1UF,25V,10%,X7R,CH4104K1B00   I185 @T6G_MB_LIB.T6G(SCH_1):PAGE101
   J33    3 VIN_MGMT SCONN288_DDR506112002KQ-SCONN288_DDR506112002KQ,SMA    I22 @T6G_MB_LIB.T6G(SCH_1):PAGE102
  C156    1      A Q_CAP_0402-0.1UF,25V,10%,X7R,CH4104K1B00   I185 @T6G_MB_LIB.T6G(SCH_1):PAGE102
  J102    3 VIN_MGMT SCONN288_DDR506112002KQ-SCONN288_DDR506112002KQ,SMA    I22 @T6G_MB_LIB.T6G(SCH_1):PAGE103
  C160    1      A Q_CAP_0402-0.1UF,25V,10%,X7R,CH4104K1B00   I185 @T6G_MB_LIB.T6G(SCH_1):PAGE103
   J27    3 VIN_MGMT SCONN288_DDR506112002KQ-SCONN288_DDR506112002KQ,SMA    I22 @T6G_MB_LIB.T6G(SCH_1):PAGE104
  C164    1      A Q_CAP_0402-0.1UF,25V,10%,X7R,CH4104K1B00   I185 @T6G_MB_LIB.T6G(SCH_1):PAGE104
  J100    3 VIN_MGMT SCONN288_DDR506112002KQ-SCONN288_DDR506112002KQ,SMA    I22 @T6G_MB_LIB.T6G(SCH_1):PAGE105
  C168    1      A Q_CAP_0402-0.1UF,25V,10%,X7R,CH4104K1B00   I185 @T6G_MB_LIB.T6G(SCH_1):PAGE105
   J29    3 VIN_MGMT SCONN288_DDR506112002KQ-SCONN288_DDR506112002KQ,SMA    I22 @T6G_MB_LIB.T6G(SCH_1):PAGE106
  C172    1      A Q_CAP_0402-0.1UF,25V,10%,X7R,CH4104K1B00   I185 @T6G_MB_LIB.T6G(SCH_1):PAGE106
   J99    3 VIN_MGMT SCONN288_DDR506112002KQ-SCONN288_DDR506112002KQ,SMA    I22 @T6G_MB_LIB.T6G(SCH_1):PAGE107
  C176    1      A Q_CAP_0402-0.1UF,25V,10%,X7R,CH4104K1B00   I185 @T6G_MB_LIB.T6G(SCH_1):PAGE107
   J37    3 VIN_MGMT SCONN288_DDR506112002KQ-SCONN288_DDR506112002KQ,SMA    I22 @T6G_MB_LIB.T6G(SCH_1):PAGE108
  C180    1      A Q_CAP_0402-0.1UF,25V,10%,X7R,CH4104K1B00   I185 @T6G_MB_LIB.T6G(SCH_1):PAGE108
  U105   10    VDD PI3CSW12ZUAEX-PI3CSW12ZUAEX,SMLF,IC,AL3CSW12000    I47 @T6G_MB_LIB.T6G(SCH_1):PAGE136
 C1336    1      A Q_CAP_0402-0.1UF,25V,10%,X7R,CH4104K1B00    I50 @T6G_MB_LIB.T6G(SCH_1):PAGE136
  U106   10    VDD PI3CSW12ZUAEX-PI3CSW12ZUAEX,SMLF,IC,AL3CSW12000    I54 @T6G_MB_LIB.T6G(SCH_1):PAGE136
 C1337    1      A Q_CAP_0402-0.1UF,25V,10%,X7R,CH4104K1B00    I56 @T6G_MB_LIB.T6G(SCH_1):PAGE136
 C1338    1      A Q_CAP_0402-0.1UF,25V,10%,X7R,CH4104K1B00    I61 @T6G_MB_LIB.T6G(SCH_1):PAGE136
  U107   10    VDD PI3CSW12ZUAEX-PI3CSW12ZUAEX,SMLF,IC,AL3CSW12000    I63 @T6G_MB_LIB.T6G(SCH_1):PAGE136
 C1339    1      A Q_CAP_0402-0.1UF,25V,10%,X7R,CH4104K1B00    I66 @T6G_MB_LIB.T6G(SCH_1):PAGE136
  U108   10    VDD PI3CSW12ZUAEX-PI3CSW12ZUAEX,SMLF,IC,AL3CSW12000    I68 @T6G_MB_LIB.T6G(SCH_1):PAGE136
  U116   15   VCCB SN74AVC4T774PWR-SN74AVC4T774PWR,SMLF,IC,AL04T774K00   I117 @T6G_MB_LIB.T6G(SCH_1):PAGE141
 C1354    1      A Q_CAP_0402-0.1UF,25V,10%,X7R,CH4104K1B00   I133 @T6G_MB_LIB.T6G(SCH_1):PAGE141
  R821    1      A Q_RES_0402LF-10K,5%,1/16W,CHIP,CS31002JB08   I185 @T6G_MB_LIB.T6G(SCH_1):PAGE141
  R825    1      A Q_RES_0402LF-10K,5%,1/16W,EMPTY,CS31002JB08   I203 @T6G_MB_LIB.T6G(SCH_1):PAGE141
  R824    1      A Q_RES_0402LF-10K,5%,1/16W,CHIP,CS31002JB08   I204 @T6G_MB_LIB.T6G(SCH_1):PAGE141
  R823    1      A Q_RES_0402LF-10K,5%,1/16W,EMPTY,CS31002JB08   I205 @T6G_MB_LIB.T6G(SCH_1):PAGE141
  R822    1      A Q_RES_0402LF-10K,5%,1/16W,CHIP,CS31002JB08   I206 @T6G_MB_LIB.T6G(SCH_1):PAGE141
  R950    2      B Q_RES_0402LF-249,1%,1/16W,CHIP,CS12492FB02     I3 @T6G_MB_LIB.T6G(SCH_1):PAGE143
  R946    1      A Q_RES_0402LF-4.7K,5%,1/16W,CHIP,CS24702JB10     I5 @T6G_MB_LIB.T6G(SCH_1):PAGE143
  R948    2      B Q_RES_0402LF-130,1%,1/16W,CHIP,CS11302FB03     I7 @T6G_MB_LIB.T6G(SCH_1):PAGE143
  R947    1      A Q_RES_0402LF-4.7K,5%,1/16W,CHIP,CS24702JB10    I11 @T6G_MB_LIB.T6G(SCH_1):PAGE143
  R944    1      A Q_RES_0402LF-4.7K,5%,1/16W,CHIP,CS24702JB10    I15 @T6G_MB_LIB.T6G(SCH_1):PAGE143
  R945    1      A Q_RES_0402LF-4.7K,5%,1/16W,CHIP,CS24702JB10    I18 @T6G_MB_LIB.T6G(SCH_1):PAGE143
 R1734    1      A Q_RES_0402LF-10K,1%,1/16W,CHIP,CS31002FB08   I244 @T6G_MB_LIB.T6G(SCH_1):PAGE148
 R1731    1      A Q_RES_0402LF-10K,1%,1/16W,EMPTY,CS31002FB08   I245 @T6G_MB_LIB.T6G(SCH_1):PAGE148
 R1728    1      A Q_RES_0402LF-10K,1%,1/16W,EMPTY,CS31002FB08   I249 @T6G_MB_LIB.T6G(SCH_1):PAGE148
 R1727    1      A Q_RES_0402LF-10K,1%,1/16W,EMPTY,CS31002FB08   I250 @T6G_MB_LIB.T6G(SCH_1):PAGE148
 R1747    1      A Q_RES_0402LF-10K,1%,1/16W,CHIP,CS31002FB08   I255 @T6G_MB_LIB.T6G(SCH_1):PAGE148
 R1746    1      A Q_RES_0402LF-10K,1%,1/16W,CHIP,CS31002FB08   I256 @T6G_MB_LIB.T6G(SCH_1):PAGE148
 R1745    1      A Q_RES_0402LF-10K,1%,1/16W,CHIP,CS31002FB08   I257 @T6G_MB_LIB.T6G(SCH_1):PAGE148
 R1744    1      A Q_RES_0402LF-10K,1%,1/16W,CHIP,CS31002FB08   I261 @T6G_MB_LIB.T6G(SCH_1):PAGE148
  U160   16    VCC 74LV4052PW-74LV4052PW,SMLF,IC,ALLV4052K19   I266 @T6G_MB_LIB.T6G(SCH_1):PAGE148
 C1554    1      A Q_CAP_C0402-0.1UF,16V,10%,X7R,CH4103K1B08   I293 @T6G_MB_LIB.T6G(SCH_1):PAGE148
  C194    1      A Q_CAP_C0402-0.1UF,16V,10%,X7R,CH4103K1B08   I299 @T6G_MB_LIB.T6G(SCH_1):PAGE148
  U212   16    VCC 74LV4052PW-74LV4052PW,SMLF,IC,ALLV4052K19   I302 @T6G_MB_LIB.T6G(SCH_1):PAGE148
 R1730    1      A Q_RES_0402LF-4.7K,5%,1/16W,EMPTY,CS24702JB10   I305 @T6G_MB_LIB.T6G(SCH_1):PAGE148
 R1659    1      A Q_RES_0402LF-4.7K,5%,1/16W,EMPTY,CS24702JB10   I309 @T6G_MB_LIB.T6G(SCH_1):PAGE148
 R1343    1      A Q_RES_0402LF-4.7K,5%,1/16W,EMPTY,CS24702JB10   I339 @T6G_MB_LIB.T6G(SCH_1):PAGE148
   U99    5    VCC SN74LVC1G07DBVR_SMLF-SN74LVC1G07DBVR,EMPTY,AL1G000A   I340 @T6G_MB_LIB.T6G(SCH_1):PAGE148
  C553    1      A Q_CAP_0402-0.1UF,25V,10%,X7R,CH4104K1B00   I342 @T6G_MB_LIB.T6G(SCH_1):PAGE148
  U147   10   DIR1 SN74AVC2T245RSWR-SN74AVC2T245RSWR,SMLF,IC,AL02T245A     I1 @T6G_MB_LIB.T6G(SCH_1):PAGE149
  U147    7   VCCA SN74AVC2T245RSWR-SN74AVC2T245RSWR,SMLF,IC,AL02T245A     I1 @T6G_MB_LIB.T6G(SCH_1):PAGE149
  U148    1   DIR1 SN74AVC4T774PWR-SN74AVC4T774PWR,SMLF,IC,AL04T774K00    I34 @T6G_MB_LIB.T6G(SCH_1):PAGE149
  U148    2   DIR2 SN74AVC4T774PWR-SN74AVC4T774PWR,SMLF,IC,AL04T774K00    I34 @T6G_MB_LIB.T6G(SCH_1):PAGE149
  U148    7   DIR3 SN74AVC4T774PWR-SN74AVC4T774PWR,SMLF,IC,AL04T774K00    I34 @T6G_MB_LIB.T6G(SCH_1):PAGE149
  U148    8   DIR4 SN74AVC4T774PWR-SN74AVC4T774PWR,SMLF,IC,AL04T774K00    I34 @T6G_MB_LIB.T6G(SCH_1):PAGE149
  U148   16   VCCA SN74AVC4T774PWR-SN74AVC4T774PWR,SMLF,IC,AL04T774K00    I34 @T6G_MB_LIB.T6G(SCH_1):PAGE149
 C1506    1      A Q_CAP_C0402-0.1UF,16V,10%,X7R,CH4103K1B08    I62 @T6G_MB_LIB.T6G(SCH_1):PAGE149
 C1503    1      A Q_CAP_C0402-0.1UF,16V,10%,X7R,CH4103K1B08    I80 @T6G_MB_LIB.T6G(SCH_1):PAGE149
 R1622    1      A Q_RES_0402LF-4.7K,5%,1/16W,CHIP,CS24702JB10    I83 @T6G_MB_LIB.T6G(SCH_1):PAGE149
 R1444    1      A Q_RES_0402LF-130,1%,1/16W,CHIP,CS11302FB03    I82 @T6G_MB_LIB.T6G(SCH_1):PAGE142
 R1507    1      A Q_RES_0402LF-1K,1%,1/16W,CHIP,CS21002FB06    I87 @T6G_MB_LIB.T6G(SCH_1):PAGE142
 PR397    1      A Q_RES_0402LF-0,5%,1/16W,CHIP,CS00002JB13    I12 @T6G_MB_LIB.T6G(SCH_1):PAGE201
 R8009    1      A Q_RES_0402LF-10K,5%,1/16W,CHIP,CS31002JB08    I26 @T6G_MB_LIB.T6G(SCH_1):PAGE201
   R20    1      A Q_RES_0402LF-10K,1%,1/16W,CHIP,CS31002FB08   I115 @T6G_MB_LIB.T6G(SCH_1):PAGE76
   R21    1      A Q_RES_0402LF-1K,1%,1/16W,EMPTY,CS21002FB06   I116 @T6G_MB_LIB.T6G(SCH_1):PAGE76
  R127    1      A Q_RES_0402LF-1K,1%,1/16W,EMPTY,CS21002FB06   I117 @T6G_MB_LIB.T6G(SCH_1):PAGE76
  R128    1      A Q_RES_0402LF-1K,1%,1/16W,EMPTY,CS21002FB06   I118 @T6G_MB_LIB.T6G(SCH_1):PAGE76
  R129    1      A Q_RES_0402LF-1K,1%,1/16W,EMPTY,CS21002FB06   I119 @T6G_MB_LIB.T6G(SCH_1):PAGE76
    J1    3 VIN_MGMT SCONN288_DDR506112002KQ-SCONN288_DDR506112002KQ,SMA   I536 @T6G_MB_LIB.T6G(SCH_1):PAGE85
 R8300    1      A Q_RES_0402LF-1K,1%,1/16W,CHIP,CS21002FB06    I82 @T6G_MB_LIB.T6G(SCH_1):PAGE168
 PR446    2      B Q_RES_0402LF-0,5%,1/16W,EMPTY,CS00002JB13     I4 @T6G_MB_LIB.T6G(SCH_1):PAGE169
 R1547    1      A Q_RES_0402LF-4.7K,5%,1/16W,CHIP,CS24702JB10   I148 @T6G_MB_LIB.T6G(SCH_1):PAGE76
 R1655    1      A Q_RES_0402LF-1K,1%,1/16W,EMPTY,CS21002FB06   I191 @T6G_MB_LIB.T6G(SCH_1):PAGE76
 PC569    2      B Q_CAP_0402-10PF,50V,1%,NPO,TMP_QCH0106F0B00    I53 @T6G_MB_LIB.T6G(SCH_1):PAGE245
PL8066    2      2 Q_INDUCTOR_SMLF-1.5UH/53A,IND,CV-15^0MZ02    I55 @T6G_MB_LIB.T6G(SCH_1):PAGE245
PC1866    1      A Q_CAPP_THLF-560UF,6.3V,20%,OSCON,CC75601MD16    I57 @T6G_MB_LIB.T6G(SCH_1):PAGE245
PC1867    1      A Q_CAPP_THLF-560UF,6.3V,20%,OSCON,CC75601MD16    I58 @T6G_MB_LIB.T6G(SCH_1):PAGE245
PC1868    1      A Q_CAP_C0805-22UF,10V,20%,X6S,CH6222MEA01    I59 @T6G_MB_LIB.T6G(SCH_1):PAGE245
PC1600    1      A Q_CAP_C0805-22UF,10V,20%,X6S,CH6222MEA01    I62 @T6G_MB_LIB.T6G(SCH_1):PAGE245
PC1869    1      A Q_CAP_0402-0.1UF,25V,10%,X7R,CH4104K1B00    I63 @T6G_MB_LIB.T6G(SCH_1):PAGE245
PR8073    1      A Q_RES_0402LF-1K,1%,1/16W,CHIP,CS21002FB06    I65 @T6G_MB_LIB.T6G(SCH_1):PAGE245
 R3435    1      A Q_RES_0402LF-4.7K,5%,1/16W,CHIP,CS24702JB10    I23 @T6G_MB_LIB.T6G(SCH_1):PAGE299
 R3437    1      A Q_RES_0402LF-100K,1%,1/16W,CHIP,CS41002FB09    I27 @T6G_MB_LIB.T6G(SCH_1):PAGE299
 R3434    1      A Q_RES_0402LF-4.7K,5%,1/16W,CHIP,CS24702JB10    I39 @T6G_MB_LIB.T6G(SCH_1):PAGE299
 R3436    1      A Q_RES_0402LF-100K,1%,1/16W,CHIP,CS41002FB09    I45 @T6G_MB_LIB.T6G(SCH_1):PAGE299
 R3433    1      A Q_RES_0402LF-4.7K,5%,1/16W,CHIP,CS24702JB10    I49 @T6G_MB_LIB.T6G(SCH_1):PAGE299
 R3432    1      A Q_RES_0402LF-4.7K,5%,1/16W,CHIP,CS24702JB10    I53 @T6G_MB_LIB.T6G(SCH_1):PAGE299
 R3438    1      A Q_RES_0402LF-100K,1%,1/16W,CHIP,CS41002FB09    I55 @T6G_MB_LIB.T6G(SCH_1):PAGE299
 R3439    1      A Q_RES_0402LF-100K,1%,1/16W,CHIP,CS41002FB09    I59 @T6G_MB_LIB.T6G(SCH_1):PAGE299
 R3429    1      A Q_RES_0402LF-100K,1%,1/16W,EMPTY,CS41002FB09   I130 @T6G_MB_LIB.T6G(SCH_1):PAGE299
 R3465    1      A Q_RES_0402LF-10K,1%,1/16W,CHIP,CS31002FB08   I132 @T6G_MB_LIB.T6G(SCH_1):PAGE299
 R3464    1      A Q_RES_0402LF-54.9K,1%,1/16W,CHIP,CS35492FB03   I134 @T6G_MB_LIB.T6G(SCH_1):PAGE299
 R3475    1      A Q_RES_0402LF-100K,1%,1/16W,CHIP,CS41002FB09   I154 @T6G_MB_LIB.T6G(SCH_1):PAGE299
 R3474    1      A Q_RES_0402LF-4.7K,5%,1/16W,CHIP,CS24702JB10   I158 @T6G_MB_LIB.T6G(SCH_1):PAGE299
 R3487    1      A Q_RES_0402LF-10K,1%,1/16W,CHIP,CS31002FB08   I166 @T6G_MB_LIB.T6G(SCH_1):PAGE299
 R3498    1      A Q_RES_0402LF-54.9K,1%,1/16W,CHIP,CS35492FB03   I167 @T6G_MB_LIB.T6G(SCH_1):PAGE299
 R3504    1      A Q_RES_0402LF-100K,1%,1/16W,CHIP,CS41002FB09   I174 @T6G_MB_LIB.T6G(SCH_1):PAGE299
 R3503    1      A Q_RES_0402LF-4.7K,5%,1/16W,CHIP,CS24702JB10   I177 @T6G_MB_LIB.T6G(SCH_1):PAGE299
 R3525    1      A Q_RES_0402LF-54.9K,1%,1/16W,CHIP,CS35492FB03   I184 @T6G_MB_LIB.T6G(SCH_1):PAGE299
 R9002    1      A Q_RES_0402LF-10K,1%,1/16W,CHIP,CS31002FB08     I8 @T6G_MB_LIB.T6G(SCH_1):PAGE330
 R4160    1      A Q_RES_0402LF-54.9K,1%,1/16W,EMPTY,CS35492FB03     I4 @T6G_MB_LIB.T6G(SCH_1):PAGE331
 R4162    1      A Q_RES_0402LF-54.9K,1%,1/16W,EMPTY,CS35492FB03     I9 @T6G_MB_LIB.T6G(SCH_1):PAGE331
 R4158    1      A Q_RES_0402LF-54.9K,1%,1/16W,EMPTY,CS35492FB03    I14 @T6G_MB_LIB.T6G(SCH_1):PAGE331
 R4165    1      A Q_RES_0402LF-4.7K,5%,1/16W,CHIP,CS24702JB10    I18 @T6G_MB_LIB.T6G(SCH_1):PAGE331
 R4166    1      A Q_RES_0402LF-4.7K,5%,1/16W,CHIP,CS24702JB10    I23 @T6G_MB_LIB.T6G(SCH_1):PAGE331
 R4164    1      A Q_RES_0402LF-4.7K,5%,1/16W,CHIP,CS24702JB10    I27 @T6G_MB_LIB.T6G(SCH_1):PAGE331
 R4168    1      A Q_RES_0402LF-100K,1%,1/16W,CHIP,CS41002FB09    I35 @T6G_MB_LIB.T6G(SCH_1):PAGE331
 R4169    1      A Q_RES_0402LF-100K,1%,1/16W,CHIP,CS41002FB09    I39 @T6G_MB_LIB.T6G(SCH_1):PAGE331
 R4167    1      A Q_RES_0402LF-100K,1%,1/16W,CHIP,CS41002FB09    I47 @T6G_MB_LIB.T6G(SCH_1):PAGE331
 R4545    1      A Q_RES_0402LF-4.7K,5%,1/16W,CHIP,CS24702JB10    I57 @T6G_MB_LIB.T6G(SCH_1):PAGE331
 R4543    1      A Q_RES_0402LF-1K,1%,1/16W,CHIP,CS21002FB06    I85 @T6G_MB_LIB.T6G(SCH_1):PAGE331
  U316    5    VCC 74LVC2G17GW-74LVC2G17GW,SMLF,IC,AL2G0017005    I86 @T6G_MB_LIB.T6G(SCH_1):PAGE331
 R4547    1      A Q_RES_0402LF-100K,1%,1/16W,EMPTY,CS41002FB09    I89 @T6G_MB_LIB.T6G(SCH_1):PAGE331
    C8    1      A Q_CAP_0402-0.1UF,25V,10%,X7R,CH4104K1B00    I93 @T6G_MB_LIB.T6G(SCH_1):PAGE331
 R4549    1      A Q_RES_0402LF-4.7K,5%,1/16W,EMPTY,CS24702JB10    I98 @T6G_MB_LIB.T6G(SCH_1):PAGE331
 R2835    1      A Q_RES_0402LF-4.7K,5%,1/16W,CHIP,CS24702JB10    I14 @T6G_MB_LIB.T6G(SCH_1):PAGE333
 R2834    1      A Q_RES_0402LF-4.7K,5%,1/16W,CHIP,CS24702JB10    I18 @T6G_MB_LIB.T6G(SCH_1):PAGE333
 R2836    1      A Q_RES_0402LF-4.7K,5%,1/16W,CHIP,CS24702JB10    I19 @T6G_MB_LIB.T6G(SCH_1):PAGE333
 R2841    1      A Q_RES_0402LF-4.7K,5%,1/16W,CHIP,CS24702JB10    I24 @T6G_MB_LIB.T6G(SCH_1):PAGE333
 R2842    1      A Q_RES_0402LF-4.7K,5%,1/16W,CHIP,CS24702JB10    I30 @T6G_MB_LIB.T6G(SCH_1):PAGE333
 R2828    1      A Q_RES_0402LF-100K,1%,1/16W,CHIP,CS41002FB09    I66 @T6G_MB_LIB.T6G(SCH_1):PAGE333
 R2832    1      A Q_RES_0402LF-100K,1%,1/16W,CHIP,CS41002FB09    I67 @T6G_MB_LIB.T6G(SCH_1):PAGE333
 R2830    1      A Q_RES_0402LF-100K,1%,1/16W,CHIP,CS41002FB09    I68 @T6G_MB_LIB.T6G(SCH_1):PAGE333
 R2837    1      A Q_RES_0402LF-100K,1%,1/16W,EMPTY,CS41002FB09    I80 @T6G_MB_LIB.T6G(SCH_1):PAGE333
 R2919    1      A Q_RES_0402LF-100K,1%,1/16W,CHIP,CS41002FB09    I91 @T6G_MB_LIB.T6G(SCH_1):PAGE333
 R2934    1      A Q_RES_0402LF-100K,1%,1/16W,CHIP,CS41002FB09   I101 @T6G_MB_LIB.T6G(SCH_1):PAGE333
 R2935    1      A Q_RES_0402LF-100K,1%,1/16W,CHIP,CS41002FB09   I109 @T6G_MB_LIB.T6G(SCH_1):PAGE333
 R3034    1      A Q_RES_0402LF-4.7K,5%,1/16W,CHIP,CS24702JB10   I129 @T6G_MB_LIB.T6G(SCH_1):PAGE333
 R3029    1      A Q_RES_0402LF-4.7K,5%,1/16W,CHIP,CS24702JB10   I144 @T6G_MB_LIB.T6G(SCH_1):PAGE333
 R3321    1      A Q_RES_0402LF-100K,1%,1/16W,CHIP,CS41002FB09   I158 @T6G_MB_LIB.T6G(SCH_1):PAGE333
 R3320    1      A Q_RES_0402LF-4.7K,5%,1/16W,CHIP,CS24702JB10   I162 @T6G_MB_LIB.T6G(SCH_1):PAGE333
 R3318    1      A Q_RES_0402LF-100K,1%,1/16W,EMPTY,CS41002FB09   I171 @T6G_MB_LIB.T6G(SCH_1):PAGE333
 R3512    1      A Q_RES_0402LF-100K,1%,1/16W,EMPTY,CS41002FB09   I174 @T6G_MB_LIB.T6G(SCH_1):PAGE333
 R3514    1      A Q_RES_0402LF-54.9K,1%,1/16W,CHIP,CS35492FB03   I175 @T6G_MB_LIB.T6G(SCH_1):PAGE333
 R3510    1      A Q_RES_0402LF-54.9K,1%,1/16W,CHIP,CS35492FB03   I176 @T6G_MB_LIB.T6G(SCH_1):PAGE333
  U253    5    VCC 74LVC2G17GW-74LVC2G17GW,SMLF,IC,AL2G0017005    I26 @T6G_MB_LIB.T6G(SCH_1):PAGE334
 C1958    1      A Q_CAP_0402-0.1UF,25V,10%,X7R,CH4104K1B00    I29 @T6G_MB_LIB.T6G(SCH_1):PAGE334
 R3456    1      A Q_RES_0402LF-100K,1%,1/16W,EMPTY,CS41002FB09   I124 @T6G_MB_LIB.T6G(SCH_1):PAGE334
 R3451    1      A Q_RES_0402LF-4.7K,5%,1/16W,EMPTY,CS24702JB10   I127 @T6G_MB_LIB.T6G(SCH_1):PAGE334
 C1957    1      A Q_CAP_0402-0.1UF,25V,10%,X7R,CH4104K1B00   I148 @T6G_MB_LIB.T6G(SCH_1):PAGE334
  U252    5    VCC 74LVC2G17GW-74LVC2G17GW,SMLF,IC,AL2G0017005   I153 @T6G_MB_LIB.T6G(SCH_1):PAGE334
 R3453    1      A Q_RES_0402LF-100K,1%,1/16W,EMPTY,CS41002FB09   I164 @T6G_MB_LIB.T6G(SCH_1):PAGE334
 R3448    1      A Q_RES_0402LF-4.7K,5%,1/16W,EMPTY,CS24702JB10   I168 @T6G_MB_LIB.T6G(SCH_1):PAGE334
  U256    5    VCC 74LVC2G17GW-74LVC2G17GW,SMLF,IC,AL2G0017005   I173 @T6G_MB_LIB.T6G(SCH_1):PAGE334
 C1977    1      A Q_CAP_0402-0.1UF,25V,10%,X7R,CH4104K1B00   I175 @T6G_MB_LIB.T6G(SCH_1):PAGE334
 R2910    1      A Q_RES_0402LF-100K,1%,1/16W,EMPTY,CS41002FB09   I187 @T6G_MB_LIB.T6G(SCH_1):PAGE334
 R2914    1      A Q_RES_0402LF-4.7K,5%,1/16W,EMPTY,CS24702JB10   I192 @T6G_MB_LIB.T6G(SCH_1):PAGE334
 C1963    1      A Q_CAP_0402-0.1UF,25V,10%,X7R,CH4104K1B00    I13 @T6G_MB_LIB.T6G(SCH_1):PAGE255
  U255    5    VCC 74LVC2G07DW7-74LVC2G07DW-7,SMLF,IC,AL002G07003    I16 @T6G_MB_LIB.T6G(SCH_1):PAGE255
 R3461    1      A Q_RES_0402LF-54.9K,1%,1/16W,CHIP,CS35492FB03    I35 @T6G_MB_LIB.T6G(SCH_1):PAGE255
 R3488    1      A Q_RES_0402LF-1K,1%,1/16W,CHIP,CS21002FB06    I40 @T6G_MB_LIB.T6G(SCH_1):PAGE255
 R3492    1      A Q_RES_0402LF-54.9K,1%,1/16W,CHIP,CS35492FB03    I47 @T6G_MB_LIB.T6G(SCH_1):PAGE255
  U257    5    VCC 74LVC2G07DW7-74LVC2G07DW-7,SMLF,IC,AL002G07003    I50 @T6G_MB_LIB.T6G(SCH_1):PAGE255
 R3494    1      A Q_RES_0402LF-54.9K,1%,1/16W,CHIP,CS35492FB03    I55 @T6G_MB_LIB.T6G(SCH_1):PAGE255
 R3490    1      A Q_RES_0402LF-1K,1%,1/16W,CHIP,CS21002FB06    I57 @T6G_MB_LIB.T6G(SCH_1):PAGE255
 C1979    1      A Q_CAP_0402-0.1UF,25V,10%,X7R,CH4104K1B00    I67 @T6G_MB_LIB.T6G(SCH_1):PAGE255
  U195    5    VCC 74LVC2G17GW-74LVC2G17GW,SMLF,IC,AL2G0017005    I65 @T6G_MB_LIB.T6G(SCH_1):PAGE256
 R2815    1      A Q_RES_0402LF-100K,1%,1/16W,EMPTY,CS41002FB09    I68 @T6G_MB_LIB.T6G(SCH_1):PAGE256
 R2820    1      A Q_RES_0402LF-4.7K,5%,1/16W,EMPTY,CS24702JB10    I78 @T6G_MB_LIB.T6G(SCH_1):PAGE256
 C1769    1      A Q_CAP_0402-0.1UF,25V,10%,X7R,CH4104K1B00    I89 @T6G_MB_LIB.T6G(SCH_1):PAGE256
  U196    5    VCC 74LVC2G17GW-74LVC2G17GW,SMLF,IC,AL2G0017005   I127 @T6G_MB_LIB.T6G(SCH_1):PAGE256
 C1770    1      A Q_CAP_0402-0.1UF,25V,10%,X7R,CH4104K1B00   I140 @T6G_MB_LIB.T6G(SCH_1):PAGE256
 R2912    1      A Q_RES_0402LF-4.7K,5%,1/16W,EMPTY,CS24702JB10   I147 @T6G_MB_LIB.T6G(SCH_1):PAGE256
 R2911    1      A Q_RES_0402LF-4.7K,5%,1/16W,EMPTY,CS24702JB10   I153 @T6G_MB_LIB.T6G(SCH_1):PAGE256
 R2936    1      A Q_RES_0402LF-100K,1%,1/16W,EMPTY,CS41002FB09   I162 @T6G_MB_LIB.T6G(SCH_1):PAGE256
 C1803    1      A Q_CAP_0402-0.1UF,25V,10%,X7R,CH4104K1B00   I166 @T6G_MB_LIB.T6G(SCH_1):PAGE256
 R3317    1      A Q_RES_0402LF-4.7K,5%,1/16W,EMPTY,CS24702JB10   I190 @T6G_MB_LIB.T6G(SCH_1):PAGE256
 R3506    1      A Q_RES_0402LF-4.7K,5%,1/16W,EMPTY,CS24702JB10   I193 @T6G_MB_LIB.T6G(SCH_1):PAGE256
  U204    5    VCC 74LVC1G126SE7-74LVC1G126SE-7,SMLF,IC,AL1G0126009   I195 @T6G_MB_LIB.T6G(SCH_1):PAGE256
 R2909    1      A Q_RES_0402LF-4.7K,5%,1/16W,CHIP,CS24702JB10   I198 @T6G_MB_LIB.T6G(SCH_1):PAGE256
 R4515    1      A Q_RES_0402LF-100K,1%,1/16W,CHIP,CS41002FB09   I200 @T6G_MB_LIB.T6G(SCH_1):PAGE256
 C1825    1      A Q_CAP_0402-0.1UF,25V,10%,X7R,CH4104K1B00    I17 @T6G_MB_LIB.T6G(SCH_1):PAGE307
  U222   14    VCC 74CBTLV3126PW-74CBTLV3126PW,SMLF,IC,AL003126K08    I32 @T6G_MB_LIB.T6G(SCH_1):PAGE307
 C1826    1      A Q_CAP_0402-0.1UF,25V,10%,X7R,CH4104K1B00    I33 @T6G_MB_LIB.T6G(SCH_1):PAGE307
 C1827    1      A Q_CAP_0402-0.1UF,25V,10%,X7R,CH4104K1B00    I77 @T6G_MB_LIB.T6G(SCH_1):PAGE307
  U223   14    VCC 74CBTLV3126PW-74CBTLV3126PW,SMLF,IC,AL003126K08    I78 @T6G_MB_LIB.T6G(SCH_1):PAGE307
  U286    5    VCC 74LVC1G126SE7-74LVC1G126SE-7,SMLF,IC,AL1G0126009    I80 @T6G_MB_LIB.T6G(SCH_1):PAGE307
   U67   14    VCC 74CBTLV3126PW-74CBTLV3126PW,SMLF,IC,AL003126K08     I1 @T6G_MB_LIB.T6G(SCH_1):PAGE336
    U7   14    VCC 74CBTLV3126PW-74CBTLV3126PW,SMLF,IC,AL003126K08     I2 @T6G_MB_LIB.T6G(SCH_1):PAGE336
  C641    1      A Q_CAP_0402-0.1UF,25V,10%,X7R,CH4104K1B00    I16 @T6G_MB_LIB.T6G(SCH_1):PAGE336
  C640    1      A Q_CAP_0402-0.1UF,25V,10%,X7R,CH4104K1B00    I47 @T6G_MB_LIB.T6G(SCH_1):PAGE336
  C639    1      A Q_CAP_0402-0.1UF,25V,10%,X7R,CH4104K1B00    I59 @T6G_MB_LIB.T6G(SCH_1):PAGE336
 C1840    1      A Q_CAP_0402-0.1UF,25V,10%,X7R,CH4104K1B00   I147 @T6G_MB_LIB.T6G(SCH_1):PAGE336
   U66    5    VCC 74LVC1G126SE7-74LVC1G126SE-7,SMLF,IC,AL1G0126009   I157 @T6G_MB_LIB.T6G(SCH_1):PAGE336
  U224    5    VCC 74LVC1G126SE7-74LVC1G126SE-7,SMLF,IC,AL1G0126009   I159 @T6G_MB_LIB.T6G(SCH_1):PAGE336
   C72    1      A Q_CAP_0402-0.1UF,25V,10%,X7R,CH4104K1B00    I40 @T6G_MB_LIB.T6G(SCH_1):PAGE337
   R53    1      A Q_RES_0402LF-4.7K,1%,1/16W,CHIP,CS24702FB06    I42 @T6G_MB_LIB.T6G(SCH_1):PAGE337
 C2344    1      A Q_CAP_0402-0.1UF,25V,10%,X7R,CH4104K1B00    I53 @T6G_MB_LIB.T6G(SCH_1):PAGE337
 R2487    1      A Q_RES_0402LF-4.7K,1%,1/16W,EMPTY,CS24702FB06    I56 @T6G_MB_LIB.T6G(SCH_1):PAGE337
 C1841    1      A Q_CAP_0402-0.1UF,25V,10%,X7R,CH4104K1B00    I12 @T6G_MB_LIB.T6G(SCH_1):PAGE342
 C1823    1      A Q_CAP_0402-0.1UF,25V,10%,X7R,CH4104K1B00    I31 @T6G_MB_LIB.T6G(SCH_1):PAGE342
 C1824    1      A Q_CAP_0402-0.1UF,25V,10%,X7R,CH4104K1B00    I41 @T6G_MB_LIB.T6G(SCH_1):PAGE342
 R3192    1      A Q_RES_0402LF-4.7K,1%,1/16W,EMPTY,CS24702FB06    I44 @T6G_MB_LIB.T6G(SCH_1):PAGE342
   C38    1      A Q_CAP_0402-0.1UF,25V,10%,X7R,CH4104K1B00    I47 @T6G_MB_LIB.T6G(SCH_1):PAGE342
 R3136    1      A Q_RES_0402LF-1K,1%,1/16W,CHIP,CS21002FB06     I6 @T6G_MB_LIB.T6G(SCH_1):PAGE343
 R3133    1      A Q_RES_0402LF-1K,1%,1/16W,CHIP,CS21002FB06    I14 @T6G_MB_LIB.T6G(SCH_1):PAGE343
 R3135    1      A Q_RES_0402LF-1K,1%,1/16W,CHIP,CS21002FB06    I16 @T6G_MB_LIB.T6G(SCH_1):PAGE343
   U58    5    VCC 74LVC2G07DW7-74LVC2G07DW-7,SMLF,IC,AL002G07003    I28 @T6G_MB_LIB.T6G(SCH_1):PAGE343
PR3795    1      A Q_RES_0402LF-25.5K,1%,1/16W,CHIP,CS32552FB06    I56 @T6G_MB_LIB.T6G(SCH_1):PAGE343
 R3147    1      A Q_RES_0402LF-1K,1%,1/16W,CHIP,CS21002FB06    I69 @T6G_MB_LIB.T6G(SCH_1):PAGE343
 R3825    1      A Q_RES_0402LF-100K,1%,1/16W,CHIP,CS41002FB09    I80 @T6G_MB_LIB.T6G(SCH_1):PAGE343
 PU200   A3  IN_A3 MAX15090BEWIT-MAX15090BEWI+T,SMLF,IC,AL015080B00    I89 @T6G_MB_LIB.T6G(SCH_1):PAGE343
 PU200   A5  IN_A5 MAX15090BEWIT-MAX15090BEWI+T,SMLF,IC,AL015080B00    I89 @T6G_MB_LIB.T6G(SCH_1):PAGE343
 PU200   B3  IN_B3 MAX15090BEWIT-MAX15090BEWI+T,SMLF,IC,AL015080B00    I89 @T6G_MB_LIB.T6G(SCH_1):PAGE343
 PU200   B5  IN_B5 MAX15090BEWIT-MAX15090BEWI+T,SMLF,IC,AL015080B00    I89 @T6G_MB_LIB.T6G(SCH_1):PAGE343
 PU200   C3  IN_C3 MAX15090BEWIT-MAX15090BEWI+T,SMLF,IC,AL015080B00    I89 @T6G_MB_LIB.T6G(SCH_1):PAGE343
 PU200   C5  IN_C5 MAX15090BEWIT-MAX15090BEWI+T,SMLF,IC,AL015080B00    I89 @T6G_MB_LIB.T6G(SCH_1):PAGE343
 PU200   D5  IN_D5 MAX15090BEWIT-MAX15090BEWI+T,SMLF,IC,AL015080B00    I89 @T6G_MB_LIB.T6G(SCH_1):PAGE343
 R3833    1      A Q_RES_0402LF-100K,1%,1/16W,CHIP,CS41002FB09   I107 @T6G_MB_LIB.T6G(SCH_1):PAGE343
PR3851    2      B Q_RES_0402LF-10K,1%,1/16W,CHIP,CS31002FB08    I18 @T6G_MB_LIB.T6G(SCH_1):PAGE344
 R3848    1      A Q_RES_0402LF-10K,1%,1/16W,CHIP,CS31002FB08    I27 @T6G_MB_LIB.T6G(SCH_1):PAGE344
PC2169    1      A Q_CAP_C0402-1UF,25V,10%,X6S,CH5104KEB02    I48 @T6G_MB_LIB.T6G(SCH_1):PAGE344
 PU207  1_2    VCC MP5016GQHLZ-MP5016GQH-L-Z,SMLF,IC,AL005016007    I51 @T6G_MB_LIB.T6G(SCH_1):PAGE344
  U241    8    VCC 74LVC2G08DP-74LVC2G08DP,SMLF,EMPTY,ALVC2G08K01     I1 @T6G_MB_LIB.T6G(SCH_1):PAGE258
  U240    8    VCC 74LVC2G08DP-74LVC2G08DP,SMLF,EMPTY,ALVC2G08K01    I11 @T6G_MB_LIB.T6G(SCH_1):PAGE258
  U242    8    VCC 74LVC2G08DP-74LVC2G08DP,SMLF,EMPTY,ALVC2G08K01    I13 @T6G_MB_LIB.T6G(SCH_1):PAGE258
  U243    5    VCC NC7SB3157_SMLF-NC7SB3157P6X,NC7SB3157P6X,EMPTY,ALSA    I15 @T6G_MB_LIB.T6G(SCH_1):PAGE258
  U244    5    VCC NC7SB3157_SMLF-NC7SB3157P6X,NC7SB3157P6X,EMPTY,ALSA    I16 @T6G_MB_LIB.T6G(SCH_1):PAGE258
  U246    5    VCC NC7SB3157_SMLF-NC7SB3157P6X,NC7SB3157P6X,EMPTY,ALSA    I17 @T6G_MB_LIB.T6G(SCH_1):PAGE258
  U245    5    VCC NC7SB3157_SMLF-NC7SB3157P6X,NC7SB3157P6X,EMPTY,ALSA    I18 @T6G_MB_LIB.T6G(SCH_1):PAGE258
 C1875    1      A Q_CAP_0402-0.1UF,25V,10%,X7R,CH4104K1B00    I21 @T6G_MB_LIB.T6G(SCH_1):PAGE258
 C1874    1      A Q_CAP_0402-0.1UF,25V,10%,X7R,CH4104K1B00    I22 @T6G_MB_LIB.T6G(SCH_1):PAGE258
 C1880    1      A Q_CAP_0402-0.1UF,25V,10%,X7R,CH4104K1B00    I27 @T6G_MB_LIB.T6G(SCH_1):PAGE258
 C1879    1      A Q_CAP_0402-0.1UF,25V,10%,X7R,CH4104K1B00    I31 @T6G_MB_LIB.T6G(SCH_1):PAGE258
 C1877    1      A Q_CAP_0402-0.1UF,25V,10%,X7R,CH4104K1B00    I34 @T6G_MB_LIB.T6G(SCH_1):PAGE258
 C1878    1      A Q_CAP_0402-0.1UF,25V,10%,X7R,CH4104K1B00    I37 @T6G_MB_LIB.T6G(SCH_1):PAGE258
 C1876    1      A Q_CAP_0402-0.1UF,25V,10%,X7R,CH4104K1B00    I41 @T6G_MB_LIB.T6G(SCH_1):PAGE258
PC2200    1      A Q_CAP_C0402-1UF,25V,10%,X6S,CH5104KEB02     I9 @T6G_MB_LIB.T6G(SCH_1):PAGE323
 PU293  1_2    VCC MP5016GQHLZ-MP5016GQH-L-Z,SMLF,IC,AL005016007    I31 @T6G_MB_LIB.T6G(SCH_1):PAGE323
 R3948    1      A Q_RES_0402LF-10K,1%,1/16W,CHIP,CS31002FB08    I37 @T6G_MB_LIB.T6G(SCH_1):PAGE323
PR3951    2      B Q_RES_0402LF-10K,1%,1/16W,CHIP,CS31002FB08    I40 @T6G_MB_LIB.T6G(SCH_1):PAGE323
PC2208    1      A Q_CAP_C0402-1UF,25V,10%,X6S,CH5104KEB02    I20 @T6G_MB_LIB.T6G(SCH_1):PAGE324
PR3963    1      A Q_RES_0402LF-25.5K,1%,1/16W,CHIP,CS32552FB06    I21 @T6G_MB_LIB.T6G(SCH_1):PAGE324
PR3967    1      A Q_RES_0402LF-10,1%,1/16W,CHIP,CS01002FB07    I43 @T6G_MB_LIB.T6G(SCH_1):PAGE324
 R3979    1      A Q_RES_0402LF-100K,1%,1/16W,CHIP,CS41002FB09    I54 @T6G_MB_LIB.T6G(SCH_1):PAGE324
 R3976    1      A Q_RES_0402LF-100K,1%,1/16W,CHIP,CS41002FB09    I76 @T6G_MB_LIB.T6G(SCH_1):PAGE324
 C1305    1      A Q_CAP_0402-0.1UF,25V,10%,X7R,CH4104K1B00    I52 @T6G_MB_LIB.T6G(SCH_1):PAGE346
 R1700    1      A Q_RES_0402LF-200K,1%,1/16W,CHIP,CS42002FB05    I72 @T6G_MB_LIB.T6G(SCH_1):PAGE346
 C1997    1      A Q_CAP_0402-0.1UF,25V,10%,X7R,CH4104K1B00    I89 @T6G_MB_LIB.T6G(SCH_1):PAGE346
  U279    8   VCCB PCA9617ADP-PCA9617ADP,SMLF,IC,AL009617K02    I93 @T6G_MB_LIB.T6G(SCH_1):PAGE346
 R3529    1      A Q_RES_0402LF-10K,1%,1/16W,CHIP,CS31002FB08    I99 @T6G_MB_LIB.T6G(SCH_1):PAGE346
 R1854    1      A Q_RES_0402LF-1K,1%,1/16W,CHIP,CS21002FB06     I2 @T6G_MB_LIB.T6G(SCH_1):PAGE350
 R1857    1      A Q_RES_0402LF-10K,1%,1/16W,CHIP,CS31002FB08    I18 @T6G_MB_LIB.T6G(SCH_1):PAGE350
PR4007    2      B Q_RES_0402LF-10K,1%,1/16W,CHIP,CS31002FB08    I40 @T6G_MB_LIB.T6G(SCH_1):PAGE350
 R4015    1      A Q_RES_0402LF-100K,1%,1/16W,CHIP,CS41002FB09    I78 @T6G_MB_LIB.T6G(SCH_1):PAGE350
 C1332    1      A Q_CAP_C0402-100NF,50V,10%,X7R,CH4106K1B01    I48 @T6G_MB_LIB.T6G(SCH_1):PAGE273
 C1333    1      A Q_CAP_C0805-10UF,16V,10%,X6S,CH6103KEA00    I49 @T6G_MB_LIB.T6G(SCH_1):PAGE273
   Q56    5      5 MOSFET_NCH_1D3S-PSMNR58-30YLH,SMLF,IC,BAMNR580000    I50 @T6G_MB_LIB.T6G(SCH_1):PAGE273
   C60    1      A Q_CAP_C0805-10UF,16V,10%,EMPTY,CH6103KEA00    I51 @T6G_MB_LIB.T6G(SCH_1):PAGE273
  U266    9    VCC ISL28022FRZT-ISL28022FRZ-T,SMLF,IC,AL028022003    I30 @T6G_MB_LIB.T6G(SCH_1):PAGE295
 C2015    1      A Q_CAP_0402-0.1UF,25V,10%,X7R,CH4104K1B00    I34 @T6G_MB_LIB.T6G(SCH_1):PAGE295
 R3628    1      A Q_RES_0402LF-4.7K,1%,1/16W,EMPTY,CS24702FB06    I88 @T6G_MB_LIB.T6G(SCH_1):PAGE295
 R3627    1      A Q_RES_0402LF-4.7K,1%,1/16W,CHIP,CS24702FB06    I89 @T6G_MB_LIB.T6G(SCH_1):PAGE295
 C2067    1      A Q_CAP_0402-0.1UF,25V,10%,X7R,CH4104K1B00   I125 @T6G_MB_LIB.T6G(SCH_1):PAGE295
  U276    9    VCC ISL28022FRZT-ISL28022FRZ-T,SMLF,IC,AL028022003   I129 @T6G_MB_LIB.T6G(SCH_1):PAGE295
 R4093    1      A Q_RES_0402LF-1K,1%,1/16W,CHIP,CS21002FB06   I149 @T6G_MB_LIB.T6G(SCH_1):PAGE295
 R4094    1      A Q_RES_0402LF-1K,1%,1/16W,CHIP,CS21002FB06   I151 @T6G_MB_LIB.T6G(SCH_1):PAGE295
 U5201   12    VCC TUSB211IRWBR-TUSB211IRWBR,SMLF,EMPTY,AL000211007    I84 @T6G_MB_LIB.T6G(SCH_1):PAGE358
 C5229    1      A Q_CAP_C0402-1UF,25V,10%,EMPTY,CH5104KEB02    I88 @T6G_MB_LIB.T6G(SCH_1):PAGE358
 C5234    1      A Q_CAP_C0402-0.1UF,25V,10%,EMPTY,CH4104KEB00    I92 @T6G_MB_LIB.T6G(SCH_1):PAGE358
 R3660    1      A Q_RES_0402LF-10K,1%,1/16W,CHIP,CS31002FB08   I159 @T6G_MB_LIB.T6G(SCH_1):PAGE358
 R3655    1      A Q_RES_0402LF-0,5%,1/16W,CHIP,CS00002JB13   I161 @T6G_MB_LIB.T6G(SCH_1):PAGE358
 R3663    1      A Q_RES_0402LF-10K,1%,1/16W,CHIP,CS31002FB08   I186 @T6G_MB_LIB.T6G(SCH_1):PAGE358
 R3656    1      A Q_RES_0402LF-10K,1%,1/16W,EMPTY,CS31002FB08   I194 @T6G_MB_LIB.T6G(SCH_1):PAGE358
 R3657    1      A Q_RES_0402LF-10K,1%,1/16W,EMPTY,CS31002FB08   I195 @T6G_MB_LIB.T6G(SCH_1):PAGE358
 R3658    1      A Q_RES_0402LF-10K,1%,1/16W,EMPTY,CS31002FB08   I196 @T6G_MB_LIB.T6G(SCH_1):PAGE358
 R3659    1      A Q_RES_0402LF-10K,1%,1/16W,EMPTY,CS31002FB08   I198 @T6G_MB_LIB.T6G(SCH_1):PAGE358
 C2010    1      A Q_CAP_0402-0.1UF,25V,10%,X7R,CH4104K1B00    I16 @T6G_MB_LIB.T6G(SCH_1):PAGE359
 R4198    1      A Q_RES_0402LF-1K,1%,1/16W,EMPTY,CS21002FB06    I82 @T6G_MB_LIB.T6G(SCH_1):PAGE359
 R4206    1      A Q_RES_0402LF-1K,1%,1/16W,EMPTY,CS21002FB06    I86 @T6G_MB_LIB.T6G(SCH_1):PAGE359
 R4190    1      A Q_RES_0402LF-1K,1%,1/16W,EMPTY,CS21002FB06    I91 @T6G_MB_LIB.T6G(SCH_1):PAGE359
 R4204    1      A Q_RES_0402LF-1K,1%,1/16W,EMPTY,CS21002FB06    I94 @T6G_MB_LIB.T6G(SCH_1):PAGE359
 R4196    1      A Q_RES_0402LF-1K,1%,1/16W,EMPTY,CS21002FB06    I95 @T6G_MB_LIB.T6G(SCH_1):PAGE359
 R4188    1      A Q_RES_0402LF-1K,1%,1/16W,EMPTY,CS21002FB06   I101 @T6G_MB_LIB.T6G(SCH_1):PAGE359
   C73    1      A Q_CAP_0402-0.1UF,25V,10%,X7R,CH4104K1B00   I104 @T6G_MB_LIB.T6G(SCH_1):PAGE359
   C32    1      A Q_CAP_0402-0.1UF,25V,10%,X7R,CH4104K1B00   I119 @T6G_MB_LIB.T6G(SCH_1):PAGE359
 R4186    1      A Q_RES_0402LF-1K,1%,1/16W,EMPTY,CS21002FB06   I122 @T6G_MB_LIB.T6G(SCH_1):PAGE359
 R4194    1      A Q_RES_0402LF-1K,1%,1/16W,EMPTY,CS21002FB06   I128 @T6G_MB_LIB.T6G(SCH_1):PAGE359
 R4202    1      A Q_RES_0402LF-1K,1%,1/16W,EMPTY,CS21002FB06   I129 @T6G_MB_LIB.T6G(SCH_1):PAGE359
   C31    1      A Q_CAP_0402-0.1UF,25V,10%,X7R,CH4104K1B00   I139 @T6G_MB_LIB.T6G(SCH_1):PAGE359
 R4184    1      A Q_RES_0402LF-1K,1%,1/16W,EMPTY,CS21002FB06   I142 @T6G_MB_LIB.T6G(SCH_1):PAGE359
 R4192    1      A Q_RES_0402LF-1K,1%,1/16W,EMPTY,CS21002FB06   I148 @T6G_MB_LIB.T6G(SCH_1):PAGE359
 R4200    1      A Q_RES_0402LF-1K,1%,1/16W,EMPTY,CS21002FB06   I149 @T6G_MB_LIB.T6G(SCH_1):PAGE359
  U270    8    VCC LM75BD-LM75BD,SMLF,IC,AL0075BD000   I164 @T6G_MB_LIB.T6G(SCH_1):PAGE359
  U271    8    VCC LM75BD-LM75BD,SMLF,IC,AL0075BD000   I165 @T6G_MB_LIB.T6G(SCH_1):PAGE359
  U272    8    VCC LM75BD-LM75BD,SMLF,IC,AL0075BD000   I166 @T6G_MB_LIB.T6G(SCH_1):PAGE359
  U273    8    VCC LM75BD-LM75BD,SMLF,IC,AL0075BD000   I167 @T6G_MB_LIB.T6G(SCH_1):PAGE359
 R4211    1      A Q_RES_0402LF-200K,1%,1/16W,CHIP,CS42002FB05   I168 @T6G_MB_LIB.T6G(SCH_1):PAGE359
 R4209    1      A Q_RES_0402LF-200K,1%,1/16W,EMPTY,CS42002FB05   I169 @T6G_MB_LIB.T6G(SCH_1):PAGE359
 R4210    1      A Q_RES_0402LF-200K,1%,1/16W,EMPTY,CS42002FB05   I170 @T6G_MB_LIB.T6G(SCH_1):PAGE359
 R4208    1      A Q_RES_0402LF-200K,1%,1/16W,EMPTY,CS42002FB05   I171 @T6G_MB_LIB.T6G(SCH_1):PAGE359
 C2013    1      A Q_CAP_0402-0.1UF,25V,10%,X7R,CH4104K1B00    I42 @T6G_MB_LIB.T6G(SCH_1):PAGE360
  U264    9    VCC ISL28022FRZT-ISL28022FRZ-T,SMLF,IC,AL028022003    I46 @T6G_MB_LIB.T6G(SCH_1):PAGE360
 C2014    1      A Q_CAP_0402-0.1UF,25V,10%,X7R,CH4104K1B00    I65 @T6G_MB_LIB.T6G(SCH_1):PAGE360
  U265    9    VCC ISL28022FRZT-ISL28022FRZ-T,SMLF,IC,AL028022003    I69 @T6G_MB_LIB.T6G(SCH_1):PAGE360
 R3623    1      A Q_RES_0402LF-4.7K,1%,1/16W,CHIP,CS24702FB06    I86 @T6G_MB_LIB.T6G(SCH_1):PAGE360
 R3621    1      A Q_RES_0402LF-4.7K,1%,1/16W,EMPTY,CS24702FB06    I87 @T6G_MB_LIB.T6G(SCH_1):PAGE360
 R3624    1      A Q_RES_0402LF-4.7K,1%,1/16W,CHIP,CS24702FB06    I89 @T6G_MB_LIB.T6G(SCH_1):PAGE360
 R3622    1      A Q_RES_0402LF-4.7K,1%,1/16W,CHIP,CS24702FB06    I90 @T6G_MB_LIB.T6G(SCH_1):PAGE360
  U263    9    VCC ISL28022FRZT-ISL28022FRZ-T,SMLF,IC,AL028022003    I94 @T6G_MB_LIB.T6G(SCH_1):PAGE360
 C2012    1      A Q_CAP_0402-0.1UF,25V,10%,X7R,CH4104K1B00    I98 @T6G_MB_LIB.T6G(SCH_1):PAGE360
 R4091    1      A Q_RES_0402LF-1K,1%,1/16W,CHIP,CS21002FB06   I122 @T6G_MB_LIB.T6G(SCH_1):PAGE360
 R4090    1      A Q_RES_0402LF-1K,1%,1/16W,CHIP,CS21002FB06   I124 @T6G_MB_LIB.T6G(SCH_1):PAGE360
 R4092    1      A Q_RES_0402LF-1K,1%,1/16W,CHIP,CS21002FB06   I126 @T6G_MB_LIB.T6G(SCH_1):PAGE360
   U64    8    VCC M24128BWMN6TP-M24128-BWMN6TP,SMLF,IC,AKE30Z00613    I35 @T6G_MB_LIB.T6G(SCH_1):PAGE361
  R717    1      A Q_RES_0402LF-10K,1%,1/16W,EMPTY,CS31002FB08    I45 @T6G_MB_LIB.T6G(SCH_1):PAGE361
  R713    1      A Q_RES_0402LF-10K,1%,1/16W,EMPTY,CS31002FB08    I47 @T6G_MB_LIB.T6G(SCH_1):PAGE361
  C629    1      A Q_CAP_0402-0.1UF,25V,10%,X7R,CH4104K1B00    I55 @T6G_MB_LIB.T6G(SCH_1):PAGE361
  R721    1      A Q_RES_0402LF-10K,1%,1/16W,CHIP,CS31002FB08    I62 @T6G_MB_LIB.T6G(SCH_1):PAGE361
   R43    1      A Q_RES_0402LF-4.7K,5%,1/16W,EMPTY,CS24702JB10    I93 @T6G_MB_LIB.T6G(SCH_1):PAGE361
   R26    1      A Q_RES_0402LF-4.7K,5%,1/16W,EMPTY,CS24702JB10    I95 @T6G_MB_LIB.T6G(SCH_1):PAGE361
 R2794    1      A Q_RES_0402LF-4.7K,5%,1/16W,CHIP,CS24702JB10   I396 @T6G_MB_LIB.T6G(SCH_1):PAGE363
  U192    8    VCC LTC4307CMS8-LTC4307CMS8,SMLF,IC,AL004307000   I398 @T6G_MB_LIB.T6G(SCH_1):PAGE363
 C1751    1      A Q_CAP_0402-0.1UF,25V,10%,X7R,CH4104K1B00   I412 @T6G_MB_LIB.T6G(SCH_1):PAGE363
 R2805    1      A Q_RES_0402LF-4.7K,5%,1/16W,EMPTY,CS24702JB10   I436 @T6G_MB_LIB.T6G(SCH_1):PAGE363
 R2807    1      A Q_RES_0402LF-4.7K,5%,1/16W,EMPTY,CS24702JB10   I438 @T6G_MB_LIB.T6G(SCH_1):PAGE363
 C1775    1      A Q_CAP_0402-0.1UF,25V,10%,X7R,CH4104K1B00    I14 @T6G_MB_LIB.T6G(SCH_1):PAGE364
 R2946    1      A Q_RES_0402LF-4.7K,5%,1/16W,EMPTY,CS24702JB10    I25 @T6G_MB_LIB.T6G(SCH_1):PAGE364
 R2940    1      A Q_RES_0402LF-4.7K,5%,1/16W,EMPTY,CS24702JB10    I28 @T6G_MB_LIB.T6G(SCH_1):PAGE364
  U278    5    VCC 74LVC1G08W57-74LVC1G08W5-7,SMLF,IC,AL1G0008020    I31 @T6G_MB_LIB.T6G(SCH_1):PAGE364
  U308    5    VCC 74LVC2G07DW7-74LVC2G07DW-7,SMLF,IC,AL002G07003    I37 @T6G_MB_LIB.T6G(SCH_1):PAGE364
   C69    1      A Q_CAP_0402-0.1UF,25V,10%,X7R,CH4104K1B00    I40 @T6G_MB_LIB.T6G(SCH_1):PAGE364
 R4264    1      A Q_RES_0402LF-4.7K,5%,1/16W,CHIP,CS24702JB10    I47 @T6G_MB_LIB.T6G(SCH_1):PAGE364
 R4551    1      A Q_RES_0402LF-54.9K,1%,1/16W,EMPTY,CS35492FB03    I51 @T6G_MB_LIB.T6G(SCH_1):PAGE364
 R4553    1      A Q_RES_0402LF-4.7K,5%,1/16W,CHIP,CS24702JB10    I55 @T6G_MB_LIB.T6G(SCH_1):PAGE364
 R4554    1      A Q_RES_0402LF-100K,1%,1/16W,CHIP,CS41002FB09    I59 @T6G_MB_LIB.T6G(SCH_1):PAGE364
 R6034    1      A Q_RES_0402LF-1K,1%,1/16W,CHIP,CS21002FB06    I18 @T6G_MB_LIB.T6G(SCH_1):PAGE348
 R6017    1      A Q_RES_0402LF-2K,5%,1/16W,EMPTY,TMP_QCS22002JB29    I28 @T6G_MB_LIB.T6G(SCH_1):PAGE349
 R6016    1      A Q_RES_0402LF-2K,5%,1/16W,EMPTY,TMP_QCS22002JB29    I29 @T6G_MB_LIB.T6G(SCH_1):PAGE349
 R1546    1      A Q_RES_0402LF-1K,1%,1/16W,CHIP,CS21002FB06    I30 @T6G_MB_LIB.T6G(SCH_1):PAGE349
 R3243    2      B Q_RES_0402LF-2.2K,5%,1/16W,EMPTY,CS22202JB07   I115 @T6G_MB_LIB.T6G(SCH_1):PAGE349
  R131    1      A Q_RES_0402LF-10K,5%,1/16W,CHIP,CS31002JB08   I116 @T6G_MB_LIB.T6G(SCH_1):PAGE349
 R3240    2      B Q_RES_0402LF-2.2K,5%,1/16W,EMPTY,CS22202JB07   I120 @T6G_MB_LIB.T6G(SCH_1):PAGE349
 R3227    2      B Q_RES_0402LF-2.2K,5%,1/16W,EMPTY,CS22202JB07   I121 @T6G_MB_LIB.T6G(SCH_1):PAGE349
 R3226    2      B Q_RES_0402LF-2.2K,5%,1/16W,EMPTY,CS22202JB07   I122 @T6G_MB_LIB.T6G(SCH_1):PAGE349
 R3004    2      B Q_RES_0402LF-2.2K,5%,1/16W,EMPTY,CS22202JB07   I123 @T6G_MB_LIB.T6G(SCH_1):PAGE349
 R2999    2      B Q_RES_0402LF-2.2K,5%,1/16W,EMPTY,CS22202JB07   I124 @T6G_MB_LIB.T6G(SCH_1):PAGE349
 R2213    2      B Q_RES_0402LF-2.2K,5%,1/16W,EMPTY,CS22202JB07   I125 @T6G_MB_LIB.T6G(SCH_1):PAGE349
 R2212    2      B Q_RES_0402LF-2.2K,5%,1/16W,EMPTY,CS22202JB07   I126 @T6G_MB_LIB.T6G(SCH_1):PAGE349
 R1460    2      B Q_RES_0402LF-2.2K,5%,1/16W,EMPTY,CS22202JB07   I127 @T6G_MB_LIB.T6G(SCH_1):PAGE349
  R332    2      B Q_RES_0402LF-2.2K,5%,1/16W,EMPTY,CS22202JB07   I128 @T6G_MB_LIB.T6G(SCH_1):PAGE349
  R331    2      B Q_RES_0402LF-2.2K,5%,1/16W,EMPTY,CS22202JB07   I129 @T6G_MB_LIB.T6G(SCH_1):PAGE349
  R330    2      B Q_RES_0402LF-2.2K,5%,1/16W,EMPTY,CS22202JB07   I130 @T6G_MB_LIB.T6G(SCH_1):PAGE349
 R6036    2      B Q_RES_0402LF-2K,1%,1/16W,EMPTY,CS22002FB07   I131 @T6G_MB_LIB.T6G(SCH_1):PAGE349
 R6037    2      B Q_RES_0402LF-2K,1%,1/16W,EMPTY,CS22002FB07   I132 @T6G_MB_LIB.T6G(SCH_1):PAGE349
  R329    2      B Q_RES_0402LF-2K,1%,1/16W,EMPTY,CS22002FB07   I133 @T6G_MB_LIB.T6G(SCH_1):PAGE349
 R1386    2      B Q_RES_0402LF-2K,1%,1/16W,EMPTY,CS22002FB07   I134 @T6G_MB_LIB.T6G(SCH_1):PAGE349
 R1385    2      B Q_RES_0402LF-2K,1%,1/16W,EMPTY,CS22002FB07   I135 @T6G_MB_LIB.T6G(SCH_1):PAGE349
 R1384    2      B Q_RES_0402LF-2K,1%,1/16W,EMPTY,CS22002FB07   I136 @T6G_MB_LIB.T6G(SCH_1):PAGE349
 R3062    2      B Q_RES_0402LF-2K,1%,1/16W,EMPTY,CS22002FB07   I137 @T6G_MB_LIB.T6G(SCH_1):PAGE349
 R1319    2      B Q_RES_0402LF-2K,1%,1/16W,EMPTY,CS22002FB07   I138 @T6G_MB_LIB.T6G(SCH_1):PAGE349
  R888    1      A Q_RES_0402LF-10K,5%,1/16W,EMPTY,CS31002JB08   I145 @T6G_MB_LIB.T6G(SCH_1):PAGE349
  R890    1      A Q_RES_0402LF-10K,5%,1/16W,EMPTY,CS31002JB08   I147 @T6G_MB_LIB.T6G(SCH_1):PAGE349
 R2693    1      A Q_RES_0402LF-1K,1%,1/16W,EMPTY,CS21002FB06     I3 @T6G_MB_LIB.T6G(SCH_1):PAGE246
 R2695    1      A Q_RES_0402LF-1K,1%,1/16W,EMPTY,CS21002FB06     I7 @T6G_MB_LIB.T6G(SCH_1):PAGE246
 R2921    1      A Q_RES_0402LF-10K,1%,1/16W,EMPTY,CS31002FB08    I35 @T6G_MB_LIB.T6G(SCH_1):PAGE246
  U248    5    VCC 74LVC1G32GW_SMLF-74LVC1G32GW,IC,ALVC1G32007    I26 @T6G_MB_LIB.T6G(SCH_1):PAGE232
 C1882    1      A Q_CAP_0402-0.1UF,25V,10%,X7R,CH4104K1B00    I28 @T6G_MB_LIB.T6G(SCH_1):PAGE232
   L17    1      1 Q_INDUCTOR_SMLF-FCM2012KF-601T/0.5A,IND,CX601T05003    I33 @T6G_MB_LIB.T6G(SCH_1):PAGE232
 R4078    1      A Q_RES_0402LF-10K,1%,1/16W,EMPTY,CS31002FB08    I47 @T6G_MB_LIB.T6G(SCH_1):PAGE232
 R4081    1      A Q_RES_0402LF-10K,1%,1/16W,CHIP,CS31002FB08    I56 @T6G_MB_LIB.T6G(SCH_1):PAGE232
 R4080    1      A Q_RES_0402LF-10K,1%,1/16W,CHIP,CS31002FB08    I59 @T6G_MB_LIB.T6G(SCH_1):PAGE232
 C1859    1      A Q_CAP_0402-0.1UF,25V,10%,X7R,CH4104K1B00     I4 @T6G_MB_LIB.T6G(SCH_1):PAGE248
  U235    1   VCCA PCA9617ADP-PCA9617ADP,SMLF,IC,AL009617K02     I6 @T6G_MB_LIB.T6G(SCH_1):PAGE248
  U236    1   VCCA PCA9617ADP-PCA9617ADP,SMLF,IC,AL009617K02    I14 @T6G_MB_LIB.T6G(SCH_1):PAGE248
 C1860    1      A Q_CAP_0402-0.1UF,25V,10%,X7R,CH4104K1B00    I15 @T6G_MB_LIB.T6G(SCH_1):PAGE248
  U200    8    VCC LTC4307CMS8-LTC4307CMS8,SMLF,IC,AL004307000    I15 @T6G_MB_LIB.T6G(SCH_1):PAGE249
  U176    8    VCC LTC4307CMS8-LTC4307CMS8,SMLF,EMPTY,AL004307000    I30 @T6G_MB_LIB.T6G(SCH_1):PAGE249
 C1796    1      A Q_CAP_0402-0.1UF,25V,10%,X7R,CH4104K1B00    I32 @T6G_MB_LIB.T6G(SCH_1):PAGE249
 R3521    1      A Q_RES_0402LF-54.9K,1%,1/16W,CHIP,CS35492FB03    I36 @T6G_MB_LIB.T6G(SCH_1):PAGE249
 R3522    1      A Q_RES_0402LF-54.9K,1%,1/16W,CHIP,CS35492FB03    I37 @T6G_MB_LIB.T6G(SCH_1):PAGE249
  U194    8    VCC LTC4307CMS8-LTC4307CMS8,SMLF,IC,AL004307000    I42 @T6G_MB_LIB.T6G(SCH_1):PAGE249
  U175    8    VCC LTC4307CMS8-LTC4307CMS8,SMLF,IC,AL004307000    I49 @T6G_MB_LIB.T6G(SCH_1):PAGE249
 C1707    1      A Q_CAP_0402-0.1UF,25V,10%,X7R,CH4104K1B00    I52 @T6G_MB_LIB.T6G(SCH_1):PAGE249
 R2667    1      A Q_RES_0402LF-2.2K,5%,1/16W,CHIP,CS22202JB07    I54 @T6G_MB_LIB.T6G(SCH_1):PAGE249
 R2669    1      A Q_RES_0402LF-2.2K,5%,1/16W,CHIP,CS22202JB07    I57 @T6G_MB_LIB.T6G(SCH_1):PAGE249
 C1708    1      A Q_CAP_0402-0.1UF,25V,10%,X7R,CH4104K1B00    I61 @T6G_MB_LIB.T6G(SCH_1):PAGE249
 R2668    1      A Q_RES_0402LF-4.7K,5%,1/16W,EMPTY,CS24702JB10    I62 @T6G_MB_LIB.T6G(SCH_1):PAGE249
 R2670    1      A Q_RES_0402LF-4.7K,5%,1/16W,EMPTY,CS24702JB10    I63 @T6G_MB_LIB.T6G(SCH_1):PAGE249
 C1766    1      A Q_CAP_0402-0.1UF,25V,10%,X7R,CH4104K1B00    I78 @T6G_MB_LIB.T6G(SCH_1):PAGE249
 R3523    1      A Q_RES_0402LF-54.9K,1%,1/16W,CHIP,CS35492FB03    I80 @T6G_MB_LIB.T6G(SCH_1):PAGE249
 R3524    1      A Q_RES_0402LF-54.9K,1%,1/16W,CHIP,CS35492FB03    I81 @T6G_MB_LIB.T6G(SCH_1):PAGE249
  C611    1      A Q_CAP_0402-0.1UF,25V,10%,X7R,CH4104K1B00     I6 @T6G_MB_LIB.T6G(SCH_1):PAGE137
  R200    1      A Q_RES_0402LF-4.7K,5%,1/16W,EMPTY,CS24702JB10    I13 @T6G_MB_LIB.T6G(SCH_1):PAGE137
   C23    1      A Q_CAP_0402-0.1UF,25V,10%,X7R,CH4104K1B00    I26 @T6G_MB_LIB.T6G(SCH_1):PAGE137
    U5    1   VCCA PCA9617ADP-PCA9617ADP,SMLF,EMPTY,AL009617K02    I48 @T6G_MB_LIB.T6G(SCH_1):PAGE137
 R3703    1      A Q_RES_0402LF-10K,1%,1/16W,EMPTY,CS31002FB08     I7 @T6G_MB_LIB.T6G(SCH_1):PAGE251
 R3706    1      A Q_RES_0402LF-10K,1%,1/16W,EMPTY,CS31002FB08     I8 @T6G_MB_LIB.T6G(SCH_1):PAGE251
 R3708    1      A Q_RES_0402LF-10K,1%,1/16W,EMPTY,CS31002FB08    I10 @T6G_MB_LIB.T6G(SCH_1):PAGE251
 R3705    1      A Q_RES_0402LF-10K,1%,1/16W,EMPTY,CS31002FB08    I27 @T6G_MB_LIB.T6G(SCH_1):PAGE251
 C2056    1      A Q_CAP_0402-0.1UF,25V,10%,X7R,CH4104K1B00    I38 @T6G_MB_LIB.T6G(SCH_1):PAGE251
 R4270    1      A Q_RES_0402LF-2.2K,5%,1/16W,EMPTY,CS22202JB07    I40 @T6G_MB_LIB.T6G(SCH_1):PAGE251
 R4269    1      A Q_RES_0402LF-2.2K,5%,1/16W,EMPTY,CS22202JB07    I41 @T6G_MB_LIB.T6G(SCH_1):PAGE251
 R3732    1      A Q_RES_0402LF-2.2K,5%,1/16W,CHIP,CS22202JB07    I42 @T6G_MB_LIB.T6G(SCH_1):PAGE251
 R3731    1      A Q_RES_0402LF-2.2K,5%,1/16W,CHIP,CS22202JB07    I43 @T6G_MB_LIB.T6G(SCH_1):PAGE251
 R3729    1      A Q_RES_0402LF-2.2K,5%,1/16W,CHIP,CS22202JB07    I44 @T6G_MB_LIB.T6G(SCH_1):PAGE251
 R3730    1      A Q_RES_0402LF-2.2K,5%,1/16W,CHIP,CS22202JB07    I45 @T6G_MB_LIB.T6G(SCH_1):PAGE251
 R3728    1      A Q_RES_0402LF-2.2K,5%,1/16W,CHIP,CS22202JB07    I47 @T6G_MB_LIB.T6G(SCH_1):PAGE251
 R3727    1      A Q_RES_0402LF-2.2K,5%,1/16W,CHIP,CS22202JB07    I48 @T6G_MB_LIB.T6G(SCH_1):PAGE251
 R3726    1      A Q_RES_0402LF-2.2K,5%,1/16W,CHIP,CS22202JB07    I49 @T6G_MB_LIB.T6G(SCH_1):PAGE251
 R3725    1      A Q_RES_0402LF-2.2K,5%,1/16W,CHIP,CS22202JB07    I50 @T6G_MB_LIB.T6G(SCH_1):PAGE251
 R3724    1      A Q_RES_0402LF-2.2K,5%,1/16W,CHIP,CS22202JB07    I52 @T6G_MB_LIB.T6G(SCH_1):PAGE251
 R3723    1      A Q_RES_0402LF-2.2K,5%,1/16W,CHIP,CS22202JB07    I53 @T6G_MB_LIB.T6G(SCH_1):PAGE251
   U39   24    VCC TCA9548APWR-TCA9548APWR,SMLF,IC,AL009548K02    I74 @T6G_MB_LIB.T6G(SCH_1):PAGE251
  R316    1      A Q_RES_0402LF-10K,1%,1/16W,EMPTY,CS31002FB08     I7 @T6G_MB_LIB.T6G(SCH_1):PAGE252
  R318    1      A Q_RES_0402LF-10K,1%,1/16W,EMPTY,CS31002FB08     I8 @T6G_MB_LIB.T6G(SCH_1):PAGE252
  R320    1      A Q_RES_0402LF-10K,1%,1/16W,EMPTY,CS31002FB08    I10 @T6G_MB_LIB.T6G(SCH_1):PAGE252
 R1822    1      A Q_RES_0402LF-10K,1%,1/16W,CHIP,CS31002FB08    I21 @T6G_MB_LIB.T6G(SCH_1):PAGE252
   U36   24    VCC TCA9548APWR-TCA9548APWR,SMLF,IC,AL009548K02    I33 @T6G_MB_LIB.T6G(SCH_1):PAGE252
  C106    1      A Q_CAP_0402-0.1UF,25V,10%,X7R,CH4104K1B00    I34 @T6G_MB_LIB.T6G(SCH_1):PAGE252
 R1089    1      A Q_RES_0402LF-2.2K,5%,1/16W,CHIP,CS22202JB07    I37 @T6G_MB_LIB.T6G(SCH_1):PAGE252
 R1090    1      A Q_RES_0402LF-2.2K,5%,1/16W,CHIP,CS22202JB07    I38 @T6G_MB_LIB.T6G(SCH_1):PAGE252
   R67    1      A Q_RES_0402LF-2.2K,5%,1/16W,CHIP,CS22202JB07    I39 @T6G_MB_LIB.T6G(SCH_1):PAGE252
   R66    1      A Q_RES_0402LF-2.2K,5%,1/16W,CHIP,CS22202JB07    I40 @T6G_MB_LIB.T6G(SCH_1):PAGE252
 R2984    1      A Q_RES_0402LF-2.2K,5%,1/16W,CHIP,CS22202JB07    I41 @T6G_MB_LIB.T6G(SCH_1):PAGE252
 R2985    1      A Q_RES_0402LF-2.2K,5%,1/16W,CHIP,CS22202JB07    I42 @T6G_MB_LIB.T6G(SCH_1):PAGE252
 R3536    1      A Q_RES_0402LF-2.2K,5%,1/16W,CHIP,CS22202JB07    I43 @T6G_MB_LIB.T6G(SCH_1):PAGE252
 R3535    1      A Q_RES_0402LF-2.2K,5%,1/16W,CHIP,CS22202JB07    I44 @T6G_MB_LIB.T6G(SCH_1):PAGE252
 R3583    1      A Q_RES_0402LF-2.2K,5%,1/16W,CHIP,CS22202JB07    I45 @T6G_MB_LIB.T6G(SCH_1):PAGE252
 R3582    1      A Q_RES_0402LF-2.2K,5%,1/16W,CHIP,CS22202JB07    I46 @T6G_MB_LIB.T6G(SCH_1):PAGE252
 R3395    1      A Q_RES_0402LF-2.2K,5%,1/16W,CHIP,CS22202JB07    I47 @T6G_MB_LIB.T6G(SCH_1):PAGE252
 R3396    1      A Q_RES_0402LF-2.2K,5%,1/16W,CHIP,CS22202JB07    I48 @T6G_MB_LIB.T6G(SCH_1):PAGE252
 R2205    1      A Q_RES_0402LF-2.2K,5%,1/16W,EMPTY,CS22202JB07    I49 @T6G_MB_LIB.T6G(SCH_1):PAGE252
 R2204    1      A Q_RES_0402LF-2.2K,5%,1/16W,EMPTY,CS22202JB07    I50 @T6G_MB_LIB.T6G(SCH_1):PAGE252
  U134    5    VCC 74LVC2G07DW7-74LVC2G07DW-7,SMLF,IC,AL002G07003     I4 @T6G_MB_LIB.T6G(SCH_1):PAGE297
 R3771    1      A Q_RES_0402LF-10K,1%,1/16W,CHIP,CS31002FB08     I7 @T6G_MB_LIB.T6G(SCH_1):PAGE297
 C1592    1      A Q_CAP_0402-0.1UF,25V,10%,X7R,CH4104K1B00    I36 @T6G_MB_LIB.T6G(SCH_1):PAGE297
 R2125    1      A Q_RES_0402LF-4.7K,5%,1/16W,CHIP,CS24702JB10    I40 @T6G_MB_LIB.T6G(SCH_1):PAGE297
  U259    5    VCC SN74LVC2G07DCKR_SMLF-SN74LVC2G07DCKR,IC,AL002G07006     I5 @T6G_MB_LIB.T6G(SCH_1):PAGE345
 C2007    1      A Q_CAP_C0402-1UF,25V,10%,X6S,CH5104KEB02     I6 @T6G_MB_LIB.T6G(SCH_1):PAGE345
 R2121    1      A Q_RES_0402LF-4.7K,5%,1/16W,CHIP,CS24702JB10    I10 @T6G_MB_LIB.T6G(SCH_1):PAGE345
  R178    1      A Q_RES_0402LF-1K,1%,1/16W,CHIP,CS21002FB06    I24 @T6G_MB_LIB.T6G(SCH_1):PAGE345
  R155    1      A Q_RES_0402LF-1K,1%,1/16W,EMPTY,CS21002FB06    I32 @T6G_MB_LIB.T6G(SCH_1):PAGE345
 R3296    1      A Q_RES_0402LF-4.7K,1%,1/16W,CHIP,CS24702FB06    I51 @T6G_MB_LIB.T6G(SCH_1):PAGE345
  U239    5    VCC 74LVC1G126SE7-74LVC1G126SE-7,SMLF,IC,AL1G0126009    I53 @T6G_MB_LIB.T6G(SCH_1):PAGE345
 C1873    1      A Q_CAP_0402-0.1UF,25V,10%,X7R,CH4104K1B00    I56 @T6G_MB_LIB.T6G(SCH_1):PAGE345
 R3298    1      A Q_RES_0402LF-10K,1%,1/16W,CHIP,CS31002FB08    I58 @T6G_MB_LIB.T6G(SCH_1):PAGE345
 R1396    2      B Q_RES_0402LF-10K,1%,1/16W,CHIP,CS31002FB08    I66 @T6G_MB_LIB.T6G(SCH_1):PAGE345
 R3271    1      A Q_RES_0402LF-1K,1%,1/16W,EMPTY,CS21002FB06     I5 @T6G_MB_LIB.T6G(SCH_1):PAGE110
 R3269    1      A Q_RES_0402LF-1K,1%,1/16W,EMPTY,CS21002FB06    I14 @T6G_MB_LIB.T6G(SCH_1):PAGE110
 R3277    1      A Q_RES_0402LF-1K,1%,1/16W,EMPTY,CS21002FB06    I19 @T6G_MB_LIB.T6G(SCH_1):PAGE110
 R3280    1      A Q_RES_0402LF-1K,1%,1/16W,EMPTY,CS21002FB06    I26 @T6G_MB_LIB.T6G(SCH_1):PAGE110
 R3275    1      A Q_RES_0402LF-1K,1%,1/16W,EMPTY,CS21002FB06    I32 @T6G_MB_LIB.T6G(SCH_1):PAGE110
 R3283    1      A Q_RES_0402LF-1K,1%,1/16W,EMPTY,CS21002FB06    I37 @T6G_MB_LIB.T6G(SCH_1):PAGE110
 R3286    1      A Q_RES_0402LF-1K,1%,1/16W,EMPTY,CS21002FB06    I45 @T6G_MB_LIB.T6G(SCH_1):PAGE110
 C1867    1      A Q_CAP_C0805-10UF,25V,10%,X6S,CH6104KEA00    I60 @T6G_MB_LIB.T6G(SCH_1):PAGE110
 C1863    1      A Q_CAP_0402-0.1UF,25V,10%,X7R,CH4104K1B00    I61 @T6G_MB_LIB.T6G(SCH_1):PAGE110
 C1864    1      A Q_CAP_0402-0.1UF,25V,10%,X7R,CH4104K1B00    I62 @T6G_MB_LIB.T6G(SCH_1):PAGE110
  U237    1   VDD1 PI3EQX12902AZLEX-PI3EQX12902AZLEX,SMLF,IC,AL012902A    I63 @T6G_MB_LIB.T6G(SCH_1):PAGE110
  U237   10   VDD2 PI3EQX12902AZLEX-PI3EQX12902AZLEX,SMLF,IC,AL012902A    I63 @T6G_MB_LIB.T6G(SCH_1):PAGE110
  U237   16   VDD3 PI3EQX12902AZLEX-PI3EQX12902AZLEX,SMLF,IC,AL012902A    I63 @T6G_MB_LIB.T6G(SCH_1):PAGE110
  U237   25   VDD4 PI3EQX12902AZLEX-PI3EQX12902AZLEX,SMLF,IC,AL012902A    I63 @T6G_MB_LIB.T6G(SCH_1):PAGE110
 C1865    1      A Q_CAP_0402-0.1UF,25V,10%,X7R,CH4104K1B00    I64 @T6G_MB_LIB.T6G(SCH_1):PAGE110
 C1866    1      A Q_CAP_0402-0.1UF,25V,10%,X7R,CH4104K1B00    I65 @T6G_MB_LIB.T6G(SCH_1):PAGE110
 R3289    1      A Q_RES_0402LF-1K,1%,1/16W,EMPTY,CS21002FB06    I77 @T6G_MB_LIB.T6G(SCH_1):PAGE110
 R3292    1      A Q_RES_0402LF-4.7K,1%,1/16W,CHIP,CS24702FB06    I89 @T6G_MB_LIB.T6G(SCH_1):PAGE110
 R3266    1      A Q_RES_0402LF-4.7K,1%,1/16W,CHIP,CS24702FB06    I93 @T6G_MB_LIB.T6G(SCH_1):PAGE110
 R4604    1      A Q_RES_0402LF-4.7K,5%,1/16W,CHIP,CS24702JB10     I5 @T6G_MB_LIB.T6G(SCH_1):PAGE368
 R4605    1      A Q_RES_0402LF-1K,1%,1/16W,CHIP,CS21002FB06    I11 @T6G_MB_LIB.T6G(SCH_1):PAGE368
 R3075    2      B Q_RES_0402LF-130,1%,1/16W,CHIP,CS11302FB03    I15 @T6G_MB_LIB.T6G(SCH_1):PAGE254
  R638    2      B Q_RES_0402LF-1K,1%,1/16W,CHIP,CS21002FB06    I35 @T6G_MB_LIB.T6G(SCH_1):PAGE82
 R1195    2      B Q_RES_0402LF-4.7K,5%,1/16W,EMPTY,CS24702JB10    I36 @T6G_MB_LIB.T6G(SCH_1):PAGE82
 R6061    2      B Q_RES_0402LF-4.7K,5%,1/16W,EMPTY,CS24702JB10    I39 @T6G_MB_LIB.T6G(SCH_1):PAGE82
 R6062    2      B Q_RES_0402LF-4.7K,5%,1/16W,EMPTY,CS24702JB10    I40 @T6G_MB_LIB.T6G(SCH_1):PAGE82
  R993    2      B Q_RES_0402LF-1K,1%,1/16W,CHIP,CS21002FB06    I53 @T6G_MB_LIB.T6G(SCH_1):PAGE82
 R1314    2      B Q_RES_0402LF-4.7K,5%,1/16W,EMPTY,CS24702JB10    I54 @T6G_MB_LIB.T6G(SCH_1):PAGE82
 R1527    2      B Q_RES_0402LF-1K,1%,1/16W,CHIP,CS21002FB06    I56 @T6G_MB_LIB.T6G(SCH_1):PAGE82
 R1189    2      B Q_RES_0402LF-1K,1%,1/16W,CHIP,CS21002FB06    I57 @T6G_MB_LIB.T6G(SCH_1):PAGE82
 R1190    2      B Q_RES_0402LF-1K,1%,1/16W,CHIP,CS21002FB06    I58 @T6G_MB_LIB.T6G(SCH_1):PAGE82
 R1187    2      B Q_RES_0402LF-1K,1%,1/16W,CHIP,CS21002FB06    I59 @T6G_MB_LIB.T6G(SCH_1):PAGE82
 R1186    2      B Q_RES_0402LF-1K,1%,1/16W,CHIP,CS21002FB06    I60 @T6G_MB_LIB.T6G(SCH_1):PAGE82
 R1188    2      B Q_RES_0402LF-1K,1%,1/16W,CHIP,CS21002FB06    I61 @T6G_MB_LIB.T6G(SCH_1):PAGE82
 R1185    2      B Q_RES_0402LF-1K,1%,1/16W,CHIP,CS21002FB06    I62 @T6G_MB_LIB.T6G(SCH_1):PAGE82
  C358    1      A Q_CAP_C0402-0.1UF,16V,10%,X7R,CH4103K1B08   I105 @T6G_MB_LIB.T6G(SCH_1):PAGE82
  C357    1      A Q_CAP_C0402-0.1UF,16V,10%,X7R,CH4103K1B08   I106 @T6G_MB_LIB.T6G(SCH_1):PAGE82
  C356    1      A Q_CAP_C0402-0.1UF,16V,10%,X7R,CH4103K1B08   I107 @T6G_MB_LIB.T6G(SCH_1):PAGE82
  C355    1      A Q_CAP_C0402-0.1UF,16V,10%,X7R,CH4103K1B08   I108 @T6G_MB_LIB.T6G(SCH_1):PAGE82
 C1176    1      A Q_CAP_C0402-0.1UF,16V,10%,X7R,CH4103K1B08   I109 @T6G_MB_LIB.T6G(SCH_1):PAGE82
 C1175    1      A Q_CAP_C0402-0.1UF,16V,10%,X7R,CH4103K1B08   I110 @T6G_MB_LIB.T6G(SCH_1):PAGE82
 C1174    1      A Q_CAP_C0402-0.1UF,16V,10%,X7R,CH4103K1B08   I111 @T6G_MB_LIB.T6G(SCH_1):PAGE82
 C1172    1      A Q_CAP_C0402-0.1UF,16V,10%,X7R,CH4103K1B08   I112 @T6G_MB_LIB.T6G(SCH_1):PAGE82
 C1173    1      A Q_CAP_C0402-0.1UF,16V,10%,X7R,CH4103K1B08   I113 @T6G_MB_LIB.T6G(SCH_1):PAGE82
 C1171    1      A Q_CAP_C0402-0.1UF,16V,10%,X7R,CH4103K1B08   I114 @T6G_MB_LIB.T6G(SCH_1):PAGE82
 R1906    1      A Q_RES_0402LF-1K,1%,1/16W,CHIP,CS21002FB06     I9 @T6G_MB_LIB.T6G(SCH_1):PAGE338
 R1905    1      A Q_RES_0402LF-1K,1%,1/16W,CHIP,CS21002FB06    I15 @T6G_MB_LIB.T6G(SCH_1):PAGE338
 R1908    1      A Q_RES_0402LF-1K,1%,1/16W,CHIP,CS21002FB06    I24 @T6G_MB_LIB.T6G(SCH_1):PAGE338
    U8    5    VCC 74LVC2G07DW7-74LVC2G07DW-7,SMLF,IC,AL002G07003    I26 @T6G_MB_LIB.T6G(SCH_1):PAGE338
 R1907    1      A Q_RES_0402LF-1K,1%,1/16W,CHIP,CS21002FB06    I28 @T6G_MB_LIB.T6G(SCH_1):PAGE338
  U211    5    VCC 74LVC2G07DW7-74LVC2G07DW-7,SMLF,IC,AL002G07003    I29 @T6G_MB_LIB.T6G(SCH_1):PAGE338
  C593    1      A Q_CAP_0402-0.1UF,25V,10%,X7R,CH4104K1B00    I30 @T6G_MB_LIB.T6G(SCH_1):PAGE338
  C592    1      A Q_CAP_0402-0.1UF,25V,10%,X7R,CH4104K1B00    I33 @T6G_MB_LIB.T6G(SCH_1):PAGE338
PC5328    1      A Q_CAP_C0402-1UF,25V,10%,X6S,CH5104KEB02    I62 @T6G_MB_LIB.T6G(SCH_1):PAGE338
PR3789    1      A Q_RES_0402LF-25.5K,1%,1/16W,CHIP,CS32552FB06    I66 @T6G_MB_LIB.T6G(SCH_1):PAGE338
PR3798    1      A Q_RES_0402LF-10,1%,1/16W,CHIP,CS01002FB07    I68 @T6G_MB_LIB.T6G(SCH_1):PAGE338
 R1150    1      A Q_RES_0402LF-10K,1%,1/16W,CHIP,CS31002FB08    I71 @T6G_MB_LIB.T6G(SCH_1):PAGE338
 R3799    1      A Q_RES_0402LF-100K,1%,1/16W,CHIP,CS41002FB09    I83 @T6G_MB_LIB.T6G(SCH_1):PAGE338
 R3797    1      A Q_RES_0402LF-100K,1%,1/16W,CHIP,CS41002FB09    I85 @T6G_MB_LIB.T6G(SCH_1):PAGE338
 R3796    1      A Q_RES_0402LF-100K,1%,1/16W,CHIP,CS41002FB09   I101 @T6G_MB_LIB.T6G(SCH_1):PAGE338
 PU202   A3  IN_A3 MAX15090BEWIT-MAX15090BEWI+T,SMLF,IC,AL015080B00   I113 @T6G_MB_LIB.T6G(SCH_1):PAGE338
 PU202   A5  IN_A5 MAX15090BEWIT-MAX15090BEWI+T,SMLF,IC,AL015080B00   I113 @T6G_MB_LIB.T6G(SCH_1):PAGE338
 PU202   B3  IN_B3 MAX15090BEWIT-MAX15090BEWI+T,SMLF,IC,AL015080B00   I113 @T6G_MB_LIB.T6G(SCH_1):PAGE338
 PU202   B5  IN_B5 MAX15090BEWIT-MAX15090BEWI+T,SMLF,IC,AL015080B00   I113 @T6G_MB_LIB.T6G(SCH_1):PAGE338
 PU202   C3  IN_C3 MAX15090BEWIT-MAX15090BEWI+T,SMLF,IC,AL015080B00   I113 @T6G_MB_LIB.T6G(SCH_1):PAGE338
 PU202   C5  IN_C5 MAX15090BEWIT-MAX15090BEWI+T,SMLF,IC,AL015080B00   I113 @T6G_MB_LIB.T6G(SCH_1):PAGE338
 PU202   D5  IN_D5 MAX15090BEWIT-MAX15090BEWI+T,SMLF,IC,AL015080B00   I113 @T6G_MB_LIB.T6G(SCH_1):PAGE338
 R1338    1      A Q_RES_0402LF-4.7K,5%,1/16W,CHIP,CS24702JB10    I29 @T6G_MB_LIB.T6G(SCH_1):PAGE83
 R6042    1      A Q_RES_0402LF-10K,5%,1/16W,CHIP,CS31002JB08    I62 @T6G_MB_LIB.T6G(SCH_1):PAGE144
 R1357    1      A Q_RES_0402LF-2.2K,5%,1/16W,CHIP,CS22202JB07    I74 @T6G_MB_LIB.T6G(SCH_1):PAGE144
 R1356    1      A Q_RES_0402LF-4.7K,5%,1/16W,CHIP,CS24702JB10    I77 @T6G_MB_LIB.T6G(SCH_1):PAGE144
 R3977    1      A Q_RES_0402LF-100K,1%,1/16W,CHIP,CS41002FB09    I52 @T6G_MB_LIB.T6G(SCH_1):PAGE324
 R3978    1      A Q_RES_0402LF-100K,1%,1/16W,CHIP,CS41002FB09    I86 @T6G_MB_LIB.T6G(SCH_1):PAGE324
 PU295   A3  IN_A3 MAX15090BEWIT-MAX15090BEWI+T,SMLF,IC,AL015080B00    I88 @T6G_MB_LIB.T6G(SCH_1):PAGE324
 PU295   A5  IN_A5 MAX15090BEWIT-MAX15090BEWI+T,SMLF,IC,AL015080B00    I88 @T6G_MB_LIB.T6G(SCH_1):PAGE324
 PU295   B3  IN_B3 MAX15090BEWIT-MAX15090BEWI+T,SMLF,IC,AL015080B00    I88 @T6G_MB_LIB.T6G(SCH_1):PAGE324
 PU295   B5  IN_B5 MAX15090BEWIT-MAX15090BEWI+T,SMLF,IC,AL015080B00    I88 @T6G_MB_LIB.T6G(SCH_1):PAGE324
 PU295   C3  IN_C3 MAX15090BEWIT-MAX15090BEWI+T,SMLF,IC,AL015080B00    I88 @T6G_MB_LIB.T6G(SCH_1):PAGE324
 PU295   C5  IN_C5 MAX15090BEWIT-MAX15090BEWI+T,SMLF,IC,AL015080B00    I88 @T6G_MB_LIB.T6G(SCH_1):PAGE324
 PU295   D5  IN_D5 MAX15090BEWIT-MAX15090BEWI+T,SMLF,IC,AL015080B00    I88 @T6G_MB_LIB.T6G(SCH_1):PAGE324
PR3839    2      B Q_RES_0402LF-10K,1%,1/16W,CHIP,CS31002FB08    I74 @T6G_MB_LIB.T6G(SCH_1):PAGE339
 R4532    1      A Q_RES_0402LF-10K,1%,1/16W,CHIP,CS31002FB08    I75 @T6G_MB_LIB.T6G(SCH_1):PAGE339
PC2159    1      A Q_CAP_C0402-1UF,25V,10%,X6S,CH5104KEB02   I111 @T6G_MB_LIB.T6G(SCH_1):PAGE339
 PU205  1_2    VCC MP5016GQHLZ-MP5016GQH-L-Z,SMLF,IC,AL005016007   I113 @T6G_MB_LIB.T6G(SCH_1):PAGE339
 R1303    2      B Q_RES_0402LF-1K,1%,1/16W,CHIP,CS21002FB06     I5 @T6G_MB_LIB.T6G(SCH_1):PAGE84
   J57    1      1 CONN8_HBB1081L200D8H-CONN8_HBB1081-L200D-8H,THLF,IA    I41 @T6G_MB_LIB.T6G(SCH_1):PAGE84
   C20    1      A Q_CAP_C0402-0.1UF,16V,10%,X7R,CH4103K1B08    I42 @T6G_MB_LIB.T6G(SCH_1):PAGE84
 PR836    2      B Q_RES_0402LF-1K,1%,1/16W,CHIP,CS21002FB06    I46 @T6G_MB_LIB.T6G(SCH_1):PAGE245
 PR831    2      B Q_RES_0402LF-47K,0.1%,1/16W,CHIP,CS34702BB05    I54 @T6G_MB_LIB.T6G(SCH_1):PAGE245
PC1599    1      A Q_CAP_C0805-22UF,10V,20%,X6S,CH6222MEA01    I60 @T6G_MB_LIB.T6G(SCH_1):PAGE245
 PR285    1      A Q_RES_0402LF-1K,1%,1/16W,CHIP,CS21002FB06    I18 @T6G_MB_LIB.T6G(SCH_1):PAGE168
  PQ13    S      S MOSFET_PCH_GDS_ESD_PROTECTED-PJA3415AE,SMLF,IC,BAMA    I19 @T6G_MB_LIB.T6G(SCH_1):PAGE168
 R8298    1      A Q_RES_0402LF-1K,1%,1/16W,CHIP,CS21002FB06    I28 @T6G_MB_LIB.T6G(SCH_1):PAGE168
 PR316    2      B Q_RES_0402LF-1,1%,1/16W,CHIP,CS-1002FB04   I133 @T6G_MB_LIB.T6G(SCH_1):PAGE168
  PQ10    S      S MOSFET_PCH_GDS_ESD_PROTECTED-PJA3415AE,SMLF,IC,BAMA    I13 @T6G_MB_LIB.T6G(SCH_1):PAGE175
  PR55    1      A Q_RES_0402LF-1K,1%,1/16W,CHIP,CS21002FB06    I17 @T6G_MB_LIB.T6G(SCH_1):PAGE175
 R8065    1      A Q_RES_0402LF-1K,1%,1/16W,CHIP,CS21002FB06    I54 @T6G_MB_LIB.T6G(SCH_1):PAGE175
 R8056    1      A Q_RES_0402LF-1K,1%,1/16W,CHIP,CS21002FB06    I90 @T6G_MB_LIB.T6G(SCH_1):PAGE175
  PR76    2      B Q_RES_0402LF-1,1%,1/16W,CHIP,CS-1002FB04   I126 @T6G_MB_LIB.T6G(SCH_1):PAGE175
 PR443    2      B Q_RES_0402LF-0,5%,1/16W,EMPTY,CS00002JB13    I27 @T6G_MB_LIB.T6G(SCH_1):PAGE176
 R8458    1      A Q_RES_0402LF-0,5%,1/16W,EMPTY,CS00002JB13     I9 @T6G_MB_LIB.T6G(SCH_1):PAGE182
  R117    1      A Q_RES_0402LF-1K,1%,1/16W,CHIP,CS21002FB06    I38 @T6G_MB_LIB.T6G(SCH_1):PAGE182
 PR130    2      B Q_RES_0402LF-1,1%,1/16W,CHIP,CS-1002FB04    I85 @T6G_MB_LIB.T6G(SCH_1):PAGE182
 PR413    2      B Q_RES_0402LF-0,5%,1/16W,EMPTY,CS00002JB13    I86 @T6G_MB_LIB.T6G(SCH_1):PAGE183
 PR477    1      A Q_RES_0402LF-0,5%,1/16W,CHIP,CS00002JB13    I12 @T6G_MB_LIB.T6G(SCH_1):PAGE184
 R8465    1      A Q_RES_0402LF-10K,5%,1/16W,CHIP,CS31002JB08    I29 @T6G_MB_LIB.T6G(SCH_1):PAGE184
 PR152    1      A Q_RES_0402LF-1K,1%,1/16W,CHIP,CS21002FB06    I17 @T6G_MB_LIB.T6G(SCH_1):PAGE185
  PQ11    S      S MOSFET_PCH_GDS_ESD_PROTECTED-PJA3415AE,SMLF,IC,BAMA    I18 @T6G_MB_LIB.T6G(SCH_1):PAGE185
 R8165    1      A Q_RES_0402LF-1K,1%,1/16W,CHIP,CS21002FB06    I27 @T6G_MB_LIB.T6G(SCH_1):PAGE185
 R8167    1      A Q_RES_0402LF-1K,1%,1/16W,CHIP,CS21002FB06    I78 @T6G_MB_LIB.T6G(SCH_1):PAGE185
 PR183    2      B Q_RES_0402LF-1,1%,1/16W,CHIP,CS-1002FB04   I129 @T6G_MB_LIB.T6G(SCH_1):PAGE185
 PR336    2      B Q_RES_0402LF-0,5%,1/16W,EMPTY,CS00002JB13    I41 @T6G_MB_LIB.T6G(SCH_1):PAGE186
  PQ12    S      S MOSFET_PCH_GDS_ESD_PROTECTED-PJA3415AE,SMLF,IC,BAMA    I13 @T6G_MB_LIB.T6G(SCH_1):PAGE192
 PR232    1      A Q_RES_0402LF-1K,1%,1/16W,CHIP,CS21002FB06    I17 @T6G_MB_LIB.T6G(SCH_1):PAGE192
 R8242    1      A Q_RES_0402LF-1K,1%,1/16W,CHIP,CS21002FB06    I51 @T6G_MB_LIB.T6G(SCH_1):PAGE192
 R8233    1      A Q_RES_0402LF-1K,1%,1/16W,CHIP,CS21002FB06    I89 @T6G_MB_LIB.T6G(SCH_1):PAGE192
 PR253    2      B Q_RES_0402LF-1,1%,1/16W,CHIP,CS-1002FB04   I124 @T6G_MB_LIB.T6G(SCH_1):PAGE192
 PR341    2      B Q_RES_0402LF-0,5%,1/16W,EMPTY,CS00002JB13    I90 @T6G_MB_LIB.T6G(SCH_1):PAGE193
 R8146    1      A Q_RES_0402LF-0,5%,1/16W,EMPTY,CS00002JB13     I9 @T6G_MB_LIB.T6G(SCH_1):PAGE199
 R8380    1      A Q_RES_0402LF-1K,1%,1/16W,CHIP,CS21002FB06    I37 @T6G_MB_LIB.T6G(SCH_1):PAGE199
 PR393    2      B Q_RES_0402LF-1,1%,1/16W,CHIP,CS-1002FB04    I84 @T6G_MB_LIB.T6G(SCH_1):PAGE199
 PR394    2      B Q_RES_0402LF-0,5%,1/16W,EMPTY,CS00002JB13    I41 @T6G_MB_LIB.T6G(SCH_1):PAGE200
   U18  K10   VCC1 LCMXO3LF9400C5BG484C-LCMXO3LF-9400C-5BG484C,SMLF,IA   I141 @T6G_MB_LIB.T6G(SCH_1):PAGE81
   U18  K11   VCC2 LCMXO3LF9400C5BG484C-LCMXO3LF-9400C-5BG484C,SMLF,IA   I141 @T6G_MB_LIB.T6G(SCH_1):PAGE81
   U18  K12   VCC3 LCMXO3LF9400C5BG484C-LCMXO3LF-9400C-5BG484C,SMLF,IA   I141 @T6G_MB_LIB.T6G(SCH_1):PAGE81
   U18  K13   VCC4 LCMXO3LF9400C5BG484C-LCMXO3LF-9400C-5BG484C,SMLF,IA   I141 @T6G_MB_LIB.T6G(SCH_1):PAGE81
   U18  L11   VCC5 LCMXO3LF9400C5BG484C-LCMXO3LF-9400C-5BG484C,SMLF,IA   I141 @T6G_MB_LIB.T6G(SCH_1):PAGE81
   U18  L12   VCC6 LCMXO3LF9400C5BG484C-LCMXO3LF-9400C-5BG484C,SMLF,IA   I141 @T6G_MB_LIB.T6G(SCH_1):PAGE81
   U18  M11   VCC7 LCMXO3LF9400C5BG484C-LCMXO3LF-9400C-5BG484C,SMLF,IA   I141 @T6G_MB_LIB.T6G(SCH_1):PAGE81
   U18  M12   VCC8 LCMXO3LF9400C5BG484C-LCMXO3LF-9400C-5BG484C,SMLF,IA   I141 @T6G_MB_LIB.T6G(SCH_1):PAGE81
   U18  N10   VCC9 LCMXO3LF9400C5BG484C-LCMXO3LF-9400C-5BG484C,SMLF,IA   I141 @T6G_MB_LIB.T6G(SCH_1):PAGE81
   U18  N11  VCC10 LCMXO3LF9400C5BG484C-LCMXO3LF-9400C-5BG484C,SMLF,IA   I141 @T6G_MB_LIB.T6G(SCH_1):PAGE81
   U18  N12  VCC11 LCMXO3LF9400C5BG484C-LCMXO3LF-9400C-5BG484C,SMLF,IA   I141 @T6G_MB_LIB.T6G(SCH_1):PAGE81
   U18  N13  VCC12 LCMXO3LF9400C5BG484C-LCMXO3LF-9400C-5BG484C,SMLF,IA   I141 @T6G_MB_LIB.T6G(SCH_1):PAGE81
   U18   C7 VCCIO0_1 LCMXO3LF9400C5BG484C-LCMXO3LF-9400C-5BG484C,SMLF,IA   I141 @T6G_MB_LIB.T6G(SCH_1):PAGE81
   U18  C12 VCCIO0_2 LCMXO3LF9400C5BG484C-LCMXO3LF-9400C-5BG484C,SMLF,IA   I141 @T6G_MB_LIB.T6G(SCH_1):PAGE81
   U18  C16 VCCIO0_3 LCMXO3LF9400C5BG484C-LCMXO3LF-9400C-5BG484C,SMLF,IA   I141 @T6G_MB_LIB.T6G(SCH_1):PAGE81
   U18  G10 VCCIO0_4 LCMXO3LF9400C5BG484C-LCMXO3LF-9400C-5BG484C,SMLF,IA   I141 @T6G_MB_LIB.T6G(SCH_1):PAGE81
   U18  G13 VCCIO0_5 LCMXO3LF9400C5BG484C-LCMXO3LF-9400C-5BG484C,SMLF,IA   I141 @T6G_MB_LIB.T6G(SCH_1):PAGE81
   U18   H9 VCCIO0_6 LCMXO3LF9400C5BG484C-LCMXO3LF-9400C-5BG484C,SMLF,IA   I141 @T6G_MB_LIB.T6G(SCH_1):PAGE81
   U18  H11 VCCIO0_7 LCMXO3LF9400C5BG484C-LCMXO3LF-9400C-5BG484C,SMLF,IA   I141 @T6G_MB_LIB.T6G(SCH_1):PAGE81
   U18  H12 VCCIO0_8 LCMXO3LF9400C5BG484C-LCMXO3LF-9400C-5BG484C,SMLF,IA   I141 @T6G_MB_LIB.T6G(SCH_1):PAGE81
   U18  H14 VCCIO0_9 LCMXO3LF9400C5BG484C-LCMXO3LF-9400C-5BG484C,SMLF,IA   I141 @T6G_MB_LIB.T6G(SCH_1):PAGE81
   U18   R9 VCCIO2_1 LCMXO3LF9400C5BG484C-LCMXO3LF-9400C-5BG484C,SMLF,IA   I141 @T6G_MB_LIB.T6G(SCH_1):PAGE81
   U18  R10 VCCIO2_2 LCMXO3LF9400C5BG484C-LCMXO3LF-9400C-5BG484C,SMLF,IA   I141 @T6G_MB_LIB.T6G(SCH_1):PAGE81
   U18  R11 VCCIO2_3 LCMXO3LF9400C5BG484C-LCMXO3LF-9400C-5BG484C,SMLF,IA   I141 @T6G_MB_LIB.T6G(SCH_1):PAGE81
   U18  R12 VCCIO2_4 LCMXO3LF9400C5BG484C-LCMXO3LF-9400C-5BG484C,SMLF,IA   I141 @T6G_MB_LIB.T6G(SCH_1):PAGE81
   U18  R13 VCCIO2_5 LCMXO3LF9400C5BG484C-LCMXO3LF-9400C-5BG484C,SMLF,IA   I141 @T6G_MB_LIB.T6G(SCH_1):PAGE81
   U18  R14 VCCIO2_6 LCMXO3LF9400C5BG484C-LCMXO3LF-9400C-5BG484C,SMLF,IA   I141 @T6G_MB_LIB.T6G(SCH_1):PAGE81
   U18   W7 VCCIO2_7 LCMXO3LF9400C5BG484C-LCMXO3LF-9400C-5BG484C,SMLF,IA   I141 @T6G_MB_LIB.T6G(SCH_1):PAGE81
   U18  W11 VCCIO2_8 LCMXO3LF9400C5BG484C-LCMXO3LF-9400C-5BG484C,SMLF,IA   I141 @T6G_MB_LIB.T6G(SCH_1):PAGE81
   U18  W16 VCCIO2_9 LCMXO3LF9400C5BG484C-LCMXO3LF-9400C-5BG484C,SMLF,IA   I141 @T6G_MB_LIB.T6G(SCH_1):PAGE81
   U18   N8 VCCIO3_1 LCMXO3LF9400C5BG484C-LCMXO3LF-9400C-5BG484C,SMLF,IA   I141 @T6G_MB_LIB.T6G(SCH_1):PAGE81
   U18   P8 VCCIO3_2 LCMXO3LF9400C5BG484C-LCMXO3LF-9400C-5BG484C,SMLF,IA   I141 @T6G_MB_LIB.T6G(SCH_1):PAGE81
   U18   V3 VCCIO3_3 LCMXO3LF9400C5BG484C-LCMXO3LF-9400C-5BG484C,SMLF,IA   I141 @T6G_MB_LIB.T6G(SCH_1):PAGE81
   U18   L8 VCCIO4_1 LCMXO3LF9400C5BG484C-LCMXO3LF-9400C-5BG484C,SMLF,IA   I141 @T6G_MB_LIB.T6G(SCH_1):PAGE81
   U18   M8 VCCIO4_2 LCMXO3LF9400C5BG484C-LCMXO3LF-9400C-5BG484C,SMLF,IA   I141 @T6G_MB_LIB.T6G(SCH_1):PAGE81
   U18   M3 VCCIO4_3 LCMXO3LF9400C5BG484C-LCMXO3LF-9400C-5BG484C,SMLF,IA   I141 @T6G_MB_LIB.T6G(SCH_1):PAGE81
  R639    2      B Q_RES_0402LF-1K,1%,1/16W,CHIP,CS21002FB06    I33 @T6G_MB_LIB.T6G(SCH_1):PAGE82
 R1071    2      B Q_RES_0402LF-4.7K,5%,1/16W,EMPTY,CS24702JB10    I38 @T6G_MB_LIB.T6G(SCH_1):PAGE82
  R757    2      B Q_RES_0402LF-4.7K,5%,1/16W,EMPTY,CS24702JB10    I41 @T6G_MB_LIB.T6G(SCH_1):PAGE82
  C362    1      A Q_CAP_C0402-0.1UF,16V,10%,X7R,CH4103K1B08   I102 @T6G_MB_LIB.T6G(SCH_1):PAGE82
  C360    1      A Q_CAP_C0402-0.1UF,16V,10%,X7R,CH4103K1B08   I103 @T6G_MB_LIB.T6G(SCH_1):PAGE82
  C361    1      A Q_CAP_C0402-0.1UF,16V,10%,X7R,CH4103K1B08   I104 @T6G_MB_LIB.T6G(SCH_1):PAGE82
  C359    1      A Q_CAP_C0402-0.1UF,16V,10%,X7R,CH4103K1B08   I135 @T6G_MB_LIB.T6G(SCH_1):PAGE82
 R1266    1      A Q_RES_0402LF-200,1%,1/16W,CHIP,CS12002FB06    I45 @T6G_MB_LIB.T6G(SCH_1):PAGE84
 R1194    1      A Q_RES_0402LF-200,1%,1/16W,CHIP,CS12002FB06    I46 @T6G_MB_LIB.T6G(SCH_1):PAGE84
 R6024    1      A Q_RES_0402LF-4.7K,5%,1/16W,EMPTY,CS24702JB10    I20 @T6G_MB_LIB.T6G(SCH_1):PAGE349
 R6023    1      A Q_RES_0402LF-2K,5%,1/16W,EMPTY,TMP_QCS22002JB29    I21 @T6G_MB_LIB.T6G(SCH_1):PAGE349
 R6021    1      A Q_RES_0402LF-2K,5%,1/16W,EMPTY,TMP_QCS22002JB29    I22 @T6G_MB_LIB.T6G(SCH_1):PAGE349
 R6022    1      A Q_RES_0402LF-2K,5%,1/16W,EMPTY,TMP_QCS22002JB29    I23 @T6G_MB_LIB.T6G(SCH_1):PAGE349
 R6020    1      A Q_RES_0402LF-2K,5%,1/16W,EMPTY,TMP_QCS22002JB29    I24 @T6G_MB_LIB.T6G(SCH_1):PAGE349
 R6019    1      A Q_RES_0402LF-2K,5%,1/16W,EMPTY,TMP_QCS22002JB29    I25 @T6G_MB_LIB.T6G(SCH_1):PAGE349
 R6018    1      A Q_RES_0402LF-2K,5%,1/16W,EMPTY,TMP_QCS22002JB29    I27 @T6G_MB_LIB.T6G(SCH_1):PAGE349
 R3242    2      B Q_RES_0402LF-2.2K,5%,1/16W,EMPTY,CS22202JB07   I119 @T6G_MB_LIB.T6G(SCH_1):PAGE349
 R3241    2      B Q_RES_0402LF-2.2K,5%,1/16W,EMPTY,CS22202JB07   I149 @T6G_MB_LIB.T6G(SCH_1):PAGE349
 R3836    1      A Q_RES_0402LF-10K,1%,1/16W,CHIP,CS31002FB08    I43 @T6G_MB_LIB.T6G(SCH_1):PAGE350
 R4013    1      A Q_RES_0402LF-100K,1%,1/16W,CHIP,CS41002FB09    I76 @T6G_MB_LIB.T6G(SCH_1):PAGE350
 R1138    1      A Q_RES_0402LF-10K,1%,1/16W,CHIP,CS31002FB08     I1 @T6G_MB_LIB.T6G(SCH_1):PAGE337
 C1274    1      A Q_CAP_0402-0.1UF,25V,10%,X7R,CH4104K1B00     I3 @T6G_MB_LIB.T6G(SCH_1):PAGE337
  OSC1    4    VDD Q_OSC4P_SMLF-50MHZ,OSC,BF650000032     I4 @T6G_MB_LIB.T6G(SCH_1):PAGE337
 U8082    5    VCC 74LVC1G126SE7-74LVC1G126SE-7,SMLF,IC,AL1G0126009     I8 @T6G_MB_LIB.T6G(SCH_1):PAGE337
   U90    6    VDD PI6CV304LE-PI6CV304LE,SMLF,IC,AL000304K01    I16 @T6G_MB_LIB.T6G(SCH_1):PAGE337
 C1275    1      A Q_CAP_0402-0.1UF,25V,10%,X7R,CH4104K1B00    I19 @T6G_MB_LIB.T6G(SCH_1):PAGE337
  U157    5    VCC 74LVC1G07GV-74LVC1G07GV,SMLF,IC,AL1G0007001    I25 @T6G_MB_LIB.T6G(SCH_1):PAGE337
   C36    1      A Q_CAP_0402-0.1UF,25V,10%,X7R,CH4104K1B00    I33 @T6G_MB_LIB.T6G(SCH_1):PAGE337
 R2488    1      A Q_RES_0402LF-4.7K,1%,1/16W,CHIP,CS24702FB06    I35 @T6G_MB_LIB.T6G(SCH_1):PAGE337
  U104    5    VCC 74LVC1G07GV-74LVC1G07GV,SMLF,IC,AL1G0007001    I38 @T6G_MB_LIB.T6G(SCH_1):PAGE337
 C1663    1      A Q_CAP_0402-0.1UF,25V,10%,X7R,CH4104K1B00    I47 @T6G_MB_LIB.T6G(SCH_1):PAGE337
  U225    5    VCC 74LVC1G126SE7-74LVC1G126SE-7,SMLF,IC,AL1G0126009     I9 @T6G_MB_LIB.T6G(SCH_1):PAGE342
  U217    5    VCC 74LVC1G126SE7-74LVC1G126SE-7,SMLF,IC,AL1G0126009    I14 @T6G_MB_LIB.T6G(SCH_1):PAGE342
 C1822    1      A Q_CAP_0402-0.1UF,25V,10%,X7R,CH4104K1B00    I16 @T6G_MB_LIB.T6G(SCH_1):PAGE342
 R3184    1      A Q_RES_0402LF-4.7K,1%,1/16W,CHIP,CS24702FB06    I18 @T6G_MB_LIB.T6G(SCH_1):PAGE342
  U218    5    VCC 74LVC1G07GV-74LVC1G07GV,SMLF,IC,AL1G0007001    I22 @T6G_MB_LIB.T6G(SCH_1):PAGE342
  U219    5    VCC 74LVC1G07GV-74LVC1G07GV,SMLF,IC,AL1G0007001    I32 @T6G_MB_LIB.T6G(SCH_1):PAGE342
 R3190    1      A Q_RES_0402LF-4.7K,1%,1/16W,CHIP,CS24702FB06    I34 @T6G_MB_LIB.T6G(SCH_1):PAGE342
 R3134    1      A Q_RES_0402LF-1K,1%,1/16W,CHIP,CS21002FB06     I4 @T6G_MB_LIB.T6G(SCH_1):PAGE343
   U59    5    VCC 74LVC2G07DW7-74LVC2G07DW-7,SMLF,IC,AL002G07003    I22 @T6G_MB_LIB.T6G(SCH_1):PAGE343
 C1810    1      A Q_CAP_0402-0.1UF,25V,10%,X7R,CH4104K1B00    I23 @T6G_MB_LIB.T6G(SCH_1):PAGE343
 C1809    1      A Q_CAP_0402-0.1UF,25V,10%,X7R,CH4104K1B00    I29 @T6G_MB_LIB.T6G(SCH_1):PAGE343
PC2140    1      A Q_CAP_C0402-1UF,25V,10%,X6S,CH5104KEB02    I55 @T6G_MB_LIB.T6G(SCH_1):PAGE343
 R3816    1      A Q_RES_0402LF-100K,1%,1/16W,CHIP,CS41002FB09    I79 @T6G_MB_LIB.T6G(SCH_1):PAGE343
PR3782    1      A Q_RES_0402LF-10,1%,1/16W,CHIP,CS01002FB07    I91 @T6G_MB_LIB.T6G(SCH_1):PAGE343
  R994    1      A Q_RES_0402LF-10K,1%,1/16W,CHIP,CS31002FB08     I7 @T6G_MB_LIB.T6G(SCH_1):PAGE132
 R1009    1      A Q_RES_0402LF-10K,1%,1/16W,CHIP,CS31002FB08    I10 @T6G_MB_LIB.T6G(SCH_1):PAGE132
 R6070    1      A Q_RES_0402LF-4.7K,5%,1/16W,EMPTY,CS24702JB10   I161 @T6G_MB_LIB.T6G(SCH_1):PAGE349
 R2907    1      A Q_RES_0402LF-5.11K,1%,1/16W,CHIP,CS25112FB04    I28 @T6G_MB_LIB.T6G(SCH_1):PAGE369
 R3667    1      A Q_RES_0402LF-1K,1%,1/16W,EMPTY,CS21002FB06    I66 @T6G_MB_LIB.T6G(SCH_1):PAGE369
 R3669    1      A Q_RES_0402LF-1K,1%,1/16W,EMPTY,CS21002FB06    I68 @T6G_MB_LIB.T6G(SCH_1):PAGE369
   L16    1      1 Q_INDUCTOR_SMLF-BLM18PG300SN1D ,IND,TMP_QCX8PG3000A    I69 @T6G_MB_LIB.T6G(SCH_1):PAGE369
   L15    2      2 Q_INDUCTOR_SMLF-BLM18PG300SN1D ,IND,TMP_QCX8PG3000A   I167 @T6G_MB_LIB.T6G(SCH_1):PAGE369
 R2344    1      A Q_RES_0402LF-4.7K,5%,1/16W,CHIP,CS24702JB10    I67 @T6G_MB_LIB.T6G(SCH_1):PAGE84
 R2346    1      A Q_RES_0402LF-100K,1%,1/16W,CHIP,CS41002FB09    I70 @T6G_MB_LIB.T6G(SCH_1):PAGE84
 R3071    2      B Q_RES_0402LF-130,1%,1/16W,CHIP,CS11302FB03    I21 @T6G_MB_LIB.T6G(SCH_1):PAGE254
 R6085    1      A Q_RES_0402LF-10K,1%,1/16W,CHIP,CS31002FB08   I298 @T6G_MB_LIB.T6G(SCH_1):PAGE80
 R3069    2      B Q_RES_0402LF-130,1%,1/16W,CHIP,CS11302FB03    I32 @T6G_MB_LIB.T6G(SCH_1):PAGE254
   C10    1      A Q_CAP_0402-0.1UF,25V,10%,X7R,CH4104K1B00    I61 @T6G_MB_LIB.T6G(SCH_1):PAGE337
   U75    5    VCC 74LVC1G17GW-74LVC1G17GW,SMLF,IC,AL1G0017K01    I64 @T6G_MB_LIB.T6G(SCH_1):PAGE337
 C1821    1      A Q_CAP_0402-0.1UF,25V,10%,X7R,CH4104K1B00    I55 @T6G_MB_LIB.T6G(SCH_1):PAGE342
  U207    5    VCC 74LVC1G17GW-74LVC1G17GW,SMLF,IC,AL1G0017K01    I58 @T6G_MB_LIB.T6G(SCH_1):PAGE342
 R3074    2      B Q_RES_0402LF-130,1%,1/16W,CHIP,CS11302FB03    I41 @T6G_MB_LIB.T6G(SCH_1):PAGE254
 R3088    2      B Q_RES_0402LF-130,1%,1/16W,CHIP,CS11302FB03    I12 @T6G_MB_LIB.T6G(SCH_1):PAGE374
 R3089    2      B Q_RES_0402LF-130,1%,1/16W,CHIP,CS11302FB03    I15 @T6G_MB_LIB.T6G(SCH_1):PAGE374
 R3087    2      B Q_RES_0402LF-130,1%,1/16W,CHIP,CS11302FB03    I16 @T6G_MB_LIB.T6G(SCH_1):PAGE374
 R3086    2      B Q_RES_0402LF-130,1%,1/16W,CHIP,CS11302FB03    I20 @T6G_MB_LIB.T6G(SCH_1):PAGE374
 R3091    2      B Q_RES_0402LF-130,1%,1/16W,CHIP,CS11302FB03    I37 @T6G_MB_LIB.T6G(SCH_1):PAGE374
 R3090    2      B Q_RES_0402LF-130,1%,1/16W,CHIP,CS11302FB03    I38 @T6G_MB_LIB.T6G(SCH_1):PAGE374
 R3092    2      B Q_RES_0402LF-130,1%,1/16W,CHIP,CS11302FB03    I41 @T6G_MB_LIB.T6G(SCH_1):PAGE374
 R3095    2      B Q_RES_0402LF-130,1%,1/16W,CHIP,CS11302FB03    I15 @T6G_MB_LIB.T6G(SCH_1):PAGE375
 R3096    2      B Q_RES_0402LF-130,1%,1/16W,CHIP,CS11302FB03    I16 @T6G_MB_LIB.T6G(SCH_1):PAGE375
 R3094    2      B Q_RES_0402LF-130,1%,1/16W,CHIP,CS11302FB03    I18 @T6G_MB_LIB.T6G(SCH_1):PAGE375
 R3093    2      B Q_RES_0402LF-130,1%,1/16W,CHIP,CS11302FB03    I20 @T6G_MB_LIB.T6G(SCH_1):PAGE375
 R3097    2      B Q_RES_0402LF-130,1%,1/16W,CHIP,CS11302FB03    I38 @T6G_MB_LIB.T6G(SCH_1):PAGE375
 R3099    2      B Q_RES_0402LF-130,1%,1/16W,CHIP,CS11302FB03    I40 @T6G_MB_LIB.T6G(SCH_1):PAGE375
 R6138    1      A Q_RES_0402LF-1K,1%,1/16W,EMPTY,CS21002FB06    I39 @T6G_MB_LIB.T6G(SCH_1):PAGE83
 R6139    1      A Q_RES_0402LF-1K,1%,1/16W,EMPTY,CS21002FB06    I55 @T6G_MB_LIB.T6G(SCH_1):PAGE83
 R6140    1      A Q_RES_0402LF-1K,1%,1/16W,EMPTY,CS21002FB06    I56 @T6G_MB_LIB.T6G(SCH_1):PAGE83
 R9008    1      A Q_RES_0402LF-4.7K,5%,1/16W,CHIP,CS24702JB10    I17 @T6G_MB_LIB.T6G(SCH_1):PAGE330
 U6000   15    VIN DS125BR111RTWR-DS125BR111RTWR,SMLF,IC,AL000125003     I1 @T6G_MB_LIB.T6G(SCH_1):PAGE111
 C6009    1      A Q_CAP_C0402-1UF,25V,10%,X6S,CH5104KEB02     I3 @T6G_MB_LIB.T6G(SCH_1):PAGE111
 C6010    1      A Q_CAP_C0805-10UF,16V,10%,X6S,CH6103KEA00     I5 @T6G_MB_LIB.T6G(SCH_1):PAGE111
 R6163    1      A Q_RES_0402LF-1K,1%,1/16W,EMPTY,CS21002FB06    I39 @T6G_MB_LIB.T6G(SCH_1):PAGE111
 R6165    1      A Q_RES_0402LF-1K,1%,1/16W,EMPTY,CS21002FB06    I41 @T6G_MB_LIB.T6G(SCH_1):PAGE111
 R6173    1      A Q_RES_0402LF-1K,1%,1/16W,EMPTY,CS21002FB06    I44 @T6G_MB_LIB.T6G(SCH_1):PAGE111
 R6171    1      A Q_RES_0402LF-1K,1%,1/16W,EMPTY,CS21002FB06    I48 @T6G_MB_LIB.T6G(SCH_1):PAGE111
 R6169    1      A Q_RES_0402LF-1K,1%,1/16W,EMPTY,CS21002FB06    I53 @T6G_MB_LIB.T6G(SCH_1):PAGE111
 R6167    1      A Q_RES_0402LF-1K,1%,1/16W,EMPTY,CS21002FB06    I57 @T6G_MB_LIB.T6G(SCH_1):PAGE111
 R6175    1      A Q_RES_0402LF-1K,1%,1/16W,EMPTY,CS21002FB06    I63 @T6G_MB_LIB.T6G(SCH_1):PAGE111
 R6177    1      A Q_RES_0402LF-1K,1%,1/16W,CHIP,CS21002FB06    I77 @T6G_MB_LIB.T6G(SCH_1):PAGE111
 R6179    1      A Q_RES_0402LF-1K,1%,1/16W,CHIP,CS21002FB06    I78 @T6G_MB_LIB.T6G(SCH_1):PAGE111
 R3925    2      B Q_RES_0402LF-1K,1%,1/16W,CHIP,CS21002FB06    I34 @T6G_MB_LIB.T6G(SCH_1):PAGE267
 C1787    1      A Q_CAP_C0402-0.1UF,16V,10%,X7R,CH4103K1B08     I6 @T6G_MB_LIB.T6G(SCH_1):PAGE371
  U143    1    VDD NCT7718W-NCT7718W,SMLF,IC,AL007718001     I8 @T6G_MB_LIB.T6G(SCH_1):PAGE371
 R1449    1      A Q_RES_0402LF-10K,5%,1/16W,CHIP,CS31002JB08    I26 @T6G_MB_LIB.T6G(SCH_1):PAGE264
 R1450    1      A Q_RES_0402LF-10K,5%,1/16W,CHIP,CS31002JB08    I39 @T6G_MB_LIB.T6G(SCH_1):PAGE264
 R6181    1      A Q_RES_0402LF-4.7K,5%,1/16W,CHIP,CS24702JB10   I381 @T6G_MB_LIB.T6G(SCH_1):PAGE148
 R6182    1      A Q_RES_0402LF-4.7K,5%,1/16W,CHIP,CS24702JB10   I384 @T6G_MB_LIB.T6G(SCH_1):PAGE148
    U6   10    VDD PI3CSW12ZUAEX-PI3CSW12ZUAEX,SMLF,IC,AL3CSW12000    I67 @T6G_MB_LIB.T6G(SCH_1):PAGE138
   C25    1      A Q_CAP_0402-0.1UF,25V,10%,X7R,CH4104K1B00    I69 @T6G_MB_LIB.T6G(SCH_1):PAGE138
 R6186    2      B Q_RES_0402LF-4.7K,5%,1/16W,EMPTY,CS24702JB10   I146 @T6G_MB_LIB.T6G(SCH_1):PAGE82
 R6188    2      B Q_RES_0402LF-4.7K,5%,1/16W,EMPTY,CS24702JB10   I152 @T6G_MB_LIB.T6G(SCH_1):PAGE82
  PJ38   12     12 SCONN21_9193031121LF-SCONN21_91930-31121LF,SMLF,IOA    I42 @T6G_MB_LIB.T6G(SCH_1):PAGE371
   U96    8   VCCB PCA9617ADP-PCA9617ADP,SMLF,IC,AL009617K02    I51 @T6G_MB_LIB.T6G(SCH_1):PAGE137
 U6001   56 AVDD33_2 CYUSB330468LTXI-CYUSB3304-68LTXI,SMLF,IC,AJ0330400A     I1 @T6G_MB_LIB.T6G(SCH_1):PAGE154
 U6001   61 AVDD33_3 CYUSB330468LTXI-CYUSB3304-68LTXI,SMLF,IC,AJ0330400A     I1 @T6G_MB_LIB.T6G(SCH_1):PAGE154
 U6001   66 AVDD33_4 CYUSB330468LTXI-CYUSB3304-68LTXI,SMLF,IC,AJ0330400A     I1 @T6G_MB_LIB.T6G(SCH_1):PAGE154
 U6001   28 VDD_IO CYUSB330468LTXI-CYUSB3304-68LTXI,SMLF,IC,AJ0330400A     I1 @T6G_MB_LIB.T6G(SCH_1):PAGE154
 R6204    1      A Q_RES_0402LF-10K,1%,1/16W,CHIP,CS31002FB08    I41 @T6G_MB_LIB.T6G(SCH_1):PAGE153
 R6205    1      A Q_RES_0402LF-10K,1%,1/16W,CHIP,CS31002FB08    I43 @T6G_MB_LIB.T6G(SCH_1):PAGE153
 R6206    1      A Q_RES_0402LF-10K,1%,1/16W,CHIP,CS31002FB08    I44 @T6G_MB_LIB.T6G(SCH_1):PAGE153
 R6207    1      A Q_RES_0402LF-10K,1%,1/16W,CHIP,CS31002FB08    I45 @T6G_MB_LIB.T6G(SCH_1):PAGE153
 L6000    1      1 Q_INDUCTOR_SMLF-BLM21PG221SN1D,IND,CX1PG221001     I3 @T6G_MB_LIB.T6G(SCH_1):PAGE154
 C6040    1      A Q_CAP_C0402-0.01UF,50V,10%,X7R,CH31006KB18     I5 @T6G_MB_LIB.T6G(SCH_1):PAGE154
 C6041    1      A Q_CAP_0402-0.1UF,25V,10%,X7R,CH4104K1B00     I7 @T6G_MB_LIB.T6G(SCH_1):PAGE154
 C6046    1      A Q_CAP_C0603-22UF,6.3V,20%,X6S,CH6221ME900    I14 @T6G_MB_LIB.T6G(SCH_1):PAGE154
 C6047    1      A Q_CAP_C0402-1UF,25V,10%,X6S,CH5104KEB02    I15 @T6G_MB_LIB.T6G(SCH_1):PAGE154
 C6048    1      A Q_CAP_0402-0.1UF,25V,10%,X7R,CH4104K1B00    I17 @T6G_MB_LIB.T6G(SCH_1):PAGE154
 C6049    1      A Q_CAP_C0402-0.01UF,50V,10%,X7R,CH31006KB18    I19 @T6G_MB_LIB.T6G(SCH_1):PAGE154
 C6050    1      A Q_CAP_0402-0.1UF,25V,10%,X7R,CH4104K1B00    I20 @T6G_MB_LIB.T6G(SCH_1):PAGE154
 C6051    1      A Q_CAP_C0402-0.01UF,50V,10%,X7R,CH31006KB18    I21 @T6G_MB_LIB.T6G(SCH_1):PAGE154
 C6053    1      A Q_CAP_C0402-0.01UF,50V,10%,X7R,CH31006KB18    I22 @T6G_MB_LIB.T6G(SCH_1):PAGE154
 C6052    1      A Q_CAP_0402-0.1UF,25V,10%,X7R,CH4104K1B00    I23 @T6G_MB_LIB.T6G(SCH_1):PAGE154
 U6003    8    VCC M24128BWMN6TP-M24128-BWMN6TP,SMLF,IC,AKE30Z00613    I64 @T6G_MB_LIB.T6G(SCH_1):PAGE153
 R6222    1      A Q_RES_0402LF-10K,1%,1/16W,CHIP,CS31002FB08    I65 @T6G_MB_LIB.T6G(SCH_1):PAGE153
 R6218    1      A Q_RES_0402LF-10K,1%,1/16W,EMPTY,CS31002FB08    I69 @T6G_MB_LIB.T6G(SCH_1):PAGE153
 R6220    1      A Q_RES_0402LF-10K,1%,1/16W,EMPTY,CS31002FB08    I70 @T6G_MB_LIB.T6G(SCH_1):PAGE153
 C6083    1      A Q_CAP_0402-0.1UF,25V,10%,X7R,CH4104K1B00    I75 @T6G_MB_LIB.T6G(SCH_1):PAGE153
 R6226    1      A Q_RES_0402LF-10K,1%,1/16W,EMPTY,CS31002FB08    I85 @T6G_MB_LIB.T6G(SCH_1):PAGE153
 R6227    1      A Q_RES_0402LF-10K,1%,1/16W,EMPTY,CS31002FB08    I86 @T6G_MB_LIB.T6G(SCH_1):PAGE153
 R6230    1      A Q_RES_0402LF-2.2K,5%,1/16W,CHIP,CS22202JB07    I45 @T6G_MB_LIB.T6G(SCH_1):PAGE371
 R6231    1      A Q_RES_0402LF-2.2K,5%,1/16W,CHIP,CS22202JB07    I46 @T6G_MB_LIB.T6G(SCH_1):PAGE371
 R6236    1      A Q_RES_0402LF-10K,1%,1/16W,EMPTY,CS31002FB08    I63 @T6G_MB_LIB.T6G(SCH_1):PAGE371
 R6239    1      A Q_RES_0402LF-10K,1%,1/16W,CHIP,CS31002FB08    I70 @T6G_MB_LIB.T6G(SCH_1):PAGE371
 R6242    1      A Q_RES_0402LF-0,5%,1/16W,CHIP,CS00002JB13     I2 @T6G_MB_LIB.T6G(SCH_1):PAGE315
 R6243    1      A Q_RES_0402LF-10K,1%,1/16W,CHIP,CS31002FB08    I32 @T6G_MB_LIB.T6G(SCH_1):PAGE315
 R6244    1      A Q_RES_0402LF-10K,1%,1/16W,CHIP,CS31002FB08    I19 @T6G_MB_LIB.T6G(SCH_1):PAGE380
 R6245    1      A Q_RES_0402LF-0,5%,1/16W,CHIP,CS00002JB13    I38 @T6G_MB_LIB.T6G(SCH_1):PAGE380
 R6246    2      B Q_RES_0402LF-130,1%,1/16W,CHIP,CS11302FB03    I45 @T6G_MB_LIB.T6G(SCH_1):PAGE254
 L6003    1      1 Q_INDUCTOR_SMLF-BLM21PG221SN1D,IND,CX1PG221001    I17 @T6G_MB_LIB.T6G(SCH_1):PAGE157
 C6087    1      A Q_CAP_0402-0.1UF,25V,10%,X7R,CH4104K1B00    I22 @T6G_MB_LIB.T6G(SCH_1):PAGE271
 R6247    1      A Q_RES_0402LF-4.7K,1%,1/16W,CHIP,CS24702FB06    I25 @T6G_MB_LIB.T6G(SCH_1):PAGE271
 U6005    9    VCC ISL28022FRZT-ISL28022FRZ-T,SMLF,IC,AL028022003    I28 @T6G_MB_LIB.T6G(SCH_1):PAGE271
 R6211    1      A Q_RES_0402LF-2.2K,5%,1/16W,CHIP,CS22202JB07    I89 @T6G_MB_LIB.T6G(SCH_1):PAGE252
 R6212    1      A Q_RES_0402LF-2.2K,5%,1/16W,CHIP,CS22202JB07    I90 @T6G_MB_LIB.T6G(SCH_1):PAGE252
 R6283    1      A Q_RES_0402LF-1K,1%,1/16W,EMPTY,CS21002FB06    I63 @T6G_MB_LIB.T6G(SCH_1):PAGE157
 R6292    1      A Q_RES_0402LF-1K,1%,1/16W,EMPTY,CS21002FB06    I77 @T6G_MB_LIB.T6G(SCH_1):PAGE157
 R6294    1      A Q_RES_0402LF-10K,1%,1/16W,CHIP,CS31002FB08    I81 @T6G_MB_LIB.T6G(SCH_1):PAGE157
 R6327    1      A Q_RES_0402LF-4.7K,1%,1/16W,EMPTY,CS24702FB06    I91 @T6G_MB_LIB.T6G(SCH_1):PAGE155
   R52    1      A Q_RES_0402LF-10K,1%,1/16W,EMPTY,CS31002FB08   I103 @T6G_MB_LIB.T6G(SCH_1):PAGE361
    C1    1      A Q_CAP_0402-0.1UF,25V,10%,X7R,CH4104K1B00   I110 @T6G_MB_LIB.T6G(SCH_1):PAGE361
   R24    1      A Q_RES_0402LF-4.7K,5%,1/16W,EMPTY,CS24702JB10   I113 @T6G_MB_LIB.T6G(SCH_1):PAGE361
    R4    1      A Q_RES_0402LF-4.7K,5%,1/16W,EMPTY,CS24702JB10   I114 @T6G_MB_LIB.T6G(SCH_1):PAGE361
    U1    8    VCC M24128BWMN6TP-M24128-BWMN6TP,SMLF,IC,AKE30Z00613    I97 @T6G_MB_LIB.T6G(SCH_1):PAGE361
   R60    1      A Q_RES_0402LF-10K,1%,1/16W,EMPTY,CS31002FB08   I101 @T6G_MB_LIB.T6G(SCH_1):PAGE361
   R68    1      A Q_RES_0402LF-1K,1%,1/16W,EMPTY,CS21002FB06   I120 @T6G_MB_LIB.T6G(SCH_1):PAGE361
  R134    2      B Q_RES_0402LF-4.7K,5%,1/16W,EMPTY,CS24702JB10   I156 @T6G_MB_LIB.T6G(SCH_1):PAGE82
  R135    2      B Q_RES_0402LF-4.7K,5%,1/16W,EMPTY,CS24702JB10   I157 @T6G_MB_LIB.T6G(SCH_1):PAGE82
   C11    1      A Q_CAP_0402-0.1UF,25V,10%,X7R,CH4104K1B00    I89 @T6G_MB_LIB.T6G(SCH_1):PAGE138
    C2    1      A Q_CAP_0402-0.1UF,25V,10%,X7R,CH4104K1B00    I59 @T6G_MB_LIB.T6G(SCH_1):PAGE137
  R201    1      A Q_RES_0402LF-4.7K,5%,1/16W,EMPTY,CS24702JB10    I62 @T6G_MB_LIB.T6G(SCH_1):PAGE137
 R6213    1      A Q_RES_0402LF-10K,1%,1/16W,CHIP,CS31002FB08    I87 @T6G_MB_LIB.T6G(SCH_1):PAGE153
 R6215    1      A Q_RES_0402LF-10K,1%,1/16W,CHIP,CS31002FB08    I89 @T6G_MB_LIB.T6G(SCH_1):PAGE153
  R354    1      A Q_RES_0402LF-10.5K,1%,1/16W,CHIP,CS31052FB03    I76 @T6G_MB_LIB.T6G(SCH_1):PAGE371
  R355    1      A Q_RES_0402LF-10.5K,1%,1/16W,CHIP,CS31052FB03    I79 @T6G_MB_LIB.T6G(SCH_1):PAGE371
   R64    2      B Q_RES_0402LF-1K,1%,1/16W,EMPTY,CS21002FB06   I166 @T6G_MB_LIB.T6G(SCH_1):PAGE82
 R2230    1      A Q_RES_0402LF-10K,1%,1/16W,EMPTY,CS31002FB08    I43 @T6G_MB_LIB.T6G(SCH_1):PAGE372
 R2233    1      A Q_RES_0402LF-1K,1%,1/16W,EMPTY,CS21002FB06    I45 @T6G_MB_LIB.T6G(SCH_1):PAGE372
 R4620    1      A Q_RES_0402LF-1K,1%,1/16W,EMPTY,CS21002FB06    I46 @T6G_MB_LIB.T6G(SCH_1):PAGE372
 R6136    1      A Q_RES_0402LF-1K,1%,1/16W,CHIP,CS21002FB06   I117 @T6G_MB_LIB.T6G(SCH_1):PAGE83
 R6137    1      A Q_RES_0402LF-1K,1%,1/16W,EMPTY,CS21002FB06   I121 @T6G_MB_LIB.T6G(SCH_1):PAGE83
 R6273    1      A Q_RES_0402LF-200K,1%,1/16W,EMPTY,CS42002FB05   I104 @T6G_MB_LIB.T6G(SCH_1):PAGE155
 R6315    1      A Q_RES_0402LF-10K,1%,1/16W,CHIP,CS31002FB08   I140 @T6G_MB_LIB.T6G(SCH_1):PAGE155
 R6277    1      A Q_RES_0402LF-10K,1%,1/16W,EMPTY,CS31002FB08   I130 @T6G_MB_LIB.T6G(SCH_1):PAGE157
 R6282    1      A Q_RES_0402LF-1K,1%,1/16W,EMPTY,CS21002FB06   I138 @T6G_MB_LIB.T6G(SCH_1):PAGE157
 R6258    1      A Q_RES_0402LF-4.7K,5%,1/16W,EMPTY,CS24702JB10   I164 @T6G_MB_LIB.T6G(SCH_1):PAGE155
 R6303    1      A Q_RES_0402LF-200K,1%,1/16W,EMPTY,CS42002FB05   I169 @T6G_MB_LIB.T6G(SCH_1):PAGE155
 R6301    1      A Q_RES_0402LF-10K,1%,1/16W,CHIP,CS31002FB08   I179 @T6G_MB_LIB.T6G(SCH_1):PAGE155
 R6297    1      A Q_RES_0402LF-10K,1%,1/16W,CHIP,CS31002FB08   I185 @T6G_MB_LIB.T6G(SCH_1):PAGE155
 R6298    1      A Q_RES_0402LF-10K,1%,1/16W,CHIP,CS31002FB08   I187 @T6G_MB_LIB.T6G(SCH_1):PAGE155
 R6308    1      A Q_RES_0402LF-200K,1%,1/16W,EMPTY,CS42002FB05   I153 @T6G_MB_LIB.T6G(SCH_1):PAGE157
 R6306    1      A Q_RES_0402LF-4.7K,1%,1/16W,CHIP,CS24702FB06   I155 @T6G_MB_LIB.T6G(SCH_1):PAGE157
 R6289    1      A Q_RES_0402LF-10K,1%,1/16W,CHIP,CS31002FB08   I195 @T6G_MB_LIB.T6G(SCH_1):PAGE155
 R6287    1      A Q_RES_0402LF-1K,1%,1/16W,CHIP,CS21002FB06   I197 @T6G_MB_LIB.T6G(SCH_1):PAGE155
 R6312    1      A Q_RES_0402LF-10K,1%,1/16W,CHIP,CS31002FB08   I205 @T6G_MB_LIB.T6G(SCH_1):PAGE155
  R496    1      A Q_RES_0402LF-10K,1%,1/16W,EMPTY,CS31002FB08    I93 @T6G_MB_LIB.T6G(SCH_1):PAGE273
  R492    1      A Q_RES_0402LF-4.7K,5%,1/16W,CHIP,CS24702JB10    I99 @T6G_MB_LIB.T6G(SCH_1):PAGE273
  R552    1      A Q_RES_0402LF-4.7K,5%,1/16W,CHIP,CS24702JB10   I104 @T6G_MB_LIB.T6G(SCH_1):PAGE273
 R1492    1      A Q_RES_0402LF-10K,5%,1/16W,CHIP,CS31002JB08   I120 @T6G_MB_LIB.T6G(SCH_1):PAGE273
  U320    5    VCC 74LVC1G66GV-74LVC1G66GV,SMLF,IC,AL001G66000    I82 @T6G_MB_LIB.T6G(SCH_1):PAGE337
  U321    5    VCC 74LVC1G66GV-74LVC1G66GV,SMLF,IC,AL001G66000    I76 @T6G_MB_LIB.T6G(SCH_1):PAGE342
 R9009    1      A Q_RES_0402LF-4.7K,5%,1/16W,CHIP,CS24702JB10    I23 @T6G_MB_LIB.T6G(SCH_1):PAGE330
 R9004    1      A Q_RES_0402LF-4.7K,5%,1/16W,CHIP,CS24702JB10    I26 @T6G_MB_LIB.T6G(SCH_1):PAGE330
 R8017    1      A Q_RES_0402LF-0,5%,1/16W,EMPTY,CS00002JB13    I85 @T6G_MB_LIB.T6G(SCH_1):PAGE144
 R8019    1      A Q_RES_0402LF-100,1%,1/16W,EMPTY,CS11002FB07    I89 @T6G_MB_LIB.T6G(SCH_1):PAGE144
 R8029    2      B Q_RES_0402LF-249,1%,1/16W,CHIP,CS12492FB02    I55 @T6G_MB_LIB.T6G(SCH_1):PAGE375
 R8028    1      A Q_RES_0402LF-4.7K,5%,1/16W,CHIP,CS24702JB10    I62 @T6G_MB_LIB.T6G(SCH_1):PAGE375
 R6071    1      A Q_RES_0402LF-4.7K,5%,1/16W,EMPTY,CS24702JB10   I214 @T6G_MB_LIB.T6G(SCH_1):PAGE348
 R2920    1      A Q_RES_0402LF-100K,1%,1/16W,CHIP,CS41002FB09   I177 @T6G_MB_LIB.T6G(SCH_1):PAGE333
 R3030    1      A Q_RES_0402LF-100K,1%,1/16W,CHIP,CS41002FB09   I178 @T6G_MB_LIB.T6G(SCH_1):PAGE333
 R3035    1      A Q_RES_0402LF-100K,1%,1/16W,CHIP,CS41002FB09   I179 @T6G_MB_LIB.T6G(SCH_1):PAGE333
 R2933    1      A Q_RES_0402LF-100K,1%,1/16W,CHIP,CS41002FB09   I180 @T6G_MB_LIB.T6G(SCH_1):PAGE333
 R4546    1      A Q_RES_0402LF-100K,1%,1/16W,EMPTY,CS41002FB09   I110 @T6G_MB_LIB.T6G(SCH_1):PAGE331
 R8037    1      A Q_RES_0402LF-10K,1%,1/16W,CHIP,CS31002FB08   I540 @T6G_MB_LIB.T6G(SCH_1):PAGE85
 R8038    1      A Q_RES_0402LF-10K,1%,1/16W,CHIP,CS31002FB08   I243 @T6G_MB_LIB.T6G(SCH_1):PAGE91
 R8039    1      A Q_RES_0402LF-10K,1%,1/16W,CHIP,CS31002FB08   I245 @T6G_MB_LIB.T6G(SCH_1):PAGE97
 R8040    1      A Q_RES_0402LF-10K,1%,1/16W,CHIP,CS31002FB08   I245 @T6G_MB_LIB.T6G(SCH_1):PAGE103
 R8082    1      A Q_RES_0402LF-10K,1%,1/16W,EMPTY,CS31002FB08   I547 @T6G_MB_LIB.T6G(SCH_1):PAGE85
 D8003    2      C SCHOTTKY_12-B0530WS7F,SMLF,EMPTY,BC000530Z41   I549 @T6G_MB_LIB.T6G(SCH_1):PAGE85
 R8085    1      A Q_RES_0402LF-10K,1%,1/16W,EMPTY,CS31002FB08   I249 @T6G_MB_LIB.T6G(SCH_1):PAGE91
 D8004    2      C SCHOTTKY_12-B0530WS7F,SMLF,EMPTY,BC000530Z41   I251 @T6G_MB_LIB.T6G(SCH_1):PAGE91
 R8088    1      A Q_RES_0402LF-10K,1%,1/16W,EMPTY,CS31002FB08   I251 @T6G_MB_LIB.T6G(SCH_1):PAGE97
 D8005    2      C SCHOTTKY_12-B0530WS7F,SMLF,EMPTY,BC000530Z41   I253 @T6G_MB_LIB.T6G(SCH_1):PAGE97
 R8091    1      A Q_RES_0402LF-10K,1%,1/16W,EMPTY,CS31002FB08   I251 @T6G_MB_LIB.T6G(SCH_1):PAGE103
 D8006    2      C SCHOTTKY_12-B0530WS7F,SMLF,EMPTY,BC000530Z41   I253 @T6G_MB_LIB.T6G(SCH_1):PAGE103
 U8004    5    VCC 74LVC2G07DW7-74LVC2G07DW-7,SMLF,EMPTY,AL002G07003    I16 @T6G_MB_LIB.T6G(SCH_1):PAGE365
 C8013    1      A Q_CAP_0402-0.1UF,25V,10%,EMPTY,CH4104K1B00    I23 @T6G_MB_LIB.T6G(SCH_1):PAGE365
 R8103    1      A Q_RES_0402LF-8.45K,1%,1/16W,EMPTY,CS28452FB06    I27 @T6G_MB_LIB.T6G(SCH_1):PAGE365
 R8107    1      A Q_RES_0402LF-10K,1%,1/16W,EMPTY,CS31002FB08    I81 @T6G_MB_LIB.T6G(SCH_1):PAGE371
 R8111    1      A Q_RES_0402LF-10K,1%,1/16W,EMPTY,CS31002FB08    I98 @T6G_MB_LIB.T6G(SCH_1):PAGE371
 R8113    1      A Q_RES_0402LF-10K,1%,1/16W,CHIP,CS31002FB08    I52 @T6G_MB_LIB.T6G(SCH_1):PAGE372
 R8119    1      A Q_RES_0402LF-1K,1%,1/16W,CHIP,CS21002FB06    I69 @T6G_MB_LIB.T6G(SCH_1):PAGE372
 R8120    1      A Q_RES_0402LF-10K,1%,1/16W,CHIP,CS31002FB08    I72 @T6G_MB_LIB.T6G(SCH_1):PAGE372
 R4489    1      A Q_RES_0402LF-4.75K,1%,1/16W,CHIP,CS24752FB03     I3 @T6G_MB_LIB.T6G(SCH_1):PAGE160
   L20    1      1 Q_INDUCTOR_SMLF-FCM2012KF-601T/0.5A,IND,CX601T05003    I24 @T6G_MB_LIB.T6G(SCH_1):PAGE160
   L19    1      1 Q_INDUCTOR_SMLF-FCM2012KF-601T/0.5A,IND,CX601T05003    I26 @T6G_MB_LIB.T6G(SCH_1):PAGE160
 R4491    1      A Q_RES_0402LF-10K,1%,1/16W,CHIP,CS31002FB08    I31 @T6G_MB_LIB.T6G(SCH_1):PAGE160
    L1    1      1 Q_INDUCTOR_SMLF-FCM2012KF-601T/0.5A,IND,CX601T05003     I2 @T6G_MB_LIB.T6G(SCH_1):PAGE379
  R580    1      A Q_RES_0402LF-10K,1%,1/16W,CHIP,CS31002FB08    I17 @T6G_MB_LIB.T6G(SCH_1):PAGE379
    L2    1      1 Q_INDUCTOR_SMLF-FCM2012KF-601T/0.5A,IND,CX601T05003    I32 @T6G_MB_LIB.T6G(SCH_1):PAGE379
  R578    1      A Q_RES_0402LF-4.75K,1%,1/16W,EMPTY,CS24752FB03    I65 @T6G_MB_LIB.T6G(SCH_1):PAGE379
PR6501    1      A Q_RES_0402LF-0,5%,1/16W,CHIP,CS00002JB13    I13 @T6G_MB_LIB.T6G(SCH_1):PAGE469
 R6505    1      A Q_RES_0402LF-10K,5%,1/16W,CHIP,CS31002JB08    I28 @T6G_MB_LIB.T6G(SCH_1):PAGE469
PR6521    1      A Q_RES_0402LF-0,5%,1/16W,CHIP,CS00002JB13    I13 @T6G_MB_LIB.T6G(SCH_1):PAGE470
  R644    1      A Q_RES_0402LF-10K,5%,1/16W,CHIP,CS31002JB08    I29 @T6G_MB_LIB.T6G(SCH_1):PAGE470
  R655    1      A Q_RES_0402LF-1K,1%,1/16W,CHIP,CS21002FB06   I127 @T6G_MB_LIB.T6G(SCH_1):PAGE475
  R652    1      A Q_RES_0402LF-1K,1%,1/16W,CHIP,CS21002FB06   I128 @T6G_MB_LIB.T6G(SCH_1):PAGE475
PR6608    2      B Q_RES_0402LF-1,1%,1/16W,CHIP,CS-1002FB04   I131 @T6G_MB_LIB.T6G(SCH_1):PAGE475
PR6615    1      A Q_RES_0402LF-1K,1%,1/16W,CHIP,CS21002FB06   I135 @T6G_MB_LIB.T6G(SCH_1):PAGE475
PR6805    1      A Q_RES_0402LF-1K,1%,1/16W,EMPTY,CS21002FB06   I166 @T6G_MB_LIB.T6G(SCH_1):PAGE475
PR6803    1      A Q_RES_0402LF-1K,1%,1/16W,EMPTY,CS21002FB06   I167 @T6G_MB_LIB.T6G(SCH_1):PAGE475
PR6817    1      A Q_RES_0402LF-1K,1%,1/16W,EMPTY,CS21002FB06   I169 @T6G_MB_LIB.T6G(SCH_1):PAGE475
  R649    1      A Q_RES_0402LF-4.7K,1%,1/16W,EMPTY,CS24702FB06   I207 @T6G_MB_LIB.T6G(SCH_1):PAGE475
PR6551    1      A Q_RES_0402LF-0,5%,1/16W,EMPTY,CS00002JB13   I185 @T6G_MB_LIB.T6G(SCH_1):PAGE476
  R665    1      A Q_RES_0402LF-1K,1%,1/16W,CHIP,CS21002FB06    I14 @T6G_MB_LIB.T6G(SCH_1):PAGE477
  R663    1      A Q_RES_0402LF-1K,1%,1/16W,CHIP,CS21002FB06    I15 @T6G_MB_LIB.T6G(SCH_1):PAGE477
PR6818    1      A Q_RES_0402LF-1K,1%,1/16W,EMPTY,CS21002FB06    I32 @T6G_MB_LIB.T6G(SCH_1):PAGE477
PR6804    1      A Q_RES_0402LF-1K,1%,1/16W,EMPTY,CS21002FB06    I36 @T6G_MB_LIB.T6G(SCH_1):PAGE477
PR6806    1      A Q_RES_0402LF-1K,1%,1/16W,EMPTY,CS21002FB06    I37 @T6G_MB_LIB.T6G(SCH_1):PAGE477
PR6538    2      B Q_RES_0402LF-1,1%,1/16W,CHIP,CS-1002FB04    I83 @T6G_MB_LIB.T6G(SCH_1):PAGE477
PR6812    1      A Q_RES_0402LF-1K,1%,1/16W,CHIP,CS21002FB06    I86 @T6G_MB_LIB.T6G(SCH_1):PAGE477
  R660    1      A Q_RES_0402LF-4.7K,1%,1/16W,EMPTY,CS24702FB06    I89 @T6G_MB_LIB.T6G(SCH_1):PAGE477
PR6620    1      A Q_RES_0402LF-0,5%,1/16W,EMPTY,CS00002JB13    I56 @T6G_MB_LIB.T6G(SCH_1):PAGE478
 R5101    1      A Q_RES_0402LF-10K,5%,1/16W,CHIP,CS31002JB08    I97 @T6G_MB_LIB.T6G(SCH_1):PAGE156
 R9000    1      A Q_RES_0402LF-1K,1%,1/16W,CHIP,CS21002FB06   I472 @T6G_MB_LIB.T6G(SCH_1):PAGE363
 R2923    1      A Q_RES_0402LF-4.7K,5%,1/16W,EMPTY,CS24702JB10    I37 @T6G_MB_LIB.T6G(SCH_1):PAGE246
 C1713    1      A Q_CAP_0402-0.1UF,25V,10%,X7R,CH4104K1B00    I61 @T6G_MB_LIB.T6G(SCH_1):PAGE246
  U181   24    VDD PCA9539RPW-PCA9539RPW,SMLF,IC,AL009539K07    I83 @T6G_MB_LIB.T6G(SCH_1):PAGE246
 R4153    1      A Q_RES_0402LF-10K,1%,1/16W,CHIP,CS31002FB08     I4 @T6G_MB_LIB.T6G(SCH_1):PAGE332
 R4155    1      A Q_RES_0402LF-4.7K,5%,1/16W,CHIP,CS24702JB10     I8 @T6G_MB_LIB.T6G(SCH_1):PAGE332
 R4121    1      A Q_RES_0402LF-10K,1%,1/16W,CHIP,CS31002FB08    I14 @T6G_MB_LIB.T6G(SCH_1):PAGE332
 R4123    1      A Q_RES_0402LF-54.9K,1%,1/16W,EMPTY,CS35492FB03    I18 @T6G_MB_LIB.T6G(SCH_1):PAGE332
 R4119    1      A Q_RES_0402LF-54.9K,1%,1/16W,EMPTY,CS35492FB03    I23 @T6G_MB_LIB.T6G(SCH_1):PAGE332
 R4126    1      A Q_RES_0402LF-4.7K,5%,1/16W,CHIP,CS24702JB10    I27 @T6G_MB_LIB.T6G(SCH_1):PAGE332
 R4127    1      A Q_RES_0402LF-4.7K,5%,1/16W,CHIP,CS24702JB10    I35 @T6G_MB_LIB.T6G(SCH_1):PAGE332
 R4125    1      A Q_RES_0402LF-4.7K,5%,1/16W,CHIP,CS24702JB10    I39 @T6G_MB_LIB.T6G(SCH_1):PAGE332
 R4156    1      A Q_RES_0402LF-100K,1%,1/16W,CHIP,CS41002FB09    I48 @T6G_MB_LIB.T6G(SCH_1):PAGE332
 R4562    1      A Q_RES_0402LF-100K,1%,1/16W,EMPTY,CS41002FB09    I55 @T6G_MB_LIB.T6G(SCH_1):PAGE332
 R4560    1      A Q_RES_0402LF-4.7K,5%,1/16W,CHIP,CS24702JB10    I62 @T6G_MB_LIB.T6G(SCH_1):PAGE332
 R4129    1      A Q_RES_0402LF-100K,1%,1/16W,CHIP,CS41002FB09    I66 @T6G_MB_LIB.T6G(SCH_1):PAGE332
 R4130    1      A Q_RES_0402LF-100K,1%,1/16W,CHIP,CS41002FB09    I70 @T6G_MB_LIB.T6G(SCH_1):PAGE332
 R4133    1      A Q_RES_0402LF-54.9K,1%,1/16W,EMPTY,CS35492FB03    I82 @T6G_MB_LIB.T6G(SCH_1):PAGE332
 R4138    1      A Q_RES_0402LF-4.7K,5%,1/16W,CHIP,CS24702JB10    I88 @T6G_MB_LIB.T6G(SCH_1):PAGE332
 R4135    1      A Q_RES_0402LF-10K,1%,1/16W,CHIP,CS31002FB08    I93 @T6G_MB_LIB.T6G(SCH_1):PAGE332
 R4131    1      A Q_RES_0402LF-54.9K,1%,1/16W,EMPTY,CS35492FB03    I97 @T6G_MB_LIB.T6G(SCH_1):PAGE332
 R4139    1      A Q_RES_0402LF-4.7K,5%,1/16W,CHIP,CS24702JB10    I99 @T6G_MB_LIB.T6G(SCH_1):PAGE332
 R4128    1      A Q_RES_0402LF-100K,1%,1/16W,CHIP,CS41002FB09   I104 @T6G_MB_LIB.T6G(SCH_1):PAGE332
 R4137    1      A Q_RES_0402LF-4.7K,5%,1/16W,CHIP,CS24702JB10   I107 @T6G_MB_LIB.T6G(SCH_1):PAGE332
 R4561    1      A Q_RES_0402LF-100K,1%,1/16W,CHIP,CS41002FB09   I110 @T6G_MB_LIB.T6G(SCH_1):PAGE332
 R4141    1      A Q_RES_0402LF-100K,1%,1/16W,CHIP,CS41002FB09   I114 @T6G_MB_LIB.T6G(SCH_1):PAGE332
 R4142    1      A Q_RES_0402LF-100K,1%,1/16W,CHIP,CS41002FB09   I122 @T6G_MB_LIB.T6G(SCH_1):PAGE332
 R4140    1      A Q_RES_0402LF-100K,1%,1/16W,CHIP,CS41002FB09   I131 @T6G_MB_LIB.T6G(SCH_1):PAGE332
 R4058    1      A Q_RES_0402LF-10K,1%,1/16W,CHIP,CS31002FB08    I13 @T6G_MB_LIB.T6G(SCH_1):PAGE330
 R9006    1      A Q_RES_0402LF-10K,1%,1/16W,CHIP,CS31002FB08    I15 @T6G_MB_LIB.T6G(SCH_1):PAGE330
 R9005    1      A Q_RES_0402LF-4.7K,5%,1/16W,CHIP,CS24702JB10    I32 @T6G_MB_LIB.T6G(SCH_1):PAGE330
 R9014    1      A Q_RES_0402LF-10K,1%,1/16W,CHIP,CS31002FB08    I51 @T6G_MB_LIB.T6G(SCH_1):PAGE330
 R8002    1      A Q_RES_0402LF-4.7K,5%,1/16W,CHIP,CS24702JB10    I55 @T6G_MB_LIB.T6G(SCH_1):PAGE330
 R8003    1      A Q_RES_0402LF-4.7K,5%,1/16W,CHIP,CS24702JB10    I57 @T6G_MB_LIB.T6G(SCH_1):PAGE330
 R9016    1      A Q_RES_0402LF-4.7K,5%,1/16W,CHIP,CS24702JB10    I61 @T6G_MB_LIB.T6G(SCH_1):PAGE330
 R9017    1      A Q_RES_0402LF-4.7K,5%,1/16W,CHIP,CS24702JB10    I72 @T6G_MB_LIB.T6G(SCH_1):PAGE330
 R9020    1      A Q_RES_0402LF-1K,1%,1/16W,EMPTY,CS21002FB06   I108 @T6G_MB_LIB.T6G(SCH_1):PAGE371
  R643    1      A Q_RES_0402LF-1K,1%,1/16W,EMPTY,CS21002FB06   I212 @T6G_MB_LIB.T6G(SCH_1):PAGE475
  R656    1      A Q_RES_0402LF-1K,1%,1/16W,EMPTY,CS21002FB06    I92 @T6G_MB_LIB.T6G(SCH_1):PAGE477
 R4476    1      A Q_RES_0402LF-10K,1%,1/16W,CHIP,CS31002FB08    I73 @T6G_MB_LIB.T6G(SCH_1):PAGE160
  R560    1      A Q_RES_0402LF-10K,1%,1/16W,CHIP,CS31002FB08    I81 @T6G_MB_LIB.T6G(SCH_1):PAGE379
 R3773    1      A Q_RES_0402LF-4.7K,5%,1/16W,EMPTY,CS24702JB10   I106 @T6G_MB_LIB.T6G(SCH_1):PAGE297
 R4173    1      A Q_RES_0402LF-100K,1%,1/16W,EMPTY,CS41002FB09   I204 @T6G_MB_LIB.T6G(SCH_1):PAGE256
 R9026    1      A Q_RES_0402LF-4.7K,5%,1/16W,CHIP,CS24702JB10   I112 @T6G_MB_LIB.T6G(SCH_1):PAGE84
 R9027    1      A Q_RES_0402LF-100K,1%,1/16W,CHIP,CS41002FB09   I114 @T6G_MB_LIB.T6G(SCH_1):PAGE84
 R1304    2      B Q_RES_0402LF-10K,1%,1/16W,CHIP,CS31002FB08   I171 @T6G_MB_LIB.T6G(SCH_1):PAGE82
 R4521    1      A Q_RES_0402LF-1K,1%,1/16W,CHIP,CS21002FB06    I73 @T6G_MB_LIB.T6G(SCH_1):PAGE232
 R3322    1      A Q_RES_0402LF-1K,1%,1/16W,CHIP,CS21002FB06    I74 @T6G_MB_LIB.T6G(SCH_1):PAGE232
 R2950    1      A Q_RES_0402LF-1K,1%,1/16W,CHIP,CS21002FB06   I475 @T6G_MB_LIB.T6G(SCH_1):PAGE363
 R3459    1      A Q_RES_0402LF-1K,1%,1/16W,CHIP,CS21002FB06    I75 @T6G_MB_LIB.T6G(SCH_1):PAGE255
 R9043    1      A Q_RES_0402LF-4.7K,5%,1/16W,CHIP,CS24702JB10   I192 @T6G_MB_LIB.T6G(SCH_1):PAGE299
 R9044    1      A Q_RES_0402LF-4.7K,1%,1/16W,EMPTY,CS24702FB06   I195 @T6G_MB_LIB.T6G(SCH_1):PAGE299
 R9032    1      A Q_RES_0402LF-10K,1%,1/16W,CHIP,CS31002FB08     I2 @T6G_MB_LIB.T6G(SCH_1):PAGE340
 U9001    5    VCC 74LVC1G08W57-74LVC1G08W5-7,SMLF,IC,AL1G0008020    I25 @T6G_MB_LIB.T6G(SCH_1):PAGE340
 C9007    1      A Q_CAP_0402-0.1UF,25V,10%,X7R,CH4104K1B00    I27 @T6G_MB_LIB.T6G(SCH_1):PAGE340
  R577    1      A Q_RES_0402LF-10K,1%,1/16W,CHIP,CS31002FB08   I118 @T6G_MB_LIB.T6G(SCH_1):PAGE338
 R1128    1      A Q_RES_0402LF-1K,1%,1/16W,CHIP,CS21002FB06    I34 @T6G_MB_LIB.T6G(SCH_1):PAGE340
   U23    5    VCC 74LVC1G08W57-74LVC1G08W5-7,SMLF,IC,AL1G0008020    I36 @T6G_MB_LIB.T6G(SCH_1):PAGE340
 C1059    1      A Q_CAP_0402-0.1UF,25V,10%,X7R,CH4104K1B00    I40 @T6G_MB_LIB.T6G(SCH_1):PAGE340
 R1131    1      A Q_RES_0402LF-1K,1%,1/16W,CHIP,CS21002FB06    I44 @T6G_MB_LIB.T6G(SCH_1):PAGE340
   U28    5    VCC SN74LVC1G07DBVR_SMLF-SN74LVC1G07DBVR,IC,AL1G0007024    I51 @T6G_MB_LIB.T6G(SCH_1):PAGE340
 C1058    1      A Q_CAP_0402-0.1UF,25V,10%,X7R,CH4104K1B00    I53 @T6G_MB_LIB.T6G(SCH_1):PAGE340
 R1133    1      A Q_RES_0402LF-1K,1%,1/16W,CHIP,CS21002FB06    I61 @T6G_MB_LIB.T6G(SCH_1):PAGE340
 R1144    1      A Q_RES_0402LF-1K,1%,1/16W,CHIP,CS21002FB06    I64 @T6G_MB_LIB.T6G(SCH_1):PAGE340
   U30    5    VCC SN74LVC1G07DBVR_SMLF-SN74LVC1G07DBVR,IC,AL1G0007024    I66 @T6G_MB_LIB.T6G(SCH_1):PAGE340
 C1060    1      A Q_CAP_0402-0.1UF,25V,10%,X7R,CH4104K1B00    I69 @T6G_MB_LIB.T6G(SCH_1):PAGE340
 U9002    5    VCC 74LVC1G32GW_SMLF-74LVC1G32GW,IC,ALVC1G32007    I74 @T6G_MB_LIB.T6G(SCH_1):PAGE340
 C9008    1      A Q_CAP_0402-0.1UF,25V,10%,X7R,CH4104K1B00    I75 @T6G_MB_LIB.T6G(SCH_1):PAGE340
 R1145    1      A Q_RES_0402LF-10K,5%,1/16W,EMPTY,CS31002JB08    I76 @T6G_MB_LIB.T6G(SCH_1):PAGE340
 C1061    1      A Q_CAP_0402-0.1UF,25V,10%,X7R,CH4104K1B00     I5 @T6G_MB_LIB.T6G(SCH_1):PAGE257
 R1176    1      A Q_RES_0402LF-10K,1%,1/16W,CHIP,CS31002FB08    I10 @T6G_MB_LIB.T6G(SCH_1):PAGE257
 C1065    1      A Q_CAP_0402-0.1UF,25V,10%,X7R,CH4104K1B00    I14 @T6G_MB_LIB.T6G(SCH_1):PAGE257
 R1167    1      A Q_RES_0402LF-1K,1%,1/16W,CHIP,CS21002FB06    I19 @T6G_MB_LIB.T6G(SCH_1):PAGE257
 R1149    1      A Q_RES_0402LF-1K,1%,1/16W,CHIP,CS21002FB06    I25 @T6G_MB_LIB.T6G(SCH_1):PAGE257
   U31    5    VCC 74LVC1G08W57-74LVC1G08W5-7,SMLF,IC,AL1G0008020    I31 @T6G_MB_LIB.T6G(SCH_1):PAGE257
 R1165    1      A Q_RES_0402LF-1K,1%,1/16W,CHIP,CS21002FB06    I32 @T6G_MB_LIB.T6G(SCH_1):PAGE257
 C1062    1      A Q_CAP_0402-0.1UF,25V,10%,X7R,CH4104K1B00    I36 @T6G_MB_LIB.T6G(SCH_1):PAGE257
   U37    5    VCC 74LVC1G32GW_SMLF-74LVC1G32GW,IC,ALVC1G32007    I40 @T6G_MB_LIB.T6G(SCH_1):PAGE257
   U34    5    VCC SN74LVC1G07DBVR_SMLF-SN74LVC1G07DBVR,IC,AL1G0007024    I45 @T6G_MB_LIB.T6G(SCH_1):PAGE257
 C1064    1      A Q_CAP_0402-0.1UF,25V,10%,X7R,CH4104K1B00    I46 @T6G_MB_LIB.T6G(SCH_1):PAGE257
 R1172    1      A Q_RES_0402LF-10K,5%,1/16W,EMPTY,CS31002JB08    I51 @T6G_MB_LIB.T6G(SCH_1):PAGE257
 C1063    1      A Q_CAP_0402-0.1UF,25V,10%,X7R,CH4104K1B00    I55 @T6G_MB_LIB.T6G(SCH_1):PAGE257
 R1171    1      A Q_RES_0402LF-1K,1%,1/16W,CHIP,CS21002FB06    I60 @T6G_MB_LIB.T6G(SCH_1):PAGE257
   U35    5    VCC 74LVC1G08W57-74LVC1G08W5-7,SMLF,IC,AL1G0008020    I63 @T6G_MB_LIB.T6G(SCH_1):PAGE257
   U33    5    VCC SN74LVC1G07DBVR_SMLF-SN74LVC1G07DBVR,IC,AL1G0007024    I64 @T6G_MB_LIB.T6G(SCH_1):PAGE257
 R1192    1      A Q_RES_0402LF-1K,1%,1/16W,CHIP,CS21002FB06   I118 @T6G_MB_LIB.T6G(SCH_1):PAGE343
   U45   10    VDD PI3CSW12ZUAEX-PI3CSW12ZUAEX,SMLF,IC,AL3CSW12000    I22 @T6G_MB_LIB.T6G(SCH_1):PAGE376
 C1069    1      A Q_CAP_C0201-0.1UF,10V,10%,X7S,CH4102K6E00    I24 @T6G_MB_LIB.T6G(SCH_1):PAGE376
   U42   10    VDD PI3CSW12ZUAEX-PI3CSW12ZUAEX,SMLF,IC,AL3CSW12000    I31 @T6G_MB_LIB.T6G(SCH_1):PAGE376
 C1067    1      A Q_CAP_C0201-0.1UF,10V,10%,X7S,CH4102K6E00    I37 @T6G_MB_LIB.T6G(SCH_1):PAGE376
   U41   10    VDD PI3CSW12ZUAEX-PI3CSW12ZUAEX,SMLF,IC,AL3CSW12000    I46 @T6G_MB_LIB.T6G(SCH_1):PAGE376
 C1066    1      A Q_CAP_C0201-0.1UF,10V,10%,X7S,CH4102K6E00    I48 @T6G_MB_LIB.T6G(SCH_1):PAGE376
   U43   10    VDD PI3CSW12ZUAEX-PI3CSW12ZUAEX,SMLF,IC,AL3CSW12000    I61 @T6G_MB_LIB.T6G(SCH_1):PAGE376
 C1068    1      A Q_CAP_C0201-0.1UF,10V,10%,X7S,CH4102K6E00    I65 @T6G_MB_LIB.T6G(SCH_1):PAGE376
   U48   10    VDD PI3CSW12ZUAEX-PI3CSW12ZUAEX,SMLF,IC,AL3CSW12000    I76 @T6G_MB_LIB.T6G(SCH_1):PAGE376
 C1073    1      A Q_CAP_C0201-0.1UF,10V,10%,X7S,CH4102K6E00    I80 @T6G_MB_LIB.T6G(SCH_1):PAGE376
 C1072    1      A Q_CAP_C0201-0.1UF,10V,10%,X7S,CH4102K6E00    I84 @T6G_MB_LIB.T6G(SCH_1):PAGE376
   U49   10    VDD PI3CSW12ZUAEX-PI3CSW12ZUAEX,SMLF,IC,AL3CSW12000    I85 @T6G_MB_LIB.T6G(SCH_1):PAGE376
 C1070    1      A Q_CAP_C0201-0.1UF,10V,10%,X7S,CH4102K6E00    I99 @T6G_MB_LIB.T6G(SCH_1):PAGE376
 C1071    1      A Q_CAP_C0201-0.1UF,10V,10%,X7S,CH4102K6E00   I105 @T6G_MB_LIB.T6G(SCH_1):PAGE376
   U46   10    VDD PI3CSW12ZUAEX-PI3CSW12ZUAEX,SMLF,IC,AL3CSW12000   I108 @T6G_MB_LIB.T6G(SCH_1):PAGE376
   U47   10    VDD PI3CSW12ZUAEX-PI3CSW12ZUAEX,SMLF,IC,AL3CSW12000   I121 @T6G_MB_LIB.T6G(SCH_1):PAGE376
 R1239    1      A Q_RES_0402LF-1K,1%,1/16W,EMPTY,CS21002FB06    I59 @T6G_MB_LIB.T6G(SCH_1):PAGE263
 R1241    1      A Q_RES_0402LF-1K,1%,1/16W,EMPTY,CS21002FB06    I60 @T6G_MB_LIB.T6G(SCH_1):PAGE263
   L25    1      1 Q_INDUCTOR_SMLF-BLM18PG300SN1D ,IND,TMP_QCX8PG3000A    I69 @T6G_MB_LIB.T6G(SCH_1):PAGE263
   L24    2      2 Q_INDUCTOR_SMLF-BLM18PG300SN1D ,IND,TMP_QCX8PG3000A   I168 @T6G_MB_LIB.T6G(SCH_1):PAGE263
 R1320    1      A Q_RES_0402LF-4.7K,1%,1/16W,CHIP,CS24702FB06    I17 @T6G_MB_LIB.T6G(SCH_1):PAGE466
 C1097    1      A Q_CAP_0402-0.1UF,25V,10%,X7R,CH4104K1B00    I19 @T6G_MB_LIB.T6G(SCH_1):PAGE466
   U55    9    VCC ISL28022FRZT-ISL28022FRZ-T,SMLF,IC,AL028022003    I28 @T6G_MB_LIB.T6G(SCH_1):PAGE466
   U56    9    VCC ISL28022FRZT-ISL28022FRZ-T,SMLF,IC,AL028022003    I29 @T6G_MB_LIB.T6G(SCH_1):PAGE466
 C1106    1      A Q_CAP_0402-0.1UF,25V,10%,X7R,CH4104K1B00    I36 @T6G_MB_LIB.T6G(SCH_1):PAGE466
 R1322    1      A Q_RES_0402LF-4.7K,1%,1/16W,CHIP,CS24702FB06    I39 @T6G_MB_LIB.T6G(SCH_1):PAGE466
   U52    9    VCC ISL28022FRZT-ISL28022FRZ-T,SMLF,IC,AL028022003    I57 @T6G_MB_LIB.T6G(SCH_1):PAGE466
 C1096    1      A Q_CAP_0402-0.1UF,25V,10%,X7R,CH4104K1B00    I66 @T6G_MB_LIB.T6G(SCH_1):PAGE466
 R1327    1      A Q_RES_0402LF-1K,1%,1/16W,EMPTY,CS21002FB06    I85 @T6G_MB_LIB.T6G(SCH_1):PAGE466
 R1328    1      A Q_RES_0402LF-1K,1%,1/16W,EMPTY,CS21002FB06    I87 @T6G_MB_LIB.T6G(SCH_1):PAGE466
 R1326    1      A Q_RES_0402LF-1K,1%,1/16W,EMPTY,CS21002FB06    I90 @T6G_MB_LIB.T6G(SCH_1):PAGE466
 R1317    1      A Q_RES_0402LF-4.7K,1%,1/16W,EMPTY,CS24702FB06    I95 @T6G_MB_LIB.T6G(SCH_1):PAGE466
 R1316    1      A Q_RES_0402LF-2.2K,5%,1/16W,CHIP,CS22202JB07    I83 @T6G_MB_LIB.T6G(SCH_1):PAGE251
 R1341    1      A Q_RES_0402LF-2.2K,5%,1/16W,CHIP,CS22202JB07    I84 @T6G_MB_LIB.T6G(SCH_1):PAGE251
    U4   10    VDD PI3CSW12ZUAEX-PI3CSW12ZUAEX,SMLF,IC,AL3CSW12000   I114 @T6G_MB_LIB.T6G(SCH_1):PAGE138
    U2    8   VCCB PCA9617ADP-PCA9617ADP,SMLF,IC,AL009617K02    I99 @T6G_MB_LIB.T6G(SCH_1):PAGE137
 R3783    1      A Q_RES_0402LF-100K,1%,1/16W,EMPTY,CS41002FB09   I131 @T6G_MB_LIB.T6G(SCH_1):PAGE338
 R3826    1      A Q_RES_0402LF-100K,1%,1/16W,EMPTY,CS41002FB09   I128 @T6G_MB_LIB.T6G(SCH_1):PAGE343
 R4452    1      A Q_RES_0402LF-10K,1%,1/16W,EMPTY,CS31002FB08    I93 @T6G_MB_LIB.T6G(SCH_1):PAGE153
 R6320    1      A Q_RES_0402LF-10K,1%,1/16W,EMPTY,CS31002FB08   I212 @T6G_MB_LIB.T6G(SCH_1):PAGE155
 R6329    1      A Q_RES_0402LF-10K,1%,1/16W,EMPTY,CS31002FB08   I213 @T6G_MB_LIB.T6G(SCH_1):PAGE155
 R8125    1      A Q_RES_0402LF-1K,1%,1/16W,CHIP,CS21002FB06   I104 @T6G_MB_LIB.T6G(SCH_1):PAGE372
 R3470    1      A Q_RES_0402LF-1K,1%,1/16W,CHIP,CS21002FB06   I202 @T6G_MB_LIB.T6G(SCH_1):PAGE299
 R8106    1      A Q_RES_0402LF-1K,1%,1/16W,CHIP,CS21002FB06    I31 @T6G_MB_LIB.T6G(SCH_1):PAGE365
 R1481    1      A Q_RES_2512LF-10,1%,2W,EMPTY,CS0100AFR00    I21 @T6G_MB_LIB.T6G(SCH_1):PAGE146
 R1052    1      A Q_RES_0402LF-1K,1%,1/16W,EMPTY,CS21002FB06    I38 @T6G_MB_LIB.T6G(SCH_1):PAGE146
 U9050    5    VCC 74LVC1G08W57-74LVC1G08W5-7,SMLF,IC,AL1G0008020    I91 @T6G_MB_LIB.T6G(SCH_1):PAGE340
 C9050    1      A Q_CAP_0402-0.1UF,25V,10%,X7R,CH4104K1B00    I94 @T6G_MB_LIB.T6G(SCH_1):PAGE340
 U9051    5    VCC 74LVC1G08W57-74LVC1G08W5-7,SMLF,IC,AL1G0008020    I78 @T6G_MB_LIB.T6G(SCH_1):PAGE257
 C9051    1      A Q_CAP_0402-0.1UF,25V,10%,X7R,CH4104K1B00    I81 @T6G_MB_LIB.T6G(SCH_1):PAGE257
 R9024    1      A Q_RES_0402LF-54.9K,1%,1/16W,CHIP,CS35492FB03   I113 @T6G_MB_LIB.T6G(SCH_1):PAGE371

P3V3_AUX_ADC @T6G_MB_LIB.T6G(SCH_1):P3V3_AUX_ADC
 R1785    1      A Q_RES_0402LF-4.7K,1%,1/16W,CHIP,CS24702FB06    I26 @T6G_MB_LIB.T6G(SCH_1):PAGE369
 R3682    1      A Q_RES_0402LF-0,5%,1/16W,CHIP,CS00002JB13    I27 @T6G_MB_LIB.T6G(SCH_1):PAGE369
 R2907    2      B Q_RES_0402LF-5.11K,1%,1/16W,CHIP,CS25112FB04    I28 @T6G_MB_LIB.T6G(SCH_1):PAGE369
 R3681    1      A Q_RES_0402LF-0,5%,1/16W,EMPTY,CS00002JB13    I30 @T6G_MB_LIB.T6G(SCH_1):PAGE369

P3V3_AUX_ADC_MAM @T6G_MB_LIB.T6G(SCH_1):P3V3_AUX_ADC_MAM
 R3681    2      B Q_RES_0402LF-0,5%,1/16W,EMPTY,CS00002JB13    I30 @T6G_MB_LIB.T6G(SCH_1):PAGE369
 C2042    1      A Q_CAP_0402-100PF,50V,5%,EMPTY,CH11006JB18    I99 @T6G_MB_LIB.T6G(SCH_1):PAGE369
  U193   10   AIN5 MAX11617EEET-MAX11617EEE+T,SMLF,EMPTY,AL011617W00   I169 @T6G_MB_LIB.T6G(SCH_1):PAGE369

P3V3_AUX_ADC_TIC @T6G_MB_LIB.T6G(SCH_1):P3V3_AUX_ADC_TIC
 R3682    2      B Q_RES_0402LF-0,5%,1/16W,CHIP,CS00002JB13    I27 @T6G_MB_LIB.T6G(SCH_1):PAGE369
 C2047    1      A Q_CAP_0402-0.1UF,25V,10%,X7R,CH4104K1B00    I98 @T6G_MB_LIB.T6G(SCH_1):PAGE369
  U269   11    IN5 ADC128D818CIMTXNOPB-ADC128D818CIMTX/NOPB,SMLF,IC,AA   I142 @T6G_MB_LIB.T6G(SCH_1):PAGE369

P3V3_AUX_CPU0_USB2_AVDD33 @T6G_MB_LIB.T6G(SCH_1):P3V3_AUX_CPU0_USB2_AVDD33
 L6003    2      2 Q_INDUCTOR_SMLF-BLM21PG221SN1D,IND,CX1PG221001    I17 @T6G_MB_LIB.T6G(SCH_1):PAGE157
 C6092    1      A Q_CAP_C0402-1UF,25V,10%,X6S,CH5104KEB02    I21 @T6G_MB_LIB.T6G(SCH_1):PAGE157
 C6094    1      A Q_CAP_C0402-0.01UF,50V,10%,X7R,CH31006KB18    I22 @T6G_MB_LIB.T6G(SCH_1):PAGE157
 C6095    1      A Q_CAP_0402-0.1UF,25V,10%,X7R,CH4104K1B00    I23 @T6G_MB_LIB.T6G(SCH_1):PAGE157
 C6093    1      A Q_CAP_C0402-1PF,50V,0.05P,COG,CH-106T0B00    I24 @T6G_MB_LIB.T6G(SCH_1):PAGE157
 C6098    1      A Q_CAP_0402-0.1UF,25V,10%,X7R,CH4104K1B00    I25 @T6G_MB_LIB.T6G(SCH_1):PAGE157
 C6097    1      A Q_CAP_C0402-0.01UF,50V,10%,X7R,CH31006KB18    I26 @T6G_MB_LIB.T6G(SCH_1):PAGE157
 C6096    1      A Q_CAP_C0402-1PF,50V,0.05P,COG,CH-106T0B00    I27 @T6G_MB_LIB.T6G(SCH_1):PAGE157
 C6101    1      A Q_CAP_0402-0.1UF,25V,10%,X7R,CH4104K1B00    I28 @T6G_MB_LIB.T6G(SCH_1):PAGE157
 C6100    1      A Q_CAP_C0402-0.01UF,50V,10%,X7R,CH31006KB18    I29 @T6G_MB_LIB.T6G(SCH_1):PAGE157
 C6099    1      A Q_CAP_C0402-1PF,50V,0.05P,COG,CH-106T0B00    I30 @T6G_MB_LIB.T6G(SCH_1):PAGE157
 C6104    1      A Q_CAP_0402-0.1UF,25V,10%,X7R,CH4104K1B00    I31 @T6G_MB_LIB.T6G(SCH_1):PAGE157
 C6103    1      A Q_CAP_C0402-0.01UF,50V,10%,X7R,CH31006KB18    I32 @T6G_MB_LIB.T6G(SCH_1):PAGE157
 C6102    1      A Q_CAP_C0402-1PF,50V,0.05P,COG,CH-106T0B00    I33 @T6G_MB_LIB.T6G(SCH_1):PAGE157
 U6002   52 VDD33_52 TUSB8042AIRGCR-TUSB8042AIRGCR,SMLF,IC,AL008042000   I119 @T6G_MB_LIB.T6G(SCH_1):PAGE157
 U6002   63 VDD33_63 TUSB8042AIRGCR-TUSB8042AIRGCR,SMLF,IC,AL008042000   I119 @T6G_MB_LIB.T6G(SCH_1):PAGE157
 R6275    2      B Q_RES_0402LF-0,5%,1/16W,CHIP,CS00002JB13   I131 @T6G_MB_LIB.T6G(SCH_1):PAGE157
 R6270    1      A Q_RES_0402LF-0,5%,1/16W,CHIP,CS00002JB13   I143 @T6G_MB_LIB.T6G(SCH_1):PAGE155
 R6264    2      B Q_RES_0402LF-0,5%,1/16W,CHIP,CS00002JB13   I151 @T6G_MB_LIB.T6G(SCH_1):PAGE155
 R6274    2      B Q_RES_0402LF-0,5%,1/16W,CHIP,CS00002JB13   I142 @T6G_MB_LIB.T6G(SCH_1):PAGE157

P3V3_AUX_CPU0_USB_AVDD33 @T6G_MB_LIB.T6G(SCH_1):P3V3_AUX_CPU0_USB_AVDD33
 U6001    4 AVDD33_1 CYUSB330468LTXI-CYUSB3304-68LTXI,SMLF,IC,AJ0330400A     I1 @T6G_MB_LIB.T6G(SCH_1):PAGE154
 L6000    2      2 Q_INDUCTOR_SMLF-BLM21PG221SN1D,IND,CX1PG221001     I3 @T6G_MB_LIB.T6G(SCH_1):PAGE154
 C6042    1      A Q_CAP_C0603-22UF,6.3V,20%,X6S,CH6221ME900     I9 @T6G_MB_LIB.T6G(SCH_1):PAGE154
 C6043    1      A Q_CAP_C0402-1UF,25V,10%,X6S,CH5104KEB02    I10 @T6G_MB_LIB.T6G(SCH_1):PAGE154
 C6044    1      A Q_CAP_0402-0.1UF,25V,10%,X7R,CH4104K1B00    I12 @T6G_MB_LIB.T6G(SCH_1):PAGE154
 C6045    1      A Q_CAP_C0402-0.01UF,50V,10%,X7R,CH31006KB18    I13 @T6G_MB_LIB.T6G(SCH_1):PAGE154

P3V3_AUX_DSC @T6G_MB_LIB.T6G(SCH_1):P3V3_AUX_DSC
 R1481    2      B Q_RES_2512LF-10,1%,2W,EMPTY,CS0100AFR00    I21 @T6G_MB_LIB.T6G(SCH_1):PAGE146
 Q7003    5      5 MOSFET_NCH_1D3S-PSMNR58-30YLH,SMLF,EMPTY,BAMNR5800A    I22 @T6G_MB_LIB.T6G(SCH_1):PAGE146

P3V3_AUX_DSC_G1 @T6G_MB_LIB.T6G(SCH_1):P3V3_AUX_DSC_G1
 Q7002    G      G MOSFET_PCH_GDS_ESD_PROTECTED-DMP2035U-7,SMLF,EMPTYA    I23 @T6G_MB_LIB.T6G(SCH_1):PAGE146
 R1052    2      B Q_RES_0402LF-1K,1%,1/16W,EMPTY,CS21002FB06    I38 @T6G_MB_LIB.T6G(SCH_1):PAGE146
 R1092    1      A Q_RES_0402LF-10M,1%,1/16W,EMPTY,CS61002FB02    I39 @T6G_MB_LIB.T6G(SCH_1):PAGE146

P3V3_AUX_DSC_G2 @T6G_MB_LIB.T6G(SCH_1):P3V3_AUX_DSC_G2
 Q7003    4      4 MOSFET_NCH_1D3S-PSMNR58-30YLH,SMLF,EMPTY,BAMNR5800A    I22 @T6G_MB_LIB.T6G(SCH_1):PAGE146
 Q7002    D      D MOSFET_PCH_GDS_ESD_PROTECTED-DMP2035U-7,SMLF,EMPTYA    I23 @T6G_MB_LIB.T6G(SCH_1):PAGE146
 R1475    1      A Q_RES_0402LF-10K,1%,1/16W,EMPTY,CS31002FB08    I28 @T6G_MB_LIB.T6G(SCH_1):PAGE146

P3V3_AUX_DSC_S1 @T6G_MB_LIB.T6G(SCH_1):P3V3_AUX_DSC_S1
 Q7002    S      S MOSFET_PCH_GDS_ESD_PROTECTED-DMP2035U-7,SMLF,EMPTYA    I23 @T6G_MB_LIB.T6G(SCH_1):PAGE146
   U60    3      C SCHOTTKY_DUAL_12A_3C-BAT54CW,SMLF,EMPTY,BCBAT54CZ13    I25 @T6G_MB_LIB.T6G(SCH_1):PAGE146
 C1114    1      A Q_CAP_C0805-22UF,16V,20%,EMPTY,CH6223MEA00    I30 @T6G_MB_LIB.T6G(SCH_1):PAGE146

P3V3_AUX_DSC_VOL @T6G_MB_LIB.T6G(SCH_1):P3V3_AUX_DSC_VOL
   U60    1      B SCHOTTKY_DUAL_12A_3C-BAT54CW,SMLF,EMPTY,BCBAT54CZ13    I25 @T6G_MB_LIB.T6G(SCH_1):PAGE146
  R896    2      B Q_RES_0402LF-30K,1%,1/16W,EMPTY,CS33002FB02    I35 @T6G_MB_LIB.T6G(SCH_1):PAGE146
  R954    1      A Q_RES_0402LF-11.5K,1%,1/16W,EMPTY,CS31152FB03    I36 @T6G_MB_LIB.T6G(SCH_1):PAGE146

P3V3_AUX_EN @T6G_MB_LIB.T6G(SCH_1):P3V3_AUX_EN
 R3118    1      A Q_RES_0402LF-86.6K,1%,1/16W,EMPTY,CS38662FB05     I2 @T6G_MB_LIB.T6G(SCH_1):PAGE245
 R3117    2      B Q_RES_0402LF-510K,5%,1/16W,EMPTY,CS45102JB03     I4 @T6G_MB_LIB.T6G(SCH_1):PAGE245
PC1870    1      A Q_CAP_0402-0.1UF,25V,10%,EMPTY,CH4104K1B00     I8 @T6G_MB_LIB.T6G(SCH_1):PAGE245
 R1571    2      B Q_RES_0402LF-0,5%,1/16W,CHIP,CS00002JB13    I11 @T6G_MB_LIB.T6G(SCH_1):PAGE245
   PU9   27     EN NCP3284AMNTXG-NCP3284AMNTXG,SMLF,IC,AL003284002    I21 @T6G_MB_LIB.T6G(SCH_1):PAGE245

P3V3_AUX_FB @T6G_MB_LIB.T6G(SCH_1):P3V3_AUX_FB
   PU9   30     FB NCP3284AMNTXG-NCP3284AMNTXG,SMLF,IC,AL003284002    I21 @T6G_MB_LIB.T6G(SCH_1):PAGE245
 PR830    1      A Q_RES_0402LF-15K,0.1%,1/16W,CHIP,CS31502BB03    I51 @T6G_MB_LIB.T6G(SCH_1):PAGE245
 PC569    1      A Q_CAP_0402-10PF,50V,1%,NPO,TMP_QCH0106F0B00    I53 @T6G_MB_LIB.T6G(SCH_1):PAGE245
 PR831    1      A Q_RES_0402LF-47K,0.1%,1/16W,CHIP,CS34702BB05    I54 @T6G_MB_LIB.T6G(SCH_1):PAGE245

P3V3_AUX_ILIM @T6G_MB_LIB.T6G(SCH_1):P3V3_AUX_ILIM
 PR834    1      A Q_RES_0402LF-21.5K,1%,1/16W,CHIP,CS32152FB04    I17 @T6G_MB_LIB.T6G(SCH_1):PAGE245
   PU9    1   ILIM NCP3284AMNTXG-NCP3284AMNTXG,SMLF,IC,AL003284002    I21 @T6G_MB_LIB.T6G(SCH_1):PAGE245

P3V3_AUX_MODE @T6G_MB_LIB.T6G(SCH_1):P3V3_AUX_MODE
   PU9   36 MODE||FSET NCP3284AMNTXG-NCP3284AMNTXG,SMLF,IC,AL003284002    I21 @T6G_MB_LIB.T6G(SCH_1):PAGE245
 PR832    1      A Q_RES_0402LF-0,5%,1/16W,CHIP,CS00002JB13    I10 @T6G_MB_LIB.T6G(SCH_1):PAGE245

P3V3_AUX_SS @T6G_MB_LIB.T6G(SCH_1):P3V3_AUX_SS
 PR833    1      A Q_RES_0402LF-1.5K,1%,1/16W,EMPTY,CS21502FB07    I15 @T6G_MB_LIB.T6G(SCH_1):PAGE245
   PU9   29     SS NCP3284AMNTXG-NCP3284AMNTXG,SMLF,IC,AL003284002    I21 @T6G_MB_LIB.T6G(SCH_1):PAGE245

P3V3_AUX_USB_HUB @T6G_MB_LIB.T6G(SCH_1):P3V3_AUX_USB_HUB
  U268    5 AVDD<0> GL852GOHY60-GL852G-OHY60,SMLF,IC,AL000852001   I100 @T6G_MB_LIB.T6G(SCH_1):PAGE358
  U268    9 AVDD<1> GL852GOHY60-GL852G-OHY60,SMLF,IC,AL000852001   I100 @T6G_MB_LIB.T6G(SCH_1):PAGE358
  U268   14 AVDD<2> GL852GOHY60-GL852G-OHY60,SMLF,IC,AL000852001   I100 @T6G_MB_LIB.T6G(SCH_1):PAGE358
  U268   27     V5 GL852GOHY60-GL852G-OHY60,SMLF,IC,AL000852001   I100 @T6G_MB_LIB.T6G(SCH_1):PAGE358
  U268   28    V33 GL852GOHY60-GL852G-OHY60,SMLF,IC,AL000852001   I100 @T6G_MB_LIB.T6G(SCH_1):PAGE358
 C2034    1      A Q_CAP_0402-0.1UF,25V,10%,X7R,CH4104K1B00   I142 @T6G_MB_LIB.T6G(SCH_1):PAGE358
 C2033    1      A Q_CAP_0402-0.1UF,25V,10%,X7R,CH4104K1B00   I143 @T6G_MB_LIB.T6G(SCH_1):PAGE358
 C2032    1      A Q_CAP_0402-0.1UF,25V,10%,X7R,CH4104K1B00   I145 @T6G_MB_LIB.T6G(SCH_1):PAGE358
 C2035    1      A Q_CAP_C0402-1UF,25V,10%,X6S,CH5104KEB02   I147 @T6G_MB_LIB.T6G(SCH_1):PAGE358
 C2031    1      A Q_CAP_C0402-1UF,25V,10%,X6S,CH5104KEB02   I148 @T6G_MB_LIB.T6G(SCH_1):PAGE358
 R3655    2      B Q_RES_0402LF-0,5%,1/16W,CHIP,CS00002JB13   I161 @T6G_MB_LIB.T6G(SCH_1):PAGE358
 C2040    1      A Q_CAP_0402-0.1UF,25V,10%,X7R,CH4104K1B00   I162 @T6G_MB_LIB.T6G(SCH_1):PAGE358
 C2039    1      A Q_CAP_0402-0.1UF,25V,10%,X7R,CH4104K1B00   I163 @T6G_MB_LIB.T6G(SCH_1):PAGE358
 C2038    1      A Q_CAP_C0402-10UF,6.3V,20%,X6S,CH6101MEB01   I164 @T6G_MB_LIB.T6G(SCH_1):PAGE358
 R3662    1      A Q_RES_0402LF-0,5%,1/16W,CHIP,CS00002JB13   I167 @T6G_MB_LIB.T6G(SCH_1):PAGE358

P3V3_AUX_VCC @T6G_MB_LIB.T6G(SCH_1):P3V3_AUX_VCC
PR8389    2      B Q_RES_0402LF-1,1%,1/16W,CHIP,CS-1002FB04    I20 @T6G_MB_LIB.T6G(SCH_1):PAGE245
   PU9    4    VCC NCP3284AMNTXG-NCP3284AMNTXG,SMLF,IC,AL003284002    I21 @T6G_MB_LIB.T6G(SCH_1):PAGE245
 PC591    1      A Q_CAP_C0603-2.2UF,16V,10%,X6S,CH5223KE901    I19 @T6G_MB_LIB.T6G(SCH_1):PAGE245

P3V3_AUX_VDRV @T6G_MB_LIB.T6G(SCH_1):P3V3_AUX_VDRV
PR8389    1      A Q_RES_0402LF-1,1%,1/16W,CHIP,CS-1002FB04    I20 @T6G_MB_LIB.T6G(SCH_1):PAGE245
   PU9    5   VDRV NCP3284AMNTXG-NCP3284AMNTXG,SMLF,IC,AL003284002    I21 @T6G_MB_LIB.T6G(SCH_1):PAGE245
 PC581    1      A Q_CAP_C0603-4.7UF,16V,10%,X6S,CH5473KE902    I12 @T6G_MB_LIB.T6G(SCH_1):PAGE245

P3V3_AUX_VOS @T6G_MB_LIB.T6G(SCH_1):P3V3_AUX_VOS
   PU9   28    VOS NCP3284AMNTXG-NCP3284AMNTXG,SMLF,IC,AL003284002    I21 @T6G_MB_LIB.T6G(SCH_1):PAGE245
 PR836    1      A Q_RES_0402LF-1K,1%,1/16W,CHIP,CS21002FB06    I46 @T6G_MB_LIB.T6G(SCH_1):PAGE245

P3V3_E1S_0 @T6G_MB_LIB.T6G(SCH_1):P3V3_E1S_0
 R3532    1      A Q_RES_0402LF-4.7K,5%,1/16W,CHIP,CS24702JB10    I78 @T6G_MB_LIB.T6G(SCH_1):PAGE346
 R3530    1      A Q_RES_0402LF-4.7K,5%,1/16W,CHIP,CS24702JB10    I80 @T6G_MB_LIB.T6G(SCH_1):PAGE346
 C1998    1      A Q_CAP_0402-0.1UF,25V,10%,X7R,CH4104K1B00    I82 @T6G_MB_LIB.T6G(SCH_1):PAGE346
  U279    1   VCCA PCA9617ADP-PCA9617ADP,SMLF,IC,AL009617K02    I93 @T6G_MB_LIB.T6G(SCH_1):PAGE346
 R3760    1      A Q_RES_0402LF-10,1%,1/16W,CHIP,CS01002FB07   I134 @T6G_MB_LIB.T6G(SCH_1):PAGE295
 R3767    1      A Q_RES_2512LF-0.002,1%,2W,CHIP,CS+002AFR06   I144 @T6G_MB_LIB.T6G(SCH_1):PAGE295
 R2317    1      A Q_RES_0402LF-10K,1%,1/16W,CHIP,CS31002FB08    I31 @T6G_MB_LIB.T6G(SCH_1):PAGE297
R10287    1      A Q_RES_0402LF-10K,1%,1/16W,CHIP,CS31002FB08    I79 @T6G_MB_LIB.T6G(SCH_1):PAGE297
 C1282    1      A Q_CAP_0402-0.1UF,25V,10%,X7R,CH4104K1B00    I87 @T6G_MB_LIB.T6G(SCH_1):PAGE297
 C1283    1      A Q_CAP_0402-0.1UF,25V,10%,X7R,CH4104K1B00    I88 @T6G_MB_LIB.T6G(SCH_1):PAGE297
   J90  B11 P3V3_AUX SCONN56_123276793-SCONN56_1-2327679-3,SMLF,IO,DFHSA    I90 @T6G_MB_LIB.T6G(SCH_1):PAGE297
   U44    5    VCC 74LVC1G17GW-74LVC1G17GW,SMLF,IC,AL1G0017K01    I97 @T6G_MB_LIB.T6G(SCH_1):PAGE297
  C508    1      A Q_CAP_0402-0.1UF,25V,10%,X7R,CH4104K1B00    I99 @T6G_MB_LIB.T6G(SCH_1):PAGE297
 R1673    1      A Q_RES_0402LF-10K,1%,1/16W,CHIP,CS31002FB08   I105 @T6G_MB_LIB.T6G(SCH_1):PAGE297

P3V3_E1S_0_EN_G @T6G_MB_LIB.T6G(SCH_1):P3V3_E1S_0_EN_G
  Q126    6     D1 MOSFET_NCH_DUAL-PJT138K,SMLF,IC,BAM138K0003     I6 @T6G_MB_LIB.T6G(SCH_1):PAGE324
  Q126    5     G2 MOSFET_NCH_DUAL-PJT138K,SMLF,IC,BAM138K0003     I7 @T6G_MB_LIB.T6G(SCH_1):PAGE324
 R4072    2      B Q_RES_0402LF-10K,1%,1/16W,CHIP,CS31002FB08     I8 @T6G_MB_LIB.T6G(SCH_1):PAGE324

P3V3_E1S_0_EN_R @T6G_MB_LIB.T6G(SCH_1):P3V3_E1S_0_EN_R
  R648    2      B Q_RES_0402LF-33,5%,1/16W,CHIP,CS03302JB10    I25 @T6G_MB_LIB.T6G(SCH_1):PAGE80
   U18  V12  PB27D LCMXO3LF9400C5BG484C-LCMXO3LF-9400C-5BG484C,SMLF,IA   I216 @T6G_MB_LIB.T6G(SCH_1):PAGE80

P3V3_E1S_0_R @T6G_MB_LIB.T6G(SCH_1):P3V3_E1S_0_R
 PU293  6_7 SOURCE MP5016GQHLZ-MP5016GQH-L-Z,SMLF,IC,AL005016007    I31 @T6G_MB_LIB.T6G(SCH_1):PAGE323
PC2204    1      A Q_CAP_C0805-10UF,16V,10%,X6S,CH6103KEA01    I34 @T6G_MB_LIB.T6G(SCH_1):PAGE323
PC2213    1      A Q_CAP_C0402-0.01UF,50V,10%,EMPTY,CH31006KB18    I46 @T6G_MB_LIB.T6G(SCH_1):PAGE324
PR4527    1      A Q_RES_0402LF-10M,1%,1/16W,CHIP,CS61002FB02    I47 @T6G_MB_LIB.T6G(SCH_1):PAGE324
 PD113    C      C SCHOTTKY_AC-B340A-13-F,SMLF,IC,BC000340Z30    I50 @T6G_MB_LIB.T6G(SCH_1):PAGE324
PC2220    1      A Q_CAP_C0805-10UF,16V,10%,X6S,CH6103KEA01    I58 @T6G_MB_LIB.T6G(SCH_1):PAGE324
  U276   11   VBUS ISL28022FRZT-ISL28022FRZ-T,SMLF,IC,AL028022003   I129 @T6G_MB_LIB.T6G(SCH_1):PAGE295
 R3758    1      A Q_RES_0402LF-10,1%,1/16W,CHIP,CS01002FB07   I132 @T6G_MB_LIB.T6G(SCH_1):PAGE295
 C2069    1      A Q_CAP_0402-0.1UF,25V,10%,X7R,CH4104K1B00   I142 @T6G_MB_LIB.T6G(SCH_1):PAGE295
 R3767    2      B Q_RES_2512LF-0.002,1%,2W,CHIP,CS+002AFR06   I144 @T6G_MB_LIB.T6G(SCH_1):PAGE295
PC2218    1      A Q_CAP_0402-0.1UF,25V,10%,X7R,CH4104K1B00    I57 @T6G_MB_LIB.T6G(SCH_1):PAGE324
 PU295   A4 OUT_A4 MAX15090BEWIT-MAX15090BEWI+T,SMLF,IC,AL015080B00    I88 @T6G_MB_LIB.T6G(SCH_1):PAGE324
 PU295   B4 OUT_B4 MAX15090BEWIT-MAX15090BEWI+T,SMLF,IC,AL015080B00    I88 @T6G_MB_LIB.T6G(SCH_1):PAGE324
 PU295   B6 OUT_B6 MAX15090BEWIT-MAX15090BEWI+T,SMLF,IC,AL015080B00    I88 @T6G_MB_LIB.T6G(SCH_1):PAGE324
 PU295   C4 OUT_C4 MAX15090BEWIT-MAX15090BEWI+T,SMLF,IC,AL015080B00    I88 @T6G_MB_LIB.T6G(SCH_1):PAGE324
 PU295   C6 OUT_C6 MAX15090BEWIT-MAX15090BEWI+T,SMLF,IC,AL015080B00    I88 @T6G_MB_LIB.T6G(SCH_1):PAGE324
 PU295   D4 OUT_D4 MAX15090BEWIT-MAX15090BEWI+T,SMLF,IC,AL015080B00    I88 @T6G_MB_LIB.T6G(SCH_1):PAGE324
 PU295   D6 OUT_D6 MAX15090BEWIT-MAX15090BEWI+T,SMLF,IC,AL015080B00    I88 @T6G_MB_LIB.T6G(SCH_1):PAGE324
 C8010    1      A Q_CAP_0402-0.1UF,25V,10%,X7R,CH4104K1B00    I64 @T6G_MB_LIB.T6G(SCH_1):PAGE323
 U8003    3    VCC APX80929SAG7-APX809-29SAG-7,SMLF,IC,AL080929000    I65 @T6G_MB_LIB.T6G(SCH_1):PAGE323
 R8098    1      A Q_RES_0402LF-10K,5%,1/16W,EMPTY,CS31002JB08    I70 @T6G_MB_LIB.T6G(SCH_1):PAGE323

P3V3_E1S_CB_0 @T6G_MB_LIB.T6G(SCH_1):P3V3_E1S_CB_0
PR3969    1      A Q_RES_0402LF-2.49K,1%,1/16W,CHIP,CS22492FB05    I39 @T6G_MB_LIB.T6G(SCH_1):PAGE324
 PU295   B1     CB MAX15090BEWIT-MAX15090BEWI+T,SMLF,IC,AL015080B00    I88 @T6G_MB_LIB.T6G(SCH_1):PAGE324

P3V3_E1S_DVDT_0 @T6G_MB_LIB.T6G(SCH_1):P3V3_E1S_DVDT_0
PC2201    1      A Q_CAP_0402-0.068UF,16V,10%,X7R,CH3683K1B09    I30 @T6G_MB_LIB.T6G(SCH_1):PAGE323
 PU293   10  DV_DT MP5016GQHLZ-MP5016GQH-L-Z,SMLF,IC,AL005016007    I31 @T6G_MB_LIB.T6G(SCH_1):PAGE323

P3V3_E1S_EN_0_R @T6G_MB_LIB.T6G(SCH_1):P3V3_E1S_EN_0_R
 R4063    2      B Q_RES_0402LF-0,5%,1/16W,CHIP,CS00002JB13     I2 @T6G_MB_LIB.T6G(SCH_1):PAGE324
 R6049    1      A Q_RES_0402LF-4.7K,5%,1/16W,CHIP,CS24702JB10     I4 @T6G_MB_LIB.T6G(SCH_1):PAGE324
  Q126    2     G1 MOSFET_NCH_DUAL-PJT138K,SMLF,IC,BAM138K0003     I6 @T6G_MB_LIB.T6G(SCH_1):PAGE324

P3V3_E1S_EN_0_R2 @T6G_MB_LIB.T6G(SCH_1):P3V3_E1S_EN_0_R2
 R3946    2      B Q_RES_0402LF-0,5%,1/16W,CHIP,CS00002JB13     I5 @T6G_MB_LIB.T6G(SCH_1):PAGE323
 PU293    9     EN MP5016GQHLZ-MP5016GQH-L-Z,SMLF,IC,AL005016007    I31 @T6G_MB_LIB.T6G(SCH_1):PAGE323

P3V3_E1S_FAULT_0 @T6G_MB_LIB.T6G(SCH_1):P3V3_E1S_FAULT_0
 R3977    2      B Q_RES_0402LF-100K,1%,1/16W,CHIP,CS41002FB09    I52 @T6G_MB_LIB.T6G(SCH_1):PAGE324
 PU295   C7 FAULT# MAX15090BEWIT-MAX15090BEWI+T,SMLF,IC,AL015080B00    I88 @T6G_MB_LIB.T6G(SCH_1):PAGE324

P3V3_E1S_GATE_0 @T6G_MB_LIB.T6G(SCH_1):P3V3_E1S_GATE_0
PC2213    2      B Q_CAP_C0402-0.01UF,50V,10%,EMPTY,CH31006KB18    I46 @T6G_MB_LIB.T6G(SCH_1):PAGE324
PR4527    2      B Q_RES_0402LF-10M,1%,1/16W,CHIP,CS61002FB02    I47 @T6G_MB_LIB.T6G(SCH_1):PAGE324
PC2216    1      A Q_CAP_C0402-6800PF,50V,10%,X7R,CH2686K1B01    I49 @T6G_MB_LIB.T6G(SCH_1):PAGE324
 PU295   A6   GATE MAX15090BEWIT-MAX15090BEWI+T,SMLF,IC,AL015080B00    I88 @T6G_MB_LIB.T6G(SCH_1):PAGE324

P3V3_E1S_GATE_0_PU293 @T6G_MB_LIB.T6G(SCH_1):P3V3_E1S_GATE_0_PU293
 PU293    8   GATE MP5016GQHLZ-MP5016GQH-L-Z,SMLF,IC,AL005016007    I31 @T6G_MB_LIB.T6G(SCH_1):PAGE323
PC2203    1      A Q_CAP_0402-100PF,50V,5%,X7R,CH11006JB18    I32 @T6G_MB_LIB.T6G(SCH_1):PAGE323

P3V3_E1S_ILIMIT_0 @T6G_MB_LIB.T6G(SCH_1):P3V3_E1S_ILIMIT_0
PR3947    2      B Q_RES_0402LF-2.8K,1%,1/16W,CHIP,CS22802FB04     I6 @T6G_MB_LIB.T6G(SCH_1):PAGE323
 PU293    4 ILIMIT MP5016GQHLZ-MP5016GQH-L-Z,SMLF,IC,AL005016007    I31 @T6G_MB_LIB.T6G(SCH_1):PAGE323

P3V3_E1S_MODE_0 @T6G_MB_LIB.T6G(SCH_1):P3V3_E1S_MODE_0
PC2197    1      A Q_CAP_0402-39PF,50V,5%,NPO,CH03906JB06     I3 @T6G_MB_LIB.T6G(SCH_1):PAGE323
PR3945    1      A Q_RES_0402LF-71.5K,1%,1/16W,CHIP,CS37152FB05     I4 @T6G_MB_LIB.T6G(SCH_1):PAGE323
 PU293    5   MODE MP5016GQHLZ-MP5016GQH-L-Z,SMLF,IC,AL005016007    I31 @T6G_MB_LIB.T6G(SCH_1):PAGE323

P3V3_E1S_OV_0 @T6G_MB_LIB.T6G(SCH_1):P3V3_E1S_OV_0
PR3965    1      A Q_RES_0402LF-15K,1%,1/16W,CHIP,CS31502FB05    I16 @T6G_MB_LIB.T6G(SCH_1):PAGE324
PR3964    2      B Q_RES_0402LF-7.15K,1%,1/16W,CHIP,CS27152FB03    I17 @T6G_MB_LIB.T6G(SCH_1):PAGE324
 PU295   D3     OV MAX15090BEWIT-MAX15090BEWI+T,SMLF,IC,AL015080B00    I88 @T6G_MB_LIB.T6G(SCH_1):PAGE324

P3V3_E1S_PWRGD_0 @T6G_MB_LIB.T6G(SCH_1):P3V3_E1S_PWRGD_0
 R3973    1      A Q_RES_0402LF-0,5%,1/16W,CHIP,CS00002JB13    I48 @T6G_MB_LIB.T6G(SCH_1):PAGE324
 PU295   D7     PG MAX15090BEWIT-MAX15090BEWI+T,SMLF,IC,AL015080B00    I88 @T6G_MB_LIB.T6G(SCH_1):PAGE324

P3V3_E1S_PWRGD_0_R @T6G_MB_LIB.T6G(SCH_1):P3V3_E1S_PWRGD_0_R
 R3973    2      B Q_RES_0402LF-0,5%,1/16W,CHIP,CS00002JB13    I48 @T6G_MB_LIB.T6G(SCH_1):PAGE324
 R3979    2      B Q_RES_0402LF-100K,1%,1/16W,CHIP,CS41002FB09    I54 @T6G_MB_LIB.T6G(SCH_1):PAGE324
   U18  U11  PB22D LCMXO3LF9400C5BG484C-LCMXO3LF-9400C-5BG484C,SMLF,IA   I216 @T6G_MB_LIB.T6G(SCH_1):PAGE80
 R8100    2      B Q_RES_0402LF-0,5%,1/16W,CHIP,CS00002JB13    I71 @T6G_MB_LIB.T6G(SCH_1):PAGE323

P3V3_E1S_PWRGD_0_R1 @T6G_MB_LIB.T6G(SCH_1):P3V3_E1S_PWRGD_0_R1
 U8003    2 RESET_L APX80929SAG7-APX809-29SAG-7,SMLF,IC,AL080929000    I65 @T6G_MB_LIB.T6G(SCH_1):PAGE323
 R8099    1      A Q_RES_0402LF-100K,1%,1/16W,CHIP,CS41002FB09    I68 @T6G_MB_LIB.T6G(SCH_1):PAGE323
 R8098    2      B Q_RES_0402LF-10K,5%,1/16W,EMPTY,CS31002JB08    I70 @T6G_MB_LIB.T6G(SCH_1):PAGE323
 R8100    1      A Q_RES_0402LF-0,5%,1/16W,CHIP,CS00002JB13    I71 @T6G_MB_LIB.T6G(SCH_1):PAGE323

P3V3_E1S_REG_0 @T6G_MB_LIB.T6G(SCH_1):P3V3_E1S_REG_0
PC2212    2      B Q_CAP_C0402-1UF,25V,10%,X6S,CH5104KEB02    I42 @T6G_MB_LIB.T6G(SCH_1):PAGE324
 PU295   D1    REG MAX15090BEWIT-MAX15090BEWI+T,SMLF,IC,AL015080B00    I88 @T6G_MB_LIB.T6G(SCH_1):PAGE324

P3V3_E1S_SENSE_0 @T6G_MB_LIB.T6G(SCH_1):P3V3_E1S_SENSE_0
PR3971    1      A Q_RES_0402LF-9.76K,1%,1/16W,CHIP,CS29762FB05    I45 @T6G_MB_LIB.T6G(SCH_1):PAGE324
 PU295   A1 ISENSE MAX15090BEWIT-MAX15090BEWI+T,SMLF,IC,AL015080B00    I88 @T6G_MB_LIB.T6G(SCH_1):PAGE324

P3V3_E1S_UV_0 @T6G_MB_LIB.T6G(SCH_1):P3V3_E1S_UV_0
PR3964    1      A Q_RES_0402LF-7.15K,1%,1/16W,CHIP,CS27152FB03    I17 @T6G_MB_LIB.T6G(SCH_1):PAGE324
PR3963    2      B Q_RES_0402LF-25.5K,1%,1/16W,CHIP,CS32552FB06    I21 @T6G_MB_LIB.T6G(SCH_1):PAGE324
 R3959    2      B Q_RES_0402LF-0,5%,1/16W,CHIP,CS00002JB13    I18 @T6G_MB_LIB.T6G(SCH_1):PAGE324
 PU295   D2     UV MAX15090BEWIT-MAX15090BEWI+T,SMLF,IC,AL015080B00    I88 @T6G_MB_LIB.T6G(SCH_1):PAGE324

P3V3_E1S_UV_0_R @T6G_MB_LIB.T6G(SCH_1):P3V3_E1S_UV_0_R
  Q126    3     D2 MOSFET_NCH_DUAL-PJT138K,SMLF,IC,BAM138K0003     I7 @T6G_MB_LIB.T6G(SCH_1):PAGE324
 R3959    1      A Q_RES_0402LF-0,5%,1/16W,CHIP,CS00002JB13    I18 @T6G_MB_LIB.T6G(SCH_1):PAGE324

P3V3_E1S_VCC_0 @T6G_MB_LIB.T6G(SCH_1):P3V3_E1S_VCC_0
PC2210    1      A Q_CAP_C0402-1UF,25V,10%,X6S,CH5104KEB02    I41 @T6G_MB_LIB.T6G(SCH_1):PAGE324
PR3967    2      B Q_RES_0402LF-10,1%,1/16W,CHIP,CS01002FB07    I43 @T6G_MB_LIB.T6G(SCH_1):PAGE324
 PU295   A2    VCC MAX15090BEWIT-MAX15090BEWI+T,SMLF,IC,AL015080B00    I88 @T6G_MB_LIB.T6G(SCH_1):PAGE324

P3V3_M2_0 @T6G_MB_LIB.T6G(SCH_1):P3V3_M2_0
   J59    2 3.3V_1 SCONN75K_APCI0155P004A-SCONN75K_APCI0155-P004A,SMLA    I88 @T6G_MB_LIB.T6G(SCH_1):PAGE345
   J59    4 3.3V_2 SCONN75K_APCI0155P004A-SCONN75K_APCI0155-P004A,SMLA    I88 @T6G_MB_LIB.T6G(SCH_1):PAGE345
   J59   12 3.3V_3 SCONN75K_APCI0155P004A-SCONN75K_APCI0155-P004A,SMLA    I88 @T6G_MB_LIB.T6G(SCH_1):PAGE345
   J59   14 3.3V_4 SCONN75K_APCI0155P004A-SCONN75K_APCI0155-P004A,SMLA    I88 @T6G_MB_LIB.T6G(SCH_1):PAGE345
   J59   16 3.3V_5 SCONN75K_APCI0155P004A-SCONN75K_APCI0155-P004A,SMLA    I88 @T6G_MB_LIB.T6G(SCH_1):PAGE345
   J59   18 3.3V_6 SCONN75K_APCI0155P004A-SCONN75K_APCI0155-P004A,SMLA    I88 @T6G_MB_LIB.T6G(SCH_1):PAGE345
   J59   70 3.3V_7 SCONN75K_APCI0155P004A-SCONN75K_APCI0155-P004A,SMLA    I88 @T6G_MB_LIB.T6G(SCH_1):PAGE345
   J59   72 3.3V_8 SCONN75K_APCI0155P004A-SCONN75K_APCI0155-P004A,SMLA    I88 @T6G_MB_LIB.T6G(SCH_1):PAGE345
   J59   74 3.3V_9 SCONN75K_APCI0155P004A-SCONN75K_APCI0155-P004A,SMLA    I88 @T6G_MB_LIB.T6G(SCH_1):PAGE345
 R3575    1      A Q_RES_0402LF-10,1%,1/16W,CHIP,CS01002FB07    I33 @T6G_MB_LIB.T6G(SCH_1):PAGE360
 R3634    1      A Q_RES_2512LF-0.002,1%,2W,CHIP,CS+002AFR06    I92 @T6G_MB_LIB.T6G(SCH_1):PAGE360
 R3295    1      A Q_RES_0402LF-4.7K,1%,1/16W,CHIP,CS24702FB06    I21 @T6G_MB_LIB.T6G(SCH_1):PAGE345
 C1920    1      A Q_CAP_C0603-22UF,6.3V,20%,X6S,CH6221ME900    I77 @T6G_MB_LIB.T6G(SCH_1):PAGE345
 C1921    1      A Q_CAP_C0603-22UF,6.3V,20%,X6S,CH6221ME900    I78 @T6G_MB_LIB.T6G(SCH_1):PAGE345
 C9922    1      A Q_CAP_C0603-22UF,6.3V,20%,X6S,CH6221ME900    I79 @T6G_MB_LIB.T6G(SCH_1):PAGE345
 C1923    1      A Q_CAP_0402-0.1UF,25V,10%,X7R,CH4104K1B00    I84 @T6G_MB_LIB.T6G(SCH_1):PAGE345
 C1924    1      A Q_CAP_0402-0.1UF,25V,10%,X7R,CH4104K1B00    I85 @T6G_MB_LIB.T6G(SCH_1):PAGE345
 C1925    1      A Q_CAP_0402-0.1UF,25V,10%,X7R,CH4104K1B00    I86 @T6G_MB_LIB.T6G(SCH_1):PAGE345

P3V3_MAX11617_2_VDD @T6G_MB_LIB.T6G(SCH_1):P3V3_MAX11617_2_VDD
   U50   16    VDD MAX11617EEET-MAX11617EEE+T,SMLF,EMPTY,AL011617W00   I156 @T6G_MB_LIB.T6G(SCH_1):PAGE263
 C1075    1      A Q_CAP_0402-0.1UF,25V,10%,X7R,CH4104K1B00   I165 @T6G_MB_LIB.T6G(SCH_1):PAGE263
 C1077    1      A Q_CAP_C0805-10UF,16V,10%,X6S,CH6103KEA00   I166 @T6G_MB_LIB.T6G(SCH_1):PAGE263
   L24    1      1 Q_INDUCTOR_SMLF-BLM18PG300SN1D ,IND,TMP_QCX8PG3000A   I168 @T6G_MB_LIB.T6G(SCH_1):PAGE263

P3V3_MAX11617_VDD @T6G_MB_LIB.T6G(SCH_1):P3V3_MAX11617_VDD
 C1757    1      A Q_CAP_0402-0.1UF,25V,10%,X7R,CH4104K1B00   I162 @T6G_MB_LIB.T6G(SCH_1):PAGE369
 C1768    1      A Q_CAP_C0805-10UF,16V,10%,X6S,CH6103KEA00   I166 @T6G_MB_LIB.T6G(SCH_1):PAGE369
   L15    1      1 Q_INDUCTOR_SMLF-BLM18PG300SN1D ,IND,TMP_QCX8PG3000A   I167 @T6G_MB_LIB.T6G(SCH_1):PAGE369
  U193   16    VDD MAX11617EEET-MAX11617EEE+T,SMLF,EMPTY,AL011617W00   I169 @T6G_MB_LIB.T6G(SCH_1):PAGE369

P3V3_OCP_1_EN_G @T6G_MB_LIB.T6G(SCH_1):P3V3_OCP_1_EN_G
  Q124    6     D1 MOSFET_NCH_DUAL-PJT138K,SMLF,IC,BAM138K0003    I23 @T6G_MB_LIB.T6G(SCH_1):PAGE338
 R4070    2      B Q_RES_0402LF-10K,1%,1/16W,CHIP,CS31002FB08    I59 @T6G_MB_LIB.T6G(SCH_1):PAGE338
  Q124    5     G2 MOSFET_NCH_DUAL-PJT138K,SMLF,IC,BAM138K0003   I112 @T6G_MB_LIB.T6G(SCH_1):PAGE338

P3V3_OCP_2_EN_G @T6G_MB_LIB.T6G(SCH_1):P3V3_OCP_2_EN_G
  Q119    6     D1 MOSFET_NCH_DUAL-PJT138K,SMLF,IC,BAM138K0003    I42 @T6G_MB_LIB.T6G(SCH_1):PAGE343
 R4067    2      B Q_RES_0402LF-10K,1%,1/16W,CHIP,CS31002FB08    I43 @T6G_MB_LIB.T6G(SCH_1):PAGE343
  Q119    5     G2 MOSFET_NCH_DUAL-PJT138K,SMLF,IC,BAM138K0003    I45 @T6G_MB_LIB.T6G(SCH_1):PAGE343

P3V3_OCP_CB_1 @T6G_MB_LIB.T6G(SCH_1):P3V3_OCP_CB_1
PR3780    1      A Q_RES_0402LF-5.36K,1%,1/16W,CHIP,CS25362FB02   I111 @T6G_MB_LIB.T6G(SCH_1):PAGE338
 PU202   B1     CB MAX15090BEWIT-MAX15090BEWI+T,SMLF,IC,AL015080B00   I113 @T6G_MB_LIB.T6G(SCH_1):PAGE338

P3V3_OCP_CB_2 @T6G_MB_LIB.T6G(SCH_1):P3V3_OCP_CB_2
PR3822    1      A Q_RES_0402LF-5.36K,1%,1/16W,CHIP,CS25362FB02    I88 @T6G_MB_LIB.T6G(SCH_1):PAGE343
 PU200   B1     CB MAX15090BEWIT-MAX15090BEWI+T,SMLF,IC,AL015080B00    I89 @T6G_MB_LIB.T6G(SCH_1):PAGE343

P3V3_OCP_DVDT_1 @T6G_MB_LIB.T6G(SCH_1):P3V3_OCP_DVDT_1
PC2161    1      A Q_CAP_0402-0.068UF,16V,10%,X7R,CH3683K1B09   I104 @T6G_MB_LIB.T6G(SCH_1):PAGE339
 PU205   10  DV_DT MP5016GQHLZ-MP5016GQH-L-Z,SMLF,IC,AL005016007   I113 @T6G_MB_LIB.T6G(SCH_1):PAGE339

P3V3_OCP_DVDT_2 @T6G_MB_LIB.T6G(SCH_1):P3V3_OCP_DVDT_2
PC1321    1      A Q_CAP_0402-0.068UF,16V,10%,X7R,CH3683K1B09    I50 @T6G_MB_LIB.T6G(SCH_1):PAGE344
 PU207   10  DV_DT MP5016GQHLZ-MP5016GQH-L-Z,SMLF,IC,AL005016007    I51 @T6G_MB_LIB.T6G(SCH_1):PAGE344

P3V3_OCP_EN_1_R @T6G_MB_LIB.T6G(SCH_1):P3V3_OCP_EN_1_R
  Q124    2     G1 MOSFET_NCH_DUAL-PJT138K,SMLF,IC,BAM138K0003    I23 @T6G_MB_LIB.T6G(SCH_1):PAGE338
 R5487    2      B Q_RES_0402LF-0,5%,1/16W,EMPTY,CS00002JB13   I126 @T6G_MB_LIB.T6G(SCH_1):PAGE338
 R4069    1      A Q_RES_0402LF-4.7K,5%,1/16W,EMPTY,CS24702JB10   I127 @T6G_MB_LIB.T6G(SCH_1):PAGE338
 R1136    2      B Q_RES_0402LF-0,5%,1/16W,EMPTY,CS00002JB13   I133 @T6G_MB_LIB.T6G(SCH_1):PAGE338
 R1486    2      B Q_RES_0402LF-0,5%,1/16W,CHIP,CS00002JB13   I135 @T6G_MB_LIB.T6G(SCH_1):PAGE338

P3V3_OCP_EN_1_R2 @T6G_MB_LIB.T6G(SCH_1):P3V3_OCP_EN_1_R2
 PU205    9     EN MP5016GQHLZ-MP5016GQH-L-Z,SMLF,IC,AL005016007   I113 @T6G_MB_LIB.T6G(SCH_1):PAGE339
 R3845    2      B Q_RES_0402LF-0,5%,1/16W,EMPTY,CS00002JB13   I131 @T6G_MB_LIB.T6G(SCH_1):PAGE339
 R1487    2      B Q_RES_0402LF-0,5%,1/16W,CHIP,CS00002JB13   I134 @T6G_MB_LIB.T6G(SCH_1):PAGE339
 R1137    2      B Q_RES_0402LF-0,5%,1/16W,EMPTY,CS00002JB13   I135 @T6G_MB_LIB.T6G(SCH_1):PAGE339

P3V3_OCP_EN_2 @T6G_MB_LIB.T6G(SCH_1):P3V3_OCP_EN_2
 PU207    9     EN MP5016GQHLZ-MP5016GQH-L-Z,SMLF,IC,AL005016007    I51 @T6G_MB_LIB.T6G(SCH_1):PAGE344
 R3631    2      B Q_RES_0402LF-0,5%,1/16W,EMPTY,CS00002JB13    I74 @T6G_MB_LIB.T6G(SCH_1):PAGE344
 R1196    2      B Q_RES_0402LF-0,5%,1/16W,EMPTY,CS00002JB13    I79 @T6G_MB_LIB.T6G(SCH_1):PAGE344
 R1521    2      B Q_RES_0402LF-0,5%,1/16W,CHIP,CS00002JB13    I80 @T6G_MB_LIB.T6G(SCH_1):PAGE344

P3V3_OCP_EN_2_R @T6G_MB_LIB.T6G(SCH_1):P3V3_OCP_EN_2_R
  Q119    2     G1 MOSFET_NCH_DUAL-PJT138K,SMLF,IC,BAM138K0003    I42 @T6G_MB_LIB.T6G(SCH_1):PAGE343
 R4066    1      A Q_RES_0402LF-4.7K,5%,1/16W,EMPTY,CS24702JB10   I121 @T6G_MB_LIB.T6G(SCH_1):PAGE343
 R4060    2      B Q_RES_0402LF-0,5%,1/16W,EMPTY,CS00002JB13   I122 @T6G_MB_LIB.T6G(SCH_1):PAGE343
 R1182    2      B Q_RES_0402LF-0,5%,1/16W,EMPTY,CS00002JB13   I129 @T6G_MB_LIB.T6G(SCH_1):PAGE343
 R1520    2      B Q_RES_0402LF-0,5%,1/16W,CHIP,CS00002JB13   I130 @T6G_MB_LIB.T6G(SCH_1):PAGE343

P3V3_OCP_FAULT_1 @T6G_MB_LIB.T6G(SCH_1):P3V3_OCP_FAULT_1
 R3796    2      B Q_RES_0402LF-100K,1%,1/16W,CHIP,CS41002FB09   I101 @T6G_MB_LIB.T6G(SCH_1):PAGE338
 PU202   C7 FAULT# MAX15090BEWIT-MAX15090BEWI+T,SMLF,IC,AL015080B00   I113 @T6G_MB_LIB.T6G(SCH_1):PAGE338

P3V3_OCP_FAULT_2 @T6G_MB_LIB.T6G(SCH_1):P3V3_OCP_FAULT_2
 PU200   C7 FAULT# MAX15090BEWIT-MAX15090BEWI+T,SMLF,IC,AL015080B00    I89 @T6G_MB_LIB.T6G(SCH_1):PAGE343
 R3833    2      B Q_RES_0402LF-100K,1%,1/16W,CHIP,CS41002FB09   I107 @T6G_MB_LIB.T6G(SCH_1):PAGE343

P3V3_OCP_GATE_1 @T6G_MB_LIB.T6G(SCH_1):P3V3_OCP_GATE_1
PC2162    1      A Q_CAP_0402-100PF,50V,5%,X7R,CH11006JB18   I106 @T6G_MB_LIB.T6G(SCH_1):PAGE339
 PU205    8   GATE MP5016GQHLZ-MP5016GQH-L-Z,SMLF,IC,AL005016007   I113 @T6G_MB_LIB.T6G(SCH_1):PAGE339

P3V3_OCP_GATE_2 @T6G_MB_LIB.T6G(SCH_1):P3V3_OCP_GATE_2
 PU200   A6   GATE MAX15090BEWIT-MAX15090BEWI+T,SMLF,IC,AL015080B00    I89 @T6G_MB_LIB.T6G(SCH_1):PAGE343
PR4523    2      B Q_RES_0402LF-10M,1%,1/16W,CHIP,CS61002FB02   I105 @T6G_MB_LIB.T6G(SCH_1):PAGE343
PC2151    1      A Q_CAP_C0402-6800PF,50V,10%,X7R,CH2686K1B01    I95 @T6G_MB_LIB.T6G(SCH_1):PAGE343
PC2149    2      B Q_CAP_C0402-0.01UF,50V,10%,EMPTY,CH31006KB18   I104 @T6G_MB_LIB.T6G(SCH_1):PAGE343

P3V3_OCP_GATE_PU202_1 @T6G_MB_LIB.T6G(SCH_1):P3V3_OCP_GATE_PU202_1
PC2144    2      B Q_CAP_C0402-0.01UF,50V,10%,EMPTY,CH31006KB18    I94 @T6G_MB_LIB.T6G(SCH_1):PAGE338
PR4525    2      B Q_RES_0402LF-10M,1%,1/16W,CHIP,CS61002FB02    I96 @T6G_MB_LIB.T6G(SCH_1):PAGE338
PC2089    1      A Q_CAP_C0402-6800PF,50V,10%,X7R,CH2686K1B01   I100 @T6G_MB_LIB.T6G(SCH_1):PAGE338
 PU202   A6   GATE MAX15090BEWIT-MAX15090BEWI+T,SMLF,IC,AL015080B00   I113 @T6G_MB_LIB.T6G(SCH_1):PAGE338

P3V3_OCP_GATE_PU207_2 @T6G_MB_LIB.T6G(SCH_1):P3V3_OCP_GATE_PU207_2
 PU207    8   GATE MP5016GQHLZ-MP5016GQH-L-Z,SMLF,IC,AL005016007    I51 @T6G_MB_LIB.T6G(SCH_1):PAGE344
PC1322    1      A Q_CAP_0402-100PF,50V,5%,X7R,CH11006JB18    I54 @T6G_MB_LIB.T6G(SCH_1):PAGE344

P3V3_OCP_ILIMIT_1 @T6G_MB_LIB.T6G(SCH_1):P3V3_OCP_ILIMIT_1
PR3846    2      B Q_RES_0402LF-1.33K,1%,1/16W,CHIP,CS21332FB05   I102 @T6G_MB_LIB.T6G(SCH_1):PAGE339
 PU205    4 ILIMIT MP5016GQHLZ-MP5016GQH-L-Z,SMLF,IC,AL005016007   I113 @T6G_MB_LIB.T6G(SCH_1):PAGE339

P3V3_OCP_ILIMIT_2 @T6G_MB_LIB.T6G(SCH_1):P3V3_OCP_ILIMIT_2
PR3856    2      B Q_RES_0402LF-1.33K,1%,1/16W,CHIP,CS21332FB05    I46 @T6G_MB_LIB.T6G(SCH_1):PAGE344
 PU207    4 ILIMIT MP5016GQHLZ-MP5016GQH-L-Z,SMLF,IC,AL005016007    I51 @T6G_MB_LIB.T6G(SCH_1):PAGE344

P3V3_OCP_MODE_1 @T6G_MB_LIB.T6G(SCH_1):P3V3_OCP_MODE_1
PC2157    1      A Q_CAP_0402-39PF,50V,5%,NPO,CH03906JB06    I98 @T6G_MB_LIB.T6G(SCH_1):PAGE339
PR3844    1      A Q_RES_0402LF-71.5K,1%,1/16W,CHIP,CS37152FB05   I100 @T6G_MB_LIB.T6G(SCH_1):PAGE339
 PU205    5   MODE MP5016GQHLZ-MP5016GQH-L-Z,SMLF,IC,AL005016007   I113 @T6G_MB_LIB.T6G(SCH_1):PAGE339

P3V3_OCP_MODE_2 @T6G_MB_LIB.T6G(SCH_1):P3V3_OCP_MODE_2
PC2168    1      A Q_CAP_0402-39PF,50V,5%,NPO,CH03906JB06    I35 @T6G_MB_LIB.T6G(SCH_1):PAGE344
PR3855    1      A Q_RES_0402LF-71.5K,1%,1/16W,CHIP,CS37152FB05    I43 @T6G_MB_LIB.T6G(SCH_1):PAGE344
 PU207    5   MODE MP5016GQHLZ-MP5016GQH-L-Z,SMLF,IC,AL005016007    I51 @T6G_MB_LIB.T6G(SCH_1):PAGE344

P3V3_OCP_OV_1 @T6G_MB_LIB.T6G(SCH_1):P3V3_OCP_OV_1
PR3790    2      B Q_RES_0402LF-7.15K,1%,1/16W,CHIP,CS27152FB03    I64 @T6G_MB_LIB.T6G(SCH_1):PAGE338
 PU202   D3     OV MAX15090BEWIT-MAX15090BEWI+T,SMLF,IC,AL015080B00   I113 @T6G_MB_LIB.T6G(SCH_1):PAGE338
PR3791    1      A Q_RES_0402LF-15K,1%,1/16W,CHIP,CS31502FB05   I114 @T6G_MB_LIB.T6G(SCH_1):PAGE338

P3V3_OCP_OV_2 @T6G_MB_LIB.T6G(SCH_1):P3V3_OCP_OV_2
PR3812    1      A Q_RES_0402LF-15K,1%,1/16W,CHIP,CS31502FB05    I51 @T6G_MB_LIB.T6G(SCH_1):PAGE343
 PU200   D3     OV MAX15090BEWIT-MAX15090BEWI+T,SMLF,IC,AL015080B00    I89 @T6G_MB_LIB.T6G(SCH_1):PAGE343
PR3829    2      B Q_RES_0402LF-7.15K,1%,1/16W,CHIP,CS27152FB03    I53 @T6G_MB_LIB.T6G(SCH_1):PAGE343

P3V3_OCP_PWRGD_1 @T6G_MB_LIB.T6G(SCH_1):P3V3_OCP_PWRGD_1
 PU202   D7     PG MAX15090BEWIT-MAX15090BEWI+T,SMLF,IC,AL015080B00   I113 @T6G_MB_LIB.T6G(SCH_1):PAGE338
 R3794    1      A Q_RES_0402LF-0,5%,1/16W,EMPTY,CS00002JB13   I132 @T6G_MB_LIB.T6G(SCH_1):PAGE338

P3V3_OCP_PWRGD_2 @T6G_MB_LIB.T6G(SCH_1):P3V3_OCP_PWRGD_2
 PU200   D7     PG MAX15090BEWIT-MAX15090BEWI+T,SMLF,IC,AL015080B00    I89 @T6G_MB_LIB.T6G(SCH_1):PAGE343
 R3832    1      A Q_RES_0402LF-0,5%,1/16W,EMPTY,CS00002JB13   I127 @T6G_MB_LIB.T6G(SCH_1):PAGE343

P3V3_OCP_REG_1 @T6G_MB_LIB.T6G(SCH_1):P3V3_OCP_REG_1
PC2093    2      B Q_CAP_C0402-1UF,25V,10%,X6S,CH5104KEB02    I67 @T6G_MB_LIB.T6G(SCH_1):PAGE338
 PU202   D1    REG MAX15090BEWIT-MAX15090BEWI+T,SMLF,IC,AL015080B00   I113 @T6G_MB_LIB.T6G(SCH_1):PAGE338

P3V3_OCP_REG_2 @T6G_MB_LIB.T6G(SCH_1):P3V3_OCP_REG_2
PC2147    2      B Q_CAP_C0402-1UF,25V,10%,X6S,CH5104KEB02    I86 @T6G_MB_LIB.T6G(SCH_1):PAGE343
 PU200   D1    REG MAX15090BEWIT-MAX15090BEWI+T,SMLF,IC,AL015080B00    I89 @T6G_MB_LIB.T6G(SCH_1):PAGE343

P3V3_OCP_SENSE_1 @T6G_MB_LIB.T6G(SCH_1):P3V3_OCP_SENSE_1
PR5481    1      A Q_RES_0402LF-4.53K,1%,1/16W,CHIP,CS24532FB03    I95 @T6G_MB_LIB.T6G(SCH_1):PAGE338
 PU202   A1 ISENSE MAX15090BEWIT-MAX15090BEWI+T,SMLF,IC,AL015080B00   I113 @T6G_MB_LIB.T6G(SCH_1):PAGE338

P3V3_OCP_SENSE_2 @T6G_MB_LIB.T6G(SCH_1):P3V3_OCP_SENSE_2
 PU200   A1 ISENSE MAX15090BEWIT-MAX15090BEWI+T,SMLF,IC,AL015080B00    I89 @T6G_MB_LIB.T6G(SCH_1):PAGE343
PR3824    1      A Q_RES_0402LF-4.53K,1%,1/16W,CHIP,CS24532FB03    I94 @T6G_MB_LIB.T6G(SCH_1):PAGE343

P3V3_OCP_SFF @T6G_MB_LIB.T6G(SCH_1):P3V3_OCP_SFF
 C1237    1      A Q_CAP_0402-0.1UF,25V,10%,X7R,CH4104K1B00   I110 @T6G_MB_LIB.T6G(SCH_1):PAGE335
 C1238    1      A Q_CAP_0402-0.1UF,25V,10%,X7R,CH4104K1B00   I111 @T6G_MB_LIB.T6G(SCH_1):PAGE335
 C1240    1      A Q_CAP_0402-0.1UF,25V,10%,X7R,CH4104K1B00   I114 @T6G_MB_LIB.T6G(SCH_1):PAGE335
   J38  B11 +3.3V_EDGE SCONN168_ME1016810202011-SCONN168_ME1016810202011,A   I168 @T6G_MB_LIB.T6G(SCH_1):PAGE335
 R3603    1      A Q_RES_0402LF-10,1%,1/16W,CHIP,CS01002FB07    I43 @T6G_MB_LIB.T6G(SCH_1):PAGE295
 R3645    1      A Q_RES_2512LF-0.002,1%,2W,CHIP,CS+002AFR06    I93 @T6G_MB_LIB.T6G(SCH_1):PAGE295
  U236    8   VCCB PCA9617ADP-PCA9617ADP,SMLF,IC,AL009617K02    I14 @T6G_MB_LIB.T6G(SCH_1):PAGE248
 C1862    1      A Q_CAP_0402-0.1UF,25V,10%,X7R,CH4104K1B00    I19 @T6G_MB_LIB.T6G(SCH_1):PAGE248
 R3500    1      A Q_RES_0402LF-4.7K,5%,1/16W,CHIP,CS24702JB10    I27 @T6G_MB_LIB.T6G(SCH_1):PAGE248
 R3501    1      A Q_RES_0402LF-4.7K,5%,1/16W,CHIP,CS24702JB10    I31 @T6G_MB_LIB.T6G(SCH_1):PAGE248
   R31    1      A Q_RES_0402LF-4.7K,1%,1/16W,EMPTY,CS24702FB06     I3 @T6G_MB_LIB.T6G(SCH_1):PAGE335
   R33    1      A Q_RES_0402LF-4.7K,1%,1/16W,EMPTY,CS24702FB06    I17 @T6G_MB_LIB.T6G(SCH_1):PAGE335
 R8423    2      B Q_RES_0402LF-1K,1%,1/16W,CHIP,CS21002FB06    I20 @T6G_MB_LIB.T6G(SCH_1):PAGE335
 R8421    2      B Q_RES_0402LF-10K,1%,1/16W,CHIP,CS31002FB08    I21 @T6G_MB_LIB.T6G(SCH_1):PAGE335
 R8420    2      B Q_RES_0402LF-1K,1%,1/16W,CHIP,CS21002FB06    I22 @T6G_MB_LIB.T6G(SCH_1):PAGE335
 C1239    1      A Q_CAP_0402-0.1UF,25V,10%,X7R,CH4104K1B00   I112 @T6G_MB_LIB.T6G(SCH_1):PAGE335
 R1824    1      A Q_RES_0402LF-10K,1%,1/16W,CHIP,CS31002FB08    I11 @T6G_MB_LIB.T6G(SCH_1):PAGE337
   R45    1      A Q_RES_0402LF-10K,1%,1/16W,CHIP,CS31002FB08    I12 @T6G_MB_LIB.T6G(SCH_1):PAGE337

P3V3_OCP_SFF_EN @T6G_MB_LIB.T6G(SCH_1):P3V3_OCP_SFF_EN
   R23    1      A Q_RES_0402LF-33,5%,1/16W,CHIP,CS03302JB10    I23 @T6G_MB_LIB.T6G(SCH_1):PAGE79
   U18   B9  PT21A LCMXO3LF9400C5BG484C-LCMXO3LF-9400C-5BG484C,SMLF,IA    I94 @T6G_MB_LIB.T6G(SCH_1):PAGE79

P3V3_OCP_SFF_EN_R @T6G_MB_LIB.T6G(SCH_1):P3V3_OCP_SFF_EN_R
   R23    2      B Q_RES_0402LF-33,5%,1/16W,CHIP,CS03302JB10    I23 @T6G_MB_LIB.T6G(SCH_1):PAGE79
 R1071    1      A Q_RES_0402LF-4.7K,5%,1/16W,EMPTY,CS24702JB10    I38 @T6G_MB_LIB.T6G(SCH_1):PAGE82
 R5487    1      A Q_RES_0402LF-0,5%,1/16W,EMPTY,CS00002JB13   I126 @T6G_MB_LIB.T6G(SCH_1):PAGE338
 R3845    1      A Q_RES_0402LF-0,5%,1/16W,EMPTY,CS00002JB13   I131 @T6G_MB_LIB.T6G(SCH_1):PAGE339
 R3263    2      B Q_RES_0402LF-0,5%,1/16W,EMPTY,CS00002JB13    I35 @T6G_MB_LIB.T6G(SCH_1):PAGE248

P3V3_OCP_SFF_R @T6G_MB_LIB.T6G(SCH_1):P3V3_OCP_SFF_R
  U266   11   VBUS ISL28022FRZT-ISL28022FRZ-T,SMLF,IC,AL028022003    I30 @T6G_MB_LIB.T6G(SCH_1):PAGE295
 R3602    1      A Q_RES_0402LF-10,1%,1/16W,CHIP,CS01002FB07    I41 @T6G_MB_LIB.T6G(SCH_1):PAGE295
 C2024    1      A Q_CAP_0402-0.1UF,25V,10%,X7R,CH4104K1B00    I50 @T6G_MB_LIB.T6G(SCH_1):PAGE295
 R3645    2      B Q_RES_2512LF-0.002,1%,2W,CHIP,CS+002AFR06    I93 @T6G_MB_LIB.T6G(SCH_1):PAGE295
PC2144    1      A Q_CAP_C0402-0.01UF,50V,10%,EMPTY,CH31006KB18    I94 @T6G_MB_LIB.T6G(SCH_1):PAGE338
PR4525    1      A Q_RES_0402LF-10M,1%,1/16W,CHIP,CS61002FB02    I96 @T6G_MB_LIB.T6G(SCH_1):PAGE338
 PD103    C      C SCHOTTKY_AC-B340A-13-F,SMLF,IC,BC000340Z30    I97 @T6G_MB_LIB.T6G(SCH_1):PAGE338
PC2091    1      A Q_CAP_0402-0.1UF,25V,10%,X7R,CH4104K1B00   I104 @T6G_MB_LIB.T6G(SCH_1):PAGE338
PC2081    1      A Q_CAP_C0805-10UF,16V,10%,X6S,CH6103KEA01   I106 @T6G_MB_LIB.T6G(SCH_1):PAGE338
 PU202   A4 OUT_A4 MAX15090BEWIT-MAX15090BEWI+T,SMLF,IC,AL015080B00   I113 @T6G_MB_LIB.T6G(SCH_1):PAGE338
 PU202   B4 OUT_B4 MAX15090BEWIT-MAX15090BEWI+T,SMLF,IC,AL015080B00   I113 @T6G_MB_LIB.T6G(SCH_1):PAGE338
 PU202   B6 OUT_B6 MAX15090BEWIT-MAX15090BEWI+T,SMLF,IC,AL015080B00   I113 @T6G_MB_LIB.T6G(SCH_1):PAGE338
 PU202   C4 OUT_C4 MAX15090BEWIT-MAX15090BEWI+T,SMLF,IC,AL015080B00   I113 @T6G_MB_LIB.T6G(SCH_1):PAGE338
 PU202   C6 OUT_C6 MAX15090BEWIT-MAX15090BEWI+T,SMLF,IC,AL015080B00   I113 @T6G_MB_LIB.T6G(SCH_1):PAGE338
 PU202   D4 OUT_D4 MAX15090BEWIT-MAX15090BEWI+T,SMLF,IC,AL015080B00   I113 @T6G_MB_LIB.T6G(SCH_1):PAGE338
 PU202   D6 OUT_D6 MAX15090BEWIT-MAX15090BEWI+T,SMLF,IC,AL015080B00   I113 @T6G_MB_LIB.T6G(SCH_1):PAGE338
PC2163    1      A Q_CAP_C0805-10UF,16V,10%,X6S,CH6103KEA01   I108 @T6G_MB_LIB.T6G(SCH_1):PAGE339
 PU205  6_7 SOURCE MP5016GQHLZ-MP5016GQH-L-Z,SMLF,IC,AL005016007   I113 @T6G_MB_LIB.T6G(SCH_1):PAGE339
 C8008    1      A Q_CAP_0402-0.1UF,25V,10%,X7R,CH4104K1B00    I79 @T6G_MB_LIB.T6G(SCH_1):PAGE340
 U8001    3    VCC APX80929SAG7-APX809-29SAG-7,SMLF,IC,AL080929000    I80 @T6G_MB_LIB.T6G(SCH_1):PAGE340
 R8092    1      A Q_RES_0402LF-10K,5%,1/16W,EMPTY,CS31002JB08    I90 @T6G_MB_LIB.T6G(SCH_1):PAGE340

P3V3_OCP_UV_1 @T6G_MB_LIB.T6G(SCH_1):P3V3_OCP_UV_1
 R3785    2      B Q_RES_0402LF-0,5%,1/16W,CHIP,CS00002JB13    I61 @T6G_MB_LIB.T6G(SCH_1):PAGE338
PR3790    1      A Q_RES_0402LF-7.15K,1%,1/16W,CHIP,CS27152FB03    I64 @T6G_MB_LIB.T6G(SCH_1):PAGE338
PR3789    2      B Q_RES_0402LF-25.5K,1%,1/16W,CHIP,CS32552FB06    I66 @T6G_MB_LIB.T6G(SCH_1):PAGE338
 PU202   D2     UV MAX15090BEWIT-MAX15090BEWI+T,SMLF,IC,AL015080B00   I113 @T6G_MB_LIB.T6G(SCH_1):PAGE338

P3V3_OCP_UV_1_R1 @T6G_MB_LIB.T6G(SCH_1):P3V3_OCP_UV_1_R1
 R3785    1      A Q_RES_0402LF-0,5%,1/16W,CHIP,CS00002JB13    I61 @T6G_MB_LIB.T6G(SCH_1):PAGE338
  Q124    3     D2 MOSFET_NCH_DUAL-PJT138K,SMLF,IC,BAM138K0003   I112 @T6G_MB_LIB.T6G(SCH_1):PAGE338

P3V3_OCP_UV_2 @T6G_MB_LIB.T6G(SCH_1):P3V3_OCP_UV_2
PR3795    2      B Q_RES_0402LF-25.5K,1%,1/16W,CHIP,CS32552FB06    I56 @T6G_MB_LIB.T6G(SCH_1):PAGE343
 PU200   D2     UV MAX15090BEWIT-MAX15090BEWI+T,SMLF,IC,AL015080B00    I89 @T6G_MB_LIB.T6G(SCH_1):PAGE343
 R3807    2      B Q_RES_0402LF-0,5%,1/16W,CHIP,CS00002JB13    I50 @T6G_MB_LIB.T6G(SCH_1):PAGE343
PR3829    1      A Q_RES_0402LF-7.15K,1%,1/16W,CHIP,CS27152FB03    I53 @T6G_MB_LIB.T6G(SCH_1):PAGE343

P3V3_OCP_UV_2_R1 @T6G_MB_LIB.T6G(SCH_1):P3V3_OCP_UV_2_R1
  Q119    3     D2 MOSFET_NCH_DUAL-PJT138K,SMLF,IC,BAM138K0003    I45 @T6G_MB_LIB.T6G(SCH_1):PAGE343
 R3807    1      A Q_RES_0402LF-0,5%,1/16W,CHIP,CS00002JB13    I50 @T6G_MB_LIB.T6G(SCH_1):PAGE343

P3V3_OCP_V3_2 @T6G_MB_LIB.T6G(SCH_1):P3V3_OCP_V3_2
 C1837    1      A Q_CAP_0402-0.1UF,25V,10%,X7R,CH4104K1B00    I23 @T6G_MB_LIB.T6G(SCH_1):PAGE341
 R3162    1      A Q_RES_0402LF-4.7K,1%,1/16W,CHIP,CS24702FB06    I26 @T6G_MB_LIB.T6G(SCH_1):PAGE341
   J35  B11 +3.3V_EDGE SCONN168_ME1016810202011-SCONN168_ME1016810202011,A   I168 @T6G_MB_LIB.T6G(SCH_1):PAGE341
 R3571    1      A Q_RES_0402LF-10,1%,1/16W,CHIP,CS01002FB07   I110 @T6G_MB_LIB.T6G(SCH_1):PAGE360
 R3633    1      A Q_RES_2512LF-0.002,1%,2W,CHIP,CS+002AFR06   I116 @T6G_MB_LIB.T6G(SCH_1):PAGE360
  U235    8   VCCB PCA9617ADP-PCA9617ADP,SMLF,IC,AL009617K02     I6 @T6G_MB_LIB.T6G(SCH_1):PAGE248
 C1861    1      A Q_CAP_0402-0.1UF,25V,10%,X7R,CH4104K1B00     I9 @T6G_MB_LIB.T6G(SCH_1):PAGE248
 R3520    1      A Q_RES_0402LF-4.7K,5%,1/16W,CHIP,CS24702JB10    I23 @T6G_MB_LIB.T6G(SCH_1):PAGE248
 R3519    1      A Q_RES_0402LF-4.7K,5%,1/16W,CHIP,CS24702JB10    I34 @T6G_MB_LIB.T6G(SCH_1):PAGE248
 R3174    2      B Q_RES_0402LF-10K,1%,1/16W,CHIP,CS31002FB08     I9 @T6G_MB_LIB.T6G(SCH_1):PAGE341
 R3173    2      B Q_RES_0402LF-1K,1%,1/16W,CHIP,CS21002FB06    I10 @T6G_MB_LIB.T6G(SCH_1):PAGE341
 R3176    2      B Q_RES_0402LF-1K,1%,1/16W,CHIP,CS21002FB06    I12 @T6G_MB_LIB.T6G(SCH_1):PAGE341
 C1835    1      A Q_CAP_0402-0.1UF,25V,10%,X7R,CH4104K1B00    I21 @T6G_MB_LIB.T6G(SCH_1):PAGE341
 C1836    1      A Q_CAP_0402-0.1UF,25V,10%,X7R,CH4104K1B00    I22 @T6G_MB_LIB.T6G(SCH_1):PAGE341
 C1838    1      A Q_CAP_0402-0.1UF,25V,10%,X7R,CH4104K1B00    I24 @T6G_MB_LIB.T6G(SCH_1):PAGE341
 R3166    1      A Q_RES_0402LF-4.7K,1%,1/16W,EMPTY,CS24702FB06    I28 @T6G_MB_LIB.T6G(SCH_1):PAGE341
 R3182    1      A Q_RES_0402LF-10K,1%,1/16W,CHIP,CS31002FB08     I3 @T6G_MB_LIB.T6G(SCH_1):PAGE342
 R3183    1      A Q_RES_0402LF-10K,1%,1/16W,CHIP,CS31002FB08     I4 @T6G_MB_LIB.T6G(SCH_1):PAGE342

P3V3_OCP_V3_2_EN_R @T6G_MB_LIB.T6G(SCH_1):P3V3_OCP_V3_2_EN_R
 R6062    1      A Q_RES_0402LF-4.7K,5%,1/16W,EMPTY,CS24702JB10    I40 @T6G_MB_LIB.T6G(SCH_1):PAGE82
   U18  V17  PB46C LCMXO3LF9400C5BG484C-LCMXO3LF-9400C-5BG484C,SMLF,IA   I216 @T6G_MB_LIB.T6G(SCH_1):PAGE80
 R4060    1      A Q_RES_0402LF-0,5%,1/16W,EMPTY,CS00002JB13   I122 @T6G_MB_LIB.T6G(SCH_1):PAGE343
 R3631    1      A Q_RES_0402LF-0,5%,1/16W,EMPTY,CS00002JB13    I74 @T6G_MB_LIB.T6G(SCH_1):PAGE344
 R3264    2      B Q_RES_0402LF-0,5%,1/16W,EMPTY,CS00002JB13    I38 @T6G_MB_LIB.T6G(SCH_1):PAGE248

P3V3_OCP_V3_2_R @T6G_MB_LIB.T6G(SCH_1):P3V3_OCP_V3_2_R
 PU200   A4 OUT_A4 MAX15090BEWIT-MAX15090BEWI+T,SMLF,IC,AL015080B00    I89 @T6G_MB_LIB.T6G(SCH_1):PAGE343
 PU200   B4 OUT_B4 MAX15090BEWIT-MAX15090BEWI+T,SMLF,IC,AL015080B00    I89 @T6G_MB_LIB.T6G(SCH_1):PAGE343
 PU200   B6 OUT_B6 MAX15090BEWIT-MAX15090BEWI+T,SMLF,IC,AL015080B00    I89 @T6G_MB_LIB.T6G(SCH_1):PAGE343
 PU200   C4 OUT_C4 MAX15090BEWIT-MAX15090BEWI+T,SMLF,IC,AL015080B00    I89 @T6G_MB_LIB.T6G(SCH_1):PAGE343
 PU200   C6 OUT_C6 MAX15090BEWIT-MAX15090BEWI+T,SMLF,IC,AL015080B00    I89 @T6G_MB_LIB.T6G(SCH_1):PAGE343
 PU200   D4 OUT_D4 MAX15090BEWIT-MAX15090BEWI+T,SMLF,IC,AL015080B00    I89 @T6G_MB_LIB.T6G(SCH_1):PAGE343
 PU200   D6 OUT_D6 MAX15090BEWIT-MAX15090BEWI+T,SMLF,IC,AL015080B00    I89 @T6G_MB_LIB.T6G(SCH_1):PAGE343
PR4523    1      A Q_RES_0402LF-10M,1%,1/16W,CHIP,CS61002FB02   I105 @T6G_MB_LIB.T6G(SCH_1):PAGE343
 PU207  6_7 SOURCE MP5016GQHLZ-MP5016GQH-L-Z,SMLF,IC,AL005016007    I51 @T6G_MB_LIB.T6G(SCH_1):PAGE344
PC2173    1      A Q_CAP_C0805-10UF,16V,10%,X6S,CH6103KEA01    I56 @T6G_MB_LIB.T6G(SCH_1):PAGE344
  U263   11   VBUS ISL28022FRZT-ISL28022FRZ-T,SMLF,IC,AL028022003    I94 @T6G_MB_LIB.T6G(SCH_1):PAGE360
 R3570    1      A Q_RES_0402LF-10,1%,1/16W,CHIP,CS01002FB07   I109 @T6G_MB_LIB.T6G(SCH_1):PAGE360
 C2017    1      A Q_CAP_0402-0.1UF,25V,10%,X7R,CH4104K1B00   I114 @T6G_MB_LIB.T6G(SCH_1):PAGE360
 R3633    2      B Q_RES_2512LF-0.002,1%,2W,CHIP,CS+002AFR06   I116 @T6G_MB_LIB.T6G(SCH_1):PAGE360
PC2149    1      A Q_CAP_C0402-0.01UF,50V,10%,EMPTY,CH31006KB18   I104 @T6G_MB_LIB.T6G(SCH_1):PAGE343
 PD109    C      C SCHOTTKY_AC-B340A-13-F,SMLF,IC,BC000340Z30   I106 @T6G_MB_LIB.T6G(SCH_1):PAGE343
PC2137    1      A Q_CAP_0402-0.1UF,25V,10%,X7R,CH4104K1B00   I108 @T6G_MB_LIB.T6G(SCH_1):PAGE343
PC2142    1      A Q_CAP_C0805-10UF,16V,10%,X6S,CH6103KEA01   I112 @T6G_MB_LIB.T6G(SCH_1):PAGE343
 C8009    1      A Q_CAP_0402-0.1UF,25V,10%,X7R,CH4104K1B00    I66 @T6G_MB_LIB.T6G(SCH_1):PAGE257
 U8002    3    VCC APX80929SAG7-APX809-29SAG-7,SMLF,IC,AL080929000    I67 @T6G_MB_LIB.T6G(SCH_1):PAGE257
 R8095    1      A Q_RES_0402LF-10K,5%,1/16W,EMPTY,CS31002JB08    I77 @T6G_MB_LIB.T6G(SCH_1):PAGE257

P3V3_OCP_VCC_1 @T6G_MB_LIB.T6G(SCH_1):P3V3_OCP_VCC_1
PR3798    2      B Q_RES_0402LF-10,1%,1/16W,CHIP,CS01002FB07    I68 @T6G_MB_LIB.T6G(SCH_1):PAGE338
PC2086    1      A Q_CAP_C0402-1UF,25V,10%,X6S,CH5104KEB02   I110 @T6G_MB_LIB.T6G(SCH_1):PAGE338
 PU202   A2    VCC MAX15090BEWIT-MAX15090BEWI+T,SMLF,IC,AL015080B00   I113 @T6G_MB_LIB.T6G(SCH_1):PAGE338

P3V3_OCP_VCC_2 @T6G_MB_LIB.T6G(SCH_1):P3V3_OCP_VCC_2
 PU200   A2    VCC MAX15090BEWIT-MAX15090BEWI+T,SMLF,IC,AL015080B00    I89 @T6G_MB_LIB.T6G(SCH_1):PAGE343
   C39    1      A Q_CAP_C0402-1UF,25V,10%,X6S,CH5104KEB02    I90 @T6G_MB_LIB.T6G(SCH_1):PAGE343
PR3782    2      B Q_RES_0402LF-10,1%,1/16W,CHIP,CS01002FB07    I91 @T6G_MB_LIB.T6G(SCH_1):PAGE343

P3V3_PDB_AUX_ADC @T6G_MB_LIB.T6G(SCH_1):P3V3_PDB_AUX_ADC
 R4567    1      A Q_RES_0402LF-5.11K,1%,1/16W,CHIP,CS25112FB04     I8 @T6G_MB_LIB.T6G(SCH_1):PAGE369
   J45   A3     A3 CONN60_101062636003K02LF-CONN60_10106263-6003K02LFA   I466 @T6G_MB_LIB.T6G(SCH_1):PAGE363

P3V3_PDB_AUX_ADC_MAM @T6G_MB_LIB.T6G(SCH_1):P3V3_PDB_AUX_ADC_MAM
 C2045    1      A Q_CAP_0402-100PF,50V,5%,EMPTY,CH11006JB18    I36 @T6G_MB_LIB.T6G(SCH_1):PAGE369
 R3687    2      B Q_RES_0402LF-0,5%,1/16W,EMPTY,CS00002JB13    I42 @T6G_MB_LIB.T6G(SCH_1):PAGE369
  U193   11   AIN6 MAX11617EEET-MAX11617EEE+T,SMLF,EMPTY,AL011617W00   I169 @T6G_MB_LIB.T6G(SCH_1):PAGE369

P3V3_PDB_AUX_ADC_TIC @T6G_MB_LIB.T6G(SCH_1):P3V3_PDB_AUX_ADC_TIC
 C2050    1      A Q_CAP_0402-0.1UF,25V,10%,X7R,CH4104K1B00    I34 @T6G_MB_LIB.T6G(SCH_1):PAGE369
 R3688    2      B Q_RES_0402LF-0,5%,1/16W,CHIP,CS00002JB13    I41 @T6G_MB_LIB.T6G(SCH_1):PAGE369
  U269   10    IN6 ADC128D818CIMTXNOPB-ADC128D818CIMTX/NOPB,SMLF,IC,AA   I142 @T6G_MB_LIB.T6G(SCH_1):PAGE369

P3V3_PWRGD_CLKGEN @T6G_MB_LIB.T6G(SCH_1):P3V3_PWRGD_CLKGEN
 R4080    2      B Q_RES_0402LF-10K,1%,1/16W,CHIP,CS31002FB08    I59 @T6G_MB_LIB.T6G(SCH_1):PAGE232
  U247   22 ^CKPWRGD_PD# 9FGL0251DKILFT-9FGL0251DKILFT,SMLF,IC,AL000251002    I77 @T6G_MB_LIB.T6G(SCH_1):PAGE232

P3V3_RTC_AUX @T6G_MB_LIB.T6G(SCH_1):P3V3_RTC_AUX
  U166    3      C SCHOTTKY_DUAL_12A_3C-BAT54CW,SMLF,IC,BCBAT54CZ13    I99 @T6G_MB_LIB.T6G(SCH_1):PAGE156
 R5052    2      B Q_RES_0402LF-0,5%,1/16W,CHIP,CS00002JB13   I100 @T6G_MB_LIB.T6G(SCH_1):PAGE156
 R5051    1      A Q_RES_0402LF-0,5%,1/16W,EMPTY,CS00002JB13   I101 @T6G_MB_LIB.T6G(SCH_1):PAGE156

P3V3_RTC_AUX_R @T6G_MB_LIB.T6G(SCH_1):P3V3_RTC_AUX_R
 R5052    1      A Q_RES_0402LF-0,5%,1/16W,CHIP,CS00002JB13   I100 @T6G_MB_LIB.T6G(SCH_1):PAGE156
 R5054    1      A Q_RES_0402LF-0,5%,1/16W,CHIP,CS00002JB13   I122 @T6G_MB_LIB.T6G(SCH_1):PAGE156

P3V3_STBY_R @T6G_MB_LIB.T6G(SCH_1):P3V3_STBY_R
 R5101    2      B Q_RES_0402LF-10K,5%,1/16W,CHIP,CS31002JB08    I97 @T6G_MB_LIB.T6G(SCH_1):PAGE156
  U166    1      B SCHOTTKY_DUAL_12A_3C-BAT54CW,SMLF,IC,BCBAT54CZ13    I99 @T6G_MB_LIB.T6G(SCH_1):PAGE156

P3V_BAT @T6G_MB_LIB.T6G(SCH_1):P3V_BAT
   BT2    1      1 CONN2_AAABAT029Y19-CONN2_AAA-BAT-029-Y19,THLF,IO,DA    I86 @T6G_MB_LIB.T6G(SCH_1):PAGE156
 R1775    1      A Q_RES_0402LF-1K,1%,1/16W,CHIP,CS21002FB06   I131 @T6G_MB_LIB.T6G(SCH_1):PAGE156

P3V_BAT_R @T6G_MB_LIB.T6G(SCH_1):P3V_BAT_R
  U166    2      A SCHOTTKY_DUAL_12A_3C-BAT54CW,SMLF,IC,BCBAT54CZ13    I99 @T6G_MB_LIB.T6G(SCH_1):PAGE156
 R1775    2      B Q_RES_0402LF-1K,1%,1/16W,CHIP,CS21002FB06   I131 @T6G_MB_LIB.T6G(SCH_1):PAGE156
  R364    1      A Q_RES_0402LF-0,5%,1/16W,CHIP,CS00002JB13   I231 @T6G_MB_LIB.T6G(SCH_1):PAGE349

P5E_CPU0_G3_RX_DN<0> @T6G_MB_LIB.T6G(SCH_1):P5E_CPU0_G3_RX_DN(0)
   U25 AL23 G3_RXN0||SATA20_RXN GENOA_SP5-SOCKET6096_13568-001,SMLF,IO,DGA^6000030   I216 @T6G_MB_LIB.T6G(SCH_1):PAGE23
   J38  A17  PERN0 SCONN168_ME1016810202011-SCONN168_ME1016810202011,A   I168 @T6G_MB_LIB.T6G(SCH_1):PAGE335

P5E_CPU0_G3_RX_DN<10> @T6G_MB_LIB.T6G(SCH_1):P5E_CPU0_G3_RX_DN(10)
   U25 AJ32 G3_RXN10||SATA32_RXN GENOA_SP5-SOCKET6096_13568-001,SMLF,IO,DGA^6000030   I216 @T6G_MB_LIB.T6G(SCH_1):PAGE23
   J38  A50 PERN10 SCONN168_ME1016810202011-SCONN168_ME1016810202011,A   I168 @T6G_MB_LIB.T6G(SCH_1):PAGE335

P5E_CPU0_G3_RX_DN<11> @T6G_MB_LIB.T6G(SCH_1):P5E_CPU0_G3_RX_DN(11)
   U25 AN32 G3_RXN11||SATA33_RXN GENOA_SP5-SOCKET6096_13568-001,SMLF,IO,DGA^6000030   I216 @T6G_MB_LIB.T6G(SCH_1):PAGE23
   J38  A53 PERN11 SCONN168_ME1016810202011-SCONN168_ME1016810202011,A   I168 @T6G_MB_LIB.T6G(SCH_1):PAGE335

P5E_CPU0_G3_RX_DN<12> @T6G_MB_LIB.T6G(SCH_1):P5E_CPU0_G3_RX_DN(12)
   U25 AK35 G3_RXN12||SATA34_RXN GENOA_SP5-SOCKET6096_13568-001,SMLF,IO,DGA^6000030   I216 @T6G_MB_LIB.T6G(SCH_1):PAGE23
   J38  A56 PERN12 SCONN168_ME1016810202011-SCONN168_ME1016810202011,A   I168 @T6G_MB_LIB.T6G(SCH_1):PAGE335

P5E_CPU0_G3_RX_DN<13> @T6G_MB_LIB.T6G(SCH_1):P5E_CPU0_G3_RX_DN(13)
   U25 AH35 G3_RXN13||SATA35_RXN GENOA_SP5-SOCKET6096_13568-001,SMLF,IO,DGA^6000030   I216 @T6G_MB_LIB.T6G(SCH_1):PAGE23
   J38  A59 PERN13 SCONN168_ME1016810202011-SCONN168_ME1016810202011,A   I168 @T6G_MB_LIB.T6G(SCH_1):PAGE335

P5E_CPU0_G3_RX_DN<14> @T6G_MB_LIB.T6G(SCH_1):P5E_CPU0_G3_RX_DN(14)
   U25 AM35 G3_RXN14||SATA36_RXN GENOA_SP5-SOCKET6096_13568-001,SMLF,IO,DGA^6000030   I216 @T6G_MB_LIB.T6G(SCH_1):PAGE23
   J38  A62 PERN14 SCONN168_ME1016810202011-SCONN168_ME1016810202011,A   I168 @T6G_MB_LIB.T6G(SCH_1):PAGE335

P5E_CPU0_G3_RX_DN<15> @T6G_MB_LIB.T6G(SCH_1):P5E_CPU0_G3_RX_DN(15)
   U25 AP35 G3_RXN15||SATA37_RXN GENOA_SP5-SOCKET6096_13568-001,SMLF,IO,DGA^6000030   I216 @T6G_MB_LIB.T6G(SCH_1):PAGE23
   J38  A65 PERN15 SCONN168_ME1016810202011-SCONN168_ME1016810202011,A   I168 @T6G_MB_LIB.T6G(SCH_1):PAGE335

P5E_CPU0_G3_RX_DN<1> @T6G_MB_LIB.T6G(SCH_1):P5E_CPU0_G3_RX_DN(1)
   U25 AJ23 G3_RXN1||SATA21_RXN GENOA_SP5-SOCKET6096_13568-001,SMLF,IO,DGA^6000030   I216 @T6G_MB_LIB.T6G(SCH_1):PAGE23
   J38  A20  PERN1 SCONN168_ME1016810202011-SCONN168_ME1016810202011,A   I168 @T6G_MB_LIB.T6G(SCH_1):PAGE335

P5E_CPU0_G3_RX_DN<2> @T6G_MB_LIB.T6G(SCH_1):P5E_CPU0_G3_RX_DN(2)
   U25 AN23 G3_RXN2||SATA22_RXN GENOA_SP5-SOCKET6096_13568-001,SMLF,IO,DGA^6000030   I216 @T6G_MB_LIB.T6G(SCH_1):PAGE23
   J38  A23  PERN2 SCONN168_ME1016810202011-SCONN168_ME1016810202011,A   I168 @T6G_MB_LIB.T6G(SCH_1):PAGE335

P5E_CPU0_G3_RX_DN<3> @T6G_MB_LIB.T6G(SCH_1):P5E_CPU0_G3_RX_DN(3)
   U25 AL26 G3_RXN3||SATA23_RXN GENOA_SP5-SOCKET6096_13568-001,SMLF,IO,DGA^6000030   I216 @T6G_MB_LIB.T6G(SCH_1):PAGE23
   J38  A26  PERN3 SCONN168_ME1016810202011-SCONN168_ME1016810202011,A   I168 @T6G_MB_LIB.T6G(SCH_1):PAGE335

P5E_CPU0_G3_RX_DN<4> @T6G_MB_LIB.T6G(SCH_1):P5E_CPU0_G3_RX_DN(4)
   U25 AJ26 G3_RXN4||SATA24_RXN GENOA_SP5-SOCKET6096_13568-001,SMLF,IO,DGA^6000030   I216 @T6G_MB_LIB.T6G(SCH_1):PAGE23
   J38  A30  PERN4 SCONN168_ME1016810202011-SCONN168_ME1016810202011,A   I168 @T6G_MB_LIB.T6G(SCH_1):PAGE335

P5E_CPU0_G3_RX_DN<5> @T6G_MB_LIB.T6G(SCH_1):P5E_CPU0_G3_RX_DN(5)
   U25 AN26 G3_RXN5||SATA25_RXN GENOA_SP5-SOCKET6096_13568-001,SMLF,IO,DGA^6000030   I216 @T6G_MB_LIB.T6G(SCH_1):PAGE23
   J38  A33  PERN5 SCONN168_ME1016810202011-SCONN168_ME1016810202011,A   I168 @T6G_MB_LIB.T6G(SCH_1):PAGE335

P5E_CPU0_G3_RX_DN<6> @T6G_MB_LIB.T6G(SCH_1):P5E_CPU0_G3_RX_DN(6)
   U25 AL29 G3_RXN6||SATA26_RXN GENOA_SP5-SOCKET6096_13568-001,SMLF,IO,DGA^6000030   I216 @T6G_MB_LIB.T6G(SCH_1):PAGE23
   J38  A36  PERN6 SCONN168_ME1016810202011-SCONN168_ME1016810202011,A   I168 @T6G_MB_LIB.T6G(SCH_1):PAGE335

P5E_CPU0_G3_RX_DN<7> @T6G_MB_LIB.T6G(SCH_1):P5E_CPU0_G3_RX_DN(7)
   U25 AJ29 G3_RXN7||SATA27_RXN GENOA_SP5-SOCKET6096_13568-001,SMLF,IO,DGA^6000030   I216 @T6G_MB_LIB.T6G(SCH_1):PAGE23
   J38  A39  PERN7 SCONN168_ME1016810202011-SCONN168_ME1016810202011,A   I168 @T6G_MB_LIB.T6G(SCH_1):PAGE335

P5E_CPU0_G3_RX_DN<8> @T6G_MB_LIB.T6G(SCH_1):P5E_CPU0_G3_RX_DN(8)
   U25 AN29 G3_RXN8||SATA30_RXN GENOA_SP5-SOCKET6096_13568-001,SMLF,IO,DGA^6000030   I216 @T6G_MB_LIB.T6G(SCH_1):PAGE23
   J38  A44  PERN8 SCONN168_ME1016810202011-SCONN168_ME1016810202011,A   I168 @T6G_MB_LIB.T6G(SCH_1):PAGE335

P5E_CPU0_G3_RX_DN<9> @T6G_MB_LIB.T6G(SCH_1):P5E_CPU0_G3_RX_DN(9)
   U25 AL32 G3_RXN9||SATA31_RXN GENOA_SP5-SOCKET6096_13568-001,SMLF,IO,DGA^6000030   I216 @T6G_MB_LIB.T6G(SCH_1):PAGE23
   J38  A47  PERN9 SCONN168_ME1016810202011-SCONN168_ME1016810202011,A   I168 @T6G_MB_LIB.T6G(SCH_1):PAGE335

P5E_CPU0_G3_RX_DP<0> @T6G_MB_LIB.T6G(SCH_1):P5E_CPU0_G3_RX_DP(0)
   U25 AL24 G3_RXP0||SATA20_RXP GENOA_SP5-SOCKET6096_13568-001,SMLF,IO,DGA^6000030   I216 @T6G_MB_LIB.T6G(SCH_1):PAGE23
   J38  A18  PERP0 SCONN168_ME1016810202011-SCONN168_ME1016810202011,A   I168 @T6G_MB_LIB.T6G(SCH_1):PAGE335

P5E_CPU0_G3_RX_DP<10> @T6G_MB_LIB.T6G(SCH_1):P5E_CPU0_G3_RX_DP(10)
   U25 AJ33 G3_RXP10||SATA32_RXP GENOA_SP5-SOCKET6096_13568-001,SMLF,IO,DGA^6000030   I216 @T6G_MB_LIB.T6G(SCH_1):PAGE23
   J38  A51 PERP10 SCONN168_ME1016810202011-SCONN168_ME1016810202011,A   I168 @T6G_MB_LIB.T6G(SCH_1):PAGE335

P5E_CPU0_G3_RX_DP<11> @T6G_MB_LIB.T6G(SCH_1):P5E_CPU0_G3_RX_DP(11)
   U25 AN33 G3_RXP11||SATA33_RXP GENOA_SP5-SOCKET6096_13568-001,SMLF,IO,DGA^6000030   I216 @T6G_MB_LIB.T6G(SCH_1):PAGE23
   J38  A54 PERP11 SCONN168_ME1016810202011-SCONN168_ME1016810202011,A   I168 @T6G_MB_LIB.T6G(SCH_1):PAGE335

P5E_CPU0_G3_RX_DP<12> @T6G_MB_LIB.T6G(SCH_1):P5E_CPU0_G3_RX_DP(12)
   U25 AK36 G3_RXP12||SATA34_RXP GENOA_SP5-SOCKET6096_13568-001,SMLF,IO,DGA^6000030   I216 @T6G_MB_LIB.T6G(SCH_1):PAGE23
   J38  A57 PERP12 SCONN168_ME1016810202011-SCONN168_ME1016810202011,A   I168 @T6G_MB_LIB.T6G(SCH_1):PAGE335

P5E_CPU0_G3_RX_DP<13> @T6G_MB_LIB.T6G(SCH_1):P5E_CPU0_G3_RX_DP(13)
   U25 AH36 G3_RXP13||SATA35_RXP GENOA_SP5-SOCKET6096_13568-001,SMLF,IO,DGA^6000030   I216 @T6G_MB_LIB.T6G(SCH_1):PAGE23
   J38  A60 PERP13 SCONN168_ME1016810202011-SCONN168_ME1016810202011,A   I168 @T6G_MB_LIB.T6G(SCH_1):PAGE335

P5E_CPU0_G3_RX_DP<14> @T6G_MB_LIB.T6G(SCH_1):P5E_CPU0_G3_RX_DP(14)
   U25 AM36 G3_RXP14||SATA36_RXP GENOA_SP5-SOCKET6096_13568-001,SMLF,IO,DGA^6000030   I216 @T6G_MB_LIB.T6G(SCH_1):PAGE23
   J38  A63 PERP14 SCONN168_ME1016810202011-SCONN168_ME1016810202011,A   I168 @T6G_MB_LIB.T6G(SCH_1):PAGE335

P5E_CPU0_G3_RX_DP<15> @T6G_MB_LIB.T6G(SCH_1):P5E_CPU0_G3_RX_DP(15)
   U25 AP36 G3_RXP15||SATA37_RXP GENOA_SP5-SOCKET6096_13568-001,SMLF,IO,DGA^6000030   I216 @T6G_MB_LIB.T6G(SCH_1):PAGE23
   J38  A66 PERP15 SCONN168_ME1016810202011-SCONN168_ME1016810202011,A   I168 @T6G_MB_LIB.T6G(SCH_1):PAGE335

P5E_CPU0_G3_RX_DP<1> @T6G_MB_LIB.T6G(SCH_1):P5E_CPU0_G3_RX_DP(1)
   U25 AJ24 G3_RXP1||SATA21_RXP GENOA_SP5-SOCKET6096_13568-001,SMLF,IO,DGA^6000030   I216 @T6G_MB_LIB.T6G(SCH_1):PAGE23
   J38  A21  PERP1 SCONN168_ME1016810202011-SCONN168_ME1016810202011,A   I168 @T6G_MB_LIB.T6G(SCH_1):PAGE335

P5E_CPU0_G3_RX_DP<2> @T6G_MB_LIB.T6G(SCH_1):P5E_CPU0_G3_RX_DP(2)
   U25 AN24 G3_RXP2||SATA22_RXP GENOA_SP5-SOCKET6096_13568-001,SMLF,IO,DGA^6000030   I216 @T6G_MB_LIB.T6G(SCH_1):PAGE23
   J38  A24  PERP2 SCONN168_ME1016810202011-SCONN168_ME1016810202011,A   I168 @T6G_MB_LIB.T6G(SCH_1):PAGE335

P5E_CPU0_G3_RX_DP<3> @T6G_MB_LIB.T6G(SCH_1):P5E_CPU0_G3_RX_DP(3)
   U25 AL27 G3_RXP3||SATA23_RXP GENOA_SP5-SOCKET6096_13568-001,SMLF,IO,DGA^6000030   I216 @T6G_MB_LIB.T6G(SCH_1):PAGE23
   J38  A27  PERP3 SCONN168_ME1016810202011-SCONN168_ME1016810202011,A   I168 @T6G_MB_LIB.T6G(SCH_1):PAGE335

P5E_CPU0_G3_RX_DP<4> @T6G_MB_LIB.T6G(SCH_1):P5E_CPU0_G3_RX_DP(4)
   U25 AJ27 G3_RXP4||SATA24_RXP GENOA_SP5-SOCKET6096_13568-001,SMLF,IO,DGA^6000030   I216 @T6G_MB_LIB.T6G(SCH_1):PAGE23
   J38  A31  PERP4 SCONN168_ME1016810202011-SCONN168_ME1016810202011,A   I168 @T6G_MB_LIB.T6G(SCH_1):PAGE335

P5E_CPU0_G3_RX_DP<5> @T6G_MB_LIB.T6G(SCH_1):P5E_CPU0_G3_RX_DP(5)
   U25 AN27 G3_RXP5||SATA25_RXP GENOA_SP5-SOCKET6096_13568-001,SMLF,IO,DGA^6000030   I216 @T6G_MB_LIB.T6G(SCH_1):PAGE23
   J38  A34  PERP5 SCONN168_ME1016810202011-SCONN168_ME1016810202011,A   I168 @T6G_MB_LIB.T6G(SCH_1):PAGE335

P5E_CPU0_G3_RX_DP<6> @T6G_MB_LIB.T6G(SCH_1):P5E_CPU0_G3_RX_DP(6)
   U25 AL30 G3_RXP6||SATA26_RXP GENOA_SP5-SOCKET6096_13568-001,SMLF,IO,DGA^6000030   I216 @T6G_MB_LIB.T6G(SCH_1):PAGE23
   J38  A37  PERP6 SCONN168_ME1016810202011-SCONN168_ME1016810202011,A   I168 @T6G_MB_LIB.T6G(SCH_1):PAGE335

P5E_CPU0_G3_RX_DP<7> @T6G_MB_LIB.T6G(SCH_1):P5E_CPU0_G3_RX_DP(7)
   U25 AJ30 G3_RXP7||SATA27_RXP GENOA_SP5-SOCKET6096_13568-001,SMLF,IO,DGA^6000030   I216 @T6G_MB_LIB.T6G(SCH_1):PAGE23
   J38  A40  PERP7 SCONN168_ME1016810202011-SCONN168_ME1016810202011,A   I168 @T6G_MB_LIB.T6G(SCH_1):PAGE335

P5E_CPU0_G3_RX_DP<8> @T6G_MB_LIB.T6G(SCH_1):P5E_CPU0_G3_RX_DP(8)
   U25 AN30 G3_RXP8||SATA30_RXP GENOA_SP5-SOCKET6096_13568-001,SMLF,IO,DGA^6000030   I216 @T6G_MB_LIB.T6G(SCH_1):PAGE23
   J38  A45  PERP8 SCONN168_ME1016810202011-SCONN168_ME1016810202011,A   I168 @T6G_MB_LIB.T6G(SCH_1):PAGE335

P5E_CPU0_G3_RX_DP<9> @T6G_MB_LIB.T6G(SCH_1):P5E_CPU0_G3_RX_DP(9)
   U25 AL33 G3_RXP9||SATA31_RXP GENOA_SP5-SOCKET6096_13568-001,SMLF,IO,DGA^6000030   I216 @T6G_MB_LIB.T6G(SCH_1):PAGE23
   J38  A48  PERP9 SCONN168_ME1016810202011-SCONN168_ME1016810202011,A   I168 @T6G_MB_LIB.T6G(SCH_1):PAGE335

P5E_CPU0_G3_TX_C_DN<0> @T6G_MB_LIB.T6G(SCH_1):P5E_CPU0_G3_TX_C_DN(0)
   J38  B18  PETP0 SCONN168_ME1016810202011-SCONN168_ME1016810202011,A   I168 @T6G_MB_LIB.T6G(SCH_1):PAGE335
 C1578    1      1 Q_CAP_DIFFBUS_C0201-DIFF BUS_0.22UF,6.3V,20%,X6S,SA   I230 @T6G_MB_LIB.T6G(SCH_1):PAGE353

P5E_CPU0_G3_TX_C_DN<10> @T6G_MB_LIB.T6G(SCH_1):P5E_CPU0_G3_TX_C_DN(10)
   J38  B51 PETP10 SCONN168_ME1016810202011-SCONN168_ME1016810202011,A   I168 @T6G_MB_LIB.T6G(SCH_1):PAGE335
 C1558    1      1 Q_CAP_DIFFBUS_C0201-DIFF BUS_0.22UF,6.3V,20%,X6S,SA   I264 @T6G_MB_LIB.T6G(SCH_1):PAGE353

P5E_CPU0_G3_TX_C_DN<11> @T6G_MB_LIB.T6G(SCH_1):P5E_CPU0_G3_TX_C_DN(11)
   J38  B54 PETP11 SCONN168_ME1016810202011-SCONN168_ME1016810202011,A   I168 @T6G_MB_LIB.T6G(SCH_1):PAGE335
 C1556    1      1 Q_CAP_DIFFBUS_C0201-DIFF BUS_0.22UF,6.3V,20%,X6S,SA   I265 @T6G_MB_LIB.T6G(SCH_1):PAGE353

P5E_CPU0_G3_TX_C_DN<12> @T6G_MB_LIB.T6G(SCH_1):P5E_CPU0_G3_TX_C_DN(12)
   J38  B57 PETP12 SCONN168_ME1016810202011-SCONN168_ME1016810202011,A   I168 @T6G_MB_LIB.T6G(SCH_1):PAGE335
   C41    1      1 Q_CAP_DIFFBUS_C0201-DIFF BUS_0.22UF,6.3V,20%,X6S,SA   I268 @T6G_MB_LIB.T6G(SCH_1):PAGE353

P5E_CPU0_G3_TX_C_DN<13> @T6G_MB_LIB.T6G(SCH_1):P5E_CPU0_G3_TX_C_DN(13)
   J38  B60 PETP13 SCONN168_ME1016810202011-SCONN168_ME1016810202011,A   I168 @T6G_MB_LIB.T6G(SCH_1):PAGE335
 C1552    1      1 Q_CAP_DIFFBUS_C0201-DIFF BUS_0.22UF,6.3V,20%,X6S,SA   I270 @T6G_MB_LIB.T6G(SCH_1):PAGE353

P5E_CPU0_G3_TX_C_DN<14> @T6G_MB_LIB.T6G(SCH_1):P5E_CPU0_G3_TX_C_DN(14)
   J38  B63 PETP14 SCONN168_ME1016810202011-SCONN168_ME1016810202011,A   I168 @T6G_MB_LIB.T6G(SCH_1):PAGE335
 C1550    1      1 Q_CAP_DIFFBUS_C0201-DIFF BUS_0.22UF,6.3V,20%,X6S,SA   I272 @T6G_MB_LIB.T6G(SCH_1):PAGE353

P5E_CPU0_G3_TX_C_DN<15> @T6G_MB_LIB.T6G(SCH_1):P5E_CPU0_G3_TX_C_DN(15)
   J38  B66 PETP15 SCONN168_ME1016810202011-SCONN168_ME1016810202011,A   I168 @T6G_MB_LIB.T6G(SCH_1):PAGE335
 C1548    1      1 Q_CAP_DIFFBUS_C0201-DIFF BUS_0.22UF,6.3V,20%,X6S,SA   I273 @T6G_MB_LIB.T6G(SCH_1):PAGE353

P5E_CPU0_G3_TX_C_DN<1> @T6G_MB_LIB.T6G(SCH_1):P5E_CPU0_G3_TX_C_DN(1)
   J38  B21  PETP1 SCONN168_ME1016810202011-SCONN168_ME1016810202011,A   I168 @T6G_MB_LIB.T6G(SCH_1):PAGE335
 C1576    1      1 Q_CAP_DIFFBUS_C0201-DIFF BUS_0.22UF,6.3V,20%,X6S,SA   I312 @T6G_MB_LIB.T6G(SCH_1):PAGE353

P5E_CPU0_G3_TX_C_DN<2> @T6G_MB_LIB.T6G(SCH_1):P5E_CPU0_G3_TX_C_DN(2)
   J38  B24  PETP2 SCONN168_ME1016810202011-SCONN168_ME1016810202011,A   I168 @T6G_MB_LIB.T6G(SCH_1):PAGE335
 C1574    1      1 Q_CAP_DIFFBUS_C0201-DIFF BUS_0.22UF,6.3V,20%,X6S,SA   I232 @T6G_MB_LIB.T6G(SCH_1):PAGE353

P5E_CPU0_G3_TX_C_DN<3> @T6G_MB_LIB.T6G(SCH_1):P5E_CPU0_G3_TX_C_DN(3)
   J38  B27  PETP3 SCONN168_ME1016810202011-SCONN168_ME1016810202011,A   I168 @T6G_MB_LIB.T6G(SCH_1):PAGE335
 C1572    1      1 Q_CAP_DIFFBUS_C0201-DIFF BUS_0.22UF,6.3V,20%,X6S,SA   I234 @T6G_MB_LIB.T6G(SCH_1):PAGE353

P5E_CPU0_G3_TX_C_DN<4> @T6G_MB_LIB.T6G(SCH_1):P5E_CPU0_G3_TX_C_DN(4)
   J38  B31  PETP4 SCONN168_ME1016810202011-SCONN168_ME1016810202011,A   I168 @T6G_MB_LIB.T6G(SCH_1):PAGE335
 C1570    1      1 Q_CAP_DIFFBUS_C0201-DIFF BUS_0.22UF,6.3V,20%,X6S,SA   I235 @T6G_MB_LIB.T6G(SCH_1):PAGE353

P5E_CPU0_G3_TX_C_DN<5> @T6G_MB_LIB.T6G(SCH_1):P5E_CPU0_G3_TX_C_DN(5)
   J38  B34  PETP5 SCONN168_ME1016810202011-SCONN168_ME1016810202011,A   I168 @T6G_MB_LIB.T6G(SCH_1):PAGE335
 C1568    1      1 Q_CAP_DIFFBUS_C0201-DIFF BUS_0.22UF,6.3V,20%,X6S,SA   I238 @T6G_MB_LIB.T6G(SCH_1):PAGE353

P5E_CPU0_G3_TX_C_DN<6> @T6G_MB_LIB.T6G(SCH_1):P5E_CPU0_G3_TX_C_DN(6)
   J38  B37  PETP6 SCONN168_ME1016810202011-SCONN168_ME1016810202011,A   I168 @T6G_MB_LIB.T6G(SCH_1):PAGE335
 C1566    1      1 Q_CAP_DIFFBUS_C0201-DIFF BUS_0.22UF,6.3V,20%,X6S,SA   I240 @T6G_MB_LIB.T6G(SCH_1):PAGE353

P5E_CPU0_G3_TX_C_DN<7> @T6G_MB_LIB.T6G(SCH_1):P5E_CPU0_G3_TX_C_DN(7)
   J38  B40  PETP7 SCONN168_ME1016810202011-SCONN168_ME1016810202011,A   I168 @T6G_MB_LIB.T6G(SCH_1):PAGE335
   C46    1      1 Q_CAP_DIFFBUS_C0201-DIFF BUS_0.22UF,6.3V,20%,X6S,SA   I242 @T6G_MB_LIB.T6G(SCH_1):PAGE353

P5E_CPU0_G3_TX_C_DN<8> @T6G_MB_LIB.T6G(SCH_1):P5E_CPU0_G3_TX_C_DN(8)
   J38  B45  PETP8 SCONN168_ME1016810202011-SCONN168_ME1016810202011,A   I168 @T6G_MB_LIB.T6G(SCH_1):PAGE335
 C1794    1      1 Q_CAP_DIFFBUS_C0201-DIFF BUS_0.22UF,6.3V,20%,X6S,SA   I260 @T6G_MB_LIB.T6G(SCH_1):PAGE353

P5E_CPU0_G3_TX_C_DN<9> @T6G_MB_LIB.T6G(SCH_1):P5E_CPU0_G3_TX_C_DN(9)
   J38  B48  PETP9 SCONN168_ME1016810202011-SCONN168_ME1016810202011,A   I168 @T6G_MB_LIB.T6G(SCH_1):PAGE335
 C1560    1      1 Q_CAP_DIFFBUS_C0201-DIFF BUS_0.22UF,6.3V,20%,X6S,SA   I262 @T6G_MB_LIB.T6G(SCH_1):PAGE353

P5E_CPU0_G3_TX_C_DP<0> @T6G_MB_LIB.T6G(SCH_1):P5E_CPU0_G3_TX_C_DP(0)
   J38  B17  PETN0 SCONN168_ME1016810202011-SCONN168_ME1016810202011,A   I168 @T6G_MB_LIB.T6G(SCH_1):PAGE335
 C1579    1      1 Q_CAP_DIFFBUS_C0201-DIFF BUS_0.22UF,6.3V,20%,X6S,SA   I229 @T6G_MB_LIB.T6G(SCH_1):PAGE353

P5E_CPU0_G3_TX_C_DP<10> @T6G_MB_LIB.T6G(SCH_1):P5E_CPU0_G3_TX_C_DP(10)
   J38  B50 PETN10 SCONN168_ME1016810202011-SCONN168_ME1016810202011,A   I168 @T6G_MB_LIB.T6G(SCH_1):PAGE335
 C1559    1      1 Q_CAP_DIFFBUS_C0201-DIFF BUS_0.22UF,6.3V,20%,X6S,SA   I263 @T6G_MB_LIB.T6G(SCH_1):PAGE353

P5E_CPU0_G3_TX_C_DP<11> @T6G_MB_LIB.T6G(SCH_1):P5E_CPU0_G3_TX_C_DP(11)
   J38  B53 PETN11 SCONN168_ME1016810202011-SCONN168_ME1016810202011,A   I168 @T6G_MB_LIB.T6G(SCH_1):PAGE335
 C1557    1      1 Q_CAP_DIFFBUS_C0201-DIFF BUS_0.22UF,6.3V,20%,X6S,SA   I266 @T6G_MB_LIB.T6G(SCH_1):PAGE353

P5E_CPU0_G3_TX_C_DP<12> @T6G_MB_LIB.T6G(SCH_1):P5E_CPU0_G3_TX_C_DP(12)
   J38  B56 PETN12 SCONN168_ME1016810202011-SCONN168_ME1016810202011,A   I168 @T6G_MB_LIB.T6G(SCH_1):PAGE335
 C1555    1      1 Q_CAP_DIFFBUS_C0201-DIFF BUS_0.22UF,6.3V,20%,X6S,SA   I267 @T6G_MB_LIB.T6G(SCH_1):PAGE353

P5E_CPU0_G3_TX_C_DP<13> @T6G_MB_LIB.T6G(SCH_1):P5E_CPU0_G3_TX_C_DP(13)
   J38  B59 PETN13 SCONN168_ME1016810202011-SCONN168_ME1016810202011,A   I168 @T6G_MB_LIB.T6G(SCH_1):PAGE335
 C1553    1      1 Q_CAP_DIFFBUS_C0201-DIFF BUS_0.22UF,6.3V,20%,X6S,SA   I269 @T6G_MB_LIB.T6G(SCH_1):PAGE353

P5E_CPU0_G3_TX_C_DP<14> @T6G_MB_LIB.T6G(SCH_1):P5E_CPU0_G3_TX_C_DP(14)
   J38  B62 PETN14 SCONN168_ME1016810202011-SCONN168_ME1016810202011,A   I168 @T6G_MB_LIB.T6G(SCH_1):PAGE335
 C1792    1      1 Q_CAP_DIFFBUS_C0201-DIFF BUS_0.22UF,6.3V,20%,X6S,SA   I271 @T6G_MB_LIB.T6G(SCH_1):PAGE353

P5E_CPU0_G3_TX_C_DP<15> @T6G_MB_LIB.T6G(SCH_1):P5E_CPU0_G3_TX_C_DP(15)
   J38  B65 PETN15 SCONN168_ME1016810202011-SCONN168_ME1016810202011,A   I168 @T6G_MB_LIB.T6G(SCH_1):PAGE335
 C1549    1      1 Q_CAP_DIFFBUS_C0201-DIFF BUS_0.22UF,6.3V,20%,X6S,SA   I274 @T6G_MB_LIB.T6G(SCH_1):PAGE353

P5E_CPU0_G3_TX_C_DP<1> @T6G_MB_LIB.T6G(SCH_1):P5E_CPU0_G3_TX_C_DP(1)
   J38  B20  PETN1 SCONN168_ME1016810202011-SCONN168_ME1016810202011,A   I168 @T6G_MB_LIB.T6G(SCH_1):PAGE335
 C1577    1      1 Q_CAP_DIFFBUS_C0201-DIFF BUS_0.22UF,6.3V,20%,X6S,SA   I311 @T6G_MB_LIB.T6G(SCH_1):PAGE353

P5E_CPU0_G3_TX_C_DP<2> @T6G_MB_LIB.T6G(SCH_1):P5E_CPU0_G3_TX_C_DP(2)
   J38  B23  PETN2 SCONN168_ME1016810202011-SCONN168_ME1016810202011,A   I168 @T6G_MB_LIB.T6G(SCH_1):PAGE335
 C1575    1      1 Q_CAP_DIFFBUS_C0201-DIFF BUS_0.22UF,6.3V,20%,X6S,SA   I231 @T6G_MB_LIB.T6G(SCH_1):PAGE353

P5E_CPU0_G3_TX_C_DP<3> @T6G_MB_LIB.T6G(SCH_1):P5E_CPU0_G3_TX_C_DP(3)
   J38  B26  PETN3 SCONN168_ME1016810202011-SCONN168_ME1016810202011,A   I168 @T6G_MB_LIB.T6G(SCH_1):PAGE335
 C1573    1      1 Q_CAP_DIFFBUS_C0201-DIFF BUS_0.22UF,6.3V,20%,X6S,SA   I233 @T6G_MB_LIB.T6G(SCH_1):PAGE353

P5E_CPU0_G3_TX_C_DP<4> @T6G_MB_LIB.T6G(SCH_1):P5E_CPU0_G3_TX_C_DP(4)
   J38  B30  PETN4 SCONN168_ME1016810202011-SCONN168_ME1016810202011,A   I168 @T6G_MB_LIB.T6G(SCH_1):PAGE335
 C1571    1      1 Q_CAP_DIFFBUS_C0201-DIFF BUS_0.22UF,6.3V,20%,X6S,SA   I236 @T6G_MB_LIB.T6G(SCH_1):PAGE353

P5E_CPU0_G3_TX_C_DP<5> @T6G_MB_LIB.T6G(SCH_1):P5E_CPU0_G3_TX_C_DP(5)
   J38  B33  PETN5 SCONN168_ME1016810202011-SCONN168_ME1016810202011,A   I168 @T6G_MB_LIB.T6G(SCH_1):PAGE335
 C1569    1      1 Q_CAP_DIFFBUS_C0201-DIFF BUS_0.22UF,6.3V,20%,X6S,SA   I237 @T6G_MB_LIB.T6G(SCH_1):PAGE353

P5E_CPU0_G3_TX_C_DP<6> @T6G_MB_LIB.T6G(SCH_1):P5E_CPU0_G3_TX_C_DP(6)
   J38  B36  PETN6 SCONN168_ME1016810202011-SCONN168_ME1016810202011,A   I168 @T6G_MB_LIB.T6G(SCH_1):PAGE335
   C47    1      1 Q_CAP_DIFFBUS_C0201-DIFF BUS_0.22UF,6.3V,20%,X6S,SA   I239 @T6G_MB_LIB.T6G(SCH_1):PAGE353

P5E_CPU0_G3_TX_C_DP<7> @T6G_MB_LIB.T6G(SCH_1):P5E_CPU0_G3_TX_C_DP(7)
   J38  B39  PETN7 SCONN168_ME1016810202011-SCONN168_ME1016810202011,A   I168 @T6G_MB_LIB.T6G(SCH_1):PAGE335
 C1565    1      1 Q_CAP_DIFFBUS_C0201-DIFF BUS_0.22UF,6.3V,20%,X6S,SA   I241 @T6G_MB_LIB.T6G(SCH_1):PAGE353

P5E_CPU0_G3_TX_C_DP<8> @T6G_MB_LIB.T6G(SCH_1):P5E_CPU0_G3_TX_C_DP(8)
   J38  B44  PETN8 SCONN168_ME1016810202011-SCONN168_ME1016810202011,A   I168 @T6G_MB_LIB.T6G(SCH_1):PAGE335
   C44    1      1 Q_CAP_DIFFBUS_C0201-DIFF BUS_0.22UF,6.3V,20%,X6S,SA   I259 @T6G_MB_LIB.T6G(SCH_1):PAGE353

P5E_CPU0_G3_TX_C_DP<9> @T6G_MB_LIB.T6G(SCH_1):P5E_CPU0_G3_TX_C_DP(9)
   J38  B47  PETN9 SCONN168_ME1016810202011-SCONN168_ME1016810202011,A   I168 @T6G_MB_LIB.T6G(SCH_1):PAGE335
 C1793    1      1 Q_CAP_DIFFBUS_C0201-DIFF BUS_0.22UF,6.3V,20%,X6S,SA   I261 @T6G_MB_LIB.T6G(SCH_1):PAGE353

P5E_CPU0_G3_TX_DN<0> @T6G_MB_LIB.T6G(SCH_1):P5E_CPU0_G3_TX_DN(0)
   U25  U24 G3_TXN0||SATA20_TXN GENOA_SP5-SOCKET6096_13568-001,SMLF,IO,DGA^6000030   I216 @T6G_MB_LIB.T6G(SCH_1):PAGE23
 C1578    2      2 Q_CAP_DIFFBUS_C0201-DIFF BUS_0.22UF,6.3V,20%,X6S,SA   I230 @T6G_MB_LIB.T6G(SCH_1):PAGE353

P5E_CPU0_G3_TX_DN<10> @T6G_MB_LIB.T6G(SCH_1):P5E_CPU0_G3_TX_DN(10)
   U25  R33 G3_TXN10||SATA32_TXN GENOA_SP5-SOCKET6096_13568-001,SMLF,IO,DGA^6000030   I216 @T6G_MB_LIB.T6G(SCH_1):PAGE23
 C1558    2      2 Q_CAP_DIFFBUS_C0201-DIFF BUS_0.22UF,6.3V,20%,X6S,SA   I264 @T6G_MB_LIB.T6G(SCH_1):PAGE353

P5E_CPU0_G3_TX_DN<11> @T6G_MB_LIB.T6G(SCH_1):P5E_CPU0_G3_TX_DN(11)
   U25  N33 G3_TXN11||SATA33_TXN GENOA_SP5-SOCKET6096_13568-001,SMLF,IO,DGA^6000030   I216 @T6G_MB_LIB.T6G(SCH_1):PAGE23
 C1556    2      2 Q_CAP_DIFFBUS_C0201-DIFF BUS_0.22UF,6.3V,20%,X6S,SA   I265 @T6G_MB_LIB.T6G(SCH_1):PAGE353

P5E_CPU0_G3_TX_DN<12> @T6G_MB_LIB.T6G(SCH_1):P5E_CPU0_G3_TX_DN(12)
   U25  U33 G3_TXN12||SATA34_TXN GENOA_SP5-SOCKET6096_13568-001,SMLF,IO,DGA^6000030   I216 @T6G_MB_LIB.T6G(SCH_1):PAGE23
   C41    2      2 Q_CAP_DIFFBUS_C0201-DIFF BUS_0.22UF,6.3V,20%,X6S,SA   I268 @T6G_MB_LIB.T6G(SCH_1):PAGE353

P5E_CPU0_G3_TX_DN<13> @T6G_MB_LIB.T6G(SCH_1):P5E_CPU0_G3_TX_DN(13)
   U25  P36 G3_TXN13||SATA35_TXN GENOA_SP5-SOCKET6096_13568-001,SMLF,IO,DGA^6000030   I216 @T6G_MB_LIB.T6G(SCH_1):PAGE23
 C1552    2      2 Q_CAP_DIFFBUS_C0201-DIFF BUS_0.22UF,6.3V,20%,X6S,SA   I270 @T6G_MB_LIB.T6G(SCH_1):PAGE353

P5E_CPU0_G3_TX_DN<14> @T6G_MB_LIB.T6G(SCH_1):P5E_CPU0_G3_TX_DN(14)
   U25  T36 G3_TXN14||SATA36_TXN GENOA_SP5-SOCKET6096_13568-001,SMLF,IO,DGA^6000030   I216 @T6G_MB_LIB.T6G(SCH_1):PAGE23
 C1550    2      2 Q_CAP_DIFFBUS_C0201-DIFF BUS_0.22UF,6.3V,20%,X6S,SA   I272 @T6G_MB_LIB.T6G(SCH_1):PAGE353

P5E_CPU0_G3_TX_DN<15> @T6G_MB_LIB.T6G(SCH_1):P5E_CPU0_G3_TX_DN(15)
   U25  V36 G3_TXN15||SATA37_TXN GENOA_SP5-SOCKET6096_13568-001,SMLF,IO,DGA^6000030   I216 @T6G_MB_LIB.T6G(SCH_1):PAGE23
 C1548    2      2 Q_CAP_DIFFBUS_C0201-DIFF BUS_0.22UF,6.3V,20%,X6S,SA   I273 @T6G_MB_LIB.T6G(SCH_1):PAGE353

P5E_CPU0_G3_TX_DN<1> @T6G_MB_LIB.T6G(SCH_1):P5E_CPU0_G3_TX_DN(1)
   U25  R24 G3_TXN1||SATA21_TXN GENOA_SP5-SOCKET6096_13568-001,SMLF,IO,DGA^6000030   I216 @T6G_MB_LIB.T6G(SCH_1):PAGE23
 C1576    2      2 Q_CAP_DIFFBUS_C0201-DIFF BUS_0.22UF,6.3V,20%,X6S,SA   I312 @T6G_MB_LIB.T6G(SCH_1):PAGE353

P5E_CPU0_G3_TX_DN<2> @T6G_MB_LIB.T6G(SCH_1):P5E_CPU0_G3_TX_DN(2)
   U25  W24 G3_TXN2||SATA22_TXN GENOA_SP5-SOCKET6096_13568-001,SMLF,IO,DGA^6000030   I216 @T6G_MB_LIB.T6G(SCH_1):PAGE23
 C1574    2      2 Q_CAP_DIFFBUS_C0201-DIFF BUS_0.22UF,6.3V,20%,X6S,SA   I232 @T6G_MB_LIB.T6G(SCH_1):PAGE353

P5E_CPU0_G3_TX_DN<3> @T6G_MB_LIB.T6G(SCH_1):P5E_CPU0_G3_TX_DN(3)
   U25  U27 G3_TXN3||SATA23_TXN GENOA_SP5-SOCKET6096_13568-001,SMLF,IO,DGA^6000030   I216 @T6G_MB_LIB.T6G(SCH_1):PAGE23
 C1572    2      2 Q_CAP_DIFFBUS_C0201-DIFF BUS_0.22UF,6.3V,20%,X6S,SA   I234 @T6G_MB_LIB.T6G(SCH_1):PAGE353

P5E_CPU0_G3_TX_DN<4> @T6G_MB_LIB.T6G(SCH_1):P5E_CPU0_G3_TX_DN(4)
   U25  R27 G3_TXN4||SATA24_TXN GENOA_SP5-SOCKET6096_13568-001,SMLF,IO,DGA^6000030   I216 @T6G_MB_LIB.T6G(SCH_1):PAGE23
 C1570    2      2 Q_CAP_DIFFBUS_C0201-DIFF BUS_0.22UF,6.3V,20%,X6S,SA   I235 @T6G_MB_LIB.T6G(SCH_1):PAGE353

P5E_CPU0_G3_TX_DN<5> @T6G_MB_LIB.T6G(SCH_1):P5E_CPU0_G3_TX_DN(5)
   U25  N27 G3_TXN5||SATA25_TXN GENOA_SP5-SOCKET6096_13568-001,SMLF,IO,DGA^6000030   I216 @T6G_MB_LIB.T6G(SCH_1):PAGE23
 C1568    2      2 Q_CAP_DIFFBUS_C0201-DIFF BUS_0.22UF,6.3V,20%,X6S,SA   I238 @T6G_MB_LIB.T6G(SCH_1):PAGE353

P5E_CPU0_G3_TX_DN<6> @T6G_MB_LIB.T6G(SCH_1):P5E_CPU0_G3_TX_DN(6)
   U25  W27 G3_TXN6||SATA26_TXN GENOA_SP5-SOCKET6096_13568-001,SMLF,IO,DGA^6000030   I216 @T6G_MB_LIB.T6G(SCH_1):PAGE23
 C1566    2      2 Q_CAP_DIFFBUS_C0201-DIFF BUS_0.22UF,6.3V,20%,X6S,SA   I240 @T6G_MB_LIB.T6G(SCH_1):PAGE353

P5E_CPU0_G3_TX_DN<7> @T6G_MB_LIB.T6G(SCH_1):P5E_CPU0_G3_TX_DN(7)
   U25  R30 G3_TXN7||SATA27_TXN GENOA_SP5-SOCKET6096_13568-001,SMLF,IO,DGA^6000030   I216 @T6G_MB_LIB.T6G(SCH_1):PAGE23
   C46    2      2 Q_CAP_DIFFBUS_C0201-DIFF BUS_0.22UF,6.3V,20%,X6S,SA   I242 @T6G_MB_LIB.T6G(SCH_1):PAGE353

P5E_CPU0_G3_TX_DN<8> @T6G_MB_LIB.T6G(SCH_1):P5E_CPU0_G3_TX_DN(8)
   U25  N30 G3_TXN8||SATA30_TXN GENOA_SP5-SOCKET6096_13568-001,SMLF,IO,DGA^6000030   I216 @T6G_MB_LIB.T6G(SCH_1):PAGE23
 C1794    2      2 Q_CAP_DIFFBUS_C0201-DIFF BUS_0.22UF,6.3V,20%,X6S,SA   I260 @T6G_MB_LIB.T6G(SCH_1):PAGE353

P5E_CPU0_G3_TX_DN<9> @T6G_MB_LIB.T6G(SCH_1):P5E_CPU0_G3_TX_DN(9)
   U25  U30 G3_TXN9||SATA31_TXN GENOA_SP5-SOCKET6096_13568-001,SMLF,IO,DGA^6000030   I216 @T6G_MB_LIB.T6G(SCH_1):PAGE23
 C1560    2      2 Q_CAP_DIFFBUS_C0201-DIFF BUS_0.22UF,6.3V,20%,X6S,SA   I262 @T6G_MB_LIB.T6G(SCH_1):PAGE353

P5E_CPU0_G3_TX_DP<0> @T6G_MB_LIB.T6G(SCH_1):P5E_CPU0_G3_TX_DP(0)
   U25  U23 G3_TXP0||SATA20_TXP GENOA_SP5-SOCKET6096_13568-001,SMLF,IO,DGA^6000030   I216 @T6G_MB_LIB.T6G(SCH_1):PAGE23
 C1579    2      2 Q_CAP_DIFFBUS_C0201-DIFF BUS_0.22UF,6.3V,20%,X6S,SA   I229 @T6G_MB_LIB.T6G(SCH_1):PAGE353

P5E_CPU0_G3_TX_DP<10> @T6G_MB_LIB.T6G(SCH_1):P5E_CPU0_G3_TX_DP(10)
   U25  R32 G3_TXP10||SATA32_TXP GENOA_SP5-SOCKET6096_13568-001,SMLF,IO,DGA^6000030   I216 @T6G_MB_LIB.T6G(SCH_1):PAGE23
 C1559    2      2 Q_CAP_DIFFBUS_C0201-DIFF BUS_0.22UF,6.3V,20%,X6S,SA   I263 @T6G_MB_LIB.T6G(SCH_1):PAGE353

P5E_CPU0_G3_TX_DP<11> @T6G_MB_LIB.T6G(SCH_1):P5E_CPU0_G3_TX_DP(11)
   U25  N32 G3_TXP11||SATA33_TXP GENOA_SP5-SOCKET6096_13568-001,SMLF,IO,DGA^6000030   I216 @T6G_MB_LIB.T6G(SCH_1):PAGE23
 C1557    2      2 Q_CAP_DIFFBUS_C0201-DIFF BUS_0.22UF,6.3V,20%,X6S,SA   I266 @T6G_MB_LIB.T6G(SCH_1):PAGE353

P5E_CPU0_G3_TX_DP<12> @T6G_MB_LIB.T6G(SCH_1):P5E_CPU0_G3_TX_DP(12)
   U25  U32 G3_TXP12||SATA34_TXP GENOA_SP5-SOCKET6096_13568-001,SMLF,IO,DGA^6000030   I216 @T6G_MB_LIB.T6G(SCH_1):PAGE23
 C1555    2      2 Q_CAP_DIFFBUS_C0201-DIFF BUS_0.22UF,6.3V,20%,X6S,SA   I267 @T6G_MB_LIB.T6G(SCH_1):PAGE353

P5E_CPU0_G3_TX_DP<13> @T6G_MB_LIB.T6G(SCH_1):P5E_CPU0_G3_TX_DP(13)
   U25  P35 G3_TXP13||SATA35_TXP GENOA_SP5-SOCKET6096_13568-001,SMLF,IO,DGA^6000030   I216 @T6G_MB_LIB.T6G(SCH_1):PAGE23
 C1553    2      2 Q_CAP_DIFFBUS_C0201-DIFF BUS_0.22UF,6.3V,20%,X6S,SA   I269 @T6G_MB_LIB.T6G(SCH_1):PAGE353

P5E_CPU0_G3_TX_DP<14> @T6G_MB_LIB.T6G(SCH_1):P5E_CPU0_G3_TX_DP(14)
   U25  T35 G3_TXP14||SATA36_TXP GENOA_SP5-SOCKET6096_13568-001,SMLF,IO,DGA^6000030   I216 @T6G_MB_LIB.T6G(SCH_1):PAGE23
 C1792    2      2 Q_CAP_DIFFBUS_C0201-DIFF BUS_0.22UF,6.3V,20%,X6S,SA   I271 @T6G_MB_LIB.T6G(SCH_1):PAGE353

P5E_CPU0_G3_TX_DP<15> @T6G_MB_LIB.T6G(SCH_1):P5E_CPU0_G3_TX_DP(15)
   U25  V35 G3_TXP15||SATA37_TXP GENOA_SP5-SOCKET6096_13568-001,SMLF,IO,DGA^6000030   I216 @T6G_MB_LIB.T6G(SCH_1):PAGE23
 C1549    2      2 Q_CAP_DIFFBUS_C0201-DIFF BUS_0.22UF,6.3V,20%,X6S,SA   I274 @T6G_MB_LIB.T6G(SCH_1):PAGE353

P5E_CPU0_G3_TX_DP<1> @T6G_MB_LIB.T6G(SCH_1):P5E_CPU0_G3_TX_DP(1)
   U25  R23 G3_TXP1||SATA21_TXP GENOA_SP5-SOCKET6096_13568-001,SMLF,IO,DGA^6000030   I216 @T6G_MB_LIB.T6G(SCH_1):PAGE23
 C1577    2      2 Q_CAP_DIFFBUS_C0201-DIFF BUS_0.22UF,6.3V,20%,X6S,SA   I311 @T6G_MB_LIB.T6G(SCH_1):PAGE353

P5E_CPU0_G3_TX_DP<2> @T6G_MB_LIB.T6G(SCH_1):P5E_CPU0_G3_TX_DP(2)
   U25  W23 G3_TXP2||SATA22_TXP GENOA_SP5-SOCKET6096_13568-001,SMLF,IO,DGA^6000030   I216 @T6G_MB_LIB.T6G(SCH_1):PAGE23
 C1575    2      2 Q_CAP_DIFFBUS_C0201-DIFF BUS_0.22UF,6.3V,20%,X6S,SA   I231 @T6G_MB_LIB.T6G(SCH_1):PAGE353

P5E_CPU0_G3_TX_DP<3> @T6G_MB_LIB.T6G(SCH_1):P5E_CPU0_G3_TX_DP(3)
   U25  U26 G3_TXP3||SATA23_TXP GENOA_SP5-SOCKET6096_13568-001,SMLF,IO,DGA^6000030   I216 @T6G_MB_LIB.T6G(SCH_1):PAGE23
 C1573    2      2 Q_CAP_DIFFBUS_C0201-DIFF BUS_0.22UF,6.3V,20%,X6S,SA   I233 @T6G_MB_LIB.T6G(SCH_1):PAGE353

P5E_CPU0_G3_TX_DP<4> @T6G_MB_LIB.T6G(SCH_1):P5E_CPU0_G3_TX_DP(4)
   U25  R26 G3_TXP4||SATA24_TXP GENOA_SP5-SOCKET6096_13568-001,SMLF,IO,DGA^6000030   I216 @T6G_MB_LIB.T6G(SCH_1):PAGE23
 C1571    2      2 Q_CAP_DIFFBUS_C0201-DIFF BUS_0.22UF,6.3V,20%,X6S,SA   I236 @T6G_MB_LIB.T6G(SCH_1):PAGE353

P5E_CPU0_G3_TX_DP<5> @T6G_MB_LIB.T6G(SCH_1):P5E_CPU0_G3_TX_DP(5)
   U25  N26 G3_TXP5||SATA25_TXP GENOA_SP5-SOCKET6096_13568-001,SMLF,IO,DGA^6000030   I216 @T6G_MB_LIB.T6G(SCH_1):PAGE23
 C1569    2      2 Q_CAP_DIFFBUS_C0201-DIFF BUS_0.22UF,6.3V,20%,X6S,SA   I237 @T6G_MB_LIB.T6G(SCH_1):PAGE353

P5E_CPU0_G3_TX_DP<6> @T6G_MB_LIB.T6G(SCH_1):P5E_CPU0_G3_TX_DP(6)
   U25  W26 G3_TXP6||SATA26_TXP GENOA_SP5-SOCKET6096_13568-001,SMLF,IO,DGA^6000030   I216 @T6G_MB_LIB.T6G(SCH_1):PAGE23
   C47    2      2 Q_CAP_DIFFBUS_C0201-DIFF BUS_0.22UF,6.3V,20%,X6S,SA   I239 @T6G_MB_LIB.T6G(SCH_1):PAGE353

P5E_CPU0_G3_TX_DP<7> @T6G_MB_LIB.T6G(SCH_1):P5E_CPU0_G3_TX_DP(7)
   U25  R29 G3_TXP7||SATA27_TXP GENOA_SP5-SOCKET6096_13568-001,SMLF,IO,DGA^6000030   I216 @T6G_MB_LIB.T6G(SCH_1):PAGE23
 C1565    2      2 Q_CAP_DIFFBUS_C0201-DIFF BUS_0.22UF,6.3V,20%,X6S,SA   I241 @T6G_MB_LIB.T6G(SCH_1):PAGE353

P5E_CPU0_G3_TX_DP<8> @T6G_MB_LIB.T6G(SCH_1):P5E_CPU0_G3_TX_DP(8)
   U25  N29 G3_TXP8||SATA30_TXP GENOA_SP5-SOCKET6096_13568-001,SMLF,IO,DGA^6000030   I216 @T6G_MB_LIB.T6G(SCH_1):PAGE23
   C44    2      2 Q_CAP_DIFFBUS_C0201-DIFF BUS_0.22UF,6.3V,20%,X6S,SA   I259 @T6G_MB_LIB.T6G(SCH_1):PAGE353

P5E_CPU0_G3_TX_DP<9> @T6G_MB_LIB.T6G(SCH_1):P5E_CPU0_G3_TX_DP(9)
   U25  U29 G3_TXP9||SATA31_TXP GENOA_SP5-SOCKET6096_13568-001,SMLF,IO,DGA^6000030   I216 @T6G_MB_LIB.T6G(SCH_1):PAGE23
 C1793    2      2 Q_CAP_DIFFBUS_C0201-DIFF BUS_0.22UF,6.3V,20%,X6S,SA   I261 @T6G_MB_LIB.T6G(SCH_1):PAGE353

P5E_CPU0_P0_RX_BUF_DN<0> @T6G_MB_LIB.T6G(SCH_1):P5E_CPU0_P0_RX_BUF_DN(0)
 U6010  EV2 A_PERN15 PT5161LRS-PT5161LRS,SMLF,IC,AJ051610U03     I3 @T6G_MB_LIB.T6G(SCH_1):PAGE383
  J108   C1     C1 CONN112_10137002101LF-CONN112_10137002-101LF,THLF,A    I72 @T6G_MB_LIB.T6G(SCH_1):PAGE320

P5E_CPU0_P0_RX_BUF_DN<10> @T6G_MB_LIB.T6G(SCH_1):P5E_CPU0_P0_RX_BUF_DN(10)
 U6010  BH2 A_PERN5 PT5161LRS-PT5161LRS,SMLF,IC,AJ051610U03     I4 @T6G_MB_LIB.T6G(SCH_1):PAGE383
  J107   C3     C3 CONN112_10137002101LF-CONN112_10137002-101LF,THLF,A    I49 @T6G_MB_LIB.T6G(SCH_1):PAGE317

P5E_CPU0_P0_RX_BUF_DN<11> @T6G_MB_LIB.T6G(SCH_1):P5E_CPU0_P0_RX_BUF_DN(11)
 U6010  BA2 A_PERN4 PT5161LRS-PT5161LRS,SMLF,IC,AJ051610U03     I4 @T6G_MB_LIB.T6G(SCH_1):PAGE383
  J107   B4     B4 CONN112_10137002101LF-CONN112_10137002-101LF,THLF,A    I49 @T6G_MB_LIB.T6G(SCH_1):PAGE317

P5E_CPU0_P0_RX_BUF_DN<12> @T6G_MB_LIB.T6G(SCH_1):P5E_CPU0_P0_RX_BUF_DN(12)
 U6010  AP2 A_PERN3 PT5161LRS-PT5161LRS,SMLF,IC,AJ051610U03     I4 @T6G_MB_LIB.T6G(SCH_1):PAGE383
  J107   C5     C5 CONN112_10137002101LF-CONN112_10137002-101LF,THLF,A    I70 @T6G_MB_LIB.T6G(SCH_1):PAGE317

P5E_CPU0_P0_RX_BUF_DN<13> @T6G_MB_LIB.T6G(SCH_1):P5E_CPU0_P0_RX_BUF_DN(13)
 U6010  AG2 A_PERN2 PT5161LRS-PT5161LRS,SMLF,IC,AJ051610U03     I4 @T6G_MB_LIB.T6G(SCH_1):PAGE383
  J107   B6     B6 CONN112_10137002101LF-CONN112_10137002-101LF,THLF,A    I70 @T6G_MB_LIB.T6G(SCH_1):PAGE317

P5E_CPU0_P0_RX_BUF_DN<14> @T6G_MB_LIB.T6G(SCH_1):P5E_CPU0_P0_RX_BUF_DN(14)
 U6010   Y2 A_PERN1 PT5161LRS-PT5161LRS,SMLF,IC,AJ051610U03     I4 @T6G_MB_LIB.T6G(SCH_1):PAGE383
  J107   C7     C7 CONN112_10137002101LF-CONN112_10137002-101LF,THLF,A    I70 @T6G_MB_LIB.T6G(SCH_1):PAGE317

P5E_CPU0_P0_RX_BUF_DN<15> @T6G_MB_LIB.T6G(SCH_1):P5E_CPU0_P0_RX_BUF_DN(15)
 U6010   N2 A_PERN0 PT5161LRS-PT5161LRS,SMLF,IC,AJ051610U03     I4 @T6G_MB_LIB.T6G(SCH_1):PAGE383
  J107   B8     B8 CONN112_10137002101LF-CONN112_10137002-101LF,THLF,A    I70 @T6G_MB_LIB.T6G(SCH_1):PAGE317

P5E_CPU0_P0_RX_BUF_DN<1> @T6G_MB_LIB.T6G(SCH_1):P5E_CPU0_P0_RX_BUF_DN(1)
 U6010  EL2 A_PERN14 PT5161LRS-PT5161LRS,SMLF,IC,AJ051610U03     I3 @T6G_MB_LIB.T6G(SCH_1):PAGE383
  J108   B2     B2 CONN112_10137002101LF-CONN112_10137002-101LF,THLF,A    I72 @T6G_MB_LIB.T6G(SCH_1):PAGE320

P5E_CPU0_P0_RX_BUF_DN<2> @T6G_MB_LIB.T6G(SCH_1):P5E_CPU0_P0_RX_BUF_DN(2)
 U6010  ED2 A_PERN13 PT5161LRS-PT5161LRS,SMLF,IC,AJ051610U03     I3 @T6G_MB_LIB.T6G(SCH_1):PAGE383
  J108   C3     C3 CONN112_10137002101LF-CONN112_10137002-101LF,THLF,A    I72 @T6G_MB_LIB.T6G(SCH_1):PAGE320

P5E_CPU0_P0_RX_BUF_DN<3> @T6G_MB_LIB.T6G(SCH_1):P5E_CPU0_P0_RX_BUF_DN(3)
 U6010  DU2 A_PERN12 PT5161LRS-PT5161LRS,SMLF,IC,AJ051610U03     I3 @T6G_MB_LIB.T6G(SCH_1):PAGE383
  J108   B4     B4 CONN112_10137002101LF-CONN112_10137002-101LF,THLF,A    I72 @T6G_MB_LIB.T6G(SCH_1):PAGE320

P5E_CPU0_P0_RX_BUF_DN<4> @T6G_MB_LIB.T6G(SCH_1):P5E_CPU0_P0_RX_BUF_DN(4)
 U6010  DK2 A_PERN11 PT5161LRS-PT5161LRS,SMLF,IC,AJ051610U03     I3 @T6G_MB_LIB.T6G(SCH_1):PAGE383
  J108   C5     C5 CONN112_10137002101LF-CONN112_10137002-101LF,THLF,A    I15 @T6G_MB_LIB.T6G(SCH_1):PAGE320

P5E_CPU0_P0_RX_BUF_DN<5> @T6G_MB_LIB.T6G(SCH_1):P5E_CPU0_P0_RX_BUF_DN(5)
 U6010  DC2 A_PERN10 PT5161LRS-PT5161LRS,SMLF,IC,AJ051610U03     I3 @T6G_MB_LIB.T6G(SCH_1):PAGE383
  J108   B6     B6 CONN112_10137002101LF-CONN112_10137002-101LF,THLF,A    I15 @T6G_MB_LIB.T6G(SCH_1):PAGE320

P5E_CPU0_P0_RX_BUF_DN<6> @T6G_MB_LIB.T6G(SCH_1):P5E_CPU0_P0_RX_BUF_DN(6)
 U6010  CT2 A_PERN9 PT5161LRS-PT5161LRS,SMLF,IC,AJ051610U03     I3 @T6G_MB_LIB.T6G(SCH_1):PAGE383
  J108   C7     C7 CONN112_10137002101LF-CONN112_10137002-101LF,THLF,A    I15 @T6G_MB_LIB.T6G(SCH_1):PAGE320

P5E_CPU0_P0_RX_BUF_DN<7> @T6G_MB_LIB.T6G(SCH_1):P5E_CPU0_P0_RX_BUF_DN(7)
 U6010  CJ2 A_PERN8 PT5161LRS-PT5161LRS,SMLF,IC,AJ051610U03     I3 @T6G_MB_LIB.T6G(SCH_1):PAGE383
  J108   B8     B8 CONN112_10137002101LF-CONN112_10137002-101LF,THLF,A    I15 @T6G_MB_LIB.T6G(SCH_1):PAGE320

P5E_CPU0_P0_RX_BUF_DN<8> @T6G_MB_LIB.T6G(SCH_1):P5E_CPU0_P0_RX_BUF_DN(8)
 U6010  CB2 A_PERN7 PT5161LRS-PT5161LRS,SMLF,IC,AJ051610U03     I4 @T6G_MB_LIB.T6G(SCH_1):PAGE383
  J107   C1     C1 CONN112_10137002101LF-CONN112_10137002-101LF,THLF,A    I49 @T6G_MB_LIB.T6G(SCH_1):PAGE317

P5E_CPU0_P0_RX_BUF_DN<9> @T6G_MB_LIB.T6G(SCH_1):P5E_CPU0_P0_RX_BUF_DN(9)
 U6010  BR2 A_PERN6 PT5161LRS-PT5161LRS,SMLF,IC,AJ051610U03     I4 @T6G_MB_LIB.T6G(SCH_1):PAGE383
  J107   B2     B2 CONN112_10137002101LF-CONN112_10137002-101LF,THLF,A    I49 @T6G_MB_LIB.T6G(SCH_1):PAGE317

P5E_CPU0_P0_RX_BUF_DP<0> @T6G_MB_LIB.T6G(SCH_1):P5E_CPU0_P0_RX_BUF_DP(0)
 U6010  EY1 A_PERP15 PT5161LRS-PT5161LRS,SMLF,IC,AJ051610U03     I3 @T6G_MB_LIB.T6G(SCH_1):PAGE383
  J108   D1     D1 CONN112_10137002101LF-CONN112_10137002-101LF,THLF,A    I72 @T6G_MB_LIB.T6G(SCH_1):PAGE320

P5E_CPU0_P0_RX_BUF_DP<10> @T6G_MB_LIB.T6G(SCH_1):P5E_CPU0_P0_RX_BUF_DP(10)
 U6010  BK1 A_PERP5 PT5161LRS-PT5161LRS,SMLF,IC,AJ051610U03     I4 @T6G_MB_LIB.T6G(SCH_1):PAGE383
  J107   D3     D3 CONN112_10137002101LF-CONN112_10137002-101LF,THLF,A    I49 @T6G_MB_LIB.T6G(SCH_1):PAGE317

P5E_CPU0_P0_RX_BUF_DP<11> @T6G_MB_LIB.T6G(SCH_1):P5E_CPU0_P0_RX_BUF_DP(11)
 U6010  BC1 A_PERP4 PT5161LRS-PT5161LRS,SMLF,IC,AJ051610U03     I4 @T6G_MB_LIB.T6G(SCH_1):PAGE383
  J107   C4     C4 CONN112_10137002101LF-CONN112_10137002-101LF,THLF,A    I49 @T6G_MB_LIB.T6G(SCH_1):PAGE317

P5E_CPU0_P0_RX_BUF_DP<12> @T6G_MB_LIB.T6G(SCH_1):P5E_CPU0_P0_RX_BUF_DP(12)
 U6010  AT1 A_PERP3 PT5161LRS-PT5161LRS,SMLF,IC,AJ051610U03     I4 @T6G_MB_LIB.T6G(SCH_1):PAGE383
  J107   D5     D5 CONN112_10137002101LF-CONN112_10137002-101LF,THLF,A    I70 @T6G_MB_LIB.T6G(SCH_1):PAGE317

P5E_CPU0_P0_RX_BUF_DP<13> @T6G_MB_LIB.T6G(SCH_1):P5E_CPU0_P0_RX_BUF_DP(13)
 U6010  AJ1 A_PERP2 PT5161LRS-PT5161LRS,SMLF,IC,AJ051610U03     I4 @T6G_MB_LIB.T6G(SCH_1):PAGE383
  J107   C6     C6 CONN112_10137002101LF-CONN112_10137002-101LF,THLF,A    I70 @T6G_MB_LIB.T6G(SCH_1):PAGE317

P5E_CPU0_P0_RX_BUF_DP<14> @T6G_MB_LIB.T6G(SCH_1):P5E_CPU0_P0_RX_BUF_DP(14)
 U6010  AB1 A_PERP1 PT5161LRS-PT5161LRS,SMLF,IC,AJ051610U03     I4 @T6G_MB_LIB.T6G(SCH_1):PAGE383
  J107   D7     D7 CONN112_10137002101LF-CONN112_10137002-101LF,THLF,A    I70 @T6G_MB_LIB.T6G(SCH_1):PAGE317

P5E_CPU0_P0_RX_BUF_DP<15> @T6G_MB_LIB.T6G(SCH_1):P5E_CPU0_P0_RX_BUF_DP(15)
 U6010   R1 A_PERP0 PT5161LRS-PT5161LRS,SMLF,IC,AJ051610U03     I4 @T6G_MB_LIB.T6G(SCH_1):PAGE383
  J107   C8     C8 CONN112_10137002101LF-CONN112_10137002-101LF,THLF,A    I70 @T6G_MB_LIB.T6G(SCH_1):PAGE317

P5E_CPU0_P0_RX_BUF_DP<1> @T6G_MB_LIB.T6G(SCH_1):P5E_CPU0_P0_RX_BUF_DP(1)
 U6010  EN1 A_PERP14 PT5161LRS-PT5161LRS,SMLF,IC,AJ051610U03     I3 @T6G_MB_LIB.T6G(SCH_1):PAGE383
  J108   C2     C2 CONN112_10137002101LF-CONN112_10137002-101LF,THLF,A    I72 @T6G_MB_LIB.T6G(SCH_1):PAGE320

P5E_CPU0_P0_RX_BUF_DP<2> @T6G_MB_LIB.T6G(SCH_1):P5E_CPU0_P0_RX_BUF_DP(2)
 U6010  EF1 A_PERP13 PT5161LRS-PT5161LRS,SMLF,IC,AJ051610U03     I3 @T6G_MB_LIB.T6G(SCH_1):PAGE383
  J108   D3     D3 CONN112_10137002101LF-CONN112_10137002-101LF,THLF,A    I72 @T6G_MB_LIB.T6G(SCH_1):PAGE320

P5E_CPU0_P0_RX_BUF_DP<3> @T6G_MB_LIB.T6G(SCH_1):P5E_CPU0_P0_RX_BUF_DP(3)
 U6010  DW1 A_PERP12 PT5161LRS-PT5161LRS,SMLF,IC,AJ051610U03     I3 @T6G_MB_LIB.T6G(SCH_1):PAGE383
  J108   C4     C4 CONN112_10137002101LF-CONN112_10137002-101LF,THLF,A    I72 @T6G_MB_LIB.T6G(SCH_1):PAGE320

P5E_CPU0_P0_RX_BUF_DP<4> @T6G_MB_LIB.T6G(SCH_1):P5E_CPU0_P0_RX_BUF_DP(4)
 U6010  DM1 A_PERP11 PT5161LRS-PT5161LRS,SMLF,IC,AJ051610U03     I3 @T6G_MB_LIB.T6G(SCH_1):PAGE383
  J108   D5     D5 CONN112_10137002101LF-CONN112_10137002-101LF,THLF,A    I15 @T6G_MB_LIB.T6G(SCH_1):PAGE320

P5E_CPU0_P0_RX_BUF_DP<5> @T6G_MB_LIB.T6G(SCH_1):P5E_CPU0_P0_RX_BUF_DP(5)
 U6010  DE1 A_PERP10 PT5161LRS-PT5161LRS,SMLF,IC,AJ051610U03     I3 @T6G_MB_LIB.T6G(SCH_1):PAGE383
  J108   C6     C6 CONN112_10137002101LF-CONN112_10137002-101LF,THLF,A    I15 @T6G_MB_LIB.T6G(SCH_1):PAGE320

P5E_CPU0_P0_RX_BUF_DP<6> @T6G_MB_LIB.T6G(SCH_1):P5E_CPU0_P0_RX_BUF_DP(6)
 U6010  CV1 A_PERP9 PT5161LRS-PT5161LRS,SMLF,IC,AJ051610U03     I3 @T6G_MB_LIB.T6G(SCH_1):PAGE383
  J108   D7     D7 CONN112_10137002101LF-CONN112_10137002-101LF,THLF,A    I15 @T6G_MB_LIB.T6G(SCH_1):PAGE320

P5E_CPU0_P0_RX_BUF_DP<7> @T6G_MB_LIB.T6G(SCH_1):P5E_CPU0_P0_RX_BUF_DP(7)
 U6010  CL1 A_PERP8 PT5161LRS-PT5161LRS,SMLF,IC,AJ051610U03     I3 @T6G_MB_LIB.T6G(SCH_1):PAGE383
  J108   C8     C8 CONN112_10137002101LF-CONN112_10137002-101LF,THLF,A    I15 @T6G_MB_LIB.T6G(SCH_1):PAGE320

P5E_CPU0_P0_RX_BUF_DP<8> @T6G_MB_LIB.T6G(SCH_1):P5E_CPU0_P0_RX_BUF_DP(8)
 U6010  CD1 A_PERP7 PT5161LRS-PT5161LRS,SMLF,IC,AJ051610U03     I4 @T6G_MB_LIB.T6G(SCH_1):PAGE383
  J107   D1     D1 CONN112_10137002101LF-CONN112_10137002-101LF,THLF,A    I49 @T6G_MB_LIB.T6G(SCH_1):PAGE317

P5E_CPU0_P0_RX_BUF_DP<9> @T6G_MB_LIB.T6G(SCH_1):P5E_CPU0_P0_RX_BUF_DP(9)
 U6010  BU1 A_PERP6 PT5161LRS-PT5161LRS,SMLF,IC,AJ051610U03     I4 @T6G_MB_LIB.T6G(SCH_1):PAGE383
  J107   C2     C2 CONN112_10137002101LF-CONN112_10137002-101LF,THLF,A    I49 @T6G_MB_LIB.T6G(SCH_1):PAGE317

P5E_CPU0_P0_RX_DN<0> @T6G_MB_LIB.T6G(SCH_1):P5E_CPU0_P0_RX_DN(0)
   U25 BW53 P0_RXN0||SATA00_RXN GENOA_SP5-SOCKET6096_13568-001,SMLF,IO,DGA^6000030   I148 @T6G_MB_LIB.T6G(SCH_1):PAGE24
 U6010 EW29 A_PETN15 PT5161LRS-PT5161LRS,SMLF,IC,AJ051610U03     I3 @T6G_MB_LIB.T6G(SCH_1):PAGE382

P5E_CPU0_P0_RX_DN<10> @T6G_MB_LIB.T6G(SCH_1):P5E_CPU0_P0_RX_DN(10)
   U25 CA44 P0_RXN10||SATA12_RXN GENOA_SP5-SOCKET6096_13568-001,SMLF,IO,DGA^6000030   I148 @T6G_MB_LIB.T6G(SCH_1):PAGE24
 U6010 BJ29 A_PETN5 PT5161LRS-PT5161LRS,SMLF,IC,AJ051610U03     I2 @T6G_MB_LIB.T6G(SCH_1):PAGE382

P5E_CPU0_P0_RX_DN<11> @T6G_MB_LIB.T6G(SCH_1):P5E_CPU0_P0_RX_DN(11)
   U25 BU44 P0_RXN11||SATA13_RXN GENOA_SP5-SOCKET6096_13568-001,SMLF,IO,DGA^6000030   I148 @T6G_MB_LIB.T6G(SCH_1):PAGE24
 U6010 BB29 A_PETN4 PT5161LRS-PT5161LRS,SMLF,IC,AJ051610U03     I2 @T6G_MB_LIB.T6G(SCH_1):PAGE382

P5E_CPU0_P0_RX_DN<12> @T6G_MB_LIB.T6G(SCH_1):P5E_CPU0_P0_RX_DN(12)
   U25 BY41 P0_RXN12||SATA14_RXN GENOA_SP5-SOCKET6096_13568-001,SMLF,IO,DGA^6000030   I148 @T6G_MB_LIB.T6G(SCH_1):PAGE24
 U6010 AR29 A_PETN3 PT5161LRS-PT5161LRS,SMLF,IC,AJ051610U03     I2 @T6G_MB_LIB.T6G(SCH_1):PAGE382

P5E_CPU0_P0_RX_DN<13> @T6G_MB_LIB.T6G(SCH_1):P5E_CPU0_P0_RX_DN(13)
   U25 CB41 P0_RXN13||SATA15_RXN GENOA_SP5-SOCKET6096_13568-001,SMLF,IO,DGA^6000030   I148 @T6G_MB_LIB.T6G(SCH_1):PAGE24
 U6010 AH29 A_PETN2 PT5161LRS-PT5161LRS,SMLF,IC,AJ051610U03     I2 @T6G_MB_LIB.T6G(SCH_1):PAGE382

P5E_CPU0_P0_RX_DN<14> @T6G_MB_LIB.T6G(SCH_1):P5E_CPU0_P0_RX_DN(14)
   U25 BV41 P0_RXN14||SATA16_RXN GENOA_SP5-SOCKET6096_13568-001,SMLF,IO,DGA^6000030   I148 @T6G_MB_LIB.T6G(SCH_1):PAGE24
 U6010 AA29 A_PETN1 PT5161LRS-PT5161LRS,SMLF,IC,AJ051610U03     I2 @T6G_MB_LIB.T6G(SCH_1):PAGE382

P5E_CPU0_P0_RX_DN<15> @T6G_MB_LIB.T6G(SCH_1):P5E_CPU0_P0_RX_DN(15)
   U25 BT41 P0_RXN15||SATA17_RXN GENOA_SP5-SOCKET6096_13568-001,SMLF,IO,DGA^6000030   I148 @T6G_MB_LIB.T6G(SCH_1):PAGE24
 U6010  P29 A_PETN0 PT5161LRS-PT5161LRS,SMLF,IC,AJ051610U03     I2 @T6G_MB_LIB.T6G(SCH_1):PAGE382

P5E_CPU0_P0_RX_DN<1> @T6G_MB_LIB.T6G(SCH_1):P5E_CPU0_P0_RX_DN(1)
   U25 CA53 P0_RXN1||SATA01_RXN GENOA_SP5-SOCKET6096_13568-001,SMLF,IO,DGA^6000030   I148 @T6G_MB_LIB.T6G(SCH_1):PAGE24
 U6010 EM29 A_PETN14 PT5161LRS-PT5161LRS,SMLF,IC,AJ051610U03     I3 @T6G_MB_LIB.T6G(SCH_1):PAGE382

P5E_CPU0_P0_RX_DN<2> @T6G_MB_LIB.T6G(SCH_1):P5E_CPU0_P0_RX_DN(2)
   U25 BU53 P0_RXN2||SATA02_RXN GENOA_SP5-SOCKET6096_13568-001,SMLF,IO,DGA^6000030   I148 @T6G_MB_LIB.T6G(SCH_1):PAGE24
 U6010 EE29 A_PETN13 PT5161LRS-PT5161LRS,SMLF,IC,AJ051610U03     I3 @T6G_MB_LIB.T6G(SCH_1):PAGE382

P5E_CPU0_P0_RX_DN<3> @T6G_MB_LIB.T6G(SCH_1):P5E_CPU0_P0_RX_DN(3)
   U25 BW50 P0_RXN3||SATA03_RXN GENOA_SP5-SOCKET6096_13568-001,SMLF,IO,DGA^6000030   I148 @T6G_MB_LIB.T6G(SCH_1):PAGE24
 U6010 DV29 A_PETN12 PT5161LRS-PT5161LRS,SMLF,IC,AJ051610U03     I3 @T6G_MB_LIB.T6G(SCH_1):PAGE382

P5E_CPU0_P0_RX_DN<4> @T6G_MB_LIB.T6G(SCH_1):P5E_CPU0_P0_RX_DN(4)
   U25 CA50 P0_RXN4||SATA04_RXN GENOA_SP5-SOCKET6096_13568-001,SMLF,IO,DGA^6000030   I148 @T6G_MB_LIB.T6G(SCH_1):PAGE24
 U6010 DL29 A_PETN11 PT5161LRS-PT5161LRS,SMLF,IC,AJ051610U03     I3 @T6G_MB_LIB.T6G(SCH_1):PAGE382

P5E_CPU0_P0_RX_DN<5> @T6G_MB_LIB.T6G(SCH_1):P5E_CPU0_P0_RX_DN(5)
   U25 BU50 P0_RXN5||SATA05_RXN GENOA_SP5-SOCKET6096_13568-001,SMLF,IO,DGA^6000030   I148 @T6G_MB_LIB.T6G(SCH_1):PAGE24
 U6010 DD29 A_PETN10 PT5161LRS-PT5161LRS,SMLF,IC,AJ051610U03     I3 @T6G_MB_LIB.T6G(SCH_1):PAGE382

P5E_CPU0_P0_RX_DN<6> @T6G_MB_LIB.T6G(SCH_1):P5E_CPU0_P0_RX_DN(6)
   U25 BW47 P0_RXN6||SATA06_RXN GENOA_SP5-SOCKET6096_13568-001,SMLF,IO,DGA^6000030   I148 @T6G_MB_LIB.T6G(SCH_1):PAGE24
 U6010 CU29 A_PETN9 PT5161LRS-PT5161LRS,SMLF,IC,AJ051610U03     I3 @T6G_MB_LIB.T6G(SCH_1):PAGE382

P5E_CPU0_P0_RX_DN<7> @T6G_MB_LIB.T6G(SCH_1):P5E_CPU0_P0_RX_DN(7)
   U25 CA47 P0_RXN7||SATA07_RXN GENOA_SP5-SOCKET6096_13568-001,SMLF,IO,DGA^6000030   I148 @T6G_MB_LIB.T6G(SCH_1):PAGE24
 U6010 CK29 A_PETN8 PT5161LRS-PT5161LRS,SMLF,IC,AJ051610U03     I3 @T6G_MB_LIB.T6G(SCH_1):PAGE382

P5E_CPU0_P0_RX_DN<8> @T6G_MB_LIB.T6G(SCH_1):P5E_CPU0_P0_RX_DN(8)
   U25 BU47 P0_RXN8||SATA10_RXN GENOA_SP5-SOCKET6096_13568-001,SMLF,IO,DGA^6000030   I148 @T6G_MB_LIB.T6G(SCH_1):PAGE24
 U6010 CC29 A_PETN7 PT5161LRS-PT5161LRS,SMLF,IC,AJ051610U03     I2 @T6G_MB_LIB.T6G(SCH_1):PAGE382

P5E_CPU0_P0_RX_DN<9> @T6G_MB_LIB.T6G(SCH_1):P5E_CPU0_P0_RX_DN(9)
   U25 BW44 P0_RXN9||SATA11_RXN GENOA_SP5-SOCKET6096_13568-001,SMLF,IO,DGA^6000030   I148 @T6G_MB_LIB.T6G(SCH_1):PAGE24
 U6010 BT29 A_PETN6 PT5161LRS-PT5161LRS,SMLF,IC,AJ051610U03     I2 @T6G_MB_LIB.T6G(SCH_1):PAGE382

P5E_CPU0_P0_RX_DP<0> @T6G_MB_LIB.T6G(SCH_1):P5E_CPU0_P0_RX_DP(0)
   U25 BW52 P0_RXP0||SATA00_RXP GENOA_SP5-SOCKET6096_13568-001,SMLF,IO,DGA^6000030   I148 @T6G_MB_LIB.T6G(SCH_1):PAGE24
 U6010 EU26 A_PETP15 PT5161LRS-PT5161LRS,SMLF,IC,AJ051610U03     I3 @T6G_MB_LIB.T6G(SCH_1):PAGE382

P5E_CPU0_P0_RX_DP<10> @T6G_MB_LIB.T6G(SCH_1):P5E_CPU0_P0_RX_DP(10)
   U25 CA43 P0_RXP10||SATA12_RXP GENOA_SP5-SOCKET6096_13568-001,SMLF,IO,DGA^6000030   I148 @T6G_MB_LIB.T6G(SCH_1):PAGE24
 U6010 BG26 A_PETP5 PT5161LRS-PT5161LRS,SMLF,IC,AJ051610U03     I2 @T6G_MB_LIB.T6G(SCH_1):PAGE382

P5E_CPU0_P0_RX_DP<11> @T6G_MB_LIB.T6G(SCH_1):P5E_CPU0_P0_RX_DP(11)
   U25 BU43 P0_RXP11||SATA13_RXP GENOA_SP5-SOCKET6096_13568-001,SMLF,IO,DGA^6000030   I148 @T6G_MB_LIB.T6G(SCH_1):PAGE24
 U6010 AY26 A_PETP4 PT5161LRS-PT5161LRS,SMLF,IC,AJ051610U03     I2 @T6G_MB_LIB.T6G(SCH_1):PAGE382

P5E_CPU0_P0_RX_DP<12> @T6G_MB_LIB.T6G(SCH_1):P5E_CPU0_P0_RX_DP(12)
   U25 BY40 P0_RXP12||SATA14_RXP GENOA_SP5-SOCKET6096_13568-001,SMLF,IO,DGA^6000030   I148 @T6G_MB_LIB.T6G(SCH_1):PAGE24
 U6010 AN26 A_PETP3 PT5161LRS-PT5161LRS,SMLF,IC,AJ051610U03     I2 @T6G_MB_LIB.T6G(SCH_1):PAGE382

P5E_CPU0_P0_RX_DP<13> @T6G_MB_LIB.T6G(SCH_1):P5E_CPU0_P0_RX_DP(13)
   U25 CB40 P0_RXP13||SATA15_RXP GENOA_SP5-SOCKET6096_13568-001,SMLF,IO,DGA^6000030   I148 @T6G_MB_LIB.T6G(SCH_1):PAGE24
 U6010 AF26 A_PETP2 PT5161LRS-PT5161LRS,SMLF,IC,AJ051610U03     I2 @T6G_MB_LIB.T6G(SCH_1):PAGE382

P5E_CPU0_P0_RX_DP<14> @T6G_MB_LIB.T6G(SCH_1):P5E_CPU0_P0_RX_DP(14)
   U25 BV40 P0_RXP14||SATA16_RXP GENOA_SP5-SOCKET6096_13568-001,SMLF,IO,DGA^6000030   I148 @T6G_MB_LIB.T6G(SCH_1):PAGE24
 U6010  W26 A_PETP1 PT5161LRS-PT5161LRS,SMLF,IC,AJ051610U03     I2 @T6G_MB_LIB.T6G(SCH_1):PAGE382

P5E_CPU0_P0_RX_DP<15> @T6G_MB_LIB.T6G(SCH_1):P5E_CPU0_P0_RX_DP(15)
   U25 BT40 P0_RXP15||SATA17_RXP GENOA_SP5-SOCKET6096_13568-001,SMLF,IO,DGA^6000030   I148 @T6G_MB_LIB.T6G(SCH_1):PAGE24
 U6010  M26 A_PETP0 PT5161LRS-PT5161LRS,SMLF,IC,AJ051610U03     I2 @T6G_MB_LIB.T6G(SCH_1):PAGE382

P5E_CPU0_P0_RX_DP<1> @T6G_MB_LIB.T6G(SCH_1):P5E_CPU0_P0_RX_DP(1)
   U25 CA52 P0_RXP1||SATA01_RXP GENOA_SP5-SOCKET6096_13568-001,SMLF,IO,DGA^6000030   I148 @T6G_MB_LIB.T6G(SCH_1):PAGE24
 U6010 EK26 A_PETP14 PT5161LRS-PT5161LRS,SMLF,IC,AJ051610U03     I3 @T6G_MB_LIB.T6G(SCH_1):PAGE382

P5E_CPU0_P0_RX_DP<2> @T6G_MB_LIB.T6G(SCH_1):P5E_CPU0_P0_RX_DP(2)
   U25 BU52 P0_RXP2||SATA02_RXP GENOA_SP5-SOCKET6096_13568-001,SMLF,IO,DGA^6000030   I148 @T6G_MB_LIB.T6G(SCH_1):PAGE24
 U6010 EC26 A_PETP13 PT5161LRS-PT5161LRS,SMLF,IC,AJ051610U03     I3 @T6G_MB_LIB.T6G(SCH_1):PAGE382

P5E_CPU0_P0_RX_DP<3> @T6G_MB_LIB.T6G(SCH_1):P5E_CPU0_P0_RX_DP(3)
   U25 BW49 P0_RXP3||SATA03_RXP GENOA_SP5-SOCKET6096_13568-001,SMLF,IO,DGA^6000030   I148 @T6G_MB_LIB.T6G(SCH_1):PAGE24
 U6010 DT26 A_PETP12 PT5161LRS-PT5161LRS,SMLF,IC,AJ051610U03     I3 @T6G_MB_LIB.T6G(SCH_1):PAGE382

P5E_CPU0_P0_RX_DP<4> @T6G_MB_LIB.T6G(SCH_1):P5E_CPU0_P0_RX_DP(4)
   U25 CA49 P0_RXP4||SATA04_RXP GENOA_SP5-SOCKET6096_13568-001,SMLF,IO,DGA^6000030   I148 @T6G_MB_LIB.T6G(SCH_1):PAGE24
 U6010 DJ26 A_PETP11 PT5161LRS-PT5161LRS,SMLF,IC,AJ051610U03     I3 @T6G_MB_LIB.T6G(SCH_1):PAGE382

P5E_CPU0_P0_RX_DP<5> @T6G_MB_LIB.T6G(SCH_1):P5E_CPU0_P0_RX_DP(5)
   U25 BU49 P0_RXP5||SATA05_RXP GENOA_SP5-SOCKET6096_13568-001,SMLF,IO,DGA^6000030   I148 @T6G_MB_LIB.T6G(SCH_1):PAGE24
 U6010 DB26 A_PETP10 PT5161LRS-PT5161LRS,SMLF,IC,AJ051610U03     I3 @T6G_MB_LIB.T6G(SCH_1):PAGE382

P5E_CPU0_P0_RX_DP<6> @T6G_MB_LIB.T6G(SCH_1):P5E_CPU0_P0_RX_DP(6)
   U25 BW46 P0_RXP6||SATA06_RXP GENOA_SP5-SOCKET6096_13568-001,SMLF,IO,DGA^6000030   I148 @T6G_MB_LIB.T6G(SCH_1):PAGE24
 U6010 CR26 A_PETP9 PT5161LRS-PT5161LRS,SMLF,IC,AJ051610U03     I3 @T6G_MB_LIB.T6G(SCH_1):PAGE382

P5E_CPU0_P0_RX_DP<7> @T6G_MB_LIB.T6G(SCH_1):P5E_CPU0_P0_RX_DP(7)
   U25 CA46 P0_RXP7||SATA07_RXP GENOA_SP5-SOCKET6096_13568-001,SMLF,IO,DGA^6000030   I148 @T6G_MB_LIB.T6G(SCH_1):PAGE24
 U6010 CH26 A_PETP8 PT5161LRS-PT5161LRS,SMLF,IC,AJ051610U03     I3 @T6G_MB_LIB.T6G(SCH_1):PAGE382

P5E_CPU0_P0_RX_DP<8> @T6G_MB_LIB.T6G(SCH_1):P5E_CPU0_P0_RX_DP(8)
   U25 BU46 P0_RXP8||SATA10_RXP GENOA_SP5-SOCKET6096_13568-001,SMLF,IO,DGA^6000030   I148 @T6G_MB_LIB.T6G(SCH_1):PAGE24
 U6010 CA26 A_PETP7 PT5161LRS-PT5161LRS,SMLF,IC,AJ051610U03     I2 @T6G_MB_LIB.T6G(SCH_1):PAGE382

P5E_CPU0_P0_RX_DP<9> @T6G_MB_LIB.T6G(SCH_1):P5E_CPU0_P0_RX_DP(9)
   U25 BW43 P0_RXP9||SATA11_RXP GENOA_SP5-SOCKET6096_13568-001,SMLF,IO,DGA^6000030   I148 @T6G_MB_LIB.T6G(SCH_1):PAGE24
 U6010 BP26 A_PETP6 PT5161LRS-PT5161LRS,SMLF,IC,AJ051610U03     I2 @T6G_MB_LIB.T6G(SCH_1):PAGE382

P5E_CPU0_P0_TX_BUF_C_DN<0> @T6G_MB_LIB.T6G(SCH_1):P5E_CPU0_P0_TX_BUF_C_DN(0)
 C6502    1      1 Q_CAP_DIFFBUS_C0201-DIFF BUS_0.22UF,6.3V,20%,X6S,SA    I78 @T6G_MB_LIB.T6G(SCH_1):PAGE384
  J108   I1     I1 CONN112_10137002101LF-CONN112_10137002-101LF,THLF,A    I72 @T6G_MB_LIB.T6G(SCH_1):PAGE320

P5E_CPU0_P0_TX_BUF_C_DN<10> @T6G_MB_LIB.T6G(SCH_1):P5E_CPU0_P0_TX_BUF_C_DN(10)
 C6522    1      1 Q_CAP_DIFFBUS_C0201-DIFF BUS_0.22UF,6.3V,20%,X6S,SA   I118 @T6G_MB_LIB.T6G(SCH_1):PAGE384
  J107   I3     I3 CONN112_10137002101LF-CONN112_10137002-101LF,THLF,A    I49 @T6G_MB_LIB.T6G(SCH_1):PAGE317

P5E_CPU0_P0_TX_BUF_C_DN<11> @T6G_MB_LIB.T6G(SCH_1):P5E_CPU0_P0_TX_BUF_C_DN(11)
 C6524    1      1 Q_CAP_DIFFBUS_C0201-DIFF BUS_0.22UF,6.3V,20%,X6S,SA   I121 @T6G_MB_LIB.T6G(SCH_1):PAGE384
  J107   H4     H4 CONN112_10137002101LF-CONN112_10137002-101LF,THLF,A    I49 @T6G_MB_LIB.T6G(SCH_1):PAGE317

P5E_CPU0_P0_TX_BUF_C_DN<12> @T6G_MB_LIB.T6G(SCH_1):P5E_CPU0_P0_TX_BUF_C_DN(12)
 C6526    1      1 Q_CAP_DIFFBUS_C0201-DIFF BUS_0.22UF,6.3V,20%,X6S,SA   I122 @T6G_MB_LIB.T6G(SCH_1):PAGE384
  J107   I5     I5 CONN112_10137002101LF-CONN112_10137002-101LF,THLF,A    I70 @T6G_MB_LIB.T6G(SCH_1):PAGE317

P5E_CPU0_P0_TX_BUF_C_DN<13> @T6G_MB_LIB.T6G(SCH_1):P5E_CPU0_P0_TX_BUF_C_DN(13)
 C6528    1      1 Q_CAP_DIFFBUS_C0201-DIFF BUS_0.22UF,6.3V,20%,X6S,SA   I125 @T6G_MB_LIB.T6G(SCH_1):PAGE384
  J107   H6     H6 CONN112_10137002101LF-CONN112_10137002-101LF,THLF,A    I70 @T6G_MB_LIB.T6G(SCH_1):PAGE317

P5E_CPU0_P0_TX_BUF_C_DN<14> @T6G_MB_LIB.T6G(SCH_1):P5E_CPU0_P0_TX_BUF_C_DN(14)
 C6530    1      1 Q_CAP_DIFFBUS_C0201-DIFF BUS_0.22UF,6.3V,20%,X6S,SA   I127 @T6G_MB_LIB.T6G(SCH_1):PAGE384
  J107   I7     I7 CONN112_10137002101LF-CONN112_10137002-101LF,THLF,A    I70 @T6G_MB_LIB.T6G(SCH_1):PAGE317

P5E_CPU0_P0_TX_BUF_C_DN<15> @T6G_MB_LIB.T6G(SCH_1):P5E_CPU0_P0_TX_BUF_C_DN(15)
 C6532    1      1 Q_CAP_DIFFBUS_C0201-DIFF BUS_0.22UF,6.3V,20%,X6S,SA   I130 @T6G_MB_LIB.T6G(SCH_1):PAGE384
  J107   H8     H8 CONN112_10137002101LF-CONN112_10137002-101LF,THLF,A    I70 @T6G_MB_LIB.T6G(SCH_1):PAGE317

P5E_CPU0_P0_TX_BUF_C_DN<1> @T6G_MB_LIB.T6G(SCH_1):P5E_CPU0_P0_TX_BUF_C_DN(1)
 C6504    1      1 Q_CAP_DIFFBUS_C0201-DIFF BUS_0.22UF,6.3V,20%,X6S,SA    I76 @T6G_MB_LIB.T6G(SCH_1):PAGE384
  J108   H2     H2 CONN112_10137002101LF-CONN112_10137002-101LF,THLF,A    I72 @T6G_MB_LIB.T6G(SCH_1):PAGE320

P5E_CPU0_P0_TX_BUF_C_DN<2> @T6G_MB_LIB.T6G(SCH_1):P5E_CPU0_P0_TX_BUF_C_DN(2)
 C6506    1      1 Q_CAP_DIFFBUS_C0201-DIFF BUS_0.22UF,6.3V,20%,X6S,SA    I72 @T6G_MB_LIB.T6G(SCH_1):PAGE384
  J108   I3     I3 CONN112_10137002101LF-CONN112_10137002-101LF,THLF,A    I72 @T6G_MB_LIB.T6G(SCH_1):PAGE320

P5E_CPU0_P0_TX_BUF_C_DN<3> @T6G_MB_LIB.T6G(SCH_1):P5E_CPU0_P0_TX_BUF_C_DN(3)
 C6508    1      1 Q_CAP_DIFFBUS_C0201-DIFF BUS_0.22UF,6.3V,20%,X6S,SA    I71 @T6G_MB_LIB.T6G(SCH_1):PAGE384
  J108   H4     H4 CONN112_10137002101LF-CONN112_10137002-101LF,THLF,A    I72 @T6G_MB_LIB.T6G(SCH_1):PAGE320

P5E_CPU0_P0_TX_BUF_C_DN<4> @T6G_MB_LIB.T6G(SCH_1):P5E_CPU0_P0_TX_BUF_C_DN(4)
 C6510    1      1 Q_CAP_DIFFBUS_C0201-DIFF BUS_0.22UF,6.3V,20%,X6S,SA    I66 @T6G_MB_LIB.T6G(SCH_1):PAGE384
  J108   I5     I5 CONN112_10137002101LF-CONN112_10137002-101LF,THLF,A    I15 @T6G_MB_LIB.T6G(SCH_1):PAGE320

P5E_CPU0_P0_TX_BUF_C_DN<5> @T6G_MB_LIB.T6G(SCH_1):P5E_CPU0_P0_TX_BUF_C_DN(5)
 C6512    1      1 Q_CAP_DIFFBUS_C0201-DIFF BUS_0.22UF,6.3V,20%,X6S,SA    I64 @T6G_MB_LIB.T6G(SCH_1):PAGE384
  J108   H6     H6 CONN112_10137002101LF-CONN112_10137002-101LF,THLF,A    I15 @T6G_MB_LIB.T6G(SCH_1):PAGE320

P5E_CPU0_P0_TX_BUF_C_DN<6> @T6G_MB_LIB.T6G(SCH_1):P5E_CPU0_P0_TX_BUF_C_DN(6)
 C6514    1      1 Q_CAP_DIFFBUS_C0201-DIFF BUS_0.22UF,6.3V,20%,X6S,SA    I61 @T6G_MB_LIB.T6G(SCH_1):PAGE384
  J108   I7     I7 CONN112_10137002101LF-CONN112_10137002-101LF,THLF,A    I15 @T6G_MB_LIB.T6G(SCH_1):PAGE320

P5E_CPU0_P0_TX_BUF_C_DN<7> @T6G_MB_LIB.T6G(SCH_1):P5E_CPU0_P0_TX_BUF_C_DN(7)
 C6516    1      1 Q_CAP_DIFFBUS_C0201-DIFF BUS_0.22UF,6.3V,20%,X6S,SA    I59 @T6G_MB_LIB.T6G(SCH_1):PAGE384
  J108   H8     H8 CONN112_10137002101LF-CONN112_10137002-101LF,THLF,A    I15 @T6G_MB_LIB.T6G(SCH_1):PAGE320

P5E_CPU0_P0_TX_BUF_C_DN<8> @T6G_MB_LIB.T6G(SCH_1):P5E_CPU0_P0_TX_BUF_C_DN(8)
 C6518    1      1 Q_CAP_DIFFBUS_C0201-DIFF BUS_0.22UF,6.3V,20%,X6S,SA   I100 @T6G_MB_LIB.T6G(SCH_1):PAGE384
  J107   I1     I1 CONN112_10137002101LF-CONN112_10137002-101LF,THLF,A    I49 @T6G_MB_LIB.T6G(SCH_1):PAGE317

P5E_CPU0_P0_TX_BUF_C_DN<9> @T6G_MB_LIB.T6G(SCH_1):P5E_CPU0_P0_TX_BUF_C_DN(9)
 C6520    1      1 Q_CAP_DIFFBUS_C0201-DIFF BUS_0.22UF,6.3V,20%,X6S,SA   I101 @T6G_MB_LIB.T6G(SCH_1):PAGE384
  J107   H2     H2 CONN112_10137002101LF-CONN112_10137002-101LF,THLF,A    I49 @T6G_MB_LIB.T6G(SCH_1):PAGE317

P5E_CPU0_P0_TX_BUF_C_DP<0> @T6G_MB_LIB.T6G(SCH_1):P5E_CPU0_P0_TX_BUF_C_DP(0)
 C6501    1      1 Q_CAP_DIFFBUS_C0201-DIFF BUS_0.22UF,6.3V,20%,X6S,SA    I77 @T6G_MB_LIB.T6G(SCH_1):PAGE384
  J108   J1     J1 CONN112_10137002101LF-CONN112_10137002-101LF,THLF,A    I72 @T6G_MB_LIB.T6G(SCH_1):PAGE320

P5E_CPU0_P0_TX_BUF_C_DP<10> @T6G_MB_LIB.T6G(SCH_1):P5E_CPU0_P0_TX_BUF_C_DP(10)
 C6521    1      1 Q_CAP_DIFFBUS_C0201-DIFF BUS_0.22UF,6.3V,20%,X6S,SA   I119 @T6G_MB_LIB.T6G(SCH_1):PAGE384
  J107   J3     J3 CONN112_10137002101LF-CONN112_10137002-101LF,THLF,A    I49 @T6G_MB_LIB.T6G(SCH_1):PAGE317

P5E_CPU0_P0_TX_BUF_C_DP<11> @T6G_MB_LIB.T6G(SCH_1):P5E_CPU0_P0_TX_BUF_C_DP(11)
 C6523    1      1 Q_CAP_DIFFBUS_C0201-DIFF BUS_0.22UF,6.3V,20%,X6S,SA   I120 @T6G_MB_LIB.T6G(SCH_1):PAGE384
  J107   I4     I4 CONN112_10137002101LF-CONN112_10137002-101LF,THLF,A    I49 @T6G_MB_LIB.T6G(SCH_1):PAGE317

P5E_CPU0_P0_TX_BUF_C_DP<12> @T6G_MB_LIB.T6G(SCH_1):P5E_CPU0_P0_TX_BUF_C_DP(12)
 C6525    1      1 Q_CAP_DIFFBUS_C0201-DIFF BUS_0.22UF,6.3V,20%,X6S,SA   I123 @T6G_MB_LIB.T6G(SCH_1):PAGE384
  J107   J5     J5 CONN112_10137002101LF-CONN112_10137002-101LF,THLF,A    I70 @T6G_MB_LIB.T6G(SCH_1):PAGE317

P5E_CPU0_P0_TX_BUF_C_DP<13> @T6G_MB_LIB.T6G(SCH_1):P5E_CPU0_P0_TX_BUF_C_DP(13)
 C6527    1      1 Q_CAP_DIFFBUS_C0201-DIFF BUS_0.22UF,6.3V,20%,X6S,SA   I124 @T6G_MB_LIB.T6G(SCH_1):PAGE384
  J107   I6     I6 CONN112_10137002101LF-CONN112_10137002-101LF,THLF,A    I70 @T6G_MB_LIB.T6G(SCH_1):PAGE317

P5E_CPU0_P0_TX_BUF_C_DP<14> @T6G_MB_LIB.T6G(SCH_1):P5E_CPU0_P0_TX_BUF_C_DP(14)
 C6529    1      1 Q_CAP_DIFFBUS_C0201-DIFF BUS_0.22UF,6.3V,20%,X6S,SA   I126 @T6G_MB_LIB.T6G(SCH_1):PAGE384
  J107   J7     J7 CONN112_10137002101LF-CONN112_10137002-101LF,THLF,A    I70 @T6G_MB_LIB.T6G(SCH_1):PAGE317

P5E_CPU0_P0_TX_BUF_C_DP<15> @T6G_MB_LIB.T6G(SCH_1):P5E_CPU0_P0_TX_BUF_C_DP(15)
 C6531    1      1 Q_CAP_DIFFBUS_C0201-DIFF BUS_0.22UF,6.3V,20%,X6S,SA   I129 @T6G_MB_LIB.T6G(SCH_1):PAGE384
  J107   I8     I8 CONN112_10137002101LF-CONN112_10137002-101LF,THLF,A    I70 @T6G_MB_LIB.T6G(SCH_1):PAGE317

P5E_CPU0_P0_TX_BUF_C_DP<1> @T6G_MB_LIB.T6G(SCH_1):P5E_CPU0_P0_TX_BUF_C_DP(1)
 C6503    1      1 Q_CAP_DIFFBUS_C0201-DIFF BUS_0.22UF,6.3V,20%,X6S,SA    I75 @T6G_MB_LIB.T6G(SCH_1):PAGE384
  J108   I2     I2 CONN112_10137002101LF-CONN112_10137002-101LF,THLF,A    I72 @T6G_MB_LIB.T6G(SCH_1):PAGE320

P5E_CPU0_P0_TX_BUF_C_DP<2> @T6G_MB_LIB.T6G(SCH_1):P5E_CPU0_P0_TX_BUF_C_DP(2)
 C6505    1      1 Q_CAP_DIFFBUS_C0201-DIFF BUS_0.22UF,6.3V,20%,X6S,SA    I74 @T6G_MB_LIB.T6G(SCH_1):PAGE384
  J108   J3     J3 CONN112_10137002101LF-CONN112_10137002-101LF,THLF,A    I72 @T6G_MB_LIB.T6G(SCH_1):PAGE320

P5E_CPU0_P0_TX_BUF_C_DP<3> @T6G_MB_LIB.T6G(SCH_1):P5E_CPU0_P0_TX_BUF_C_DP(3)
 C6507    1      1 Q_CAP_DIFFBUS_C0201-DIFF BUS_0.22UF,6.3V,20%,X6S,SA    I73 @T6G_MB_LIB.T6G(SCH_1):PAGE384
  J108   I4     I4 CONN112_10137002101LF-CONN112_10137002-101LF,THLF,A    I72 @T6G_MB_LIB.T6G(SCH_1):PAGE320

P5E_CPU0_P0_TX_BUF_C_DP<4> @T6G_MB_LIB.T6G(SCH_1):P5E_CPU0_P0_TX_BUF_C_DP(4)
 C6509    1      1 Q_CAP_DIFFBUS_C0201-DIFF BUS_0.22UF,6.3V,20%,X6S,SA    I65 @T6G_MB_LIB.T6G(SCH_1):PAGE384
  J108   J5     J5 CONN112_10137002101LF-CONN112_10137002-101LF,THLF,A    I15 @T6G_MB_LIB.T6G(SCH_1):PAGE320

P5E_CPU0_P0_TX_BUF_C_DP<5> @T6G_MB_LIB.T6G(SCH_1):P5E_CPU0_P0_TX_BUF_C_DP(5)
 C6511    1      1 Q_CAP_DIFFBUS_C0201-DIFF BUS_0.22UF,6.3V,20%,X6S,SA    I63 @T6G_MB_LIB.T6G(SCH_1):PAGE384
  J108   I6     I6 CONN112_10137002101LF-CONN112_10137002-101LF,THLF,A    I15 @T6G_MB_LIB.T6G(SCH_1):PAGE320

P5E_CPU0_P0_TX_BUF_C_DP<6> @T6G_MB_LIB.T6G(SCH_1):P5E_CPU0_P0_TX_BUF_C_DP(6)
 C6513    1      1 Q_CAP_DIFFBUS_C0201-DIFF BUS_0.22UF,6.3V,20%,X6S,SA    I60 @T6G_MB_LIB.T6G(SCH_1):PAGE384
  J108   J7     J7 CONN112_10137002101LF-CONN112_10137002-101LF,THLF,A    I15 @T6G_MB_LIB.T6G(SCH_1):PAGE320

P5E_CPU0_P0_TX_BUF_C_DP<7> @T6G_MB_LIB.T6G(SCH_1):P5E_CPU0_P0_TX_BUF_C_DP(7)
 C6515    1      1 Q_CAP_DIFFBUS_C0201-DIFF BUS_0.22UF,6.3V,20%,X6S,SA    I62 @T6G_MB_LIB.T6G(SCH_1):PAGE384
  J108   I8     I8 CONN112_10137002101LF-CONN112_10137002-101LF,THLF,A    I15 @T6G_MB_LIB.T6G(SCH_1):PAGE320

P5E_CPU0_P0_TX_BUF_C_DP<8> @T6G_MB_LIB.T6G(SCH_1):P5E_CPU0_P0_TX_BUF_C_DP(8)
 C6517    1      1 Q_CAP_DIFFBUS_C0201-DIFF BUS_0.22UF,6.3V,20%,X6S,SA    I99 @T6G_MB_LIB.T6G(SCH_1):PAGE384
  J107   J1     J1 CONN112_10137002101LF-CONN112_10137002-101LF,THLF,A    I49 @T6G_MB_LIB.T6G(SCH_1):PAGE317

P5E_CPU0_P0_TX_BUF_C_DP<9> @T6G_MB_LIB.T6G(SCH_1):P5E_CPU0_P0_TX_BUF_C_DP(9)
 C6519    1      1 Q_CAP_DIFFBUS_C0201-DIFF BUS_0.22UF,6.3V,20%,X6S,SA   I102 @T6G_MB_LIB.T6G(SCH_1):PAGE384
  J107   I2     I2 CONN112_10137002101LF-CONN112_10137002-101LF,THLF,A    I49 @T6G_MB_LIB.T6G(SCH_1):PAGE317

P5E_CPU0_P0_TX_BUF_DN<0> @T6G_MB_LIB.T6G(SCH_1):P5E_CPU0_P0_TX_BUF_DN(0)
 U6010 EW10 B_PETN15 PT5161LRS-PT5161LRS,SMLF,IC,AJ051610U03     I2 @T6G_MB_LIB.T6G(SCH_1):PAGE384
 C6502    2      2 Q_CAP_DIFFBUS_C0201-DIFF BUS_0.22UF,6.3V,20%,X6S,SA    I78 @T6G_MB_LIB.T6G(SCH_1):PAGE384

P5E_CPU0_P0_TX_BUF_DN<10> @T6G_MB_LIB.T6G(SCH_1):P5E_CPU0_P0_TX_BUF_DN(10)
 U6010 BJ10 B_PETN5 PT5161LRS-PT5161LRS,SMLF,IC,AJ051610U03     I1 @T6G_MB_LIB.T6G(SCH_1):PAGE384
 C6522    2      2 Q_CAP_DIFFBUS_C0201-DIFF BUS_0.22UF,6.3V,20%,X6S,SA   I118 @T6G_MB_LIB.T6G(SCH_1):PAGE384

P5E_CPU0_P0_TX_BUF_DN<11> @T6G_MB_LIB.T6G(SCH_1):P5E_CPU0_P0_TX_BUF_DN(11)
 U6010 BB10 B_PETN4 PT5161LRS-PT5161LRS,SMLF,IC,AJ051610U03     I1 @T6G_MB_LIB.T6G(SCH_1):PAGE384
 C6524    2      2 Q_CAP_DIFFBUS_C0201-DIFF BUS_0.22UF,6.3V,20%,X6S,SA   I121 @T6G_MB_LIB.T6G(SCH_1):PAGE384

P5E_CPU0_P0_TX_BUF_DN<12> @T6G_MB_LIB.T6G(SCH_1):P5E_CPU0_P0_TX_BUF_DN(12)
 U6010 AR10 B_PETN3 PT5161LRS-PT5161LRS,SMLF,IC,AJ051610U03     I1 @T6G_MB_LIB.T6G(SCH_1):PAGE384
 C6526    2      2 Q_CAP_DIFFBUS_C0201-DIFF BUS_0.22UF,6.3V,20%,X6S,SA   I122 @T6G_MB_LIB.T6G(SCH_1):PAGE384

P5E_CPU0_P0_TX_BUF_DN<13> @T6G_MB_LIB.T6G(SCH_1):P5E_CPU0_P0_TX_BUF_DN(13)
 U6010 AH10 B_PETN2 PT5161LRS-PT5161LRS,SMLF,IC,AJ051610U03     I1 @T6G_MB_LIB.T6G(SCH_1):PAGE384
 C6528    2      2 Q_CAP_DIFFBUS_C0201-DIFF BUS_0.22UF,6.3V,20%,X6S,SA   I125 @T6G_MB_LIB.T6G(SCH_1):PAGE384

P5E_CPU0_P0_TX_BUF_DN<14> @T6G_MB_LIB.T6G(SCH_1):P5E_CPU0_P0_TX_BUF_DN(14)
 U6010 AA10 B_PETN1 PT5161LRS-PT5161LRS,SMLF,IC,AJ051610U03     I1 @T6G_MB_LIB.T6G(SCH_1):PAGE384
 C6530    2      2 Q_CAP_DIFFBUS_C0201-DIFF BUS_0.22UF,6.3V,20%,X6S,SA   I127 @T6G_MB_LIB.T6G(SCH_1):PAGE384

P5E_CPU0_P0_TX_BUF_DN<15> @T6G_MB_LIB.T6G(SCH_1):P5E_CPU0_P0_TX_BUF_DN(15)
 U6010  P10 B_PETN0 PT5161LRS-PT5161LRS,SMLF,IC,AJ051610U03     I1 @T6G_MB_LIB.T6G(SCH_1):PAGE384
 C6532    2      2 Q_CAP_DIFFBUS_C0201-DIFF BUS_0.22UF,6.3V,20%,X6S,SA   I130 @T6G_MB_LIB.T6G(SCH_1):PAGE384

P5E_CPU0_P0_TX_BUF_DN<1> @T6G_MB_LIB.T6G(SCH_1):P5E_CPU0_P0_TX_BUF_DN(1)
 U6010 EM10 B_PETN14 PT5161LRS-PT5161LRS,SMLF,IC,AJ051610U03     I2 @T6G_MB_LIB.T6G(SCH_1):PAGE384
 C6504    2      2 Q_CAP_DIFFBUS_C0201-DIFF BUS_0.22UF,6.3V,20%,X6S,SA    I76 @T6G_MB_LIB.T6G(SCH_1):PAGE384

P5E_CPU0_P0_TX_BUF_DN<2> @T6G_MB_LIB.T6G(SCH_1):P5E_CPU0_P0_TX_BUF_DN(2)
 U6010 EE10 B_PETN13 PT5161LRS-PT5161LRS,SMLF,IC,AJ051610U03     I2 @T6G_MB_LIB.T6G(SCH_1):PAGE384
 C6506    2      2 Q_CAP_DIFFBUS_C0201-DIFF BUS_0.22UF,6.3V,20%,X6S,SA    I72 @T6G_MB_LIB.T6G(SCH_1):PAGE384

P5E_CPU0_P0_TX_BUF_DN<3> @T6G_MB_LIB.T6G(SCH_1):P5E_CPU0_P0_TX_BUF_DN(3)
 U6010 DV10 B_PETN12 PT5161LRS-PT5161LRS,SMLF,IC,AJ051610U03     I2 @T6G_MB_LIB.T6G(SCH_1):PAGE384
 C6508    2      2 Q_CAP_DIFFBUS_C0201-DIFF BUS_0.22UF,6.3V,20%,X6S,SA    I71 @T6G_MB_LIB.T6G(SCH_1):PAGE384

P5E_CPU0_P0_TX_BUF_DN<4> @T6G_MB_LIB.T6G(SCH_1):P5E_CPU0_P0_TX_BUF_DN(4)
 U6010 DL10 B_PETN11 PT5161LRS-PT5161LRS,SMLF,IC,AJ051610U03     I2 @T6G_MB_LIB.T6G(SCH_1):PAGE384
 C6510    2      2 Q_CAP_DIFFBUS_C0201-DIFF BUS_0.22UF,6.3V,20%,X6S,SA    I66 @T6G_MB_LIB.T6G(SCH_1):PAGE384

P5E_CPU0_P0_TX_BUF_DN<5> @T6G_MB_LIB.T6G(SCH_1):P5E_CPU0_P0_TX_BUF_DN(5)
 U6010 DD10 B_PETN10 PT5161LRS-PT5161LRS,SMLF,IC,AJ051610U03     I2 @T6G_MB_LIB.T6G(SCH_1):PAGE384
 C6512    2      2 Q_CAP_DIFFBUS_C0201-DIFF BUS_0.22UF,6.3V,20%,X6S,SA    I64 @T6G_MB_LIB.T6G(SCH_1):PAGE384

P5E_CPU0_P0_TX_BUF_DN<6> @T6G_MB_LIB.T6G(SCH_1):P5E_CPU0_P0_TX_BUF_DN(6)
 U6010 CU10 B_PETN9 PT5161LRS-PT5161LRS,SMLF,IC,AJ051610U03     I2 @T6G_MB_LIB.T6G(SCH_1):PAGE384
 C6514    2      2 Q_CAP_DIFFBUS_C0201-DIFF BUS_0.22UF,6.3V,20%,X6S,SA    I61 @T6G_MB_LIB.T6G(SCH_1):PAGE384

P5E_CPU0_P0_TX_BUF_DN<7> @T6G_MB_LIB.T6G(SCH_1):P5E_CPU0_P0_TX_BUF_DN(7)
 U6010 CK10 B_PETN8 PT5161LRS-PT5161LRS,SMLF,IC,AJ051610U03     I2 @T6G_MB_LIB.T6G(SCH_1):PAGE384
 C6516    2      2 Q_CAP_DIFFBUS_C0201-DIFF BUS_0.22UF,6.3V,20%,X6S,SA    I59 @T6G_MB_LIB.T6G(SCH_1):PAGE384

P5E_CPU0_P0_TX_BUF_DN<8> @T6G_MB_LIB.T6G(SCH_1):P5E_CPU0_P0_TX_BUF_DN(8)
 U6010 CC10 B_PETN7 PT5161LRS-PT5161LRS,SMLF,IC,AJ051610U03     I1 @T6G_MB_LIB.T6G(SCH_1):PAGE384
 C6518    2      2 Q_CAP_DIFFBUS_C0201-DIFF BUS_0.22UF,6.3V,20%,X6S,SA   I100 @T6G_MB_LIB.T6G(SCH_1):PAGE384

P5E_CPU0_P0_TX_BUF_DN<9> @T6G_MB_LIB.T6G(SCH_1):P5E_CPU0_P0_TX_BUF_DN(9)
 U6010 BT10 B_PETN6 PT5161LRS-PT5161LRS,SMLF,IC,AJ051610U03     I1 @T6G_MB_LIB.T6G(SCH_1):PAGE384
 C6520    2      2 Q_CAP_DIFFBUS_C0201-DIFF BUS_0.22UF,6.3V,20%,X6S,SA   I101 @T6G_MB_LIB.T6G(SCH_1):PAGE384

P5E_CPU0_P0_TX_BUF_DP<0> @T6G_MB_LIB.T6G(SCH_1):P5E_CPU0_P0_TX_BUF_DP(0)
 U6010  EU7 B_PETP15 PT5161LRS-PT5161LRS,SMLF,IC,AJ051610U03     I2 @T6G_MB_LIB.T6G(SCH_1):PAGE384
 C6501    2      2 Q_CAP_DIFFBUS_C0201-DIFF BUS_0.22UF,6.3V,20%,X6S,SA    I77 @T6G_MB_LIB.T6G(SCH_1):PAGE384

P5E_CPU0_P0_TX_BUF_DP<10> @T6G_MB_LIB.T6G(SCH_1):P5E_CPU0_P0_TX_BUF_DP(10)
 U6010  BG7 B_PETP5 PT5161LRS-PT5161LRS,SMLF,IC,AJ051610U03     I1 @T6G_MB_LIB.T6G(SCH_1):PAGE384
 C6521    2      2 Q_CAP_DIFFBUS_C0201-DIFF BUS_0.22UF,6.3V,20%,X6S,SA   I119 @T6G_MB_LIB.T6G(SCH_1):PAGE384

P5E_CPU0_P0_TX_BUF_DP<11> @T6G_MB_LIB.T6G(SCH_1):P5E_CPU0_P0_TX_BUF_DP(11)
 U6010  AY7 B_PETP4 PT5161LRS-PT5161LRS,SMLF,IC,AJ051610U03     I1 @T6G_MB_LIB.T6G(SCH_1):PAGE384
 C6523    2      2 Q_CAP_DIFFBUS_C0201-DIFF BUS_0.22UF,6.3V,20%,X6S,SA   I120 @T6G_MB_LIB.T6G(SCH_1):PAGE384

P5E_CPU0_P0_TX_BUF_DP<12> @T6G_MB_LIB.T6G(SCH_1):P5E_CPU0_P0_TX_BUF_DP(12)
 U6010  AN7 B_PETP3 PT5161LRS-PT5161LRS,SMLF,IC,AJ051610U03     I1 @T6G_MB_LIB.T6G(SCH_1):PAGE384
 C6525    2      2 Q_CAP_DIFFBUS_C0201-DIFF BUS_0.22UF,6.3V,20%,X6S,SA   I123 @T6G_MB_LIB.T6G(SCH_1):PAGE384

P5E_CPU0_P0_TX_BUF_DP<13> @T6G_MB_LIB.T6G(SCH_1):P5E_CPU0_P0_TX_BUF_DP(13)
 U6010  AF7 B_PETP2 PT5161LRS-PT5161LRS,SMLF,IC,AJ051610U03     I1 @T6G_MB_LIB.T6G(SCH_1):PAGE384
 C6527    2      2 Q_CAP_DIFFBUS_C0201-DIFF BUS_0.22UF,6.3V,20%,X6S,SA   I124 @T6G_MB_LIB.T6G(SCH_1):PAGE384

P5E_CPU0_P0_TX_BUF_DP<14> @T6G_MB_LIB.T6G(SCH_1):P5E_CPU0_P0_TX_BUF_DP(14)
 U6010   W7 B_PETP1 PT5161LRS-PT5161LRS,SMLF,IC,AJ051610U03     I1 @T6G_MB_LIB.T6G(SCH_1):PAGE384
 C6529    2      2 Q_CAP_DIFFBUS_C0201-DIFF BUS_0.22UF,6.3V,20%,X6S,SA   I126 @T6G_MB_LIB.T6G(SCH_1):PAGE384

P5E_CPU0_P0_TX_BUF_DP<15> @T6G_MB_LIB.T6G(SCH_1):P5E_CPU0_P0_TX_BUF_DP(15)
 U6010   M7 B_PETP0 PT5161LRS-PT5161LRS,SMLF,IC,AJ051610U03     I1 @T6G_MB_LIB.T6G(SCH_1):PAGE384
 C6531    2      2 Q_CAP_DIFFBUS_C0201-DIFF BUS_0.22UF,6.3V,20%,X6S,SA   I129 @T6G_MB_LIB.T6G(SCH_1):PAGE384

P5E_CPU0_P0_TX_BUF_DP<1> @T6G_MB_LIB.T6G(SCH_1):P5E_CPU0_P0_TX_BUF_DP(1)
 U6010  EK7 B_PETP14 PT5161LRS-PT5161LRS,SMLF,IC,AJ051610U03     I2 @T6G_MB_LIB.T6G(SCH_1):PAGE384
 C6503    2      2 Q_CAP_DIFFBUS_C0201-DIFF BUS_0.22UF,6.3V,20%,X6S,SA    I75 @T6G_MB_LIB.T6G(SCH_1):PAGE384

P5E_CPU0_P0_TX_BUF_DP<2> @T6G_MB_LIB.T6G(SCH_1):P5E_CPU0_P0_TX_BUF_DP(2)
 U6010  EC7 B_PETP13 PT5161LRS-PT5161LRS,SMLF,IC,AJ051610U03     I2 @T6G_MB_LIB.T6G(SCH_1):PAGE384
 C6505    2      2 Q_CAP_DIFFBUS_C0201-DIFF BUS_0.22UF,6.3V,20%,X6S,SA    I74 @T6G_MB_LIB.T6G(SCH_1):PAGE384

P5E_CPU0_P0_TX_BUF_DP<3> @T6G_MB_LIB.T6G(SCH_1):P5E_CPU0_P0_TX_BUF_DP(3)
 U6010  DT7 B_PETP12 PT5161LRS-PT5161LRS,SMLF,IC,AJ051610U03     I2 @T6G_MB_LIB.T6G(SCH_1):PAGE384
 C6507    2      2 Q_CAP_DIFFBUS_C0201-DIFF BUS_0.22UF,6.3V,20%,X6S,SA    I73 @T6G_MB_LIB.T6G(SCH_1):PAGE384

P5E_CPU0_P0_TX_BUF_DP<4> @T6G_MB_LIB.T6G(SCH_1):P5E_CPU0_P0_TX_BUF_DP(4)
 U6010  DJ7 B_PETP11 PT5161LRS-PT5161LRS,SMLF,IC,AJ051610U03     I2 @T6G_MB_LIB.T6G(SCH_1):PAGE384
 C6509    2      2 Q_CAP_DIFFBUS_C0201-DIFF BUS_0.22UF,6.3V,20%,X6S,SA    I65 @T6G_MB_LIB.T6G(SCH_1):PAGE384

P5E_CPU0_P0_TX_BUF_DP<5> @T6G_MB_LIB.T6G(SCH_1):P5E_CPU0_P0_TX_BUF_DP(5)
 U6010  DB7 B_PETP10 PT5161LRS-PT5161LRS,SMLF,IC,AJ051610U03     I2 @T6G_MB_LIB.T6G(SCH_1):PAGE384
 C6511    2      2 Q_CAP_DIFFBUS_C0201-DIFF BUS_0.22UF,6.3V,20%,X6S,SA    I63 @T6G_MB_LIB.T6G(SCH_1):PAGE384

P5E_CPU0_P0_TX_BUF_DP<6> @T6G_MB_LIB.T6G(SCH_1):P5E_CPU0_P0_TX_BUF_DP(6)
 U6010  CR7 B_PETP9 PT5161LRS-PT5161LRS,SMLF,IC,AJ051610U03     I2 @T6G_MB_LIB.T6G(SCH_1):PAGE384
 C6513    2      2 Q_CAP_DIFFBUS_C0201-DIFF BUS_0.22UF,6.3V,20%,X6S,SA    I60 @T6G_MB_LIB.T6G(SCH_1):PAGE384

P5E_CPU0_P0_TX_BUF_DP<7> @T6G_MB_LIB.T6G(SCH_1):P5E_CPU0_P0_TX_BUF_DP(7)
 U6010  CH7 B_PETP8 PT5161LRS-PT5161LRS,SMLF,IC,AJ051610U03     I2 @T6G_MB_LIB.T6G(SCH_1):PAGE384
 C6515    2      2 Q_CAP_DIFFBUS_C0201-DIFF BUS_0.22UF,6.3V,20%,X6S,SA    I62 @T6G_MB_LIB.T6G(SCH_1):PAGE384

P5E_CPU0_P0_TX_BUF_DP<8> @T6G_MB_LIB.T6G(SCH_1):P5E_CPU0_P0_TX_BUF_DP(8)
 U6010  CA7 B_PETP7 PT5161LRS-PT5161LRS,SMLF,IC,AJ051610U03     I1 @T6G_MB_LIB.T6G(SCH_1):PAGE384
 C6517    2      2 Q_CAP_DIFFBUS_C0201-DIFF BUS_0.22UF,6.3V,20%,X6S,SA    I99 @T6G_MB_LIB.T6G(SCH_1):PAGE384

P5E_CPU0_P0_TX_BUF_DP<9> @T6G_MB_LIB.T6G(SCH_1):P5E_CPU0_P0_TX_BUF_DP(9)
 U6010  BP7 B_PETP6 PT5161LRS-PT5161LRS,SMLF,IC,AJ051610U03     I1 @T6G_MB_LIB.T6G(SCH_1):PAGE384
 C6519    2      2 Q_CAP_DIFFBUS_C0201-DIFF BUS_0.22UF,6.3V,20%,X6S,SA   I102 @T6G_MB_LIB.T6G(SCH_1):PAGE384

P5E_CPU0_P0_TX_C_DN<0> @T6G_MB_LIB.T6G(SCH_1):P5E_CPU0_P0_TX_C_DN(0)
  C932    1      1 Q_CAP_DIFFBUS_C0201-DIFF BUS_0.22UF,6.3V,20%,X6S,SA    I21 @T6G_MB_LIB.T6G(SCH_1):PAGE351
 U6010 EV34 B_PERP15 PT5161LRS-PT5161LRS,SMLF,IC,AJ051610U03     I4 @T6G_MB_LIB.T6G(SCH_1):PAGE381

P5E_CPU0_P0_TX_C_DN<10> @T6G_MB_LIB.T6G(SCH_1):P5E_CPU0_P0_TX_C_DN(10)
  C912    1      1 Q_CAP_DIFFBUS_C0201-DIFF BUS_0.22UF,6.3V,20%,X6S,SA    I58 @T6G_MB_LIB.T6G(SCH_1):PAGE351
 U6010 BH34 B_PERP5 PT5161LRS-PT5161LRS,SMLF,IC,AJ051610U03     I3 @T6G_MB_LIB.T6G(SCH_1):PAGE381

P5E_CPU0_P0_TX_C_DN<11> @T6G_MB_LIB.T6G(SCH_1):P5E_CPU0_P0_TX_C_DN(11)
  C910    1      1 Q_CAP_DIFFBUS_C0201-DIFF BUS_0.22UF,6.3V,20%,X6S,SA    I60 @T6G_MB_LIB.T6G(SCH_1):PAGE351
 U6010 BA34 B_PERP4 PT5161LRS-PT5161LRS,SMLF,IC,AJ051610U03     I3 @T6G_MB_LIB.T6G(SCH_1):PAGE381

P5E_CPU0_P0_TX_C_DN<12> @T6G_MB_LIB.T6G(SCH_1):P5E_CPU0_P0_TX_C_DN(12)
  C908    1      1 Q_CAP_DIFFBUS_C0201-DIFF BUS_0.22UF,6.3V,20%,X6S,SA    I62 @T6G_MB_LIB.T6G(SCH_1):PAGE351
 U6010 AP34 B_PERP3 PT5161LRS-PT5161LRS,SMLF,IC,AJ051610U03     I3 @T6G_MB_LIB.T6G(SCH_1):PAGE381

P5E_CPU0_P0_TX_C_DN<13> @T6G_MB_LIB.T6G(SCH_1):P5E_CPU0_P0_TX_C_DN(13)
  C906    1      1 Q_CAP_DIFFBUS_C0201-DIFF BUS_0.22UF,6.3V,20%,X6S,SA    I63 @T6G_MB_LIB.T6G(SCH_1):PAGE351
 U6010 AJ35 B_PERN2 PT5161LRS-PT5161LRS,SMLF,IC,AJ051610U03     I3 @T6G_MB_LIB.T6G(SCH_1):PAGE381

P5E_CPU0_P0_TX_C_DN<14> @T6G_MB_LIB.T6G(SCH_1):P5E_CPU0_P0_TX_C_DN(14)
  C904    1      1 Q_CAP_DIFFBUS_C0201-DIFF BUS_0.22UF,6.3V,20%,X6S,SA    I66 @T6G_MB_LIB.T6G(SCH_1):PAGE351
 U6010  Y34 B_PERP1 PT5161LRS-PT5161LRS,SMLF,IC,AJ051610U03     I3 @T6G_MB_LIB.T6G(SCH_1):PAGE381

P5E_CPU0_P0_TX_C_DN<15> @T6G_MB_LIB.T6G(SCH_1):P5E_CPU0_P0_TX_C_DN(15)
  C902    1      1 Q_CAP_DIFFBUS_C0201-DIFF BUS_0.22UF,6.3V,20%,X6S,SA    I68 @T6G_MB_LIB.T6G(SCH_1):PAGE351
 U6010  N34 B_PERP0 PT5161LRS-PT5161LRS,SMLF,IC,AJ051610U03     I3 @T6G_MB_LIB.T6G(SCH_1):PAGE381

P5E_CPU0_P0_TX_C_DN<1> @T6G_MB_LIB.T6G(SCH_1):P5E_CPU0_P0_TX_C_DN(1)
  C930    1      1 Q_CAP_DIFFBUS_C0201-DIFF BUS_0.22UF,6.3V,20%,X6S,SA    I24 @T6G_MB_LIB.T6G(SCH_1):PAGE351
 U6010 EN35 B_PERN14 PT5161LRS-PT5161LRS,SMLF,IC,AJ051610U03     I4 @T6G_MB_LIB.T6G(SCH_1):PAGE381

P5E_CPU0_P0_TX_C_DN<2> @T6G_MB_LIB.T6G(SCH_1):P5E_CPU0_P0_TX_C_DN(2)
  C928    1      1 Q_CAP_DIFFBUS_C0201-DIFF BUS_0.22UF,6.3V,20%,X6S,SA    I25 @T6G_MB_LIB.T6G(SCH_1):PAGE351
 U6010 ED34 B_PERP13 PT5161LRS-PT5161LRS,SMLF,IC,AJ051610U03     I4 @T6G_MB_LIB.T6G(SCH_1):PAGE381

P5E_CPU0_P0_TX_C_DN<3> @T6G_MB_LIB.T6G(SCH_1):P5E_CPU0_P0_TX_C_DN(3)
  C926    1      1 Q_CAP_DIFFBUS_C0201-DIFF BUS_0.22UF,6.3V,20%,X6S,SA    I28 @T6G_MB_LIB.T6G(SCH_1):PAGE351
 U6010 DU34 B_PERP12 PT5161LRS-PT5161LRS,SMLF,IC,AJ051610U03     I4 @T6G_MB_LIB.T6G(SCH_1):PAGE381

P5E_CPU0_P0_TX_C_DN<4> @T6G_MB_LIB.T6G(SCH_1):P5E_CPU0_P0_TX_C_DN(4)
  C924    1      1 Q_CAP_DIFFBUS_C0201-DIFF BUS_0.22UF,6.3V,20%,X6S,SA    I30 @T6G_MB_LIB.T6G(SCH_1):PAGE351
 U6010 DK34 B_PERP11 PT5161LRS-PT5161LRS,SMLF,IC,AJ051610U03     I4 @T6G_MB_LIB.T6G(SCH_1):PAGE381

P5E_CPU0_P0_TX_C_DN<5> @T6G_MB_LIB.T6G(SCH_1):P5E_CPU0_P0_TX_C_DN(5)
  C922    1      1 Q_CAP_DIFFBUS_C0201-DIFF BUS_0.22UF,6.3V,20%,X6S,SA    I32 @T6G_MB_LIB.T6G(SCH_1):PAGE351
 U6010 DC34 B_PERP10 PT5161LRS-PT5161LRS,SMLF,IC,AJ051610U03     I4 @T6G_MB_LIB.T6G(SCH_1):PAGE381

P5E_CPU0_P0_TX_C_DN<6> @T6G_MB_LIB.T6G(SCH_1):P5E_CPU0_P0_TX_C_DN(6)
  C920    1      1 Q_CAP_DIFFBUS_C0201-DIFF BUS_0.22UF,6.3V,20%,X6S,SA    I34 @T6G_MB_LIB.T6G(SCH_1):PAGE351
 U6010 CT34 B_PERP9 PT5161LRS-PT5161LRS,SMLF,IC,AJ051610U03     I4 @T6G_MB_LIB.T6G(SCH_1):PAGE381

P5E_CPU0_P0_TX_C_DN<7> @T6G_MB_LIB.T6G(SCH_1):P5E_CPU0_P0_TX_C_DN(7)
  C918    1      1 Q_CAP_DIFFBUS_C0201-DIFF BUS_0.22UF,6.3V,20%,X6S,SA    I35 @T6G_MB_LIB.T6G(SCH_1):PAGE351
 U6010 CJ34 B_PERP8 PT5161LRS-PT5161LRS,SMLF,IC,AJ051610U03     I4 @T6G_MB_LIB.T6G(SCH_1):PAGE381

P5E_CPU0_P0_TX_C_DN<8> @T6G_MB_LIB.T6G(SCH_1):P5E_CPU0_P0_TX_C_DN(8)
  C916    1      1 Q_CAP_DIFFBUS_C0201-DIFF BUS_0.22UF,6.3V,20%,X6S,SA    I53 @T6G_MB_LIB.T6G(SCH_1):PAGE351
 U6010 CB34 B_PERP7 PT5161LRS-PT5161LRS,SMLF,IC,AJ051610U03     I3 @T6G_MB_LIB.T6G(SCH_1):PAGE381

P5E_CPU0_P0_TX_C_DN<9> @T6G_MB_LIB.T6G(SCH_1):P5E_CPU0_P0_TX_C_DN(9)
  C914    1      1 Q_CAP_DIFFBUS_C0201-DIFF BUS_0.22UF,6.3V,20%,X6S,SA    I56 @T6G_MB_LIB.T6G(SCH_1):PAGE351
 U6010 BR34 B_PERP6 PT5161LRS-PT5161LRS,SMLF,IC,AJ051610U03     I3 @T6G_MB_LIB.T6G(SCH_1):PAGE381

P5E_CPU0_P0_TX_C_DP<0> @T6G_MB_LIB.T6G(SCH_1):P5E_CPU0_P0_TX_C_DP(0)
  C933    1      1 Q_CAP_DIFFBUS_C0201-DIFF BUS_0.22UF,6.3V,20%,X6S,SA    I22 @T6G_MB_LIB.T6G(SCH_1):PAGE351
 U6010 EY35 B_PERN15 PT5161LRS-PT5161LRS,SMLF,IC,AJ051610U03     I4 @T6G_MB_LIB.T6G(SCH_1):PAGE381

P5E_CPU0_P0_TX_C_DP<10> @T6G_MB_LIB.T6G(SCH_1):P5E_CPU0_P0_TX_C_DP(10)
  C913    1      1 Q_CAP_DIFFBUS_C0201-DIFF BUS_0.22UF,6.3V,20%,X6S,SA    I57 @T6G_MB_LIB.T6G(SCH_1):PAGE351
 U6010 BK35 B_PERN5 PT5161LRS-PT5161LRS,SMLF,IC,AJ051610U03     I3 @T6G_MB_LIB.T6G(SCH_1):PAGE381

P5E_CPU0_P0_TX_C_DP<11> @T6G_MB_LIB.T6G(SCH_1):P5E_CPU0_P0_TX_C_DP(11)
  C911    1      1 Q_CAP_DIFFBUS_C0201-DIFF BUS_0.22UF,6.3V,20%,X6S,SA    I59 @T6G_MB_LIB.T6G(SCH_1):PAGE351
 U6010 BC35 B_PERN4 PT5161LRS-PT5161LRS,SMLF,IC,AJ051610U03     I3 @T6G_MB_LIB.T6G(SCH_1):PAGE381

P5E_CPU0_P0_TX_C_DP<12> @T6G_MB_LIB.T6G(SCH_1):P5E_CPU0_P0_TX_C_DP(12)
  C909    1      1 Q_CAP_DIFFBUS_C0201-DIFF BUS_0.22UF,6.3V,20%,X6S,SA    I61 @T6G_MB_LIB.T6G(SCH_1):PAGE351
 U6010 AT35 B_PERN3 PT5161LRS-PT5161LRS,SMLF,IC,AJ051610U03     I3 @T6G_MB_LIB.T6G(SCH_1):PAGE381

P5E_CPU0_P0_TX_C_DP<13> @T6G_MB_LIB.T6G(SCH_1):P5E_CPU0_P0_TX_C_DP(13)
  C907    1      1 Q_CAP_DIFFBUS_C0201-DIFF BUS_0.22UF,6.3V,20%,X6S,SA    I64 @T6G_MB_LIB.T6G(SCH_1):PAGE351
 U6010 AG34 B_PERP2 PT5161LRS-PT5161LRS,SMLF,IC,AJ051610U03     I3 @T6G_MB_LIB.T6G(SCH_1):PAGE381

P5E_CPU0_P0_TX_C_DP<14> @T6G_MB_LIB.T6G(SCH_1):P5E_CPU0_P0_TX_C_DP(14)
  C905    1      1 Q_CAP_DIFFBUS_C0201-DIFF BUS_0.22UF,6.3V,20%,X6S,SA    I65 @T6G_MB_LIB.T6G(SCH_1):PAGE351
 U6010 AB35 B_PERN1 PT5161LRS-PT5161LRS,SMLF,IC,AJ051610U03     I3 @T6G_MB_LIB.T6G(SCH_1):PAGE381

P5E_CPU0_P0_TX_C_DP<15> @T6G_MB_LIB.T6G(SCH_1):P5E_CPU0_P0_TX_C_DP(15)
  C903    1      1 Q_CAP_DIFFBUS_C0201-DIFF BUS_0.22UF,6.3V,20%,X6S,SA    I67 @T6G_MB_LIB.T6G(SCH_1):PAGE351
 U6010  R35 B_PERN0 PT5161LRS-PT5161LRS,SMLF,IC,AJ051610U03     I3 @T6G_MB_LIB.T6G(SCH_1):PAGE381

P5E_CPU0_P0_TX_C_DP<1> @T6G_MB_LIB.T6G(SCH_1):P5E_CPU0_P0_TX_C_DP(1)
  C931    1      1 Q_CAP_DIFFBUS_C0201-DIFF BUS_0.22UF,6.3V,20%,X6S,SA    I23 @T6G_MB_LIB.T6G(SCH_1):PAGE351
 U6010 EL34 B_PERP14 PT5161LRS-PT5161LRS,SMLF,IC,AJ051610U03     I4 @T6G_MB_LIB.T6G(SCH_1):PAGE381

P5E_CPU0_P0_TX_C_DP<2> @T6G_MB_LIB.T6G(SCH_1):P5E_CPU0_P0_TX_C_DP(2)
  C929    1      1 Q_CAP_DIFFBUS_C0201-DIFF BUS_0.22UF,6.3V,20%,X6S,SA    I26 @T6G_MB_LIB.T6G(SCH_1):PAGE351
 U6010 EF35 B_PERN13 PT5161LRS-PT5161LRS,SMLF,IC,AJ051610U03     I4 @T6G_MB_LIB.T6G(SCH_1):PAGE381

P5E_CPU0_P0_TX_C_DP<3> @T6G_MB_LIB.T6G(SCH_1):P5E_CPU0_P0_TX_C_DP(3)
  C927    1      1 Q_CAP_DIFFBUS_C0201-DIFF BUS_0.22UF,6.3V,20%,X6S,SA    I27 @T6G_MB_LIB.T6G(SCH_1):PAGE351
 U6010 DW35 B_PERN12 PT5161LRS-PT5161LRS,SMLF,IC,AJ051610U03     I4 @T6G_MB_LIB.T6G(SCH_1):PAGE381

P5E_CPU0_P0_TX_C_DP<4> @T6G_MB_LIB.T6G(SCH_1):P5E_CPU0_P0_TX_C_DP(4)
  C925    1      1 Q_CAP_DIFFBUS_C0201-DIFF BUS_0.22UF,6.3V,20%,X6S,SA    I29 @T6G_MB_LIB.T6G(SCH_1):PAGE351
 U6010 DM35 B_PERN11 PT5161LRS-PT5161LRS,SMLF,IC,AJ051610U03     I4 @T6G_MB_LIB.T6G(SCH_1):PAGE381

P5E_CPU0_P0_TX_C_DP<5> @T6G_MB_LIB.T6G(SCH_1):P5E_CPU0_P0_TX_C_DP(5)
  C923    1      1 Q_CAP_DIFFBUS_C0201-DIFF BUS_0.22UF,6.3V,20%,X6S,SA    I31 @T6G_MB_LIB.T6G(SCH_1):PAGE351
 U6010 DE35 B_PERN10 PT5161LRS-PT5161LRS,SMLF,IC,AJ051610U03     I4 @T6G_MB_LIB.T6G(SCH_1):PAGE381

P5E_CPU0_P0_TX_C_DP<6> @T6G_MB_LIB.T6G(SCH_1):P5E_CPU0_P0_TX_C_DP(6)
  C921    1      1 Q_CAP_DIFFBUS_C0201-DIFF BUS_0.22UF,6.3V,20%,X6S,SA    I33 @T6G_MB_LIB.T6G(SCH_1):PAGE351
 U6010 CV35 B_PERN9 PT5161LRS-PT5161LRS,SMLF,IC,AJ051610U03     I4 @T6G_MB_LIB.T6G(SCH_1):PAGE381

P5E_CPU0_P0_TX_C_DP<7> @T6G_MB_LIB.T6G(SCH_1):P5E_CPU0_P0_TX_C_DP(7)
  C919    1      1 Q_CAP_DIFFBUS_C0201-DIFF BUS_0.22UF,6.3V,20%,X6S,SA    I36 @T6G_MB_LIB.T6G(SCH_1):PAGE351
 U6010 CL35 B_PERN8 PT5161LRS-PT5161LRS,SMLF,IC,AJ051610U03     I4 @T6G_MB_LIB.T6G(SCH_1):PAGE381

P5E_CPU0_P0_TX_C_DP<8> @T6G_MB_LIB.T6G(SCH_1):P5E_CPU0_P0_TX_C_DP(8)
  C917    1      1 Q_CAP_DIFFBUS_C0201-DIFF BUS_0.22UF,6.3V,20%,X6S,SA    I54 @T6G_MB_LIB.T6G(SCH_1):PAGE351
 U6010 CD35 B_PERN7 PT5161LRS-PT5161LRS,SMLF,IC,AJ051610U03     I3 @T6G_MB_LIB.T6G(SCH_1):PAGE381

P5E_CPU0_P0_TX_C_DP<9> @T6G_MB_LIB.T6G(SCH_1):P5E_CPU0_P0_TX_C_DP(9)
  C915    1      1 Q_CAP_DIFFBUS_C0201-DIFF BUS_0.22UF,6.3V,20%,X6S,SA    I55 @T6G_MB_LIB.T6G(SCH_1):PAGE351
 U6010 BU35 B_PERN6 PT5161LRS-PT5161LRS,SMLF,IC,AJ051610U03     I3 @T6G_MB_LIB.T6G(SCH_1):PAGE381

P5E_CPU0_P0_TX_DN<0> @T6G_MB_LIB.T6G(SCH_1):P5E_CPU0_P0_TX_DN(0)
   U25 CN52 P0_TXN0||SATA00_TXN GENOA_SP5-SOCKET6096_13568-001,SMLF,IO,DGA^6000030   I148 @T6G_MB_LIB.T6G(SCH_1):PAGE24
  C932    2      2 Q_CAP_DIFFBUS_C0201-DIFF BUS_0.22UF,6.3V,20%,X6S,SA    I21 @T6G_MB_LIB.T6G(SCH_1):PAGE351

P5E_CPU0_P0_TX_DN<10> @T6G_MB_LIB.T6G(SCH_1):P5E_CPU0_P0_TX_DN(10)
   U25 CR43 P0_TXN10||SATA12_TXN GENOA_SP5-SOCKET6096_13568-001,SMLF,IO,DGA^6000030   I148 @T6G_MB_LIB.T6G(SCH_1):PAGE24
  C912    2      2 Q_CAP_DIFFBUS_C0201-DIFF BUS_0.22UF,6.3V,20%,X6S,SA    I58 @T6G_MB_LIB.T6G(SCH_1):PAGE351

P5E_CPU0_P0_TX_DN<11> @T6G_MB_LIB.T6G(SCH_1):P5E_CPU0_P0_TX_DN(11)
   U25 CU43 P0_TXN11||SATA13_TXN GENOA_SP5-SOCKET6096_13568-001,SMLF,IO,DGA^6000030   I148 @T6G_MB_LIB.T6G(SCH_1):PAGE24
  C910    2      2 Q_CAP_DIFFBUS_C0201-DIFF BUS_0.22UF,6.3V,20%,X6S,SA    I60 @T6G_MB_LIB.T6G(SCH_1):PAGE351

P5E_CPU0_P0_TX_DN<12> @T6G_MB_LIB.T6G(SCH_1):P5E_CPU0_P0_TX_DN(12)
   U25 CN43 P0_TXN12||SATA14_TXN GENOA_SP5-SOCKET6096_13568-001,SMLF,IO,DGA^6000030   I148 @T6G_MB_LIB.T6G(SCH_1):PAGE24
  C908    2      2 Q_CAP_DIFFBUS_C0201-DIFF BUS_0.22UF,6.3V,20%,X6S,SA    I62 @T6G_MB_LIB.T6G(SCH_1):PAGE351

P5E_CPU0_P0_TX_DN<13> @T6G_MB_LIB.T6G(SCH_1):P5E_CPU0_P0_TX_DN(13)
   U25 CT40 P0_TXN13||SATA15_TXN GENOA_SP5-SOCKET6096_13568-001,SMLF,IO,DGA^6000030   I148 @T6G_MB_LIB.T6G(SCH_1):PAGE24
  C906    2      2 Q_CAP_DIFFBUS_C0201-DIFF BUS_0.22UF,6.3V,20%,X6S,SA    I63 @T6G_MB_LIB.T6G(SCH_1):PAGE351

P5E_CPU0_P0_TX_DN<14> @T6G_MB_LIB.T6G(SCH_1):P5E_CPU0_P0_TX_DN(14)
   U25 CP40 P0_TXN14||SATA16_TXN GENOA_SP5-SOCKET6096_13568-001,SMLF,IO,DGA^6000030   I148 @T6G_MB_LIB.T6G(SCH_1):PAGE24
  C904    2      2 Q_CAP_DIFFBUS_C0201-DIFF BUS_0.22UF,6.3V,20%,X6S,SA    I66 @T6G_MB_LIB.T6G(SCH_1):PAGE351

P5E_CPU0_P0_TX_DN<15> @T6G_MB_LIB.T6G(SCH_1):P5E_CPU0_P0_TX_DN(15)
   U25 CM40 P0_TXN15||SATA17_TXN GENOA_SP5-SOCKET6096_13568-001,SMLF,IO,DGA^6000030   I148 @T6G_MB_LIB.T6G(SCH_1):PAGE24
  C902    2      2 Q_CAP_DIFFBUS_C0201-DIFF BUS_0.22UF,6.3V,20%,X6S,SA    I68 @T6G_MB_LIB.T6G(SCH_1):PAGE351

P5E_CPU0_P0_TX_DN<1> @T6G_MB_LIB.T6G(SCH_1):P5E_CPU0_P0_TX_DN(1)
   U25 CR52 P0_TXN1||SATA01_TXN GENOA_SP5-SOCKET6096_13568-001,SMLF,IO,DGA^6000030   I148 @T6G_MB_LIB.T6G(SCH_1):PAGE24
  C930    2      2 Q_CAP_DIFFBUS_C0201-DIFF BUS_0.22UF,6.3V,20%,X6S,SA    I24 @T6G_MB_LIB.T6G(SCH_1):PAGE351

P5E_CPU0_P0_TX_DN<2> @T6G_MB_LIB.T6G(SCH_1):P5E_CPU0_P0_TX_DN(2)
   U25 CL52 P0_TXN2||SATA02_TXN GENOA_SP5-SOCKET6096_13568-001,SMLF,IO,DGA^6000030   I148 @T6G_MB_LIB.T6G(SCH_1):PAGE24
  C928    2      2 Q_CAP_DIFFBUS_C0201-DIFF BUS_0.22UF,6.3V,20%,X6S,SA    I25 @T6G_MB_LIB.T6G(SCH_1):PAGE351

P5E_CPU0_P0_TX_DN<3> @T6G_MB_LIB.T6G(SCH_1):P5E_CPU0_P0_TX_DN(3)
   U25 CN49 P0_TXN3||SATA03_TXN GENOA_SP5-SOCKET6096_13568-001,SMLF,IO,DGA^6000030   I148 @T6G_MB_LIB.T6G(SCH_1):PAGE24
  C926    2      2 Q_CAP_DIFFBUS_C0201-DIFF BUS_0.22UF,6.3V,20%,X6S,SA    I28 @T6G_MB_LIB.T6G(SCH_1):PAGE351

P5E_CPU0_P0_TX_DN<4> @T6G_MB_LIB.T6G(SCH_1):P5E_CPU0_P0_TX_DN(4)
   U25 CR49 P0_TXN4||SATA04_TXN GENOA_SP5-SOCKET6096_13568-001,SMLF,IO,DGA^6000030   I148 @T6G_MB_LIB.T6G(SCH_1):PAGE24
  C924    2      2 Q_CAP_DIFFBUS_C0201-DIFF BUS_0.22UF,6.3V,20%,X6S,SA    I30 @T6G_MB_LIB.T6G(SCH_1):PAGE351

P5E_CPU0_P0_TX_DN<5> @T6G_MB_LIB.T6G(SCH_1):P5E_CPU0_P0_TX_DN(5)
   U25 CU49 P0_TXN5||SATA05_TXN GENOA_SP5-SOCKET6096_13568-001,SMLF,IO,DGA^6000030   I148 @T6G_MB_LIB.T6G(SCH_1):PAGE24
  C922    2      2 Q_CAP_DIFFBUS_C0201-DIFF BUS_0.22UF,6.3V,20%,X6S,SA    I32 @T6G_MB_LIB.T6G(SCH_1):PAGE351

P5E_CPU0_P0_TX_DN<6> @T6G_MB_LIB.T6G(SCH_1):P5E_CPU0_P0_TX_DN(6)
   U25 CL49 P0_TXN6||SATA06_TXN GENOA_SP5-SOCKET6096_13568-001,SMLF,IO,DGA^6000030   I148 @T6G_MB_LIB.T6G(SCH_1):PAGE24
  C920    2      2 Q_CAP_DIFFBUS_C0201-DIFF BUS_0.22UF,6.3V,20%,X6S,SA    I34 @T6G_MB_LIB.T6G(SCH_1):PAGE351

P5E_CPU0_P0_TX_DN<7> @T6G_MB_LIB.T6G(SCH_1):P5E_CPU0_P0_TX_DN(7)
   U25 CR46 P0_TXN7||SATA07_TXN GENOA_SP5-SOCKET6096_13568-001,SMLF,IO,DGA^6000030   I148 @T6G_MB_LIB.T6G(SCH_1):PAGE24
  C918    2      2 Q_CAP_DIFFBUS_C0201-DIFF BUS_0.22UF,6.3V,20%,X6S,SA    I35 @T6G_MB_LIB.T6G(SCH_1):PAGE351

P5E_CPU0_P0_TX_DN<8> @T6G_MB_LIB.T6G(SCH_1):P5E_CPU0_P0_TX_DN(8)
   U25 CU46 P0_TXN8||SATA10_TXN GENOA_SP5-SOCKET6096_13568-001,SMLF,IO,DGA^6000030   I148 @T6G_MB_LIB.T6G(SCH_1):PAGE24
  C916    2      2 Q_CAP_DIFFBUS_C0201-DIFF BUS_0.22UF,6.3V,20%,X6S,SA    I53 @T6G_MB_LIB.T6G(SCH_1):PAGE351

P5E_CPU0_P0_TX_DN<9> @T6G_MB_LIB.T6G(SCH_1):P5E_CPU0_P0_TX_DN(9)
   U25 CN46 P0_TXN9||SATA11_TXN GENOA_SP5-SOCKET6096_13568-001,SMLF,IO,DGA^6000030   I148 @T6G_MB_LIB.T6G(SCH_1):PAGE24
  C914    2      2 Q_CAP_DIFFBUS_C0201-DIFF BUS_0.22UF,6.3V,20%,X6S,SA    I56 @T6G_MB_LIB.T6G(SCH_1):PAGE351

P5E_CPU0_P0_TX_DP<0> @T6G_MB_LIB.T6G(SCH_1):P5E_CPU0_P0_TX_DP(0)
   U25 CN53 P0_TXP0||SATA00_TXP GENOA_SP5-SOCKET6096_13568-001,SMLF,IO,DGA^6000030   I148 @T6G_MB_LIB.T6G(SCH_1):PAGE24
  C933    2      2 Q_CAP_DIFFBUS_C0201-DIFF BUS_0.22UF,6.3V,20%,X6S,SA    I22 @T6G_MB_LIB.T6G(SCH_1):PAGE351

P5E_CPU0_P0_TX_DP<10> @T6G_MB_LIB.T6G(SCH_1):P5E_CPU0_P0_TX_DP(10)
   U25 CR44 P0_TXP10||SATA12_TXP GENOA_SP5-SOCKET6096_13568-001,SMLF,IO,DGA^6000030   I148 @T6G_MB_LIB.T6G(SCH_1):PAGE24
  C913    2      2 Q_CAP_DIFFBUS_C0201-DIFF BUS_0.22UF,6.3V,20%,X6S,SA    I57 @T6G_MB_LIB.T6G(SCH_1):PAGE351

P5E_CPU0_P0_TX_DP<11> @T6G_MB_LIB.T6G(SCH_1):P5E_CPU0_P0_TX_DP(11)
   U25 CU44 P0_TXP11||SATA13_TXP GENOA_SP5-SOCKET6096_13568-001,SMLF,IO,DGA^6000030   I148 @T6G_MB_LIB.T6G(SCH_1):PAGE24
  C911    2      2 Q_CAP_DIFFBUS_C0201-DIFF BUS_0.22UF,6.3V,20%,X6S,SA    I59 @T6G_MB_LIB.T6G(SCH_1):PAGE351

P5E_CPU0_P0_TX_DP<12> @T6G_MB_LIB.T6G(SCH_1):P5E_CPU0_P0_TX_DP(12)
   U25 CN44 P0_TXP12||SATA14_TXP GENOA_SP5-SOCKET6096_13568-001,SMLF,IO,DGA^6000030   I148 @T6G_MB_LIB.T6G(SCH_1):PAGE24
  C909    2      2 Q_CAP_DIFFBUS_C0201-DIFF BUS_0.22UF,6.3V,20%,X6S,SA    I61 @T6G_MB_LIB.T6G(SCH_1):PAGE351

P5E_CPU0_P0_TX_DP<13> @T6G_MB_LIB.T6G(SCH_1):P5E_CPU0_P0_TX_DP(13)
   U25 CT41 P0_TXP13||SATA15_TXP GENOA_SP5-SOCKET6096_13568-001,SMLF,IO,DGA^6000030   I148 @T6G_MB_LIB.T6G(SCH_1):PAGE24
  C907    2      2 Q_CAP_DIFFBUS_C0201-DIFF BUS_0.22UF,6.3V,20%,X6S,SA    I64 @T6G_MB_LIB.T6G(SCH_1):PAGE351

P5E_CPU0_P0_TX_DP<14> @T6G_MB_LIB.T6G(SCH_1):P5E_CPU0_P0_TX_DP(14)
   U25 CP41 P0_TXP14||SATA16_TXP GENOA_SP5-SOCKET6096_13568-001,SMLF,IO,DGA^6000030   I148 @T6G_MB_LIB.T6G(SCH_1):PAGE24
  C905    2      2 Q_CAP_DIFFBUS_C0201-DIFF BUS_0.22UF,6.3V,20%,X6S,SA    I65 @T6G_MB_LIB.T6G(SCH_1):PAGE351

P5E_CPU0_P0_TX_DP<15> @T6G_MB_LIB.T6G(SCH_1):P5E_CPU0_P0_TX_DP(15)
   U25 CM41 P0_TXP15||SATA17_TXP GENOA_SP5-SOCKET6096_13568-001,SMLF,IO,DGA^6000030   I148 @T6G_MB_LIB.T6G(SCH_1):PAGE24
  C903    2      2 Q_CAP_DIFFBUS_C0201-DIFF BUS_0.22UF,6.3V,20%,X6S,SA    I67 @T6G_MB_LIB.T6G(SCH_1):PAGE351

P5E_CPU0_P0_TX_DP<1> @T6G_MB_LIB.T6G(SCH_1):P5E_CPU0_P0_TX_DP(1)
   U25 CR53 P0_TXP1||SATA01_TXP GENOA_SP5-SOCKET6096_13568-001,SMLF,IO,DGA^6000030   I148 @T6G_MB_LIB.T6G(SCH_1):PAGE24
  C931    2      2 Q_CAP_DIFFBUS_C0201-DIFF BUS_0.22UF,6.3V,20%,X6S,SA    I23 @T6G_MB_LIB.T6G(SCH_1):PAGE351

P5E_CPU0_P0_TX_DP<2> @T6G_MB_LIB.T6G(SCH_1):P5E_CPU0_P0_TX_DP(2)
   U25 CL53 P0_TXP2||SATA02_TXP GENOA_SP5-SOCKET6096_13568-001,SMLF,IO,DGA^6000030   I148 @T6G_MB_LIB.T6G(SCH_1):PAGE24
  C929    2      2 Q_CAP_DIFFBUS_C0201-DIFF BUS_0.22UF,6.3V,20%,X6S,SA    I26 @T6G_MB_LIB.T6G(SCH_1):PAGE351

P5E_CPU0_P0_TX_DP<3> @T6G_MB_LIB.T6G(SCH_1):P5E_CPU0_P0_TX_DP(3)
   U25 CN50 P0_TXP3||SATA03_TXP GENOA_SP5-SOCKET6096_13568-001,SMLF,IO,DGA^6000030   I148 @T6G_MB_LIB.T6G(SCH_1):PAGE24
  C927    2      2 Q_CAP_DIFFBUS_C0201-DIFF BUS_0.22UF,6.3V,20%,X6S,SA    I27 @T6G_MB_LIB.T6G(SCH_1):PAGE351

P5E_CPU0_P0_TX_DP<4> @T6G_MB_LIB.T6G(SCH_1):P5E_CPU0_P0_TX_DP(4)
   U25 CR50 P0_TXP4||SATA04_TXP GENOA_SP5-SOCKET6096_13568-001,SMLF,IO,DGA^6000030   I148 @T6G_MB_LIB.T6G(SCH_1):PAGE24
  C925    2      2 Q_CAP_DIFFBUS_C0201-DIFF BUS_0.22UF,6.3V,20%,X6S,SA    I29 @T6G_MB_LIB.T6G(SCH_1):PAGE351

P5E_CPU0_P0_TX_DP<5> @T6G_MB_LIB.T6G(SCH_1):P5E_CPU0_P0_TX_DP(5)
   U25 CU50 P0_TXP5||SATA05_TXP GENOA_SP5-SOCKET6096_13568-001,SMLF,IO,DGA^6000030   I148 @T6G_MB_LIB.T6G(SCH_1):PAGE24
  C923    2      2 Q_CAP_DIFFBUS_C0201-DIFF BUS_0.22UF,6.3V,20%,X6S,SA    I31 @T6G_MB_LIB.T6G(SCH_1):PAGE351

P5E_CPU0_P0_TX_DP<6> @T6G_MB_LIB.T6G(SCH_1):P5E_CPU0_P0_TX_DP(6)
   U25 CL50 P0_TXP6||SATA06_TXP GENOA_SP5-SOCKET6096_13568-001,SMLF,IO,DGA^6000030   I148 @T6G_MB_LIB.T6G(SCH_1):PAGE24
  C921    2      2 Q_CAP_DIFFBUS_C0201-DIFF BUS_0.22UF,6.3V,20%,X6S,SA    I33 @T6G_MB_LIB.T6G(SCH_1):PAGE351

P5E_CPU0_P0_TX_DP<7> @T6G_MB_LIB.T6G(SCH_1):P5E_CPU0_P0_TX_DP(7)
   U25 CR47 P0_TXP7||SATA07_TXP GENOA_SP5-SOCKET6096_13568-001,SMLF,IO,DGA^6000030   I148 @T6G_MB_LIB.T6G(SCH_1):PAGE24
  C919    2      2 Q_CAP_DIFFBUS_C0201-DIFF BUS_0.22UF,6.3V,20%,X6S,SA    I36 @T6G_MB_LIB.T6G(SCH_1):PAGE351

P5E_CPU0_P0_TX_DP<8> @T6G_MB_LIB.T6G(SCH_1):P5E_CPU0_P0_TX_DP(8)
   U25 CU47 P0_TXP8||SATA10_TXP GENOA_SP5-SOCKET6096_13568-001,SMLF,IO,DGA^6000030   I148 @T6G_MB_LIB.T6G(SCH_1):PAGE24
  C917    2      2 Q_CAP_DIFFBUS_C0201-DIFF BUS_0.22UF,6.3V,20%,X6S,SA    I54 @T6G_MB_LIB.T6G(SCH_1):PAGE351

P5E_CPU0_P0_TX_DP<9> @T6G_MB_LIB.T6G(SCH_1):P5E_CPU0_P0_TX_DP(9)
   U25 CN47 P0_TXP9||SATA11_TXP GENOA_SP5-SOCKET6096_13568-001,SMLF,IO,DGA^6000030   I148 @T6G_MB_LIB.T6G(SCH_1):PAGE24
  C915    2      2 Q_CAP_DIFFBUS_C0201-DIFF BUS_0.22UF,6.3V,20%,X6S,SA    I55 @T6G_MB_LIB.T6G(SCH_1):PAGE351

P5E_CPU0_P1_RX_BUF_DN<0> @T6G_MB_LIB.T6G(SCH_1):P5E_CPU0_P1_RX_BUF_DN(0)
 U6011  EV2 A_PERN15 PT5161LRS-PT5161LRS,SMLF,IC,AJ051610U03    I38 @T6G_MB_LIB.T6G(SCH_1):PAGE406
  J108   F1     F1 CONN112_10137002101LF-CONN112_10137002-101LF,THLF,A    I72 @T6G_MB_LIB.T6G(SCH_1):PAGE320

P5E_CPU0_P1_RX_BUF_DN<10> @T6G_MB_LIB.T6G(SCH_1):P5E_CPU0_P1_RX_BUF_DN(10)
 U6011  BH2 A_PERN5 PT5161LRS-PT5161LRS,SMLF,IC,AJ051610U03     I1 @T6G_MB_LIB.T6G(SCH_1):PAGE406
  J107   F3     F3 CONN112_10137002101LF-CONN112_10137002-101LF,THLF,A    I49 @T6G_MB_LIB.T6G(SCH_1):PAGE317

P5E_CPU0_P1_RX_BUF_DN<11> @T6G_MB_LIB.T6G(SCH_1):P5E_CPU0_P1_RX_BUF_DN(11)
 U6011  BA2 A_PERN4 PT5161LRS-PT5161LRS,SMLF,IC,AJ051610U03     I1 @T6G_MB_LIB.T6G(SCH_1):PAGE406
  J107   E4     E4 CONN112_10137002101LF-CONN112_10137002-101LF,THLF,A    I49 @T6G_MB_LIB.T6G(SCH_1):PAGE317

P5E_CPU0_P1_RX_BUF_DN<12> @T6G_MB_LIB.T6G(SCH_1):P5E_CPU0_P1_RX_BUF_DN(12)
 U6011  AP2 A_PERN3 PT5161LRS-PT5161LRS,SMLF,IC,AJ051610U03     I1 @T6G_MB_LIB.T6G(SCH_1):PAGE406
  J107   F5     F5 CONN112_10137002101LF-CONN112_10137002-101LF,THLF,A    I70 @T6G_MB_LIB.T6G(SCH_1):PAGE317

P5E_CPU0_P1_RX_BUF_DN<13> @T6G_MB_LIB.T6G(SCH_1):P5E_CPU0_P1_RX_BUF_DN(13)
 U6011  AG2 A_PERN2 PT5161LRS-PT5161LRS,SMLF,IC,AJ051610U03     I1 @T6G_MB_LIB.T6G(SCH_1):PAGE406
  J107   E6     E6 CONN112_10137002101LF-CONN112_10137002-101LF,THLF,A    I70 @T6G_MB_LIB.T6G(SCH_1):PAGE317

P5E_CPU0_P1_RX_BUF_DN<14> @T6G_MB_LIB.T6G(SCH_1):P5E_CPU0_P1_RX_BUF_DN(14)
 U6011   Y2 A_PERN1 PT5161LRS-PT5161LRS,SMLF,IC,AJ051610U03     I1 @T6G_MB_LIB.T6G(SCH_1):PAGE406
  J107   F7     F7 CONN112_10137002101LF-CONN112_10137002-101LF,THLF,A    I70 @T6G_MB_LIB.T6G(SCH_1):PAGE317

P5E_CPU0_P1_RX_BUF_DN<15> @T6G_MB_LIB.T6G(SCH_1):P5E_CPU0_P1_RX_BUF_DN(15)
 U6011   N2 A_PERN0 PT5161LRS-PT5161LRS,SMLF,IC,AJ051610U03     I1 @T6G_MB_LIB.T6G(SCH_1):PAGE406
  J107   E8     E8 CONN112_10137002101LF-CONN112_10137002-101LF,THLF,A    I70 @T6G_MB_LIB.T6G(SCH_1):PAGE317

P5E_CPU0_P1_RX_BUF_DN<1> @T6G_MB_LIB.T6G(SCH_1):P5E_CPU0_P1_RX_BUF_DN(1)
 U6011  EL2 A_PERN14 PT5161LRS-PT5161LRS,SMLF,IC,AJ051610U03    I38 @T6G_MB_LIB.T6G(SCH_1):PAGE406
  J108   E2     E2 CONN112_10137002101LF-CONN112_10137002-101LF,THLF,A    I72 @T6G_MB_LIB.T6G(SCH_1):PAGE320

P5E_CPU0_P1_RX_BUF_DN<2> @T6G_MB_LIB.T6G(SCH_1):P5E_CPU0_P1_RX_BUF_DN(2)
 U6011  ED2 A_PERN13 PT5161LRS-PT5161LRS,SMLF,IC,AJ051610U03    I38 @T6G_MB_LIB.T6G(SCH_1):PAGE406
  J108   F3     F3 CONN112_10137002101LF-CONN112_10137002-101LF,THLF,A    I72 @T6G_MB_LIB.T6G(SCH_1):PAGE320

P5E_CPU0_P1_RX_BUF_DN<3> @T6G_MB_LIB.T6G(SCH_1):P5E_CPU0_P1_RX_BUF_DN(3)
 U6011  DU2 A_PERN12 PT5161LRS-PT5161LRS,SMLF,IC,AJ051610U03    I38 @T6G_MB_LIB.T6G(SCH_1):PAGE406
  J108   E4     E4 CONN112_10137002101LF-CONN112_10137002-101LF,THLF,A    I72 @T6G_MB_LIB.T6G(SCH_1):PAGE320

P5E_CPU0_P1_RX_BUF_DN<4> @T6G_MB_LIB.T6G(SCH_1):P5E_CPU0_P1_RX_BUF_DN(4)
 U6011  DK2 A_PERN11 PT5161LRS-PT5161LRS,SMLF,IC,AJ051610U03    I38 @T6G_MB_LIB.T6G(SCH_1):PAGE406
  J108   F5     F5 CONN112_10137002101LF-CONN112_10137002-101LF,THLF,A    I15 @T6G_MB_LIB.T6G(SCH_1):PAGE320

P5E_CPU0_P1_RX_BUF_DN<5> @T6G_MB_LIB.T6G(SCH_1):P5E_CPU0_P1_RX_BUF_DN(5)
 U6011  DC2 A_PERN10 PT5161LRS-PT5161LRS,SMLF,IC,AJ051610U03    I38 @T6G_MB_LIB.T6G(SCH_1):PAGE406
  J108   E6     E6 CONN112_10137002101LF-CONN112_10137002-101LF,THLF,A    I15 @T6G_MB_LIB.T6G(SCH_1):PAGE320

P5E_CPU0_P1_RX_BUF_DN<6> @T6G_MB_LIB.T6G(SCH_1):P5E_CPU0_P1_RX_BUF_DN(6)
 U6011  CT2 A_PERN9 PT5161LRS-PT5161LRS,SMLF,IC,AJ051610U03    I38 @T6G_MB_LIB.T6G(SCH_1):PAGE406
  J108   F7     F7 CONN112_10137002101LF-CONN112_10137002-101LF,THLF,A    I15 @T6G_MB_LIB.T6G(SCH_1):PAGE320

P5E_CPU0_P1_RX_BUF_DN<7> @T6G_MB_LIB.T6G(SCH_1):P5E_CPU0_P1_RX_BUF_DN(7)
 U6011  CJ2 A_PERN8 PT5161LRS-PT5161LRS,SMLF,IC,AJ051610U03    I38 @T6G_MB_LIB.T6G(SCH_1):PAGE406
  J108   E8     E8 CONN112_10137002101LF-CONN112_10137002-101LF,THLF,A    I15 @T6G_MB_LIB.T6G(SCH_1):PAGE320

P5E_CPU0_P1_RX_BUF_DN<8> @T6G_MB_LIB.T6G(SCH_1):P5E_CPU0_P1_RX_BUF_DN(8)
 U6011  CB2 A_PERN7 PT5161LRS-PT5161LRS,SMLF,IC,AJ051610U03     I1 @T6G_MB_LIB.T6G(SCH_1):PAGE406
  J107   F1     F1 CONN112_10137002101LF-CONN112_10137002-101LF,THLF,A    I49 @T6G_MB_LIB.T6G(SCH_1):PAGE317

P5E_CPU0_P1_RX_BUF_DN<9> @T6G_MB_LIB.T6G(SCH_1):P5E_CPU0_P1_RX_BUF_DN(9)
 U6011  BR2 A_PERN6 PT5161LRS-PT5161LRS,SMLF,IC,AJ051610U03     I1 @T6G_MB_LIB.T6G(SCH_1):PAGE406
  J107   E2     E2 CONN112_10137002101LF-CONN112_10137002-101LF,THLF,A    I49 @T6G_MB_LIB.T6G(SCH_1):PAGE317

P5E_CPU0_P1_RX_BUF_DP<0> @T6G_MB_LIB.T6G(SCH_1):P5E_CPU0_P1_RX_BUF_DP(0)
 U6011  EY1 A_PERP15 PT5161LRS-PT5161LRS,SMLF,IC,AJ051610U03    I38 @T6G_MB_LIB.T6G(SCH_1):PAGE406
  J108   G1     G1 CONN112_10137002101LF-CONN112_10137002-101LF,THLF,A    I72 @T6G_MB_LIB.T6G(SCH_1):PAGE320

P5E_CPU0_P1_RX_BUF_DP<10> @T6G_MB_LIB.T6G(SCH_1):P5E_CPU0_P1_RX_BUF_DP(10)
 U6011  BK1 A_PERP5 PT5161LRS-PT5161LRS,SMLF,IC,AJ051610U03     I1 @T6G_MB_LIB.T6G(SCH_1):PAGE406
  J107   G3     G3 CONN112_10137002101LF-CONN112_10137002-101LF,THLF,A    I49 @T6G_MB_LIB.T6G(SCH_1):PAGE317

P5E_CPU0_P1_RX_BUF_DP<11> @T6G_MB_LIB.T6G(SCH_1):P5E_CPU0_P1_RX_BUF_DP(11)
 U6011  BC1 A_PERP4 PT5161LRS-PT5161LRS,SMLF,IC,AJ051610U03     I1 @T6G_MB_LIB.T6G(SCH_1):PAGE406
  J107   F4     F4 CONN112_10137002101LF-CONN112_10137002-101LF,THLF,A    I49 @T6G_MB_LIB.T6G(SCH_1):PAGE317

P5E_CPU0_P1_RX_BUF_DP<12> @T6G_MB_LIB.T6G(SCH_1):P5E_CPU0_P1_RX_BUF_DP(12)
 U6011  AT1 A_PERP3 PT5161LRS-PT5161LRS,SMLF,IC,AJ051610U03     I1 @T6G_MB_LIB.T6G(SCH_1):PAGE406
  J107   G5     G5 CONN112_10137002101LF-CONN112_10137002-101LF,THLF,A    I70 @T6G_MB_LIB.T6G(SCH_1):PAGE317

P5E_CPU0_P1_RX_BUF_DP<13> @T6G_MB_LIB.T6G(SCH_1):P5E_CPU0_P1_RX_BUF_DP(13)
 U6011  AJ1 A_PERP2 PT5161LRS-PT5161LRS,SMLF,IC,AJ051610U03     I1 @T6G_MB_LIB.T6G(SCH_1):PAGE406
  J107   F6     F6 CONN112_10137002101LF-CONN112_10137002-101LF,THLF,A    I70 @T6G_MB_LIB.T6G(SCH_1):PAGE317

P5E_CPU0_P1_RX_BUF_DP<14> @T6G_MB_LIB.T6G(SCH_1):P5E_CPU0_P1_RX_BUF_DP(14)
 U6011  AB1 A_PERP1 PT5161LRS-PT5161LRS,SMLF,IC,AJ051610U03     I1 @T6G_MB_LIB.T6G(SCH_1):PAGE406
  J107   G7     G7 CONN112_10137002101LF-CONN112_10137002-101LF,THLF,A    I70 @T6G_MB_LIB.T6G(SCH_1):PAGE317

P5E_CPU0_P1_RX_BUF_DP<15> @T6G_MB_LIB.T6G(SCH_1):P5E_CPU0_P1_RX_BUF_DP(15)
 U6011   R1 A_PERP0 PT5161LRS-PT5161LRS,SMLF,IC,AJ051610U03     I1 @T6G_MB_LIB.T6G(SCH_1):PAGE406
  J107   F8     F8 CONN112_10137002101LF-CONN112_10137002-101LF,THLF,A    I70 @T6G_MB_LIB.T6G(SCH_1):PAGE317

P5E_CPU0_P1_RX_BUF_DP<1> @T6G_MB_LIB.T6G(SCH_1):P5E_CPU0_P1_RX_BUF_DP(1)
 U6011  EN1 A_PERP14 PT5161LRS-PT5161LRS,SMLF,IC,AJ051610U03    I38 @T6G_MB_LIB.T6G(SCH_1):PAGE406
  J108   F2     F2 CONN112_10137002101LF-CONN112_10137002-101LF,THLF,A    I72 @T6G_MB_LIB.T6G(SCH_1):PAGE320

P5E_CPU0_P1_RX_BUF_DP<2> @T6G_MB_LIB.T6G(SCH_1):P5E_CPU0_P1_RX_BUF_DP(2)
 U6011  EF1 A_PERP13 PT5161LRS-PT5161LRS,SMLF,IC,AJ051610U03    I38 @T6G_MB_LIB.T6G(SCH_1):PAGE406
  J108   G3     G3 CONN112_10137002101LF-CONN112_10137002-101LF,THLF,A    I72 @T6G_MB_LIB.T6G(SCH_1):PAGE320

P5E_CPU0_P1_RX_BUF_DP<3> @T6G_MB_LIB.T6G(SCH_1):P5E_CPU0_P1_RX_BUF_DP(3)
 U6011  DW1 A_PERP12 PT5161LRS-PT5161LRS,SMLF,IC,AJ051610U03    I38 @T6G_MB_LIB.T6G(SCH_1):PAGE406
  J108   F4     F4 CONN112_10137002101LF-CONN112_10137002-101LF,THLF,A    I72 @T6G_MB_LIB.T6G(SCH_1):PAGE320

P5E_CPU0_P1_RX_BUF_DP<4> @T6G_MB_LIB.T6G(SCH_1):P5E_CPU0_P1_RX_BUF_DP(4)
 U6011  DM1 A_PERP11 PT5161LRS-PT5161LRS,SMLF,IC,AJ051610U03    I38 @T6G_MB_LIB.T6G(SCH_1):PAGE406
  J108   G5     G5 CONN112_10137002101LF-CONN112_10137002-101LF,THLF,A    I15 @T6G_MB_LIB.T6G(SCH_1):PAGE320

P5E_CPU0_P1_RX_BUF_DP<5> @T6G_MB_LIB.T6G(SCH_1):P5E_CPU0_P1_RX_BUF_DP(5)
 U6011  DE1 A_PERP10 PT5161LRS-PT5161LRS,SMLF,IC,AJ051610U03    I38 @T6G_MB_LIB.T6G(SCH_1):PAGE406
  J108   F6     F6 CONN112_10137002101LF-CONN112_10137002-101LF,THLF,A    I15 @T6G_MB_LIB.T6G(SCH_1):PAGE320

P5E_CPU0_P1_RX_BUF_DP<6> @T6G_MB_LIB.T6G(SCH_1):P5E_CPU0_P1_RX_BUF_DP(6)
 U6011  CV1 A_PERP9 PT5161LRS-PT5161LRS,SMLF,IC,AJ051610U03    I38 @T6G_MB_LIB.T6G(SCH_1):PAGE406
  J108   G7     G7 CONN112_10137002101LF-CONN112_10137002-101LF,THLF,A    I15 @T6G_MB_LIB.T6G(SCH_1):PAGE320

P5E_CPU0_P1_RX_BUF_DP<7> @T6G_MB_LIB.T6G(SCH_1):P5E_CPU0_P1_RX_BUF_DP(7)
 U6011  CL1 A_PERP8 PT5161LRS-PT5161LRS,SMLF,IC,AJ051610U03    I38 @T6G_MB_LIB.T6G(SCH_1):PAGE406
  J108   F8     F8 CONN112_10137002101LF-CONN112_10137002-101LF,THLF,A    I15 @T6G_MB_LIB.T6G(SCH_1):PAGE320

P5E_CPU0_P1_RX_BUF_DP<8> @T6G_MB_LIB.T6G(SCH_1):P5E_CPU0_P1_RX_BUF_DP(8)
 U6011  CD1 A_PERP7 PT5161LRS-PT5161LRS,SMLF,IC,AJ051610U03     I1 @T6G_MB_LIB.T6G(SCH_1):PAGE406
  J107   G1     G1 CONN112_10137002101LF-CONN112_10137002-101LF,THLF,A    I49 @T6G_MB_LIB.T6G(SCH_1):PAGE317

P5E_CPU0_P1_RX_BUF_DP<9> @T6G_MB_LIB.T6G(SCH_1):P5E_CPU0_P1_RX_BUF_DP(9)
 U6011  BU1 A_PERP6 PT5161LRS-PT5161LRS,SMLF,IC,AJ051610U03     I1 @T6G_MB_LIB.T6G(SCH_1):PAGE406
  J107   F2     F2 CONN112_10137002101LF-CONN112_10137002-101LF,THLF,A    I49 @T6G_MB_LIB.T6G(SCH_1):PAGE317

P5E_CPU0_P1_RX_DN<0> @T6G_MB_LIB.T6G(SCH_1):P5E_CPU0_P1_RX_DN(0)
   U25 CE53 P1_RXN0 GENOA_SP5-SOCKET6096_13568-001,SMLF,IO,DGA^6000030   I149 @T6G_MB_LIB.T6G(SCH_1):PAGE24
 U6011 EW29 A_PETN15 PT5161LRS-PT5161LRS,SMLF,IC,AJ051610U03    I38 @T6G_MB_LIB.T6G(SCH_1):PAGE405

P5E_CPU0_P1_RX_DN<10> @T6G_MB_LIB.T6G(SCH_1):P5E_CPU0_P1_RX_DN(10)
   U25 CG44 P1_RXN10 GENOA_SP5-SOCKET6096_13568-001,SMLF,IO,DGA^6000030   I149 @T6G_MB_LIB.T6G(SCH_1):PAGE24
 U6011 BJ29 A_PETN5 PT5161LRS-PT5161LRS,SMLF,IC,AJ051610U03     I1 @T6G_MB_LIB.T6G(SCH_1):PAGE405

P5E_CPU0_P1_RX_DN<11> @T6G_MB_LIB.T6G(SCH_1):P5E_CPU0_P1_RX_DN(11)
   U25 CJ44 P1_RXN11 GENOA_SP5-SOCKET6096_13568-001,SMLF,IO,DGA^6000030   I149 @T6G_MB_LIB.T6G(SCH_1):PAGE24
 U6011 BB29 A_PETN4 PT5161LRS-PT5161LRS,SMLF,IC,AJ051610U03     I1 @T6G_MB_LIB.T6G(SCH_1):PAGE405

P5E_CPU0_P1_RX_DN<12> @T6G_MB_LIB.T6G(SCH_1):P5E_CPU0_P1_RX_DN(12)
   U25 CC44 P1_RXN12 GENOA_SP5-SOCKET6096_13568-001,SMLF,IO,DGA^6000030   I149 @T6G_MB_LIB.T6G(SCH_1):PAGE24
 U6011 AR29 A_PETN3 PT5161LRS-PT5161LRS,SMLF,IC,AJ051610U03     I1 @T6G_MB_LIB.T6G(SCH_1):PAGE405

P5E_CPU0_P1_RX_DN<13> @T6G_MB_LIB.T6G(SCH_1):P5E_CPU0_P1_RX_DN(13)
   U25 CH41 P1_RXN13 GENOA_SP5-SOCKET6096_13568-001,SMLF,IO,DGA^6000030   I149 @T6G_MB_LIB.T6G(SCH_1):PAGE24
 U6011 AH29 A_PETN2 PT5161LRS-PT5161LRS,SMLF,IC,AJ051610U03     I1 @T6G_MB_LIB.T6G(SCH_1):PAGE405

P5E_CPU0_P1_RX_DN<14> @T6G_MB_LIB.T6G(SCH_1):P5E_CPU0_P1_RX_DN(14)
   U25 CF41 P1_RXN14 GENOA_SP5-SOCKET6096_13568-001,SMLF,IO,DGA^6000030   I149 @T6G_MB_LIB.T6G(SCH_1):PAGE24
 U6011 AA29 A_PETN1 PT5161LRS-PT5161LRS,SMLF,IC,AJ051610U03     I1 @T6G_MB_LIB.T6G(SCH_1):PAGE405

P5E_CPU0_P1_RX_DN<15> @T6G_MB_LIB.T6G(SCH_1):P5E_CPU0_P1_RX_DN(15)
   U25 CD41 P1_RXN15 GENOA_SP5-SOCKET6096_13568-001,SMLF,IO,DGA^6000030   I149 @T6G_MB_LIB.T6G(SCH_1):PAGE24
 U6011  P29 A_PETN0 PT5161LRS-PT5161LRS,SMLF,IC,AJ051610U03     I1 @T6G_MB_LIB.T6G(SCH_1):PAGE405

P5E_CPU0_P1_RX_DN<1> @T6G_MB_LIB.T6G(SCH_1):P5E_CPU0_P1_RX_DN(1)
   U25 CG53 P1_RXN1 GENOA_SP5-SOCKET6096_13568-001,SMLF,IO,DGA^6000030   I149 @T6G_MB_LIB.T6G(SCH_1):PAGE24
 U6011 EM29 A_PETN14 PT5161LRS-PT5161LRS,SMLF,IC,AJ051610U03    I38 @T6G_MB_LIB.T6G(SCH_1):PAGE405

P5E_CPU0_P1_RX_DN<2> @T6G_MB_LIB.T6G(SCH_1):P5E_CPU0_P1_RX_DN(2)
   U25 CC53 P1_RXN2 GENOA_SP5-SOCKET6096_13568-001,SMLF,IO,DGA^6000030   I149 @T6G_MB_LIB.T6G(SCH_1):PAGE24
 U6011 EE29 A_PETN13 PT5161LRS-PT5161LRS,SMLF,IC,AJ051610U03    I38 @T6G_MB_LIB.T6G(SCH_1):PAGE405

P5E_CPU0_P1_RX_DN<3> @T6G_MB_LIB.T6G(SCH_1):P5E_CPU0_P1_RX_DN(3)
   U25 CE50 P1_RXN3 GENOA_SP5-SOCKET6096_13568-001,SMLF,IO,DGA^6000030   I149 @T6G_MB_LIB.T6G(SCH_1):PAGE24
 U6011 DV29 A_PETN12 PT5161LRS-PT5161LRS,SMLF,IC,AJ051610U03    I38 @T6G_MB_LIB.T6G(SCH_1):PAGE405

P5E_CPU0_P1_RX_DN<4> @T6G_MB_LIB.T6G(SCH_1):P5E_CPU0_P1_RX_DN(4)
   U25 CG50 P1_RXN4 GENOA_SP5-SOCKET6096_13568-001,SMLF,IO,DGA^6000030   I149 @T6G_MB_LIB.T6G(SCH_1):PAGE24
 U6011 DL29 A_PETN11 PT5161LRS-PT5161LRS,SMLF,IC,AJ051610U03    I38 @T6G_MB_LIB.T6G(SCH_1):PAGE405

P5E_CPU0_P1_RX_DN<5> @T6G_MB_LIB.T6G(SCH_1):P5E_CPU0_P1_RX_DN(5)
   U25 CC50 P1_RXN5 GENOA_SP5-SOCKET6096_13568-001,SMLF,IO,DGA^6000030   I149 @T6G_MB_LIB.T6G(SCH_1):PAGE24
 U6011 DD29 A_PETN10 PT5161LRS-PT5161LRS,SMLF,IC,AJ051610U03    I38 @T6G_MB_LIB.T6G(SCH_1):PAGE405

P5E_CPU0_P1_RX_DN<6> @T6G_MB_LIB.T6G(SCH_1):P5E_CPU0_P1_RX_DN(6)
   U25 CE47 P1_RXN6 GENOA_SP5-SOCKET6096_13568-001,SMLF,IO,DGA^6000030   I149 @T6G_MB_LIB.T6G(SCH_1):PAGE24
 U6011 CU29 A_PETN9 PT5161LRS-PT5161LRS,SMLF,IC,AJ051610U03    I38 @T6G_MB_LIB.T6G(SCH_1):PAGE405

P5E_CPU0_P1_RX_DN<7> @T6G_MB_LIB.T6G(SCH_1):P5E_CPU0_P1_RX_DN(7)
   U25 CG47 P1_RXN7 GENOA_SP5-SOCKET6096_13568-001,SMLF,IO,DGA^6000030   I149 @T6G_MB_LIB.T6G(SCH_1):PAGE24
 U6011 CK29 A_PETN8 PT5161LRS-PT5161LRS,SMLF,IC,AJ051610U03    I38 @T6G_MB_LIB.T6G(SCH_1):PAGE405

P5E_CPU0_P1_RX_DN<8> @T6G_MB_LIB.T6G(SCH_1):P5E_CPU0_P1_RX_DN(8)
   U25 CC47 P1_RXN8 GENOA_SP5-SOCKET6096_13568-001,SMLF,IO,DGA^6000030   I149 @T6G_MB_LIB.T6G(SCH_1):PAGE24
 U6011 CC29 A_PETN7 PT5161LRS-PT5161LRS,SMLF,IC,AJ051610U03     I1 @T6G_MB_LIB.T6G(SCH_1):PAGE405

P5E_CPU0_P1_RX_DN<9> @T6G_MB_LIB.T6G(SCH_1):P5E_CPU0_P1_RX_DN(9)
   U25 CE44 P1_RXN9 GENOA_SP5-SOCKET6096_13568-001,SMLF,IO,DGA^6000030   I149 @T6G_MB_LIB.T6G(SCH_1):PAGE24
 U6011 BT29 A_PETN6 PT5161LRS-PT5161LRS,SMLF,IC,AJ051610U03     I1 @T6G_MB_LIB.T6G(SCH_1):PAGE405

P5E_CPU0_P1_RX_DP<0> @T6G_MB_LIB.T6G(SCH_1):P5E_CPU0_P1_RX_DP(0)
   U25 CE52 P1_RXP0 GENOA_SP5-SOCKET6096_13568-001,SMLF,IO,DGA^6000030   I149 @T6G_MB_LIB.T6G(SCH_1):PAGE24
 U6011 EU26 A_PETP15 PT5161LRS-PT5161LRS,SMLF,IC,AJ051610U03    I38 @T6G_MB_LIB.T6G(SCH_1):PAGE405

P5E_CPU0_P1_RX_DP<10> @T6G_MB_LIB.T6G(SCH_1):P5E_CPU0_P1_RX_DP(10)
   U25 CG43 P1_RXP10 GENOA_SP5-SOCKET6096_13568-001,SMLF,IO,DGA^6000030   I149 @T6G_MB_LIB.T6G(SCH_1):PAGE24
 U6011 BG26 A_PETP5 PT5161LRS-PT5161LRS,SMLF,IC,AJ051610U03     I1 @T6G_MB_LIB.T6G(SCH_1):PAGE405

P5E_CPU0_P1_RX_DP<11> @T6G_MB_LIB.T6G(SCH_1):P5E_CPU0_P1_RX_DP(11)
   U25 CJ43 P1_RXP11 GENOA_SP5-SOCKET6096_13568-001,SMLF,IO,DGA^6000030   I149 @T6G_MB_LIB.T6G(SCH_1):PAGE24
 U6011 AY26 A_PETP4 PT5161LRS-PT5161LRS,SMLF,IC,AJ051610U03     I1 @T6G_MB_LIB.T6G(SCH_1):PAGE405

P5E_CPU0_P1_RX_DP<12> @T6G_MB_LIB.T6G(SCH_1):P5E_CPU0_P1_RX_DP(12)
   U25 CC43 P1_RXP12 GENOA_SP5-SOCKET6096_13568-001,SMLF,IO,DGA^6000030   I149 @T6G_MB_LIB.T6G(SCH_1):PAGE24
 U6011 AN26 A_PETP3 PT5161LRS-PT5161LRS,SMLF,IC,AJ051610U03     I1 @T6G_MB_LIB.T6G(SCH_1):PAGE405

P5E_CPU0_P1_RX_DP<13> @T6G_MB_LIB.T6G(SCH_1):P5E_CPU0_P1_RX_DP(13)
   U25 CH40 P1_RXP13 GENOA_SP5-SOCKET6096_13568-001,SMLF,IO,DGA^6000030   I149 @T6G_MB_LIB.T6G(SCH_1):PAGE24
 U6011 AF26 A_PETP2 PT5161LRS-PT5161LRS,SMLF,IC,AJ051610U03     I1 @T6G_MB_LIB.T6G(SCH_1):PAGE405

P5E_CPU0_P1_RX_DP<14> @T6G_MB_LIB.T6G(SCH_1):P5E_CPU0_P1_RX_DP(14)
   U25 CF40 P1_RXP14 GENOA_SP5-SOCKET6096_13568-001,SMLF,IO,DGA^6000030   I149 @T6G_MB_LIB.T6G(SCH_1):PAGE24
 U6011  W26 A_PETP1 PT5161LRS-PT5161LRS,SMLF,IC,AJ051610U03     I1 @T6G_MB_LIB.T6G(SCH_1):PAGE405

P5E_CPU0_P1_RX_DP<15> @T6G_MB_LIB.T6G(SCH_1):P5E_CPU0_P1_RX_DP(15)
   U25 CD40 P1_RXP15 GENOA_SP5-SOCKET6096_13568-001,SMLF,IO,DGA^6000030   I149 @T6G_MB_LIB.T6G(SCH_1):PAGE24
 U6011  M26 A_PETP0 PT5161LRS-PT5161LRS,SMLF,IC,AJ051610U03     I1 @T6G_MB_LIB.T6G(SCH_1):PAGE405

P5E_CPU0_P1_RX_DP<1> @T6G_MB_LIB.T6G(SCH_1):P5E_CPU0_P1_RX_DP(1)
   U25 CG52 P1_RXP1 GENOA_SP5-SOCKET6096_13568-001,SMLF,IO,DGA^6000030   I149 @T6G_MB_LIB.T6G(SCH_1):PAGE24
 U6011 EK26 A_PETP14 PT5161LRS-PT5161LRS,SMLF,IC,AJ051610U03    I38 @T6G_MB_LIB.T6G(SCH_1):PAGE405

P5E_CPU0_P1_RX_DP<2> @T6G_MB_LIB.T6G(SCH_1):P5E_CPU0_P1_RX_DP(2)
   U25 CC52 P1_RXP2 GENOA_SP5-SOCKET6096_13568-001,SMLF,IO,DGA^6000030   I149 @T6G_MB_LIB.T6G(SCH_1):PAGE24
 U6011 EC26 A_PETP13 PT5161LRS-PT5161LRS,SMLF,IC,AJ051610U03    I38 @T6G_MB_LIB.T6G(SCH_1):PAGE405

P5E_CPU0_P1_RX_DP<3> @T6G_MB_LIB.T6G(SCH_1):P5E_CPU0_P1_RX_DP(3)
   U25 CE49 P1_RXP3 GENOA_SP5-SOCKET6096_13568-001,SMLF,IO,DGA^6000030   I149 @T6G_MB_LIB.T6G(SCH_1):PAGE24
 U6011 DT26 A_PETP12 PT5161LRS-PT5161LRS,SMLF,IC,AJ051610U03    I38 @T6G_MB_LIB.T6G(SCH_1):PAGE405

P5E_CPU0_P1_RX_DP<4> @T6G_MB_LIB.T6G(SCH_1):P5E_CPU0_P1_RX_DP(4)
   U25 CG49 P1_RXP4 GENOA_SP5-SOCKET6096_13568-001,SMLF,IO,DGA^6000030   I149 @T6G_MB_LIB.T6G(SCH_1):PAGE24
 U6011 DJ26 A_PETP11 PT5161LRS-PT5161LRS,SMLF,IC,AJ051610U03    I38 @T6G_MB_LIB.T6G(SCH_1):PAGE405

P5E_CPU0_P1_RX_DP<5> @T6G_MB_LIB.T6G(SCH_1):P5E_CPU0_P1_RX_DP(5)
   U25 CC49 P1_RXP5 GENOA_SP5-SOCKET6096_13568-001,SMLF,IO,DGA^6000030   I149 @T6G_MB_LIB.T6G(SCH_1):PAGE24
 U6011 DB26 A_PETP10 PT5161LRS-PT5161LRS,SMLF,IC,AJ051610U03    I38 @T6G_MB_LIB.T6G(SCH_1):PAGE405

P5E_CPU0_P1_RX_DP<6> @T6G_MB_LIB.T6G(SCH_1):P5E_CPU0_P1_RX_DP(6)
   U25 CE46 P1_RXP6 GENOA_SP5-SOCKET6096_13568-001,SMLF,IO,DGA^6000030   I149 @T6G_MB_LIB.T6G(SCH_1):PAGE24
 U6011 CR26 A_PETP9 PT5161LRS-PT5161LRS,SMLF,IC,AJ051610U03    I38 @T6G_MB_LIB.T6G(SCH_1):PAGE405

P5E_CPU0_P1_RX_DP<7> @T6G_MB_LIB.T6G(SCH_1):P5E_CPU0_P1_RX_DP(7)
   U25 CG46 P1_RXP7 GENOA_SP5-SOCKET6096_13568-001,SMLF,IO,DGA^6000030   I149 @T6G_MB_LIB.T6G(SCH_1):PAGE24
 U6011 CH26 A_PETP8 PT5161LRS-PT5161LRS,SMLF,IC,AJ051610U03    I38 @T6G_MB_LIB.T6G(SCH_1):PAGE405

P5E_CPU0_P1_RX_DP<8> @T6G_MB_LIB.T6G(SCH_1):P5E_CPU0_P1_RX_DP(8)
   U25 CC46 P1_RXP8 GENOA_SP5-SOCKET6096_13568-001,SMLF,IO,DGA^6000030   I149 @T6G_MB_LIB.T6G(SCH_1):PAGE24
 U6011 CA26 A_PETP7 PT5161LRS-PT5161LRS,SMLF,IC,AJ051610U03     I1 @T6G_MB_LIB.T6G(SCH_1):PAGE405

P5E_CPU0_P1_RX_DP<9> @T6G_MB_LIB.T6G(SCH_1):P5E_CPU0_P1_RX_DP(9)
   U25 CE43 P1_RXP9 GENOA_SP5-SOCKET6096_13568-001,SMLF,IO,DGA^6000030   I149 @T6G_MB_LIB.T6G(SCH_1):PAGE24
 U6011 BP26 A_PETP6 PT5161LRS-PT5161LRS,SMLF,IC,AJ051610U03     I1 @T6G_MB_LIB.T6G(SCH_1):PAGE405

P5E_CPU0_P1_TX_BUF_C_DN<0> @T6G_MB_LIB.T6G(SCH_1):P5E_CPU0_P1_TX_BUF_C_DN(0)
 C6534    1      1 Q_CAP_DIFFBUS_C0201-DIFF BUS_0.22UF,6.3V,20%,X6S,SA    I47 @T6G_MB_LIB.T6G(SCH_1):PAGE407
  J108   L1     L1 CONN112_10137002101LF-CONN112_10137002-101LF,THLF,A    I72 @T6G_MB_LIB.T6G(SCH_1):PAGE320

P5E_CPU0_P1_TX_BUF_C_DN<10> @T6G_MB_LIB.T6G(SCH_1):P5E_CPU0_P1_TX_BUF_C_DN(10)
 C6554    1      1 Q_CAP_DIFFBUS_C0201-DIFF BUS_0.22UF,6.3V,20%,X6S,SA    I97 @T6G_MB_LIB.T6G(SCH_1):PAGE407
  J107   L3     L3 CONN112_10137002101LF-CONN112_10137002-101LF,THLF,A    I49 @T6G_MB_LIB.T6G(SCH_1):PAGE317

P5E_CPU0_P1_TX_BUF_C_DN<11> @T6G_MB_LIB.T6G(SCH_1):P5E_CPU0_P1_TX_BUF_C_DN(11)
 C6556    1      1 Q_CAP_DIFFBUS_C0201-DIFF BUS_0.22UF,6.3V,20%,X6S,SA    I94 @T6G_MB_LIB.T6G(SCH_1):PAGE407
  J107   K4     K4 CONN112_10137002101LF-CONN112_10137002-101LF,THLF,A    I49 @T6G_MB_LIB.T6G(SCH_1):PAGE317

P5E_CPU0_P1_TX_BUF_C_DN<12> @T6G_MB_LIB.T6G(SCH_1):P5E_CPU0_P1_TX_BUF_C_DN(12)
 C6558    1      1 Q_CAP_DIFFBUS_C0201-DIFF BUS_0.22UF,6.3V,20%,X6S,SA    I92 @T6G_MB_LIB.T6G(SCH_1):PAGE407
  J107   L5     L5 CONN112_10137002101LF-CONN112_10137002-101LF,THLF,A    I70 @T6G_MB_LIB.T6G(SCH_1):PAGE317

P5E_CPU0_P1_TX_BUF_C_DN<13> @T6G_MB_LIB.T6G(SCH_1):P5E_CPU0_P1_TX_BUF_C_DN(13)
 C6560    1      1 Q_CAP_DIFFBUS_C0201-DIFF BUS_0.22UF,6.3V,20%,X6S,SA    I90 @T6G_MB_LIB.T6G(SCH_1):PAGE407
  J107   K6     K6 CONN112_10137002101LF-CONN112_10137002-101LF,THLF,A    I70 @T6G_MB_LIB.T6G(SCH_1):PAGE317

P5E_CPU0_P1_TX_BUF_C_DN<14> @T6G_MB_LIB.T6G(SCH_1):P5E_CPU0_P1_TX_BUF_C_DN(14)
 C6562    1      1 Q_CAP_DIFFBUS_C0201-DIFF BUS_0.22UF,6.3V,20%,X6S,SA    I88 @T6G_MB_LIB.T6G(SCH_1):PAGE407
  J107   L7     L7 CONN112_10137002101LF-CONN112_10137002-101LF,THLF,A    I70 @T6G_MB_LIB.T6G(SCH_1):PAGE317

P5E_CPU0_P1_TX_BUF_C_DN<15> @T6G_MB_LIB.T6G(SCH_1):P5E_CPU0_P1_TX_BUF_C_DN(15)
 C6564    1      1 Q_CAP_DIFFBUS_C0201-DIFF BUS_0.22UF,6.3V,20%,X6S,SA    I86 @T6G_MB_LIB.T6G(SCH_1):PAGE407
  J107   K8     K8 CONN112_10137002101LF-CONN112_10137002-101LF,THLF,A    I70 @T6G_MB_LIB.T6G(SCH_1):PAGE317

P5E_CPU0_P1_TX_BUF_C_DN<1> @T6G_MB_LIB.T6G(SCH_1):P5E_CPU0_P1_TX_BUF_C_DN(1)
 C6536    1      1 Q_CAP_DIFFBUS_C0201-DIFF BUS_0.22UF,6.3V,20%,X6S,SA    I44 @T6G_MB_LIB.T6G(SCH_1):PAGE407
  J108   K2     K2 CONN112_10137002101LF-CONN112_10137002-101LF,THLF,A    I72 @T6G_MB_LIB.T6G(SCH_1):PAGE320

P5E_CPU0_P1_TX_BUF_C_DN<2> @T6G_MB_LIB.T6G(SCH_1):P5E_CPU0_P1_TX_BUF_C_DN(2)
 C6538    1      1 Q_CAP_DIFFBUS_C0201-DIFF BUS_0.22UF,6.3V,20%,X6S,SA    I26 @T6G_MB_LIB.T6G(SCH_1):PAGE407
  J108   L3     L3 CONN112_10137002101LF-CONN112_10137002-101LF,THLF,A    I72 @T6G_MB_LIB.T6G(SCH_1):PAGE320

P5E_CPU0_P1_TX_BUF_C_DN<3> @T6G_MB_LIB.T6G(SCH_1):P5E_CPU0_P1_TX_BUF_C_DN(3)
 C6540    1      1 Q_CAP_DIFFBUS_C0201-DIFF BUS_0.22UF,6.3V,20%,X6S,SA    I24 @T6G_MB_LIB.T6G(SCH_1):PAGE407
  J108   K4     K4 CONN112_10137002101LF-CONN112_10137002-101LF,THLF,A    I72 @T6G_MB_LIB.T6G(SCH_1):PAGE320

P5E_CPU0_P1_TX_BUF_C_DN<4> @T6G_MB_LIB.T6G(SCH_1):P5E_CPU0_P1_TX_BUF_C_DN(4)
 C6542    1      1 Q_CAP_DIFFBUS_C0201-DIFF BUS_0.22UF,6.3V,20%,X6S,SA    I23 @T6G_MB_LIB.T6G(SCH_1):PAGE407
  J108   L5     L5 CONN112_10137002101LF-CONN112_10137002-101LF,THLF,A    I15 @T6G_MB_LIB.T6G(SCH_1):PAGE320

P5E_CPU0_P1_TX_BUF_C_DN<5> @T6G_MB_LIB.T6G(SCH_1):P5E_CPU0_P1_TX_BUF_C_DN(5)
 C6544    1      1 Q_CAP_DIFFBUS_C0201-DIFF BUS_0.22UF,6.3V,20%,X6S,SA    I21 @T6G_MB_LIB.T6G(SCH_1):PAGE407
  J108   K6     K6 CONN112_10137002101LF-CONN112_10137002-101LF,THLF,A    I15 @T6G_MB_LIB.T6G(SCH_1):PAGE320

P5E_CPU0_P1_TX_BUF_C_DN<6> @T6G_MB_LIB.T6G(SCH_1):P5E_CPU0_P1_TX_BUF_C_DN(6)
 C6546    1      1 Q_CAP_DIFFBUS_C0201-DIFF BUS_0.22UF,6.3V,20%,X6S,SA    I19 @T6G_MB_LIB.T6G(SCH_1):PAGE407
  J108   L7     L7 CONN112_10137002101LF-CONN112_10137002-101LF,THLF,A    I15 @T6G_MB_LIB.T6G(SCH_1):PAGE320

P5E_CPU0_P1_TX_BUF_C_DN<7> @T6G_MB_LIB.T6G(SCH_1):P5E_CPU0_P1_TX_BUF_C_DN(7)
 C6548    1      1 Q_CAP_DIFFBUS_C0201-DIFF BUS_0.22UF,6.3V,20%,X6S,SA    I15 @T6G_MB_LIB.T6G(SCH_1):PAGE407
  J108   K8     K8 CONN112_10137002101LF-CONN112_10137002-101LF,THLF,A    I15 @T6G_MB_LIB.T6G(SCH_1):PAGE320

P5E_CPU0_P1_TX_BUF_C_DN<8> @T6G_MB_LIB.T6G(SCH_1):P5E_CPU0_P1_TX_BUF_C_DN(8)
 C6550    1      1 Q_CAP_DIFFBUS_C0201-DIFF BUS_0.22UF,6.3V,20%,X6S,SA   I104 @T6G_MB_LIB.T6G(SCH_1):PAGE407
  J107   L1     L1 CONN112_10137002101LF-CONN112_10137002-101LF,THLF,A    I49 @T6G_MB_LIB.T6G(SCH_1):PAGE317

P5E_CPU0_P1_TX_BUF_C_DN<9> @T6G_MB_LIB.T6G(SCH_1):P5E_CPU0_P1_TX_BUF_C_DN(9)
 C6552    1      1 Q_CAP_DIFFBUS_C0201-DIFF BUS_0.22UF,6.3V,20%,X6S,SA   I103 @T6G_MB_LIB.T6G(SCH_1):PAGE407
  J107   K2     K2 CONN112_10137002101LF-CONN112_10137002-101LF,THLF,A    I49 @T6G_MB_LIB.T6G(SCH_1):PAGE317

P5E_CPU0_P1_TX_BUF_C_DP<0> @T6G_MB_LIB.T6G(SCH_1):P5E_CPU0_P1_TX_BUF_C_DP(0)
 C6533    1      1 Q_CAP_DIFFBUS_C0201-DIFF BUS_0.22UF,6.3V,20%,X6S,SA    I46 @T6G_MB_LIB.T6G(SCH_1):PAGE407
  J108   M1     M1 CONN112_10137002101LF-CONN112_10137002-101LF,THLF,A    I72 @T6G_MB_LIB.T6G(SCH_1):PAGE320

P5E_CPU0_P1_TX_BUF_C_DP<10> @T6G_MB_LIB.T6G(SCH_1):P5E_CPU0_P1_TX_BUF_C_DP(10)
 C6553    1      1 Q_CAP_DIFFBUS_C0201-DIFF BUS_0.22UF,6.3V,20%,X6S,SA    I96 @T6G_MB_LIB.T6G(SCH_1):PAGE407
  J107   M3     M3 CONN112_10137002101LF-CONN112_10137002-101LF,THLF,A    I49 @T6G_MB_LIB.T6G(SCH_1):PAGE317

P5E_CPU0_P1_TX_BUF_C_DP<11> @T6G_MB_LIB.T6G(SCH_1):P5E_CPU0_P1_TX_BUF_C_DP(11)
 C6555    1      1 Q_CAP_DIFFBUS_C0201-DIFF BUS_0.22UF,6.3V,20%,X6S,SA    I95 @T6G_MB_LIB.T6G(SCH_1):PAGE407
  J107   L4     L4 CONN112_10137002101LF-CONN112_10137002-101LF,THLF,A    I49 @T6G_MB_LIB.T6G(SCH_1):PAGE317

P5E_CPU0_P1_TX_BUF_C_DP<12> @T6G_MB_LIB.T6G(SCH_1):P5E_CPU0_P1_TX_BUF_C_DP(12)
 C6557    1      1 Q_CAP_DIFFBUS_C0201-DIFF BUS_0.22UF,6.3V,20%,X6S,SA    I93 @T6G_MB_LIB.T6G(SCH_1):PAGE407
  J107   M5     M5 CONN112_10137002101LF-CONN112_10137002-101LF,THLF,A    I70 @T6G_MB_LIB.T6G(SCH_1):PAGE317

P5E_CPU0_P1_TX_BUF_C_DP<13> @T6G_MB_LIB.T6G(SCH_1):P5E_CPU0_P1_TX_BUF_C_DP(13)
 C6559    1      1 Q_CAP_DIFFBUS_C0201-DIFF BUS_0.22UF,6.3V,20%,X6S,SA    I91 @T6G_MB_LIB.T6G(SCH_1):PAGE407
  J107   L6     L6 CONN112_10137002101LF-CONN112_10137002-101LF,THLF,A    I70 @T6G_MB_LIB.T6G(SCH_1):PAGE317

P5E_CPU0_P1_TX_BUF_C_DP<14> @T6G_MB_LIB.T6G(SCH_1):P5E_CPU0_P1_TX_BUF_C_DP(14)
 C6561    1      1 Q_CAP_DIFFBUS_C0201-DIFF BUS_0.22UF,6.3V,20%,X6S,SA    I89 @T6G_MB_LIB.T6G(SCH_1):PAGE407
  J107   M7     M7 CONN112_10137002101LF-CONN112_10137002-101LF,THLF,A    I70 @T6G_MB_LIB.T6G(SCH_1):PAGE317

P5E_CPU0_P1_TX_BUF_C_DP<15> @T6G_MB_LIB.T6G(SCH_1):P5E_CPU0_P1_TX_BUF_C_DP(15)
 C6563    1      1 Q_CAP_DIFFBUS_C0201-DIFF BUS_0.22UF,6.3V,20%,X6S,SA    I87 @T6G_MB_LIB.T6G(SCH_1):PAGE407
  J107   L8     L8 CONN112_10137002101LF-CONN112_10137002-101LF,THLF,A    I70 @T6G_MB_LIB.T6G(SCH_1):PAGE317

P5E_CPU0_P1_TX_BUF_C_DP<1> @T6G_MB_LIB.T6G(SCH_1):P5E_CPU0_P1_TX_BUF_C_DP(1)
 C6535    1      1 Q_CAP_DIFFBUS_C0201-DIFF BUS_0.22UF,6.3V,20%,X6S,SA    I45 @T6G_MB_LIB.T6G(SCH_1):PAGE407
  J108   L2     L2 CONN112_10137002101LF-CONN112_10137002-101LF,THLF,A    I72 @T6G_MB_LIB.T6G(SCH_1):PAGE320

P5E_CPU0_P1_TX_BUF_C_DP<2> @T6G_MB_LIB.T6G(SCH_1):P5E_CPU0_P1_TX_BUF_C_DP(2)
 C6537    1      1 Q_CAP_DIFFBUS_C0201-DIFF BUS_0.22UF,6.3V,20%,X6S,SA    I27 @T6G_MB_LIB.T6G(SCH_1):PAGE407
  J108   M3     M3 CONN112_10137002101LF-CONN112_10137002-101LF,THLF,A    I72 @T6G_MB_LIB.T6G(SCH_1):PAGE320

P5E_CPU0_P1_TX_BUF_C_DP<3> @T6G_MB_LIB.T6G(SCH_1):P5E_CPU0_P1_TX_BUF_C_DP(3)
 C6539    1      1 Q_CAP_DIFFBUS_C0201-DIFF BUS_0.22UF,6.3V,20%,X6S,SA    I25 @T6G_MB_LIB.T6G(SCH_1):PAGE407
  J108   L4     L4 CONN112_10137002101LF-CONN112_10137002-101LF,THLF,A    I72 @T6G_MB_LIB.T6G(SCH_1):PAGE320

P5E_CPU0_P1_TX_BUF_C_DP<4> @T6G_MB_LIB.T6G(SCH_1):P5E_CPU0_P1_TX_BUF_C_DP(4)
 C6541    1      1 Q_CAP_DIFFBUS_C0201-DIFF BUS_0.22UF,6.3V,20%,X6S,SA    I22 @T6G_MB_LIB.T6G(SCH_1):PAGE407
  J108   M5     M5 CONN112_10137002101LF-CONN112_10137002-101LF,THLF,A    I15 @T6G_MB_LIB.T6G(SCH_1):PAGE320

P5E_CPU0_P1_TX_BUF_C_DP<5> @T6G_MB_LIB.T6G(SCH_1):P5E_CPU0_P1_TX_BUF_C_DP(5)
 C6543    1      1 Q_CAP_DIFFBUS_C0201-DIFF BUS_0.22UF,6.3V,20%,X6S,SA    I20 @T6G_MB_LIB.T6G(SCH_1):PAGE407
  J108   L6     L6 CONN112_10137002101LF-CONN112_10137002-101LF,THLF,A    I15 @T6G_MB_LIB.T6G(SCH_1):PAGE320

P5E_CPU0_P1_TX_BUF_C_DP<6> @T6G_MB_LIB.T6G(SCH_1):P5E_CPU0_P1_TX_BUF_C_DP(6)
 C6545    1      1 Q_CAP_DIFFBUS_C0201-DIFF BUS_0.22UF,6.3V,20%,X6S,SA    I18 @T6G_MB_LIB.T6G(SCH_1):PAGE407
  J108   M7     M7 CONN112_10137002101LF-CONN112_10137002-101LF,THLF,A    I15 @T6G_MB_LIB.T6G(SCH_1):PAGE320

P5E_CPU0_P1_TX_BUF_C_DP<7> @T6G_MB_LIB.T6G(SCH_1):P5E_CPU0_P1_TX_BUF_C_DP(7)
 C6547    1      1 Q_CAP_DIFFBUS_C0201-DIFF BUS_0.22UF,6.3V,20%,X6S,SA    I16 @T6G_MB_LIB.T6G(SCH_1):PAGE407
  J108   L8     L8 CONN112_10137002101LF-CONN112_10137002-101LF,THLF,A    I15 @T6G_MB_LIB.T6G(SCH_1):PAGE320

P5E_CPU0_P1_TX_BUF_C_DP<8> @T6G_MB_LIB.T6G(SCH_1):P5E_CPU0_P1_TX_BUF_C_DP(8)
 C6549    1      1 Q_CAP_DIFFBUS_C0201-DIFF BUS_0.22UF,6.3V,20%,X6S,SA   I105 @T6G_MB_LIB.T6G(SCH_1):PAGE407
  J107   M1     M1 CONN112_10137002101LF-CONN112_10137002-101LF,THLF,A    I49 @T6G_MB_LIB.T6G(SCH_1):PAGE317

P5E_CPU0_P1_TX_BUF_C_DP<9> @T6G_MB_LIB.T6G(SCH_1):P5E_CPU0_P1_TX_BUF_C_DP(9)
 C6551    1      1 Q_CAP_DIFFBUS_C0201-DIFF BUS_0.22UF,6.3V,20%,X6S,SA   I102 @T6G_MB_LIB.T6G(SCH_1):PAGE407
  J107   L2     L2 CONN112_10137002101LF-CONN112_10137002-101LF,THLF,A    I49 @T6G_MB_LIB.T6G(SCH_1):PAGE317

P5E_CPU0_P1_TX_BUF_DN<0> @T6G_MB_LIB.T6G(SCH_1):P5E_CPU0_P1_TX_BUF_DN(0)
 C6534    2      2 Q_CAP_DIFFBUS_C0201-DIFF BUS_0.22UF,6.3V,20%,X6S,SA    I47 @T6G_MB_LIB.T6G(SCH_1):PAGE407
 U6011 EW10 B_PETN15 PT5161LRS-PT5161LRS,SMLF,IC,AJ051610U03   I142 @T6G_MB_LIB.T6G(SCH_1):PAGE407

P5E_CPU0_P1_TX_BUF_DN<10> @T6G_MB_LIB.T6G(SCH_1):P5E_CPU0_P1_TX_BUF_DN(10)
 U6011 BJ10 B_PETN5 PT5161LRS-PT5161LRS,SMLF,IC,AJ051610U03    I43 @T6G_MB_LIB.T6G(SCH_1):PAGE407
 C6554    2      2 Q_CAP_DIFFBUS_C0201-DIFF BUS_0.22UF,6.3V,20%,X6S,SA    I97 @T6G_MB_LIB.T6G(SCH_1):PAGE407

P5E_CPU0_P1_TX_BUF_DN<11> @T6G_MB_LIB.T6G(SCH_1):P5E_CPU0_P1_TX_BUF_DN(11)
 U6011 BB10 B_PETN4 PT5161LRS-PT5161LRS,SMLF,IC,AJ051610U03    I43 @T6G_MB_LIB.T6G(SCH_1):PAGE407
 C6556    2      2 Q_CAP_DIFFBUS_C0201-DIFF BUS_0.22UF,6.3V,20%,X6S,SA    I94 @T6G_MB_LIB.T6G(SCH_1):PAGE407

P5E_CPU0_P1_TX_BUF_DN<12> @T6G_MB_LIB.T6G(SCH_1):P5E_CPU0_P1_TX_BUF_DN(12)
 U6011 AR10 B_PETN3 PT5161LRS-PT5161LRS,SMLF,IC,AJ051610U03    I43 @T6G_MB_LIB.T6G(SCH_1):PAGE407
 C6558    2      2 Q_CAP_DIFFBUS_C0201-DIFF BUS_0.22UF,6.3V,20%,X6S,SA    I92 @T6G_MB_LIB.T6G(SCH_1):PAGE407

P5E_CPU0_P1_TX_BUF_DN<13> @T6G_MB_LIB.T6G(SCH_1):P5E_CPU0_P1_TX_BUF_DN(13)
 U6011 AH10 B_PETN2 PT5161LRS-PT5161LRS,SMLF,IC,AJ051610U03    I43 @T6G_MB_LIB.T6G(SCH_1):PAGE407
 C6560    2      2 Q_CAP_DIFFBUS_C0201-DIFF BUS_0.22UF,6.3V,20%,X6S,SA    I90 @T6G_MB_LIB.T6G(SCH_1):PAGE407

P5E_CPU0_P1_TX_BUF_DN<14> @T6G_MB_LIB.T6G(SCH_1):P5E_CPU0_P1_TX_BUF_DN(14)
 U6011 AA10 B_PETN1 PT5161LRS-PT5161LRS,SMLF,IC,AJ051610U03    I43 @T6G_MB_LIB.T6G(SCH_1):PAGE407
 C6562    2      2 Q_CAP_DIFFBUS_C0201-DIFF BUS_0.22UF,6.3V,20%,X6S,SA    I88 @T6G_MB_LIB.T6G(SCH_1):PAGE407

P5E_CPU0_P1_TX_BUF_DN<15> @T6G_MB_LIB.T6G(SCH_1):P5E_CPU0_P1_TX_BUF_DN(15)
 U6011  P10 B_PETN0 PT5161LRS-PT5161LRS,SMLF,IC,AJ051610U03    I43 @T6G_MB_LIB.T6G(SCH_1):PAGE407
 C6564    2      2 Q_CAP_DIFFBUS_C0201-DIFF BUS_0.22UF,6.3V,20%,X6S,SA    I86 @T6G_MB_LIB.T6G(SCH_1):PAGE407

P5E_CPU0_P1_TX_BUF_DN<1> @T6G_MB_LIB.T6G(SCH_1):P5E_CPU0_P1_TX_BUF_DN(1)
 C6536    2      2 Q_CAP_DIFFBUS_C0201-DIFF BUS_0.22UF,6.3V,20%,X6S,SA    I44 @T6G_MB_LIB.T6G(SCH_1):PAGE407
 U6011 EM10 B_PETN14 PT5161LRS-PT5161LRS,SMLF,IC,AJ051610U03   I142 @T6G_MB_LIB.T6G(SCH_1):PAGE407

P5E_CPU0_P1_TX_BUF_DN<2> @T6G_MB_LIB.T6G(SCH_1):P5E_CPU0_P1_TX_BUF_DN(2)
 C6538    2      2 Q_CAP_DIFFBUS_C0201-DIFF BUS_0.22UF,6.3V,20%,X6S,SA    I26 @T6G_MB_LIB.T6G(SCH_1):PAGE407
 U6011 EE10 B_PETN13 PT5161LRS-PT5161LRS,SMLF,IC,AJ051610U03   I142 @T6G_MB_LIB.T6G(SCH_1):PAGE407

P5E_CPU0_P1_TX_BUF_DN<3> @T6G_MB_LIB.T6G(SCH_1):P5E_CPU0_P1_TX_BUF_DN(3)
 C6540    2      2 Q_CAP_DIFFBUS_C0201-DIFF BUS_0.22UF,6.3V,20%,X6S,SA    I24 @T6G_MB_LIB.T6G(SCH_1):PAGE407
 U6011 DV10 B_PETN12 PT5161LRS-PT5161LRS,SMLF,IC,AJ051610U03   I142 @T6G_MB_LIB.T6G(SCH_1):PAGE407

P5E_CPU0_P1_TX_BUF_DN<4> @T6G_MB_LIB.T6G(SCH_1):P5E_CPU0_P1_TX_BUF_DN(4)
 C6542    2      2 Q_CAP_DIFFBUS_C0201-DIFF BUS_0.22UF,6.3V,20%,X6S,SA    I23 @T6G_MB_LIB.T6G(SCH_1):PAGE407
 U6011 DL10 B_PETN11 PT5161LRS-PT5161LRS,SMLF,IC,AJ051610U03   I142 @T6G_MB_LIB.T6G(SCH_1):PAGE407

P5E_CPU0_P1_TX_BUF_DN<5> @T6G_MB_LIB.T6G(SCH_1):P5E_CPU0_P1_TX_BUF_DN(5)
 C6544    2      2 Q_CAP_DIFFBUS_C0201-DIFF BUS_0.22UF,6.3V,20%,X6S,SA    I21 @T6G_MB_LIB.T6G(SCH_1):PAGE407
 U6011 DD10 B_PETN10 PT5161LRS-PT5161LRS,SMLF,IC,AJ051610U03   I142 @T6G_MB_LIB.T6G(SCH_1):PAGE407

P5E_CPU0_P1_TX_BUF_DN<6> @T6G_MB_LIB.T6G(SCH_1):P5E_CPU0_P1_TX_BUF_DN(6)
 C6546    2      2 Q_CAP_DIFFBUS_C0201-DIFF BUS_0.22UF,6.3V,20%,X6S,SA    I19 @T6G_MB_LIB.T6G(SCH_1):PAGE407
 U6011 CU10 B_PETN9 PT5161LRS-PT5161LRS,SMLF,IC,AJ051610U03   I142 @T6G_MB_LIB.T6G(SCH_1):PAGE407

P5E_CPU0_P1_TX_BUF_DN<7> @T6G_MB_LIB.T6G(SCH_1):P5E_CPU0_P1_TX_BUF_DN(7)
 C6548    2      2 Q_CAP_DIFFBUS_C0201-DIFF BUS_0.22UF,6.3V,20%,X6S,SA    I15 @T6G_MB_LIB.T6G(SCH_1):PAGE407
 U6011 CK10 B_PETN8 PT5161LRS-PT5161LRS,SMLF,IC,AJ051610U03   I142 @T6G_MB_LIB.T6G(SCH_1):PAGE407

P5E_CPU0_P1_TX_BUF_DN<8> @T6G_MB_LIB.T6G(SCH_1):P5E_CPU0_P1_TX_BUF_DN(8)
 U6011 CC10 B_PETN7 PT5161LRS-PT5161LRS,SMLF,IC,AJ051610U03    I43 @T6G_MB_LIB.T6G(SCH_1):PAGE407
 C6550    2      2 Q_CAP_DIFFBUS_C0201-DIFF BUS_0.22UF,6.3V,20%,X6S,SA   I104 @T6G_MB_LIB.T6G(SCH_1):PAGE407

P5E_CPU0_P1_TX_BUF_DN<9> @T6G_MB_LIB.T6G(SCH_1):P5E_CPU0_P1_TX_BUF_DN(9)
 U6011 BT10 B_PETN6 PT5161LRS-PT5161LRS,SMLF,IC,AJ051610U03    I43 @T6G_MB_LIB.T6G(SCH_1):PAGE407
 C6552    2      2 Q_CAP_DIFFBUS_C0201-DIFF BUS_0.22UF,6.3V,20%,X6S,SA   I103 @T6G_MB_LIB.T6G(SCH_1):PAGE407

P5E_CPU0_P1_TX_BUF_DP<0> @T6G_MB_LIB.T6G(SCH_1):P5E_CPU0_P1_TX_BUF_DP(0)
 C6533    2      2 Q_CAP_DIFFBUS_C0201-DIFF BUS_0.22UF,6.3V,20%,X6S,SA    I46 @T6G_MB_LIB.T6G(SCH_1):PAGE407
 U6011  EU7 B_PETP15 PT5161LRS-PT5161LRS,SMLF,IC,AJ051610U03   I142 @T6G_MB_LIB.T6G(SCH_1):PAGE407

P5E_CPU0_P1_TX_BUF_DP<10> @T6G_MB_LIB.T6G(SCH_1):P5E_CPU0_P1_TX_BUF_DP(10)
 U6011  BG7 B_PETP5 PT5161LRS-PT5161LRS,SMLF,IC,AJ051610U03    I43 @T6G_MB_LIB.T6G(SCH_1):PAGE407
 C6553    2      2 Q_CAP_DIFFBUS_C0201-DIFF BUS_0.22UF,6.3V,20%,X6S,SA    I96 @T6G_MB_LIB.T6G(SCH_1):PAGE407

P5E_CPU0_P1_TX_BUF_DP<11> @T6G_MB_LIB.T6G(SCH_1):P5E_CPU0_P1_TX_BUF_DP(11)
 U6011  AY7 B_PETP4 PT5161LRS-PT5161LRS,SMLF,IC,AJ051610U03    I43 @T6G_MB_LIB.T6G(SCH_1):PAGE407
 C6555    2      2 Q_CAP_DIFFBUS_C0201-DIFF BUS_0.22UF,6.3V,20%,X6S,SA    I95 @T6G_MB_LIB.T6G(SCH_1):PAGE407

P5E_CPU0_P1_TX_BUF_DP<12> @T6G_MB_LIB.T6G(SCH_1):P5E_CPU0_P1_TX_BUF_DP(12)
 U6011  AN7 B_PETP3 PT5161LRS-PT5161LRS,SMLF,IC,AJ051610U03    I43 @T6G_MB_LIB.T6G(SCH_1):PAGE407
 C6557    2      2 Q_CAP_DIFFBUS_C0201-DIFF BUS_0.22UF,6.3V,20%,X6S,SA    I93 @T6G_MB_LIB.T6G(SCH_1):PAGE407

P5E_CPU0_P1_TX_BUF_DP<13> @T6G_MB_LIB.T6G(SCH_1):P5E_CPU0_P1_TX_BUF_DP(13)
 U6011  AF7 B_PETP2 PT5161LRS-PT5161LRS,SMLF,IC,AJ051610U03    I43 @T6G_MB_LIB.T6G(SCH_1):PAGE407
 C6559    2      2 Q_CAP_DIFFBUS_C0201-DIFF BUS_0.22UF,6.3V,20%,X6S,SA    I91 @T6G_MB_LIB.T6G(SCH_1):PAGE407

P5E_CPU0_P1_TX_BUF_DP<14> @T6G_MB_LIB.T6G(SCH_1):P5E_CPU0_P1_TX_BUF_DP(14)
 U6011   W7 B_PETP1 PT5161LRS-PT5161LRS,SMLF,IC,AJ051610U03    I43 @T6G_MB_LIB.T6G(SCH_1):PAGE407
 C6561    2      2 Q_CAP_DIFFBUS_C0201-DIFF BUS_0.22UF,6.3V,20%,X6S,SA    I89 @T6G_MB_LIB.T6G(SCH_1):PAGE407

P5E_CPU0_P1_TX_BUF_DP<15> @T6G_MB_LIB.T6G(SCH_1):P5E_CPU0_P1_TX_BUF_DP(15)
 U6011   M7 B_PETP0 PT5161LRS-PT5161LRS,SMLF,IC,AJ051610U03    I43 @T6G_MB_LIB.T6G(SCH_1):PAGE407
 C6563    2      2 Q_CAP_DIFFBUS_C0201-DIFF BUS_0.22UF,6.3V,20%,X6S,SA    I87 @T6G_MB_LIB.T6G(SCH_1):PAGE407

P5E_CPU0_P1_TX_BUF_DP<1> @T6G_MB_LIB.T6G(SCH_1):P5E_CPU0_P1_TX_BUF_DP(1)
 C6535    2      2 Q_CAP_DIFFBUS_C0201-DIFF BUS_0.22UF,6.3V,20%,X6S,SA    I45 @T6G_MB_LIB.T6G(SCH_1):PAGE407
 U6011  EK7 B_PETP14 PT5161LRS-PT5161LRS,SMLF,IC,AJ051610U03   I142 @T6G_MB_LIB.T6G(SCH_1):PAGE407

P5E_CPU0_P1_TX_BUF_DP<2> @T6G_MB_LIB.T6G(SCH_1):P5E_CPU0_P1_TX_BUF_DP(2)
 C6537    2      2 Q_CAP_DIFFBUS_C0201-DIFF BUS_0.22UF,6.3V,20%,X6S,SA    I27 @T6G_MB_LIB.T6G(SCH_1):PAGE407
 U6011  EC7 B_PETP13 PT5161LRS-PT5161LRS,SMLF,IC,AJ051610U03   I142 @T6G_MB_LIB.T6G(SCH_1):PAGE407

P5E_CPU0_P1_TX_BUF_DP<3> @T6G_MB_LIB.T6G(SCH_1):P5E_CPU0_P1_TX_BUF_DP(3)
 C6539    2      2 Q_CAP_DIFFBUS_C0201-DIFF BUS_0.22UF,6.3V,20%,X6S,SA    I25 @T6G_MB_LIB.T6G(SCH_1):PAGE407
 U6011  DT7 B_PETP12 PT5161LRS-PT5161LRS,SMLF,IC,AJ051610U03   I142 @T6G_MB_LIB.T6G(SCH_1):PAGE407

P5E_CPU0_P1_TX_BUF_DP<4> @T6G_MB_LIB.T6G(SCH_1):P5E_CPU0_P1_TX_BUF_DP(4)
 C6541    2      2 Q_CAP_DIFFBUS_C0201-DIFF BUS_0.22UF,6.3V,20%,X6S,SA    I22 @T6G_MB_LIB.T6G(SCH_1):PAGE407
 U6011  DJ7 B_PETP11 PT5161LRS-PT5161LRS,SMLF,IC,AJ051610U03   I142 @T6G_MB_LIB.T6G(SCH_1):PAGE407

P5E_CPU0_P1_TX_BUF_DP<5> @T6G_MB_LIB.T6G(SCH_1):P5E_CPU0_P1_TX_BUF_DP(5)
 C6543    2      2 Q_CAP_DIFFBUS_C0201-DIFF BUS_0.22UF,6.3V,20%,X6S,SA    I20 @T6G_MB_LIB.T6G(SCH_1):PAGE407
 U6011  DB7 B_PETP10 PT5161LRS-PT5161LRS,SMLF,IC,AJ051610U03   I142 @T6G_MB_LIB.T6G(SCH_1):PAGE407

P5E_CPU0_P1_TX_BUF_DP<6> @T6G_MB_LIB.T6G(SCH_1):P5E_CPU0_P1_TX_BUF_DP(6)
 C6545    2      2 Q_CAP_DIFFBUS_C0201-DIFF BUS_0.22UF,6.3V,20%,X6S,SA    I18 @T6G_MB_LIB.T6G(SCH_1):PAGE407
 U6011  CR7 B_PETP9 PT5161LRS-PT5161LRS,SMLF,IC,AJ051610U03   I142 @T6G_MB_LIB.T6G(SCH_1):PAGE407

P5E_CPU0_P1_TX_BUF_DP<7> @T6G_MB_LIB.T6G(SCH_1):P5E_CPU0_P1_TX_BUF_DP(7)
 C6547    2      2 Q_CAP_DIFFBUS_C0201-DIFF BUS_0.22UF,6.3V,20%,X6S,SA    I16 @T6G_MB_LIB.T6G(SCH_1):PAGE407
 U6011  CH7 B_PETP8 PT5161LRS-PT5161LRS,SMLF,IC,AJ051610U03   I142 @T6G_MB_LIB.T6G(SCH_1):PAGE407

P5E_CPU0_P1_TX_BUF_DP<8> @T6G_MB_LIB.T6G(SCH_1):P5E_CPU0_P1_TX_BUF_DP(8)
 U6011  CA7 B_PETP7 PT5161LRS-PT5161LRS,SMLF,IC,AJ051610U03    I43 @T6G_MB_LIB.T6G(SCH_1):PAGE407
 C6549    2      2 Q_CAP_DIFFBUS_C0201-DIFF BUS_0.22UF,6.3V,20%,X6S,SA   I105 @T6G_MB_LIB.T6G(SCH_1):PAGE407

P5E_CPU0_P1_TX_BUF_DP<9> @T6G_MB_LIB.T6G(SCH_1):P5E_CPU0_P1_TX_BUF_DP(9)
 U6011  BP7 B_PETP6 PT5161LRS-PT5161LRS,SMLF,IC,AJ051610U03    I43 @T6G_MB_LIB.T6G(SCH_1):PAGE407
 C6551    2      2 Q_CAP_DIFFBUS_C0201-DIFF BUS_0.22UF,6.3V,20%,X6S,SA   I102 @T6G_MB_LIB.T6G(SCH_1):PAGE407

P5E_CPU0_P1_TX_C_DN<0> @T6G_MB_LIB.T6G(SCH_1):P5E_CPU0_P1_TX_C_DN(0)
  C964    1      1 Q_CAP_DIFFBUS_C0201-DIFF BUS_0.22UF,6.3V,20%,X6S,SA   I122 @T6G_MB_LIB.T6G(SCH_1):PAGE351
 U6011 EV34 B_PERP15 PT5161LRS-PT5161LRS,SMLF,IC,AJ051610U03    I38 @T6G_MB_LIB.T6G(SCH_1):PAGE404

P5E_CPU0_P1_TX_C_DN<10> @T6G_MB_LIB.T6G(SCH_1):P5E_CPU0_P1_TX_C_DN(10)
  C944    1      1 Q_CAP_DIFFBUS_C0201-DIFF BUS_0.22UF,6.3V,20%,X6S,SA   I156 @T6G_MB_LIB.T6G(SCH_1):PAGE351
 U6011 BH34 B_PERP5 PT5161LRS-PT5161LRS,SMLF,IC,AJ051610U03     I1 @T6G_MB_LIB.T6G(SCH_1):PAGE404

P5E_CPU0_P1_TX_C_DN<11> @T6G_MB_LIB.T6G(SCH_1):P5E_CPU0_P1_TX_C_DN(11)
  C942    1      1 Q_CAP_DIFFBUS_C0201-DIFF BUS_0.22UF,6.3V,20%,X6S,SA   I158 @T6G_MB_LIB.T6G(SCH_1):PAGE351
 U6011 BA34 B_PERP4 PT5161LRS-PT5161LRS,SMLF,IC,AJ051610U03     I1 @T6G_MB_LIB.T6G(SCH_1):PAGE404

P5E_CPU0_P1_TX_C_DN<12> @T6G_MB_LIB.T6G(SCH_1):P5E_CPU0_P1_TX_C_DN(12)
  C940    1      1 Q_CAP_DIFFBUS_C0201-DIFF BUS_0.22UF,6.3V,20%,X6S,SA   I160 @T6G_MB_LIB.T6G(SCH_1):PAGE351
 U6011 AP34 B_PERP3 PT5161LRS-PT5161LRS,SMLF,IC,AJ051610U03     I1 @T6G_MB_LIB.T6G(SCH_1):PAGE404

P5E_CPU0_P1_TX_C_DN<13> @T6G_MB_LIB.T6G(SCH_1):P5E_CPU0_P1_TX_C_DN(13)
  C938    1      1 Q_CAP_DIFFBUS_C0201-DIFF BUS_0.22UF,6.3V,20%,X6S,SA   I165 @T6G_MB_LIB.T6G(SCH_1):PAGE351
 U6011 AG34 B_PERP2 PT5161LRS-PT5161LRS,SMLF,IC,AJ051610U03     I1 @T6G_MB_LIB.T6G(SCH_1):PAGE404

P5E_CPU0_P1_TX_C_DN<14> @T6G_MB_LIB.T6G(SCH_1):P5E_CPU0_P1_TX_C_DN(14)
  C936    1      1 Q_CAP_DIFFBUS_C0201-DIFF BUS_0.22UF,6.3V,20%,X6S,SA   I167 @T6G_MB_LIB.T6G(SCH_1):PAGE351
 U6011 AB35 B_PERN1 PT5161LRS-PT5161LRS,SMLF,IC,AJ051610U03     I1 @T6G_MB_LIB.T6G(SCH_1):PAGE404

P5E_CPU0_P1_TX_C_DN<15> @T6G_MB_LIB.T6G(SCH_1):P5E_CPU0_P1_TX_C_DN(15)
  C934    1      1 Q_CAP_DIFFBUS_C0201-DIFF BUS_0.22UF,6.3V,20%,X6S,SA   I169 @T6G_MB_LIB.T6G(SCH_1):PAGE351
 U6011  N34 B_PERP0 PT5161LRS-PT5161LRS,SMLF,IC,AJ051610U03     I1 @T6G_MB_LIB.T6G(SCH_1):PAGE404

P5E_CPU0_P1_TX_C_DN<1> @T6G_MB_LIB.T6G(SCH_1):P5E_CPU0_P1_TX_C_DN(1)
  C962    1      1 Q_CAP_DIFFBUS_C0201-DIFF BUS_0.22UF,6.3V,20%,X6S,SA   I124 @T6G_MB_LIB.T6G(SCH_1):PAGE351
 U6011 EN35 B_PERN14 PT5161LRS-PT5161LRS,SMLF,IC,AJ051610U03    I38 @T6G_MB_LIB.T6G(SCH_1):PAGE404

P5E_CPU0_P1_TX_C_DN<2> @T6G_MB_LIB.T6G(SCH_1):P5E_CPU0_P1_TX_C_DN(2)
  C960    1      1 Q_CAP_DIFFBUS_C0201-DIFF BUS_0.22UF,6.3V,20%,X6S,SA   I126 @T6G_MB_LIB.T6G(SCH_1):PAGE351
 U6011 ED34 B_PERP13 PT5161LRS-PT5161LRS,SMLF,IC,AJ051610U03    I38 @T6G_MB_LIB.T6G(SCH_1):PAGE404

P5E_CPU0_P1_TX_C_DN<3> @T6G_MB_LIB.T6G(SCH_1):P5E_CPU0_P1_TX_C_DN(3)
  C958    1      1 Q_CAP_DIFFBUS_C0201-DIFF BUS_0.22UF,6.3V,20%,X6S,SA   I128 @T6G_MB_LIB.T6G(SCH_1):PAGE351
 U6011 DU34 B_PERP12 PT5161LRS-PT5161LRS,SMLF,IC,AJ051610U03    I38 @T6G_MB_LIB.T6G(SCH_1):PAGE404

P5E_CPU0_P1_TX_C_DN<4> @T6G_MB_LIB.T6G(SCH_1):P5E_CPU0_P1_TX_C_DN(4)
  C956    1      1 Q_CAP_DIFFBUS_C0201-DIFF BUS_0.22UF,6.3V,20%,X6S,SA   I207 @T6G_MB_LIB.T6G(SCH_1):PAGE351
 U6011 DK34 B_PERP11 PT5161LRS-PT5161LRS,SMLF,IC,AJ051610U03    I38 @T6G_MB_LIB.T6G(SCH_1):PAGE404

P5E_CPU0_P1_TX_C_DN<5> @T6G_MB_LIB.T6G(SCH_1):P5E_CPU0_P1_TX_C_DN(5)
  C954    1      1 Q_CAP_DIFFBUS_C0201-DIFF BUS_0.22UF,6.3V,20%,X6S,SA   I133 @T6G_MB_LIB.T6G(SCH_1):PAGE351
 U6011 DC34 B_PERP10 PT5161LRS-PT5161LRS,SMLF,IC,AJ051610U03    I38 @T6G_MB_LIB.T6G(SCH_1):PAGE404

P5E_CPU0_P1_TX_C_DN<6> @T6G_MB_LIB.T6G(SCH_1):P5E_CPU0_P1_TX_C_DN(6)
  C952    1      1 Q_CAP_DIFFBUS_C0201-DIFF BUS_0.22UF,6.3V,20%,X6S,SA   I135 @T6G_MB_LIB.T6G(SCH_1):PAGE351
 U6011 CT34 B_PERP9 PT5161LRS-PT5161LRS,SMLF,IC,AJ051610U03    I38 @T6G_MB_LIB.T6G(SCH_1):PAGE404

P5E_CPU0_P1_TX_C_DN<7> @T6G_MB_LIB.T6G(SCH_1):P5E_CPU0_P1_TX_C_DN(7)
  C950    1      1 Q_CAP_DIFFBUS_C0201-DIFF BUS_0.22UF,6.3V,20%,X6S,SA   I137 @T6G_MB_LIB.T6G(SCH_1):PAGE351
 U6011 CJ34 B_PERP8 PT5161LRS-PT5161LRS,SMLF,IC,AJ051610U03    I38 @T6G_MB_LIB.T6G(SCH_1):PAGE404

P5E_CPU0_P1_TX_C_DN<8> @T6G_MB_LIB.T6G(SCH_1):P5E_CPU0_P1_TX_C_DN(8)
  C948    1      1 Q_CAP_DIFFBUS_C0201-DIFF BUS_0.22UF,6.3V,20%,X6S,SA   I152 @T6G_MB_LIB.T6G(SCH_1):PAGE351
 U6011 CB34 B_PERP7 PT5161LRS-PT5161LRS,SMLF,IC,AJ051610U03     I1 @T6G_MB_LIB.T6G(SCH_1):PAGE404

P5E_CPU0_P1_TX_C_DN<9> @T6G_MB_LIB.T6G(SCH_1):P5E_CPU0_P1_TX_C_DN(9)
  C946    1      1 Q_CAP_DIFFBUS_C0201-DIFF BUS_0.22UF,6.3V,20%,X6S,SA   I154 @T6G_MB_LIB.T6G(SCH_1):PAGE351
 U6011 BR34 B_PERP6 PT5161LRS-PT5161LRS,SMLF,IC,AJ051610U03     I1 @T6G_MB_LIB.T6G(SCH_1):PAGE404

P5E_CPU0_P1_TX_C_DP<0> @T6G_MB_LIB.T6G(SCH_1):P5E_CPU0_P1_TX_C_DP(0)
  C965    1      1 Q_CAP_DIFFBUS_C0201-DIFF BUS_0.22UF,6.3V,20%,X6S,SA   I121 @T6G_MB_LIB.T6G(SCH_1):PAGE351
 U6011 EY35 B_PERN15 PT5161LRS-PT5161LRS,SMLF,IC,AJ051610U03    I38 @T6G_MB_LIB.T6G(SCH_1):PAGE404

P5E_CPU0_P1_TX_C_DP<10> @T6G_MB_LIB.T6G(SCH_1):P5E_CPU0_P1_TX_C_DP(10)
  C945    1      1 Q_CAP_DIFFBUS_C0201-DIFF BUS_0.22UF,6.3V,20%,X6S,SA   I155 @T6G_MB_LIB.T6G(SCH_1):PAGE351
 U6011 BK35 B_PERN5 PT5161LRS-PT5161LRS,SMLF,IC,AJ051610U03     I1 @T6G_MB_LIB.T6G(SCH_1):PAGE404

P5E_CPU0_P1_TX_C_DP<11> @T6G_MB_LIB.T6G(SCH_1):P5E_CPU0_P1_TX_C_DP(11)
  C943    1      1 Q_CAP_DIFFBUS_C0201-DIFF BUS_0.22UF,6.3V,20%,X6S,SA   I157 @T6G_MB_LIB.T6G(SCH_1):PAGE351
 U6011 BC35 B_PERN4 PT5161LRS-PT5161LRS,SMLF,IC,AJ051610U03     I1 @T6G_MB_LIB.T6G(SCH_1):PAGE404

P5E_CPU0_P1_TX_C_DP<12> @T6G_MB_LIB.T6G(SCH_1):P5E_CPU0_P1_TX_C_DP(12)
  C941    1      1 Q_CAP_DIFFBUS_C0201-DIFF BUS_0.22UF,6.3V,20%,X6S,SA   I159 @T6G_MB_LIB.T6G(SCH_1):PAGE351
 U6011 AT35 B_PERN3 PT5161LRS-PT5161LRS,SMLF,IC,AJ051610U03     I1 @T6G_MB_LIB.T6G(SCH_1):PAGE404

P5E_CPU0_P1_TX_C_DP<13> @T6G_MB_LIB.T6G(SCH_1):P5E_CPU0_P1_TX_C_DP(13)
  C939    1      1 Q_CAP_DIFFBUS_C0201-DIFF BUS_0.22UF,6.3V,20%,X6S,SA   I164 @T6G_MB_LIB.T6G(SCH_1):PAGE351
 U6011 AJ35 B_PERN2 PT5161LRS-PT5161LRS,SMLF,IC,AJ051610U03     I1 @T6G_MB_LIB.T6G(SCH_1):PAGE404

P5E_CPU0_P1_TX_C_DP<14> @T6G_MB_LIB.T6G(SCH_1):P5E_CPU0_P1_TX_C_DP(14)
  C937    1      1 Q_CAP_DIFFBUS_C0201-DIFF BUS_0.22UF,6.3V,20%,X6S,SA   I166 @T6G_MB_LIB.T6G(SCH_1):PAGE351
 U6011  Y34 B_PERP1 PT5161LRS-PT5161LRS,SMLF,IC,AJ051610U03     I1 @T6G_MB_LIB.T6G(SCH_1):PAGE404

P5E_CPU0_P1_TX_C_DP<15> @T6G_MB_LIB.T6G(SCH_1):P5E_CPU0_P1_TX_C_DP(15)
  C935    1      1 Q_CAP_DIFFBUS_C0201-DIFF BUS_0.22UF,6.3V,20%,X6S,SA   I168 @T6G_MB_LIB.T6G(SCH_1):PAGE351
 U6011  R35 B_PERN0 PT5161LRS-PT5161LRS,SMLF,IC,AJ051610U03     I1 @T6G_MB_LIB.T6G(SCH_1):PAGE404

P5E_CPU0_P1_TX_C_DP<1> @T6G_MB_LIB.T6G(SCH_1):P5E_CPU0_P1_TX_C_DP(1)
  C963    1      1 Q_CAP_DIFFBUS_C0201-DIFF BUS_0.22UF,6.3V,20%,X6S,SA   I123 @T6G_MB_LIB.T6G(SCH_1):PAGE351
 U6011 EL34 B_PERP14 PT5161LRS-PT5161LRS,SMLF,IC,AJ051610U03    I38 @T6G_MB_LIB.T6G(SCH_1):PAGE404

P5E_CPU0_P1_TX_C_DP<2> @T6G_MB_LIB.T6G(SCH_1):P5E_CPU0_P1_TX_C_DP(2)
  C961    1      1 Q_CAP_DIFFBUS_C0201-DIFF BUS_0.22UF,6.3V,20%,X6S,SA   I125 @T6G_MB_LIB.T6G(SCH_1):PAGE351
 U6011 EF35 B_PERN13 PT5161LRS-PT5161LRS,SMLF,IC,AJ051610U03    I38 @T6G_MB_LIB.T6G(SCH_1):PAGE404

P5E_CPU0_P1_TX_C_DP<3> @T6G_MB_LIB.T6G(SCH_1):P5E_CPU0_P1_TX_C_DP(3)
  C959    1      1 Q_CAP_DIFFBUS_C0201-DIFF BUS_0.22UF,6.3V,20%,X6S,SA   I127 @T6G_MB_LIB.T6G(SCH_1):PAGE351
 U6011 DW35 B_PERN12 PT5161LRS-PT5161LRS,SMLF,IC,AJ051610U03    I38 @T6G_MB_LIB.T6G(SCH_1):PAGE404

P5E_CPU0_P1_TX_C_DP<4> @T6G_MB_LIB.T6G(SCH_1):P5E_CPU0_P1_TX_C_DP(4)
  C957    1      1 Q_CAP_DIFFBUS_C0201-DIFF BUS_0.22UF,6.3V,20%,X6S,SA   I206 @T6G_MB_LIB.T6G(SCH_1):PAGE351
 U6011 DM35 B_PERN11 PT5161LRS-PT5161LRS,SMLF,IC,AJ051610U03    I38 @T6G_MB_LIB.T6G(SCH_1):PAGE404

P5E_CPU0_P1_TX_C_DP<5> @T6G_MB_LIB.T6G(SCH_1):P5E_CPU0_P1_TX_C_DP(5)
  C955    1      1 Q_CAP_DIFFBUS_C0201-DIFF BUS_0.22UF,6.3V,20%,X6S,SA   I208 @T6G_MB_LIB.T6G(SCH_1):PAGE351
 U6011 DE35 B_PERN10 PT5161LRS-PT5161LRS,SMLF,IC,AJ051610U03    I38 @T6G_MB_LIB.T6G(SCH_1):PAGE404

P5E_CPU0_P1_TX_C_DP<6> @T6G_MB_LIB.T6G(SCH_1):P5E_CPU0_P1_TX_C_DP(6)
  C953    1      1 Q_CAP_DIFFBUS_C0201-DIFF BUS_0.22UF,6.3V,20%,X6S,SA   I134 @T6G_MB_LIB.T6G(SCH_1):PAGE351
 U6011 CV35 B_PERN9 PT5161LRS-PT5161LRS,SMLF,IC,AJ051610U03    I38 @T6G_MB_LIB.T6G(SCH_1):PAGE404

P5E_CPU0_P1_TX_C_DP<7> @T6G_MB_LIB.T6G(SCH_1):P5E_CPU0_P1_TX_C_DP(7)
  C951    1      1 Q_CAP_DIFFBUS_C0201-DIFF BUS_0.22UF,6.3V,20%,X6S,SA   I136 @T6G_MB_LIB.T6G(SCH_1):PAGE351
 U6011 CL35 B_PERN8 PT5161LRS-PT5161LRS,SMLF,IC,AJ051610U03    I38 @T6G_MB_LIB.T6G(SCH_1):PAGE404

P5E_CPU0_P1_TX_C_DP<8> @T6G_MB_LIB.T6G(SCH_1):P5E_CPU0_P1_TX_C_DP(8)
  C949    1      1 Q_CAP_DIFFBUS_C0201-DIFF BUS_0.22UF,6.3V,20%,X6S,SA   I151 @T6G_MB_LIB.T6G(SCH_1):PAGE351
 U6011 CD35 B_PERN7 PT5161LRS-PT5161LRS,SMLF,IC,AJ051610U03     I1 @T6G_MB_LIB.T6G(SCH_1):PAGE404

P5E_CPU0_P1_TX_C_DP<9> @T6G_MB_LIB.T6G(SCH_1):P5E_CPU0_P1_TX_C_DP(9)
  C947    1      1 Q_CAP_DIFFBUS_C0201-DIFF BUS_0.22UF,6.3V,20%,X6S,SA   I153 @T6G_MB_LIB.T6G(SCH_1):PAGE351
 U6011 BU35 B_PERN6 PT5161LRS-PT5161LRS,SMLF,IC,AJ051610U03     I1 @T6G_MB_LIB.T6G(SCH_1):PAGE404

P5E_CPU0_P1_TX_DN<0> @T6G_MB_LIB.T6G(SCH_1):P5E_CPU0_P1_TX_DN(0)
   U25 CU52 P1_TXN0 GENOA_SP5-SOCKET6096_13568-001,SMLF,IO,DGA^6000030   I149 @T6G_MB_LIB.T6G(SCH_1):PAGE24
  C964    2      2 Q_CAP_DIFFBUS_C0201-DIFF BUS_0.22UF,6.3V,20%,X6S,SA   I122 @T6G_MB_LIB.T6G(SCH_1):PAGE351

P5E_CPU0_P1_TX_DN<10> @T6G_MB_LIB.T6G(SCH_1):P5E_CPU0_P1_TX_DN(10)
   U25 DA43 P1_TXN10 GENOA_SP5-SOCKET6096_13568-001,SMLF,IO,DGA^6000030   I149 @T6G_MB_LIB.T6G(SCH_1):PAGE24
  C944    2      2 Q_CAP_DIFFBUS_C0201-DIFF BUS_0.22UF,6.3V,20%,X6S,SA   I156 @T6G_MB_LIB.T6G(SCH_1):PAGE351

P5E_CPU0_P1_TX_DN<11> @T6G_MB_LIB.T6G(SCH_1):P5E_CPU0_P1_TX_DN(11)
   U25 DC43 P1_TXN11 GENOA_SP5-SOCKET6096_13568-001,SMLF,IO,DGA^6000030   I149 @T6G_MB_LIB.T6G(SCH_1):PAGE24
  C942    2      2 Q_CAP_DIFFBUS_C0201-DIFF BUS_0.22UF,6.3V,20%,X6S,SA   I158 @T6G_MB_LIB.T6G(SCH_1):PAGE351

P5E_CPU0_P1_TX_DN<12> @T6G_MB_LIB.T6G(SCH_1):P5E_CPU0_P1_TX_DN(12)
   U25 CW43 P1_TXN12 GENOA_SP5-SOCKET6096_13568-001,SMLF,IO,DGA^6000030   I149 @T6G_MB_LIB.T6G(SCH_1):PAGE24
  C940    2      2 Q_CAP_DIFFBUS_C0201-DIFF BUS_0.22UF,6.3V,20%,X6S,SA   I160 @T6G_MB_LIB.T6G(SCH_1):PAGE351

P5E_CPU0_P1_TX_DN<13> @T6G_MB_LIB.T6G(SCH_1):P5E_CPU0_P1_TX_DN(13)
   U25 DB40 P1_TXN13 GENOA_SP5-SOCKET6096_13568-001,SMLF,IO,DGA^6000030   I149 @T6G_MB_LIB.T6G(SCH_1):PAGE24
  C938    2      2 Q_CAP_DIFFBUS_C0201-DIFF BUS_0.22UF,6.3V,20%,X6S,SA   I165 @T6G_MB_LIB.T6G(SCH_1):PAGE351

P5E_CPU0_P1_TX_DN<14> @T6G_MB_LIB.T6G(SCH_1):P5E_CPU0_P1_TX_DN(14)
   U25 CY40 P1_TXN14 GENOA_SP5-SOCKET6096_13568-001,SMLF,IO,DGA^6000030   I149 @T6G_MB_LIB.T6G(SCH_1):PAGE24
  C936    2      2 Q_CAP_DIFFBUS_C0201-DIFF BUS_0.22UF,6.3V,20%,X6S,SA   I167 @T6G_MB_LIB.T6G(SCH_1):PAGE351

P5E_CPU0_P1_TX_DN<15> @T6G_MB_LIB.T6G(SCH_1):P5E_CPU0_P1_TX_DN(15)
   U25 CV40 P1_TXN15 GENOA_SP5-SOCKET6096_13568-001,SMLF,IO,DGA^6000030   I149 @T6G_MB_LIB.T6G(SCH_1):PAGE24
  C934    2      2 Q_CAP_DIFFBUS_C0201-DIFF BUS_0.22UF,6.3V,20%,X6S,SA   I169 @T6G_MB_LIB.T6G(SCH_1):PAGE351

P5E_CPU0_P1_TX_DN<1> @T6G_MB_LIB.T6G(SCH_1):P5E_CPU0_P1_TX_DN(1)
   U25 DA52 P1_TXN1 GENOA_SP5-SOCKET6096_13568-001,SMLF,IO,DGA^6000030   I149 @T6G_MB_LIB.T6G(SCH_1):PAGE24
  C962    2      2 Q_CAP_DIFFBUS_C0201-DIFF BUS_0.22UF,6.3V,20%,X6S,SA   I124 @T6G_MB_LIB.T6G(SCH_1):PAGE351

P5E_CPU0_P1_TX_DN<2> @T6G_MB_LIB.T6G(SCH_1):P5E_CPU0_P1_TX_DN(2)
   U25 DC52 P1_TXN2 GENOA_SP5-SOCKET6096_13568-001,SMLF,IO,DGA^6000030   I149 @T6G_MB_LIB.T6G(SCH_1):PAGE24
  C960    2      2 Q_CAP_DIFFBUS_C0201-DIFF BUS_0.22UF,6.3V,20%,X6S,SA   I126 @T6G_MB_LIB.T6G(SCH_1):PAGE351

P5E_CPU0_P1_TX_DN<3> @T6G_MB_LIB.T6G(SCH_1):P5E_CPU0_P1_TX_DN(3)
   U25 CW52 P1_TXN3 GENOA_SP5-SOCKET6096_13568-001,SMLF,IO,DGA^6000030   I149 @T6G_MB_LIB.T6G(SCH_1):PAGE24
  C958    2      2 Q_CAP_DIFFBUS_C0201-DIFF BUS_0.22UF,6.3V,20%,X6S,SA   I128 @T6G_MB_LIB.T6G(SCH_1):PAGE351

P5E_CPU0_P1_TX_DN<4> @T6G_MB_LIB.T6G(SCH_1):P5E_CPU0_P1_TX_DN(4)
   U25 DA49 P1_TXN4 GENOA_SP5-SOCKET6096_13568-001,SMLF,IO,DGA^6000030   I149 @T6G_MB_LIB.T6G(SCH_1):PAGE24
  C956    2      2 Q_CAP_DIFFBUS_C0201-DIFF BUS_0.22UF,6.3V,20%,X6S,SA   I207 @T6G_MB_LIB.T6G(SCH_1):PAGE351

P5E_CPU0_P1_TX_DN<5> @T6G_MB_LIB.T6G(SCH_1):P5E_CPU0_P1_TX_DN(5)
   U25 DC49 P1_TXN5 GENOA_SP5-SOCKET6096_13568-001,SMLF,IO,DGA^6000030   I149 @T6G_MB_LIB.T6G(SCH_1):PAGE24
  C954    2      2 Q_CAP_DIFFBUS_C0201-DIFF BUS_0.22UF,6.3V,20%,X6S,SA   I133 @T6G_MB_LIB.T6G(SCH_1):PAGE351

P5E_CPU0_P1_TX_DN<6> @T6G_MB_LIB.T6G(SCH_1):P5E_CPU0_P1_TX_DN(6)
   U25 CW49 P1_TXN6 GENOA_SP5-SOCKET6096_13568-001,SMLF,IO,DGA^6000030   I149 @T6G_MB_LIB.T6G(SCH_1):PAGE24
  C952    2      2 Q_CAP_DIFFBUS_C0201-DIFF BUS_0.22UF,6.3V,20%,X6S,SA   I135 @T6G_MB_LIB.T6G(SCH_1):PAGE351

P5E_CPU0_P1_TX_DN<7> @T6G_MB_LIB.T6G(SCH_1):P5E_CPU0_P1_TX_DN(7)
   U25 DA46 P1_TXN7 GENOA_SP5-SOCKET6096_13568-001,SMLF,IO,DGA^6000030   I149 @T6G_MB_LIB.T6G(SCH_1):PAGE24
  C950    2      2 Q_CAP_DIFFBUS_C0201-DIFF BUS_0.22UF,6.3V,20%,X6S,SA   I137 @T6G_MB_LIB.T6G(SCH_1):PAGE351

P5E_CPU0_P1_TX_DN<8> @T6G_MB_LIB.T6G(SCH_1):P5E_CPU0_P1_TX_DN(8)
   U25 DC46 P1_TXN8 GENOA_SP5-SOCKET6096_13568-001,SMLF,IO,DGA^6000030   I149 @T6G_MB_LIB.T6G(SCH_1):PAGE24
  C948    2      2 Q_CAP_DIFFBUS_C0201-DIFF BUS_0.22UF,6.3V,20%,X6S,SA   I152 @T6G_MB_LIB.T6G(SCH_1):PAGE351

P5E_CPU0_P1_TX_DN<9> @T6G_MB_LIB.T6G(SCH_1):P5E_CPU0_P1_TX_DN(9)
   U25 CW46 P1_TXN9 GENOA_SP5-SOCKET6096_13568-001,SMLF,IO,DGA^6000030   I149 @T6G_MB_LIB.T6G(SCH_1):PAGE24
  C946    2      2 Q_CAP_DIFFBUS_C0201-DIFF BUS_0.22UF,6.3V,20%,X6S,SA   I154 @T6G_MB_LIB.T6G(SCH_1):PAGE351

P5E_CPU0_P1_TX_DP<0> @T6G_MB_LIB.T6G(SCH_1):P5E_CPU0_P1_TX_DP(0)
   U25 CU53 P1_TXP0 GENOA_SP5-SOCKET6096_13568-001,SMLF,IO,DGA^6000030   I149 @T6G_MB_LIB.T6G(SCH_1):PAGE24
  C965    2      2 Q_CAP_DIFFBUS_C0201-DIFF BUS_0.22UF,6.3V,20%,X6S,SA   I121 @T6G_MB_LIB.T6G(SCH_1):PAGE351

P5E_CPU0_P1_TX_DP<10> @T6G_MB_LIB.T6G(SCH_1):P5E_CPU0_P1_TX_DP(10)
   U25 DA44 P1_TXP10 GENOA_SP5-SOCKET6096_13568-001,SMLF,IO,DGA^6000030   I149 @T6G_MB_LIB.T6G(SCH_1):PAGE24
  C945    2      2 Q_CAP_DIFFBUS_C0201-DIFF BUS_0.22UF,6.3V,20%,X6S,SA   I155 @T6G_MB_LIB.T6G(SCH_1):PAGE351

P5E_CPU0_P1_TX_DP<11> @T6G_MB_LIB.T6G(SCH_1):P5E_CPU0_P1_TX_DP(11)
   U25 DC44 P1_TXP11 GENOA_SP5-SOCKET6096_13568-001,SMLF,IO,DGA^6000030   I149 @T6G_MB_LIB.T6G(SCH_1):PAGE24
  C943    2      2 Q_CAP_DIFFBUS_C0201-DIFF BUS_0.22UF,6.3V,20%,X6S,SA   I157 @T6G_MB_LIB.T6G(SCH_1):PAGE351

P5E_CPU0_P1_TX_DP<12> @T6G_MB_LIB.T6G(SCH_1):P5E_CPU0_P1_TX_DP(12)
   U25 CW44 P1_TXP12 GENOA_SP5-SOCKET6096_13568-001,SMLF,IO,DGA^6000030   I149 @T6G_MB_LIB.T6G(SCH_1):PAGE24
  C941    2      2 Q_CAP_DIFFBUS_C0201-DIFF BUS_0.22UF,6.3V,20%,X6S,SA   I159 @T6G_MB_LIB.T6G(SCH_1):PAGE351

P5E_CPU0_P1_TX_DP<13> @T6G_MB_LIB.T6G(SCH_1):P5E_CPU0_P1_TX_DP(13)
   U25 DB41 P1_TXP13 GENOA_SP5-SOCKET6096_13568-001,SMLF,IO,DGA^6000030   I149 @T6G_MB_LIB.T6G(SCH_1):PAGE24
  C939    2      2 Q_CAP_DIFFBUS_C0201-DIFF BUS_0.22UF,6.3V,20%,X6S,SA   I164 @T6G_MB_LIB.T6G(SCH_1):PAGE351

P5E_CPU0_P1_TX_DP<14> @T6G_MB_LIB.T6G(SCH_1):P5E_CPU0_P1_TX_DP(14)
   U25 CY41 P1_TXP14 GENOA_SP5-SOCKET6096_13568-001,SMLF,IO,DGA^6000030   I149 @T6G_MB_LIB.T6G(SCH_1):PAGE24
  C937    2      2 Q_CAP_DIFFBUS_C0201-DIFF BUS_0.22UF,6.3V,20%,X6S,SA   I166 @T6G_MB_LIB.T6G(SCH_1):PAGE351

P5E_CPU0_P1_TX_DP<15> @T6G_MB_LIB.T6G(SCH_1):P5E_CPU0_P1_TX_DP(15)
   U25 CV41 P1_TXP15 GENOA_SP5-SOCKET6096_13568-001,SMLF,IO,DGA^6000030   I149 @T6G_MB_LIB.T6G(SCH_1):PAGE24
  C935    2      2 Q_CAP_DIFFBUS_C0201-DIFF BUS_0.22UF,6.3V,20%,X6S,SA   I168 @T6G_MB_LIB.T6G(SCH_1):PAGE351

P5E_CPU0_P1_TX_DP<1> @T6G_MB_LIB.T6G(SCH_1):P5E_CPU0_P1_TX_DP(1)
   U25 DA53 P1_TXP1 GENOA_SP5-SOCKET6096_13568-001,SMLF,IO,DGA^6000030   I149 @T6G_MB_LIB.T6G(SCH_1):PAGE24
  C963    2      2 Q_CAP_DIFFBUS_C0201-DIFF BUS_0.22UF,6.3V,20%,X6S,SA   I123 @T6G_MB_LIB.T6G(SCH_1):PAGE351

P5E_CPU0_P1_TX_DP<2> @T6G_MB_LIB.T6G(SCH_1):P5E_CPU0_P1_TX_DP(2)
   U25 DC53 P1_TXP2 GENOA_SP5-SOCKET6096_13568-001,SMLF,IO,DGA^6000030   I149 @T6G_MB_LIB.T6G(SCH_1):PAGE24
  C961    2      2 Q_CAP_DIFFBUS_C0201-DIFF BUS_0.22UF,6.3V,20%,X6S,SA   I125 @T6G_MB_LIB.T6G(SCH_1):PAGE351

P5E_CPU0_P1_TX_DP<3> @T6G_MB_LIB.T6G(SCH_1):P5E_CPU0_P1_TX_DP(3)
   U25 CW53 P1_TXP3 GENOA_SP5-SOCKET6096_13568-001,SMLF,IO,DGA^6000030   I149 @T6G_MB_LIB.T6G(SCH_1):PAGE24
  C959    2      2 Q_CAP_DIFFBUS_C0201-DIFF BUS_0.22UF,6.3V,20%,X6S,SA   I127 @T6G_MB_LIB.T6G(SCH_1):PAGE351

P5E_CPU0_P1_TX_DP<4> @T6G_MB_LIB.T6G(SCH_1):P5E_CPU0_P1_TX_DP(4)
   U25 DA50 P1_TXP4 GENOA_SP5-SOCKET6096_13568-001,SMLF,IO,DGA^6000030   I149 @T6G_MB_LIB.T6G(SCH_1):PAGE24
  C957    2      2 Q_CAP_DIFFBUS_C0201-DIFF BUS_0.22UF,6.3V,20%,X6S,SA   I206 @T6G_MB_LIB.T6G(SCH_1):PAGE351

P5E_CPU0_P1_TX_DP<5> @T6G_MB_LIB.T6G(SCH_1):P5E_CPU0_P1_TX_DP(5)
   U25 DC50 P1_TXP5 GENOA_SP5-SOCKET6096_13568-001,SMLF,IO,DGA^6000030   I149 @T6G_MB_LIB.T6G(SCH_1):PAGE24
  C955    2      2 Q_CAP_DIFFBUS_C0201-DIFF BUS_0.22UF,6.3V,20%,X6S,SA   I208 @T6G_MB_LIB.T6G(SCH_1):PAGE351

P5E_CPU0_P1_TX_DP<6> @T6G_MB_LIB.T6G(SCH_1):P5E_CPU0_P1_TX_DP(6)
   U25 CW50 P1_TXP6 GENOA_SP5-SOCKET6096_13568-001,SMLF,IO,DGA^6000030   I149 @T6G_MB_LIB.T6G(SCH_1):PAGE24
  C953    2      2 Q_CAP_DIFFBUS_C0201-DIFF BUS_0.22UF,6.3V,20%,X6S,SA   I134 @T6G_MB_LIB.T6G(SCH_1):PAGE351

P5E_CPU0_P1_TX_DP<7> @T6G_MB_LIB.T6G(SCH_1):P5E_CPU0_P1_TX_DP(7)
   U25 DA47 P1_TXP7 GENOA_SP5-SOCKET6096_13568-001,SMLF,IO,DGA^6000030   I149 @T6G_MB_LIB.T6G(SCH_1):PAGE24
  C951    2      2 Q_CAP_DIFFBUS_C0201-DIFF BUS_0.22UF,6.3V,20%,X6S,SA   I136 @T6G_MB_LIB.T6G(SCH_1):PAGE351

P5E_CPU0_P1_TX_DP<8> @T6G_MB_LIB.T6G(SCH_1):P5E_CPU0_P1_TX_DP(8)
   U25 DC47 P1_TXP8 GENOA_SP5-SOCKET6096_13568-001,SMLF,IO,DGA^6000030   I149 @T6G_MB_LIB.T6G(SCH_1):PAGE24
  C949    2      2 Q_CAP_DIFFBUS_C0201-DIFF BUS_0.22UF,6.3V,20%,X6S,SA   I151 @T6G_MB_LIB.T6G(SCH_1):PAGE351

P5E_CPU0_P1_TX_DP<9> @T6G_MB_LIB.T6G(SCH_1):P5E_CPU0_P1_TX_DP(9)
   U25 CW47 P1_TXP9 GENOA_SP5-SOCKET6096_13568-001,SMLF,IO,DGA^6000030   I149 @T6G_MB_LIB.T6G(SCH_1):PAGE24
  C947    2      2 Q_CAP_DIFFBUS_C0201-DIFF BUS_0.22UF,6.3V,20%,X6S,SA   I153 @T6G_MB_LIB.T6G(SCH_1):PAGE351

P5E_CPU0_P2_RX_BUF_DN<0> @T6G_MB_LIB.T6G(SCH_1):P5E_CPU0_P2_RX_BUF_DN(0)
 U6012  EV2 A_PERN15 PT5161LRS-PT5161LRS,SMLF,IC,AJ051610U03    I38 @T6G_MB_LIB.T6G(SCH_1):PAGE417
  J106   C1     C1 CONN112_10137002101LF-CONN112_10137002-101LF,THLF,A    I74 @T6G_MB_LIB.T6G(SCH_1):PAGE327

P5E_CPU0_P2_RX_BUF_DN<10> @T6G_MB_LIB.T6G(SCH_1):P5E_CPU0_P2_RX_BUF_DN(10)
 U6012  BH2 A_PERN5 PT5161LRS-PT5161LRS,SMLF,IC,AJ051610U03     I1 @T6G_MB_LIB.T6G(SCH_1):PAGE417
  J105   C3     C3 CONN112_10137002101LF-CONN112_10137002-101LF,THLF,A    I75 @T6G_MB_LIB.T6G(SCH_1):PAGE326

P5E_CPU0_P2_RX_BUF_DN<11> @T6G_MB_LIB.T6G(SCH_1):P5E_CPU0_P2_RX_BUF_DN(11)
 U6012  BA2 A_PERN4 PT5161LRS-PT5161LRS,SMLF,IC,AJ051610U03     I1 @T6G_MB_LIB.T6G(SCH_1):PAGE417
  J105   B4     B4 CONN112_10137002101LF-CONN112_10137002-101LF,THLF,A    I75 @T6G_MB_LIB.T6G(SCH_1):PAGE326

P5E_CPU0_P2_RX_BUF_DN<12> @T6G_MB_LIB.T6G(SCH_1):P5E_CPU0_P2_RX_BUF_DN(12)
 U6012  AP2 A_PERN3 PT5161LRS-PT5161LRS,SMLF,IC,AJ051610U03     I1 @T6G_MB_LIB.T6G(SCH_1):PAGE417
  J105   C5     C5 CONN112_10137002101LF-CONN112_10137002-101LF,THLF,A    I76 @T6G_MB_LIB.T6G(SCH_1):PAGE326

P5E_CPU0_P2_RX_BUF_DN<13> @T6G_MB_LIB.T6G(SCH_1):P5E_CPU0_P2_RX_BUF_DN(13)
 U6012  AG2 A_PERN2 PT5161LRS-PT5161LRS,SMLF,IC,AJ051610U03     I1 @T6G_MB_LIB.T6G(SCH_1):PAGE417
  J105   B6     B6 CONN112_10137002101LF-CONN112_10137002-101LF,THLF,A    I76 @T6G_MB_LIB.T6G(SCH_1):PAGE326

P5E_CPU0_P2_RX_BUF_DN<14> @T6G_MB_LIB.T6G(SCH_1):P5E_CPU0_P2_RX_BUF_DN(14)
 U6012   Y2 A_PERN1 PT5161LRS-PT5161LRS,SMLF,IC,AJ051610U03     I1 @T6G_MB_LIB.T6G(SCH_1):PAGE417
  J105   C7     C7 CONN112_10137002101LF-CONN112_10137002-101LF,THLF,A    I76 @T6G_MB_LIB.T6G(SCH_1):PAGE326

P5E_CPU0_P2_RX_BUF_DN<15> @T6G_MB_LIB.T6G(SCH_1):P5E_CPU0_P2_RX_BUF_DN(15)
 U6012   N2 A_PERN0 PT5161LRS-PT5161LRS,SMLF,IC,AJ051610U03     I1 @T6G_MB_LIB.T6G(SCH_1):PAGE417
  J105   B8     B8 CONN112_10137002101LF-CONN112_10137002-101LF,THLF,A    I76 @T6G_MB_LIB.T6G(SCH_1):PAGE326

P5E_CPU0_P2_RX_BUF_DN<1> @T6G_MB_LIB.T6G(SCH_1):P5E_CPU0_P2_RX_BUF_DN(1)
 U6012  EL2 A_PERN14 PT5161LRS-PT5161LRS,SMLF,IC,AJ051610U03    I38 @T6G_MB_LIB.T6G(SCH_1):PAGE417
  J106   B2     B2 CONN112_10137002101LF-CONN112_10137002-101LF,THLF,A    I74 @T6G_MB_LIB.T6G(SCH_1):PAGE327

P5E_CPU0_P2_RX_BUF_DN<2> @T6G_MB_LIB.T6G(SCH_1):P5E_CPU0_P2_RX_BUF_DN(2)
 U6012  ED2 A_PERN13 PT5161LRS-PT5161LRS,SMLF,IC,AJ051610U03    I38 @T6G_MB_LIB.T6G(SCH_1):PAGE417
  J106   C3     C3 CONN112_10137002101LF-CONN112_10137002-101LF,THLF,A    I74 @T6G_MB_LIB.T6G(SCH_1):PAGE327

P5E_CPU0_P2_RX_BUF_DN<3> @T6G_MB_LIB.T6G(SCH_1):P5E_CPU0_P2_RX_BUF_DN(3)
 U6012  DU2 A_PERN12 PT5161LRS-PT5161LRS,SMLF,IC,AJ051610U03    I38 @T6G_MB_LIB.T6G(SCH_1):PAGE417
  J106   B4     B4 CONN112_10137002101LF-CONN112_10137002-101LF,THLF,A    I74 @T6G_MB_LIB.T6G(SCH_1):PAGE327

P5E_CPU0_P2_RX_BUF_DN<4> @T6G_MB_LIB.T6G(SCH_1):P5E_CPU0_P2_RX_BUF_DN(4)
 U6012  DK2 A_PERN11 PT5161LRS-PT5161LRS,SMLF,IC,AJ051610U03    I38 @T6G_MB_LIB.T6G(SCH_1):PAGE417
  J106   C5     C5 CONN112_10137002101LF-CONN112_10137002-101LF,THLF,A    I19 @T6G_MB_LIB.T6G(SCH_1):PAGE327

P5E_CPU0_P2_RX_BUF_DN<5> @T6G_MB_LIB.T6G(SCH_1):P5E_CPU0_P2_RX_BUF_DN(5)
 U6012  DC2 A_PERN10 PT5161LRS-PT5161LRS,SMLF,IC,AJ051610U03    I38 @T6G_MB_LIB.T6G(SCH_1):PAGE417
  J106   B6     B6 CONN112_10137002101LF-CONN112_10137002-101LF,THLF,A    I19 @T6G_MB_LIB.T6G(SCH_1):PAGE327

P5E_CPU0_P2_RX_BUF_DN<6> @T6G_MB_LIB.T6G(SCH_1):P5E_CPU0_P2_RX_BUF_DN(6)
 U6012  CT2 A_PERN9 PT5161LRS-PT5161LRS,SMLF,IC,AJ051610U03    I38 @T6G_MB_LIB.T6G(SCH_1):PAGE417
  J106   C7     C7 CONN112_10137002101LF-CONN112_10137002-101LF,THLF,A    I19 @T6G_MB_LIB.T6G(SCH_1):PAGE327

P5E_CPU0_P2_RX_BUF_DN<7> @T6G_MB_LIB.T6G(SCH_1):P5E_CPU0_P2_RX_BUF_DN(7)
 U6012  CJ2 A_PERN8 PT5161LRS-PT5161LRS,SMLF,IC,AJ051610U03    I38 @T6G_MB_LIB.T6G(SCH_1):PAGE417
  J106   B8     B8 CONN112_10137002101LF-CONN112_10137002-101LF,THLF,A    I19 @T6G_MB_LIB.T6G(SCH_1):PAGE327

P5E_CPU0_P2_RX_BUF_DN<8> @T6G_MB_LIB.T6G(SCH_1):P5E_CPU0_P2_RX_BUF_DN(8)
 U6012  CB2 A_PERN7 PT5161LRS-PT5161LRS,SMLF,IC,AJ051610U03     I1 @T6G_MB_LIB.T6G(SCH_1):PAGE417
  J105   C1     C1 CONN112_10137002101LF-CONN112_10137002-101LF,THLF,A    I75 @T6G_MB_LIB.T6G(SCH_1):PAGE326

P5E_CPU0_P2_RX_BUF_DN<9> @T6G_MB_LIB.T6G(SCH_1):P5E_CPU0_P2_RX_BUF_DN(9)
 U6012  BR2 A_PERN6 PT5161LRS-PT5161LRS,SMLF,IC,AJ051610U03     I1 @T6G_MB_LIB.T6G(SCH_1):PAGE417
  J105   B2     B2 CONN112_10137002101LF-CONN112_10137002-101LF,THLF,A    I75 @T6G_MB_LIB.T6G(SCH_1):PAGE326

P5E_CPU0_P2_RX_BUF_DP<0> @T6G_MB_LIB.T6G(SCH_1):P5E_CPU0_P2_RX_BUF_DP(0)
 U6012  EY1 A_PERP15 PT5161LRS-PT5161LRS,SMLF,IC,AJ051610U03    I38 @T6G_MB_LIB.T6G(SCH_1):PAGE417
  J106   D1     D1 CONN112_10137002101LF-CONN112_10137002-101LF,THLF,A    I74 @T6G_MB_LIB.T6G(SCH_1):PAGE327

P5E_CPU0_P2_RX_BUF_DP<10> @T6G_MB_LIB.T6G(SCH_1):P5E_CPU0_P2_RX_BUF_DP(10)
 U6012  BK1 A_PERP5 PT5161LRS-PT5161LRS,SMLF,IC,AJ051610U03     I1 @T6G_MB_LIB.T6G(SCH_1):PAGE417
  J105   D3     D3 CONN112_10137002101LF-CONN112_10137002-101LF,THLF,A    I75 @T6G_MB_LIB.T6G(SCH_1):PAGE326

P5E_CPU0_P2_RX_BUF_DP<11> @T6G_MB_LIB.T6G(SCH_1):P5E_CPU0_P2_RX_BUF_DP(11)
 U6012  BC1 A_PERP4 PT5161LRS-PT5161LRS,SMLF,IC,AJ051610U03     I1 @T6G_MB_LIB.T6G(SCH_1):PAGE417
  J105   C4     C4 CONN112_10137002101LF-CONN112_10137002-101LF,THLF,A    I75 @T6G_MB_LIB.T6G(SCH_1):PAGE326

P5E_CPU0_P2_RX_BUF_DP<12> @T6G_MB_LIB.T6G(SCH_1):P5E_CPU0_P2_RX_BUF_DP(12)
 U6012  AT1 A_PERP3 PT5161LRS-PT5161LRS,SMLF,IC,AJ051610U03     I1 @T6G_MB_LIB.T6G(SCH_1):PAGE417
  J105   D5     D5 CONN112_10137002101LF-CONN112_10137002-101LF,THLF,A    I76 @T6G_MB_LIB.T6G(SCH_1):PAGE326

P5E_CPU0_P2_RX_BUF_DP<13> @T6G_MB_LIB.T6G(SCH_1):P5E_CPU0_P2_RX_BUF_DP(13)
 U6012  AJ1 A_PERP2 PT5161LRS-PT5161LRS,SMLF,IC,AJ051610U03     I1 @T6G_MB_LIB.T6G(SCH_1):PAGE417
  J105   C6     C6 CONN112_10137002101LF-CONN112_10137002-101LF,THLF,A    I76 @T6G_MB_LIB.T6G(SCH_1):PAGE326

P5E_CPU0_P2_RX_BUF_DP<14> @T6G_MB_LIB.T6G(SCH_1):P5E_CPU0_P2_RX_BUF_DP(14)
 U6012  AB1 A_PERP1 PT5161LRS-PT5161LRS,SMLF,IC,AJ051610U03     I1 @T6G_MB_LIB.T6G(SCH_1):PAGE417
  J105   D7     D7 CONN112_10137002101LF-CONN112_10137002-101LF,THLF,A    I76 @T6G_MB_LIB.T6G(SCH_1):PAGE326

P5E_CPU0_P2_RX_BUF_DP<15> @T6G_MB_LIB.T6G(SCH_1):P5E_CPU0_P2_RX_BUF_DP(15)
 U6012   R1 A_PERP0 PT5161LRS-PT5161LRS,SMLF,IC,AJ051610U03     I1 @T6G_MB_LIB.T6G(SCH_1):PAGE417
  J105   C8     C8 CONN112_10137002101LF-CONN112_10137002-101LF,THLF,A    I76 @T6G_MB_LIB.T6G(SCH_1):PAGE326

P5E_CPU0_P2_RX_BUF_DP<1> @T6G_MB_LIB.T6G(SCH_1):P5E_CPU0_P2_RX_BUF_DP(1)
 U6012  EN1 A_PERP14 PT5161LRS-PT5161LRS,SMLF,IC,AJ051610U03    I38 @T6G_MB_LIB.T6G(SCH_1):PAGE417
  J106   C2     C2 CONN112_10137002101LF-CONN112_10137002-101LF,THLF,A    I74 @T6G_MB_LIB.T6G(SCH_1):PAGE327

P5E_CPU0_P2_RX_BUF_DP<2> @T6G_MB_LIB.T6G(SCH_1):P5E_CPU0_P2_RX_BUF_DP(2)
 U6012  EF1 A_PERP13 PT5161LRS-PT5161LRS,SMLF,IC,AJ051610U03    I38 @T6G_MB_LIB.T6G(SCH_1):PAGE417
  J106   D3     D3 CONN112_10137002101LF-CONN112_10137002-101LF,THLF,A    I74 @T6G_MB_LIB.T6G(SCH_1):PAGE327

P5E_CPU0_P2_RX_BUF_DP<3> @T6G_MB_LIB.T6G(SCH_1):P5E_CPU0_P2_RX_BUF_DP(3)
 U6012  DW1 A_PERP12 PT5161LRS-PT5161LRS,SMLF,IC,AJ051610U03    I38 @T6G_MB_LIB.T6G(SCH_1):PAGE417
  J106   C4     C4 CONN112_10137002101LF-CONN112_10137002-101LF,THLF,A    I74 @T6G_MB_LIB.T6G(SCH_1):PAGE327

P5E_CPU0_P2_RX_BUF_DP<4> @T6G_MB_LIB.T6G(SCH_1):P5E_CPU0_P2_RX_BUF_DP(4)
 U6012  DM1 A_PERP11 PT5161LRS-PT5161LRS,SMLF,IC,AJ051610U03    I38 @T6G_MB_LIB.T6G(SCH_1):PAGE417
  J106   D5     D5 CONN112_10137002101LF-CONN112_10137002-101LF,THLF,A    I19 @T6G_MB_LIB.T6G(SCH_1):PAGE327

P5E_CPU0_P2_RX_BUF_DP<5> @T6G_MB_LIB.T6G(SCH_1):P5E_CPU0_P2_RX_BUF_DP(5)
 U6012  DE1 A_PERP10 PT5161LRS-PT5161LRS,SMLF,IC,AJ051610U03    I38 @T6G_MB_LIB.T6G(SCH_1):PAGE417
  J106   C6     C6 CONN112_10137002101LF-CONN112_10137002-101LF,THLF,A    I19 @T6G_MB_LIB.T6G(SCH_1):PAGE327

P5E_CPU0_P2_RX_BUF_DP<6> @T6G_MB_LIB.T6G(SCH_1):P5E_CPU0_P2_RX_BUF_DP(6)
 U6012  CV1 A_PERP9 PT5161LRS-PT5161LRS,SMLF,IC,AJ051610U03    I38 @T6G_MB_LIB.T6G(SCH_1):PAGE417
  J106   D7     D7 CONN112_10137002101LF-CONN112_10137002-101LF,THLF,A    I19 @T6G_MB_LIB.T6G(SCH_1):PAGE327

P5E_CPU0_P2_RX_BUF_DP<7> @T6G_MB_LIB.T6G(SCH_1):P5E_CPU0_P2_RX_BUF_DP(7)
 U6012  CL1 A_PERP8 PT5161LRS-PT5161LRS,SMLF,IC,AJ051610U03    I38 @T6G_MB_LIB.T6G(SCH_1):PAGE417
  J106   C8     C8 CONN112_10137002101LF-CONN112_10137002-101LF,THLF,A    I19 @T6G_MB_LIB.T6G(SCH_1):PAGE327

P5E_CPU0_P2_RX_BUF_DP<8> @T6G_MB_LIB.T6G(SCH_1):P5E_CPU0_P2_RX_BUF_DP(8)
 U6012  CD1 A_PERP7 PT5161LRS-PT5161LRS,SMLF,IC,AJ051610U03     I1 @T6G_MB_LIB.T6G(SCH_1):PAGE417
  J105   D1     D1 CONN112_10137002101LF-CONN112_10137002-101LF,THLF,A    I75 @T6G_MB_LIB.T6G(SCH_1):PAGE326

P5E_CPU0_P2_RX_BUF_DP<9> @T6G_MB_LIB.T6G(SCH_1):P5E_CPU0_P2_RX_BUF_DP(9)
 U6012  BU1 A_PERP6 PT5161LRS-PT5161LRS,SMLF,IC,AJ051610U03     I1 @T6G_MB_LIB.T6G(SCH_1):PAGE417
  J105   C2     C2 CONN112_10137002101LF-CONN112_10137002-101LF,THLF,A    I75 @T6G_MB_LIB.T6G(SCH_1):PAGE326

P5E_CPU0_P2_RX_DN<0> @T6G_MB_LIB.T6G(SCH_1):P5E_CPU0_P2_RX_DN(0)
   U25 CM36 P2_RXN0 GENOA_SP5-SOCKET6096_13568-001,SMLF,IO,DGA^6000030   I147 @T6G_MB_LIB.T6G(SCH_1):PAGE25
 U6012 EW29 A_PETN15 PT5161LRS-PT5161LRS,SMLF,IC,AJ051610U03    I38 @T6G_MB_LIB.T6G(SCH_1):PAGE416

P5E_CPU0_P2_RX_DN<10> @T6G_MB_LIB.T6G(SCH_1):P5E_CPU0_P2_RX_DN(10)
   U25 CU27 P2_RXN10 GENOA_SP5-SOCKET6096_13568-001,SMLF,IO,DGA^6000030   I147 @T6G_MB_LIB.T6G(SCH_1):PAGE25
 U6012 BJ29 A_PETN5 PT5161LRS-PT5161LRS,SMLF,IC,AJ051610U03     I1 @T6G_MB_LIB.T6G(SCH_1):PAGE416

P5E_CPU0_P2_RX_DN<11> @T6G_MB_LIB.T6G(SCH_1):P5E_CPU0_P2_RX_DN(11)
   U25 CR27 P2_RXN11 GENOA_SP5-SOCKET6096_13568-001,SMLF,IO,DGA^6000030   I147 @T6G_MB_LIB.T6G(SCH_1):PAGE25
 U6012 BB29 A_PETN4 PT5161LRS-PT5161LRS,SMLF,IC,AJ051610U03     I1 @T6G_MB_LIB.T6G(SCH_1):PAGE416

P5E_CPU0_P2_RX_DN<12> @T6G_MB_LIB.T6G(SCH_1):P5E_CPU0_P2_RX_DN(12)
   U25 CN27 P2_RXN12 GENOA_SP5-SOCKET6096_13568-001,SMLF,IO,DGA^6000030   I147 @T6G_MB_LIB.T6G(SCH_1):PAGE25
 U6012 AR29 A_PETN3 PT5161LRS-PT5161LRS,SMLF,IC,AJ051610U03     I1 @T6G_MB_LIB.T6G(SCH_1):PAGE416

P5E_CPU0_P2_RX_DN<13> @T6G_MB_LIB.T6G(SCH_1):P5E_CPU0_P2_RX_DN(13)
   U25 CL24 P2_RXN13 GENOA_SP5-SOCKET6096_13568-001,SMLF,IO,DGA^6000030   I147 @T6G_MB_LIB.T6G(SCH_1):PAGE25
 U6012 AH29 A_PETN2 PT5161LRS-PT5161LRS,SMLF,IC,AJ051610U03     I1 @T6G_MB_LIB.T6G(SCH_1):PAGE416

P5E_CPU0_P2_RX_DN<14> @T6G_MB_LIB.T6G(SCH_1):P5E_CPU0_P2_RX_DN(14)
   U25 CR24 P2_RXN14 GENOA_SP5-SOCKET6096_13568-001,SMLF,IO,DGA^6000030   I147 @T6G_MB_LIB.T6G(SCH_1):PAGE25
 U6012 AA29 A_PETN1 PT5161LRS-PT5161LRS,SMLF,IC,AJ051610U03     I1 @T6G_MB_LIB.T6G(SCH_1):PAGE416

P5E_CPU0_P2_RX_DN<15> @T6G_MB_LIB.T6G(SCH_1):P5E_CPU0_P2_RX_DN(15)
   U25 CN24 P2_RXN15 GENOA_SP5-SOCKET6096_13568-001,SMLF,IO,DGA^6000030   I147 @T6G_MB_LIB.T6G(SCH_1):PAGE25
 U6012  P29 A_PETN0 PT5161LRS-PT5161LRS,SMLF,IC,AJ051610U03     I1 @T6G_MB_LIB.T6G(SCH_1):PAGE416

P5E_CPU0_P2_RX_DN<1> @T6G_MB_LIB.T6G(SCH_1):P5E_CPU0_P2_RX_DN(1)
   U25 CP36 P2_RXN1 GENOA_SP5-SOCKET6096_13568-001,SMLF,IO,DGA^6000030   I147 @T6G_MB_LIB.T6G(SCH_1):PAGE25
 U6012 EM29 A_PETN14 PT5161LRS-PT5161LRS,SMLF,IC,AJ051610U03    I38 @T6G_MB_LIB.T6G(SCH_1):PAGE416

P5E_CPU0_P2_RX_DN<2> @T6G_MB_LIB.T6G(SCH_1):P5E_CPU0_P2_RX_DN(2)
   U25 CT36 P2_RXN2 GENOA_SP5-SOCKET6096_13568-001,SMLF,IO,DGA^6000030   I147 @T6G_MB_LIB.T6G(SCH_1):PAGE25
 U6012 EE29 A_PETN13 PT5161LRS-PT5161LRS,SMLF,IC,AJ051610U03    I38 @T6G_MB_LIB.T6G(SCH_1):PAGE416

P5E_CPU0_P2_RX_DN<3> @T6G_MB_LIB.T6G(SCH_1):P5E_CPU0_P2_RX_DN(3)
   U25 CN33 P2_RXN3 GENOA_SP5-SOCKET6096_13568-001,SMLF,IO,DGA^6000030   I147 @T6G_MB_LIB.T6G(SCH_1):PAGE25
 U6012 DV29 A_PETN12 PT5161LRS-PT5161LRS,SMLF,IC,AJ051610U03    I38 @T6G_MB_LIB.T6G(SCH_1):PAGE416

P5E_CPU0_P2_RX_DN<4> @T6G_MB_LIB.T6G(SCH_1):P5E_CPU0_P2_RX_DN(4)
   U25 CU33 P2_RXN4 GENOA_SP5-SOCKET6096_13568-001,SMLF,IO,DGA^6000030   I147 @T6G_MB_LIB.T6G(SCH_1):PAGE25
 U6012 DL29 A_PETN11 PT5161LRS-PT5161LRS,SMLF,IC,AJ051610U03    I38 @T6G_MB_LIB.T6G(SCH_1):PAGE416

P5E_CPU0_P2_RX_DN<5> @T6G_MB_LIB.T6G(SCH_1):P5E_CPU0_P2_RX_DN(5)
   U25 CR33 P2_RXN5 GENOA_SP5-SOCKET6096_13568-001,SMLF,IO,DGA^6000030   I147 @T6G_MB_LIB.T6G(SCH_1):PAGE25
 U6012 DD29 A_PETN10 PT5161LRS-PT5161LRS,SMLF,IC,AJ051610U03    I38 @T6G_MB_LIB.T6G(SCH_1):PAGE416

P5E_CPU0_P2_RX_DN<6> @T6G_MB_LIB.T6G(SCH_1):P5E_CPU0_P2_RX_DN(6)
   U25 CN30 P2_RXN6 GENOA_SP5-SOCKET6096_13568-001,SMLF,IO,DGA^6000030   I147 @T6G_MB_LIB.T6G(SCH_1):PAGE25
 U6012 CU29 A_PETN9 PT5161LRS-PT5161LRS,SMLF,IC,AJ051610U03    I38 @T6G_MB_LIB.T6G(SCH_1):PAGE416

P5E_CPU0_P2_RX_DN<7> @T6G_MB_LIB.T6G(SCH_1):P5E_CPU0_P2_RX_DN(7)
   U25 CU30 P2_RXN7 GENOA_SP5-SOCKET6096_13568-001,SMLF,IO,DGA^6000030   I147 @T6G_MB_LIB.T6G(SCH_1):PAGE25
 U6012 CK29 A_PETN8 PT5161LRS-PT5161LRS,SMLF,IC,AJ051610U03    I38 @T6G_MB_LIB.T6G(SCH_1):PAGE416

P5E_CPU0_P2_RX_DN<8> @T6G_MB_LIB.T6G(SCH_1):P5E_CPU0_P2_RX_DN(8)
   U25 CR30 P2_RXN8 GENOA_SP5-SOCKET6096_13568-001,SMLF,IO,DGA^6000030   I147 @T6G_MB_LIB.T6G(SCH_1):PAGE25
 U6012 CC29 A_PETN7 PT5161LRS-PT5161LRS,SMLF,IC,AJ051610U03     I1 @T6G_MB_LIB.T6G(SCH_1):PAGE416

P5E_CPU0_P2_RX_DN<9> @T6G_MB_LIB.T6G(SCH_1):P5E_CPU0_P2_RX_DN(9)
   U25 CL27 P2_RXN9 GENOA_SP5-SOCKET6096_13568-001,SMLF,IO,DGA^6000030   I147 @T6G_MB_LIB.T6G(SCH_1):PAGE25
 U6012 BT29 A_PETN6 PT5161LRS-PT5161LRS,SMLF,IC,AJ051610U03     I1 @T6G_MB_LIB.T6G(SCH_1):PAGE416

P5E_CPU0_P2_RX_DP<0> @T6G_MB_LIB.T6G(SCH_1):P5E_CPU0_P2_RX_DP(0)
   U25 CM35 P2_RXP0 GENOA_SP5-SOCKET6096_13568-001,SMLF,IO,DGA^6000030   I147 @T6G_MB_LIB.T6G(SCH_1):PAGE25
 U6012 EU26 A_PETP15 PT5161LRS-PT5161LRS,SMLF,IC,AJ051610U03    I38 @T6G_MB_LIB.T6G(SCH_1):PAGE416

P5E_CPU0_P2_RX_DP<10> @T6G_MB_LIB.T6G(SCH_1):P5E_CPU0_P2_RX_DP(10)
   U25 CU26 P2_RXP10 GENOA_SP5-SOCKET6096_13568-001,SMLF,IO,DGA^6000030   I147 @T6G_MB_LIB.T6G(SCH_1):PAGE25
 U6012 BG26 A_PETP5 PT5161LRS-PT5161LRS,SMLF,IC,AJ051610U03     I1 @T6G_MB_LIB.T6G(SCH_1):PAGE416

P5E_CPU0_P2_RX_DP<11> @T6G_MB_LIB.T6G(SCH_1):P5E_CPU0_P2_RX_DP(11)
   U25 CR26 P2_RXP11 GENOA_SP5-SOCKET6096_13568-001,SMLF,IO,DGA^6000030   I147 @T6G_MB_LIB.T6G(SCH_1):PAGE25
 U6012 AY26 A_PETP4 PT5161LRS-PT5161LRS,SMLF,IC,AJ051610U03     I1 @T6G_MB_LIB.T6G(SCH_1):PAGE416

P5E_CPU0_P2_RX_DP<12> @T6G_MB_LIB.T6G(SCH_1):P5E_CPU0_P2_RX_DP(12)
   U25 CN26 P2_RXP12 GENOA_SP5-SOCKET6096_13568-001,SMLF,IO,DGA^6000030   I147 @T6G_MB_LIB.T6G(SCH_1):PAGE25
 U6012 AN26 A_PETP3 PT5161LRS-PT5161LRS,SMLF,IC,AJ051610U03     I1 @T6G_MB_LIB.T6G(SCH_1):PAGE416

P5E_CPU0_P2_RX_DP<13> @T6G_MB_LIB.T6G(SCH_1):P5E_CPU0_P2_RX_DP(13)
   U25 CL23 P2_RXP13 GENOA_SP5-SOCKET6096_13568-001,SMLF,IO,DGA^6000030   I147 @T6G_MB_LIB.T6G(SCH_1):PAGE25
 U6012 AF26 A_PETP2 PT5161LRS-PT5161LRS,SMLF,IC,AJ051610U03     I1 @T6G_MB_LIB.T6G(SCH_1):PAGE416

P5E_CPU0_P2_RX_DP<14> @T6G_MB_LIB.T6G(SCH_1):P5E_CPU0_P2_RX_DP(14)
   U25 CR23 P2_RXP14 GENOA_SP5-SOCKET6096_13568-001,SMLF,IO,DGA^6000030   I147 @T6G_MB_LIB.T6G(SCH_1):PAGE25
 U6012  W26 A_PETP1 PT5161LRS-PT5161LRS,SMLF,IC,AJ051610U03     I1 @T6G_MB_LIB.T6G(SCH_1):PAGE416

P5E_CPU0_P2_RX_DP<15> @T6G_MB_LIB.T6G(SCH_1):P5E_CPU0_P2_RX_DP(15)
   U25 CN23 P2_RXP15 GENOA_SP5-SOCKET6096_13568-001,SMLF,IO,DGA^6000030   I147 @T6G_MB_LIB.T6G(SCH_1):PAGE25
 U6012  M26 A_PETP0 PT5161LRS-PT5161LRS,SMLF,IC,AJ051610U03     I1 @T6G_MB_LIB.T6G(SCH_1):PAGE416

P5E_CPU0_P2_RX_DP<1> @T6G_MB_LIB.T6G(SCH_1):P5E_CPU0_P2_RX_DP(1)
   U25 CP35 P2_RXP1 GENOA_SP5-SOCKET6096_13568-001,SMLF,IO,DGA^6000030   I147 @T6G_MB_LIB.T6G(SCH_1):PAGE25
 U6012 EK26 A_PETP14 PT5161LRS-PT5161LRS,SMLF,IC,AJ051610U03    I38 @T6G_MB_LIB.T6G(SCH_1):PAGE416

P5E_CPU0_P2_RX_DP<2> @T6G_MB_LIB.T6G(SCH_1):P5E_CPU0_P2_RX_DP(2)
   U25 CT35 P2_RXP2 GENOA_SP5-SOCKET6096_13568-001,SMLF,IO,DGA^6000030   I147 @T6G_MB_LIB.T6G(SCH_1):PAGE25
 U6012 EC26 A_PETP13 PT5161LRS-PT5161LRS,SMLF,IC,AJ051610U03    I38 @T6G_MB_LIB.T6G(SCH_1):PAGE416

P5E_CPU0_P2_RX_DP<3> @T6G_MB_LIB.T6G(SCH_1):P5E_CPU0_P2_RX_DP(3)
   U25 CN32 P2_RXP3 GENOA_SP5-SOCKET6096_13568-001,SMLF,IO,DGA^6000030   I147 @T6G_MB_LIB.T6G(SCH_1):PAGE25
 U6012 DT26 A_PETP12 PT5161LRS-PT5161LRS,SMLF,IC,AJ051610U03    I38 @T6G_MB_LIB.T6G(SCH_1):PAGE416

P5E_CPU0_P2_RX_DP<4> @T6G_MB_LIB.T6G(SCH_1):P5E_CPU0_P2_RX_DP(4)
   U25 CU32 P2_RXP4 GENOA_SP5-SOCKET6096_13568-001,SMLF,IO,DGA^6000030   I147 @T6G_MB_LIB.T6G(SCH_1):PAGE25
 U6012 DJ26 A_PETP11 PT5161LRS-PT5161LRS,SMLF,IC,AJ051610U03    I38 @T6G_MB_LIB.T6G(SCH_1):PAGE416

P5E_CPU0_P2_RX_DP<5> @T6G_MB_LIB.T6G(SCH_1):P5E_CPU0_P2_RX_DP(5)
   U25 CR32 P2_RXP5 GENOA_SP5-SOCKET6096_13568-001,SMLF,IO,DGA^6000030   I147 @T6G_MB_LIB.T6G(SCH_1):PAGE25
 U6012 DB26 A_PETP10 PT5161LRS-PT5161LRS,SMLF,IC,AJ051610U03    I38 @T6G_MB_LIB.T6G(SCH_1):PAGE416

P5E_CPU0_P2_RX_DP<6> @T6G_MB_LIB.T6G(SCH_1):P5E_CPU0_P2_RX_DP(6)
   U25 CN29 P2_RXP6 GENOA_SP5-SOCKET6096_13568-001,SMLF,IO,DGA^6000030   I147 @T6G_MB_LIB.T6G(SCH_1):PAGE25
 U6012 CR26 A_PETP9 PT5161LRS-PT5161LRS,SMLF,IC,AJ051610U03    I38 @T6G_MB_LIB.T6G(SCH_1):PAGE416

P5E_CPU0_P2_RX_DP<7> @T6G_MB_LIB.T6G(SCH_1):P5E_CPU0_P2_RX_DP(7)
   U25 CU29 P2_RXP7 GENOA_SP5-SOCKET6096_13568-001,SMLF,IO,DGA^6000030   I147 @T6G_MB_LIB.T6G(SCH_1):PAGE25
 U6012 CH26 A_PETP8 PT5161LRS-PT5161LRS,SMLF,IC,AJ051610U03    I38 @T6G_MB_LIB.T6G(SCH_1):PAGE416

P5E_CPU0_P2_RX_DP<8> @T6G_MB_LIB.T6G(SCH_1):P5E_CPU0_P2_RX_DP(8)
   U25 CR29 P2_RXP8 GENOA_SP5-SOCKET6096_13568-001,SMLF,IO,DGA^6000030   I147 @T6G_MB_LIB.T6G(SCH_1):PAGE25
 U6012 CA26 A_PETP7 PT5161LRS-PT5161LRS,SMLF,IC,AJ051610U03     I1 @T6G_MB_LIB.T6G(SCH_1):PAGE416

P5E_CPU0_P2_RX_DP<9> @T6G_MB_LIB.T6G(SCH_1):P5E_CPU0_P2_RX_DP(9)
   U25 CL26 P2_RXP9 GENOA_SP5-SOCKET6096_13568-001,SMLF,IO,DGA^6000030   I147 @T6G_MB_LIB.T6G(SCH_1):PAGE25
 U6012 BP26 A_PETP6 PT5161LRS-PT5161LRS,SMLF,IC,AJ051610U03     I1 @T6G_MB_LIB.T6G(SCH_1):PAGE416

P5E_CPU0_P2_TX_BUF_C_DN<0> @T6G_MB_LIB.T6G(SCH_1):P5E_CPU0_P2_TX_BUF_C_DN(0)
 C6566    1      1 Q_CAP_DIFFBUS_C0201-DIFF BUS_0.22UF,6.3V,20%,X6S,SA    I48 @T6G_MB_LIB.T6G(SCH_1):PAGE418
  J106   I1     I1 CONN112_10137002101LF-CONN112_10137002-101LF,THLF,A    I74 @T6G_MB_LIB.T6G(SCH_1):PAGE327

P5E_CPU0_P2_TX_BUF_C_DN<10> @T6G_MB_LIB.T6G(SCH_1):P5E_CPU0_P2_TX_BUF_C_DN(10)
 C6586    1      1 Q_CAP_DIFFBUS_C0201-DIFF BUS_0.22UF,6.3V,20%,X6S,SA    I98 @T6G_MB_LIB.T6G(SCH_1):PAGE418
  J105   I3     I3 CONN112_10137002101LF-CONN112_10137002-101LF,THLF,A    I75 @T6G_MB_LIB.T6G(SCH_1):PAGE326

P5E_CPU0_P2_TX_BUF_C_DN<11> @T6G_MB_LIB.T6G(SCH_1):P5E_CPU0_P2_TX_BUF_C_DN(11)
 C6588    1      1 Q_CAP_DIFFBUS_C0201-DIFF BUS_0.22UF,6.3V,20%,X6S,SA    I96 @T6G_MB_LIB.T6G(SCH_1):PAGE418
  J105   H4     H4 CONN112_10137002101LF-CONN112_10137002-101LF,THLF,A    I75 @T6G_MB_LIB.T6G(SCH_1):PAGE326

P5E_CPU0_P2_TX_BUF_C_DN<12> @T6G_MB_LIB.T6G(SCH_1):P5E_CPU0_P2_TX_BUF_C_DN(12)
 C6590    1      1 Q_CAP_DIFFBUS_C0201-DIFF BUS_0.22UF,6.3V,20%,X6S,SA    I94 @T6G_MB_LIB.T6G(SCH_1):PAGE418
  J105   I5     I5 CONN112_10137002101LF-CONN112_10137002-101LF,THLF,A    I76 @T6G_MB_LIB.T6G(SCH_1):PAGE326

P5E_CPU0_P2_TX_BUF_C_DN<13> @T6G_MB_LIB.T6G(SCH_1):P5E_CPU0_P2_TX_BUF_C_DN(13)
 C6592    1      1 Q_CAP_DIFFBUS_C0201-DIFF BUS_0.22UF,6.3V,20%,X6S,SA    I92 @T6G_MB_LIB.T6G(SCH_1):PAGE418
  J105   H6     H6 CONN112_10137002101LF-CONN112_10137002-101LF,THLF,A    I76 @T6G_MB_LIB.T6G(SCH_1):PAGE326

P5E_CPU0_P2_TX_BUF_C_DN<14> @T6G_MB_LIB.T6G(SCH_1):P5E_CPU0_P2_TX_BUF_C_DN(14)
 C6594    1      1 Q_CAP_DIFFBUS_C0201-DIFF BUS_0.22UF,6.3V,20%,X6S,SA    I90 @T6G_MB_LIB.T6G(SCH_1):PAGE418
  J105   I7     I7 CONN112_10137002101LF-CONN112_10137002-101LF,THLF,A    I76 @T6G_MB_LIB.T6G(SCH_1):PAGE326

P5E_CPU0_P2_TX_BUF_C_DN<15> @T6G_MB_LIB.T6G(SCH_1):P5E_CPU0_P2_TX_BUF_C_DN(15)
 C6596    1      1 Q_CAP_DIFFBUS_C0201-DIFF BUS_0.22UF,6.3V,20%,X6S,SA    I88 @T6G_MB_LIB.T6G(SCH_1):PAGE418
  J105   H8     H8 CONN112_10137002101LF-CONN112_10137002-101LF,THLF,A    I76 @T6G_MB_LIB.T6G(SCH_1):PAGE326

P5E_CPU0_P2_TX_BUF_C_DN<1> @T6G_MB_LIB.T6G(SCH_1):P5E_CPU0_P2_TX_BUF_C_DN(1)
 C6568    1      1 Q_CAP_DIFFBUS_C0201-DIFF BUS_0.22UF,6.3V,20%,X6S,SA    I33 @T6G_MB_LIB.T6G(SCH_1):PAGE418
  J106   H2     H2 CONN112_10137002101LF-CONN112_10137002-101LF,THLF,A    I74 @T6G_MB_LIB.T6G(SCH_1):PAGE327

P5E_CPU0_P2_TX_BUF_C_DN<2> @T6G_MB_LIB.T6G(SCH_1):P5E_CPU0_P2_TX_BUF_C_DN(2)
 C6570    1      1 Q_CAP_DIFFBUS_C0201-DIFF BUS_0.22UF,6.3V,20%,X6S,SA    I31 @T6G_MB_LIB.T6G(SCH_1):PAGE418
  J106   I3     I3 CONN112_10137002101LF-CONN112_10137002-101LF,THLF,A    I74 @T6G_MB_LIB.T6G(SCH_1):PAGE327

P5E_CPU0_P2_TX_BUF_C_DN<3> @T6G_MB_LIB.T6G(SCH_1):P5E_CPU0_P2_TX_BUF_C_DN(3)
 C6572    1      1 Q_CAP_DIFFBUS_C0201-DIFF BUS_0.22UF,6.3V,20%,X6S,SA    I29 @T6G_MB_LIB.T6G(SCH_1):PAGE418
  J106   H4     H4 CONN112_10137002101LF-CONN112_10137002-101LF,THLF,A    I74 @T6G_MB_LIB.T6G(SCH_1):PAGE327

P5E_CPU0_P2_TX_BUF_C_DN<4> @T6G_MB_LIB.T6G(SCH_1):P5E_CPU0_P2_TX_BUF_C_DN(4)
 C6574    1      1 Q_CAP_DIFFBUS_C0201-DIFF BUS_0.22UF,6.3V,20%,X6S,SA    I28 @T6G_MB_LIB.T6G(SCH_1):PAGE418
  J106   I5     I5 CONN112_10137002101LF-CONN112_10137002-101LF,THLF,A    I19 @T6G_MB_LIB.T6G(SCH_1):PAGE327

P5E_CPU0_P2_TX_BUF_C_DN<5> @T6G_MB_LIB.T6G(SCH_1):P5E_CPU0_P2_TX_BUF_C_DN(5)
 C6576    1      1 Q_CAP_DIFFBUS_C0201-DIFF BUS_0.22UF,6.3V,20%,X6S,SA    I26 @T6G_MB_LIB.T6G(SCH_1):PAGE418
  J106   H6     H6 CONN112_10137002101LF-CONN112_10137002-101LF,THLF,A    I19 @T6G_MB_LIB.T6G(SCH_1):PAGE327

P5E_CPU0_P2_TX_BUF_C_DN<6> @T6G_MB_LIB.T6G(SCH_1):P5E_CPU0_P2_TX_BUF_C_DN(6)
 C6578    1      1 Q_CAP_DIFFBUS_C0201-DIFF BUS_0.22UF,6.3V,20%,X6S,SA    I20 @T6G_MB_LIB.T6G(SCH_1):PAGE418
  J106   I7     I7 CONN112_10137002101LF-CONN112_10137002-101LF,THLF,A    I19 @T6G_MB_LIB.T6G(SCH_1):PAGE327

P5E_CPU0_P2_TX_BUF_C_DN<7> @T6G_MB_LIB.T6G(SCH_1):P5E_CPU0_P2_TX_BUF_C_DN(7)
 C6580    1      1 Q_CAP_DIFFBUS_C0201-DIFF BUS_0.22UF,6.3V,20%,X6S,SA    I17 @T6G_MB_LIB.T6G(SCH_1):PAGE418
  J106   H8     H8 CONN112_10137002101LF-CONN112_10137002-101LF,THLF,A    I19 @T6G_MB_LIB.T6G(SCH_1):PAGE327

P5E_CPU0_P2_TX_BUF_C_DN<8> @T6G_MB_LIB.T6G(SCH_1):P5E_CPU0_P2_TX_BUF_C_DN(8)
 C6582    1      1 Q_CAP_DIFFBUS_C0201-DIFF BUS_0.22UF,6.3V,20%,X6S,SA   I105 @T6G_MB_LIB.T6G(SCH_1):PAGE418
  J105   I1     I1 CONN112_10137002101LF-CONN112_10137002-101LF,THLF,A    I75 @T6G_MB_LIB.T6G(SCH_1):PAGE326

P5E_CPU0_P2_TX_BUF_C_DN<9> @T6G_MB_LIB.T6G(SCH_1):P5E_CPU0_P2_TX_BUF_C_DN(9)
 C6584    1      1 Q_CAP_DIFFBUS_C0201-DIFF BUS_0.22UF,6.3V,20%,X6S,SA   I100 @T6G_MB_LIB.T6G(SCH_1):PAGE418
  J105   H2     H2 CONN112_10137002101LF-CONN112_10137002-101LF,THLF,A    I75 @T6G_MB_LIB.T6G(SCH_1):PAGE326

P5E_CPU0_P2_TX_BUF_C_DP<0> @T6G_MB_LIB.T6G(SCH_1):P5E_CPU0_P2_TX_BUF_C_DP(0)
 C6565    1      1 Q_CAP_DIFFBUS_C0201-DIFF BUS_0.22UF,6.3V,20%,X6S,SA    I49 @T6G_MB_LIB.T6G(SCH_1):PAGE418
  J106   J1     J1 CONN112_10137002101LF-CONN112_10137002-101LF,THLF,A    I74 @T6G_MB_LIB.T6G(SCH_1):PAGE327

P5E_CPU0_P2_TX_BUF_C_DP<10> @T6G_MB_LIB.T6G(SCH_1):P5E_CPU0_P2_TX_BUF_C_DP(10)
 C6585    1      1 Q_CAP_DIFFBUS_C0201-DIFF BUS_0.22UF,6.3V,20%,X6S,SA    I99 @T6G_MB_LIB.T6G(SCH_1):PAGE418
  J105   J3     J3 CONN112_10137002101LF-CONN112_10137002-101LF,THLF,A    I75 @T6G_MB_LIB.T6G(SCH_1):PAGE326

P5E_CPU0_P2_TX_BUF_C_DP<11> @T6G_MB_LIB.T6G(SCH_1):P5E_CPU0_P2_TX_BUF_C_DP(11)
 C6587    1      1 Q_CAP_DIFFBUS_C0201-DIFF BUS_0.22UF,6.3V,20%,X6S,SA    I97 @T6G_MB_LIB.T6G(SCH_1):PAGE418
  J105   I4     I4 CONN112_10137002101LF-CONN112_10137002-101LF,THLF,A    I75 @T6G_MB_LIB.T6G(SCH_1):PAGE326

P5E_CPU0_P2_TX_BUF_C_DP<12> @T6G_MB_LIB.T6G(SCH_1):P5E_CPU0_P2_TX_BUF_C_DP(12)
 C6589    1      1 Q_CAP_DIFFBUS_C0201-DIFF BUS_0.22UF,6.3V,20%,X6S,SA    I95 @T6G_MB_LIB.T6G(SCH_1):PAGE418
  J105   J5     J5 CONN112_10137002101LF-CONN112_10137002-101LF,THLF,A    I76 @T6G_MB_LIB.T6G(SCH_1):PAGE326

P5E_CPU0_P2_TX_BUF_C_DP<13> @T6G_MB_LIB.T6G(SCH_1):P5E_CPU0_P2_TX_BUF_C_DP(13)
 C6591    1      1 Q_CAP_DIFFBUS_C0201-DIFF BUS_0.22UF,6.3V,20%,X6S,SA    I93 @T6G_MB_LIB.T6G(SCH_1):PAGE418
  J105   I6     I6 CONN112_10137002101LF-CONN112_10137002-101LF,THLF,A    I76 @T6G_MB_LIB.T6G(SCH_1):PAGE326

P5E_CPU0_P2_TX_BUF_C_DP<14> @T6G_MB_LIB.T6G(SCH_1):P5E_CPU0_P2_TX_BUF_C_DP(14)
 C6593    1      1 Q_CAP_DIFFBUS_C0201-DIFF BUS_0.22UF,6.3V,20%,X6S,SA    I91 @T6G_MB_LIB.T6G(SCH_1):PAGE418
  J105   J7     J7 CONN112_10137002101LF-CONN112_10137002-101LF,THLF,A    I76 @T6G_MB_LIB.T6G(SCH_1):PAGE326

P5E_CPU0_P2_TX_BUF_C_DP<15> @T6G_MB_LIB.T6G(SCH_1):P5E_CPU0_P2_TX_BUF_C_DP(15)
 C6595    1      1 Q_CAP_DIFFBUS_C0201-DIFF BUS_0.22UF,6.3V,20%,X6S,SA    I89 @T6G_MB_LIB.T6G(SCH_1):PAGE418
  J105   I8     I8 CONN112_10137002101LF-CONN112_10137002-101LF,THLF,A    I76 @T6G_MB_LIB.T6G(SCH_1):PAGE326

P5E_CPU0_P2_TX_BUF_C_DP<1> @T6G_MB_LIB.T6G(SCH_1):P5E_CPU0_P2_TX_BUF_C_DP(1)
 C6567    1      1 Q_CAP_DIFFBUS_C0201-DIFF BUS_0.22UF,6.3V,20%,X6S,SA    I32 @T6G_MB_LIB.T6G(SCH_1):PAGE418
  J106   I2     I2 CONN112_10137002101LF-CONN112_10137002-101LF,THLF,A    I74 @T6G_MB_LIB.T6G(SCH_1):PAGE327

P5E_CPU0_P2_TX_BUF_C_DP<2> @T6G_MB_LIB.T6G(SCH_1):P5E_CPU0_P2_TX_BUF_C_DP(2)
 C6569    1      1 Q_CAP_DIFFBUS_C0201-DIFF BUS_0.22UF,6.3V,20%,X6S,SA    I34 @T6G_MB_LIB.T6G(SCH_1):PAGE418
  J106   J3     J3 CONN112_10137002101LF-CONN112_10137002-101LF,THLF,A    I74 @T6G_MB_LIB.T6G(SCH_1):PAGE327

P5E_CPU0_P2_TX_BUF_C_DP<3> @T6G_MB_LIB.T6G(SCH_1):P5E_CPU0_P2_TX_BUF_C_DP(3)
 C6571    1      1 Q_CAP_DIFFBUS_C0201-DIFF BUS_0.22UF,6.3V,20%,X6S,SA    I30 @T6G_MB_LIB.T6G(SCH_1):PAGE418
  J106   I4     I4 CONN112_10137002101LF-CONN112_10137002-101LF,THLF,A    I74 @T6G_MB_LIB.T6G(SCH_1):PAGE327

P5E_CPU0_P2_TX_BUF_C_DP<4> @T6G_MB_LIB.T6G(SCH_1):P5E_CPU0_P2_TX_BUF_C_DP(4)
 C6573    1      1 Q_CAP_DIFFBUS_C0201-DIFF BUS_0.22UF,6.3V,20%,X6S,SA    I27 @T6G_MB_LIB.T6G(SCH_1):PAGE418
  J106   J5     J5 CONN112_10137002101LF-CONN112_10137002-101LF,THLF,A    I19 @T6G_MB_LIB.T6G(SCH_1):PAGE327

P5E_CPU0_P2_TX_BUF_C_DP<5> @T6G_MB_LIB.T6G(SCH_1):P5E_CPU0_P2_TX_BUF_C_DP(5)
 C6575    1      1 Q_CAP_DIFFBUS_C0201-DIFF BUS_0.22UF,6.3V,20%,X6S,SA    I25 @T6G_MB_LIB.T6G(SCH_1):PAGE418
  J106   I6     I6 CONN112_10137002101LF-CONN112_10137002-101LF,THLF,A    I19 @T6G_MB_LIB.T6G(SCH_1):PAGE327

P5E_CPU0_P2_TX_BUF_C_DP<6> @T6G_MB_LIB.T6G(SCH_1):P5E_CPU0_P2_TX_BUF_C_DP(6)
 C6577    1      1 Q_CAP_DIFFBUS_C0201-DIFF BUS_0.22UF,6.3V,20%,X6S,SA    I19 @T6G_MB_LIB.T6G(SCH_1):PAGE418
  J106   J7     J7 CONN112_10137002101LF-CONN112_10137002-101LF,THLF,A    I19 @T6G_MB_LIB.T6G(SCH_1):PAGE327

P5E_CPU0_P2_TX_BUF_C_DP<7> @T6G_MB_LIB.T6G(SCH_1):P5E_CPU0_P2_TX_BUF_C_DP(7)
 C6579    1      1 Q_CAP_DIFFBUS_C0201-DIFF BUS_0.22UF,6.3V,20%,X6S,SA    I18 @T6G_MB_LIB.T6G(SCH_1):PAGE418
  J106   I8     I8 CONN112_10137002101LF-CONN112_10137002-101LF,THLF,A    I19 @T6G_MB_LIB.T6G(SCH_1):PAGE327

P5E_CPU0_P2_TX_BUF_C_DP<8> @T6G_MB_LIB.T6G(SCH_1):P5E_CPU0_P2_TX_BUF_C_DP(8)
 C6581    1      1 Q_CAP_DIFFBUS_C0201-DIFF BUS_0.22UF,6.3V,20%,X6S,SA   I104 @T6G_MB_LIB.T6G(SCH_1):PAGE418
  J105   J1     J1 CONN112_10137002101LF-CONN112_10137002-101LF,THLF,A    I75 @T6G_MB_LIB.T6G(SCH_1):PAGE326

P5E_CPU0_P2_TX_BUF_C_DP<9> @T6G_MB_LIB.T6G(SCH_1):P5E_CPU0_P2_TX_BUF_C_DP(9)
 C6583    1      1 Q_CAP_DIFFBUS_C0201-DIFF BUS_0.22UF,6.3V,20%,X6S,SA   I101 @T6G_MB_LIB.T6G(SCH_1):PAGE418
  J105   I2     I2 CONN112_10137002101LF-CONN112_10137002-101LF,THLF,A    I75 @T6G_MB_LIB.T6G(SCH_1):PAGE326

P5E_CPU0_P2_TX_BUF_DN<0> @T6G_MB_LIB.T6G(SCH_1):P5E_CPU0_P2_TX_BUF_DN(0)
 C6566    2      2 Q_CAP_DIFFBUS_C0201-DIFF BUS_0.22UF,6.3V,20%,X6S,SA    I48 @T6G_MB_LIB.T6G(SCH_1):PAGE418
 U6012 EW10 B_PETN15 PT5161LRS-PT5161LRS,SMLF,IC,AJ051610U03   I142 @T6G_MB_LIB.T6G(SCH_1):PAGE418

P5E_CPU0_P2_TX_BUF_DN<10> @T6G_MB_LIB.T6G(SCH_1):P5E_CPU0_P2_TX_BUF_DN(10)
 U6012 BJ10 B_PETN5 PT5161LRS-PT5161LRS,SMLF,IC,AJ051610U03    I47 @T6G_MB_LIB.T6G(SCH_1):PAGE418
 C6586    2      2 Q_CAP_DIFFBUS_C0201-DIFF BUS_0.22UF,6.3V,20%,X6S,SA    I98 @T6G_MB_LIB.T6G(SCH_1):PAGE418

P5E_CPU0_P2_TX_BUF_DN<11> @T6G_MB_LIB.T6G(SCH_1):P5E_CPU0_P2_TX_BUF_DN(11)
 U6012 BB10 B_PETN4 PT5161LRS-PT5161LRS,SMLF,IC,AJ051610U03    I47 @T6G_MB_LIB.T6G(SCH_1):PAGE418
 C6588    2      2 Q_CAP_DIFFBUS_C0201-DIFF BUS_0.22UF,6.3V,20%,X6S,SA    I96 @T6G_MB_LIB.T6G(SCH_1):PAGE418

P5E_CPU0_P2_TX_BUF_DN<12> @T6G_MB_LIB.T6G(SCH_1):P5E_CPU0_P2_TX_BUF_DN(12)
 U6012 AR10 B_PETN3 PT5161LRS-PT5161LRS,SMLF,IC,AJ051610U03    I47 @T6G_MB_LIB.T6G(SCH_1):PAGE418
 C6590    2      2 Q_CAP_DIFFBUS_C0201-DIFF BUS_0.22UF,6.3V,20%,X6S,SA    I94 @T6G_MB_LIB.T6G(SCH_1):PAGE418

P5E_CPU0_P2_TX_BUF_DN<13> @T6G_MB_LIB.T6G(SCH_1):P5E_CPU0_P2_TX_BUF_DN(13)
 U6012 AH10 B_PETN2 PT5161LRS-PT5161LRS,SMLF,IC,AJ051610U03    I47 @T6G_MB_LIB.T6G(SCH_1):PAGE418
 C6592    2      2 Q_CAP_DIFFBUS_C0201-DIFF BUS_0.22UF,6.3V,20%,X6S,SA    I92 @T6G_MB_LIB.T6G(SCH_1):PAGE418

P5E_CPU0_P2_TX_BUF_DN<14> @T6G_MB_LIB.T6G(SCH_1):P5E_CPU0_P2_TX_BUF_DN(14)
 U6012 AA10 B_PETN1 PT5161LRS-PT5161LRS,SMLF,IC,AJ051610U03    I47 @T6G_MB_LIB.T6G(SCH_1):PAGE418
 C6594    2      2 Q_CAP_DIFFBUS_C0201-DIFF BUS_0.22UF,6.3V,20%,X6S,SA    I90 @T6G_MB_LIB.T6G(SCH_1):PAGE418

P5E_CPU0_P2_TX_BUF_DN<15> @T6G_MB_LIB.T6G(SCH_1):P5E_CPU0_P2_TX_BUF_DN(15)
 U6012  P10 B_PETN0 PT5161LRS-PT5161LRS,SMLF,IC,AJ051610U03    I47 @T6G_MB_LIB.T6G(SCH_1):PAGE418
 C6596    2      2 Q_CAP_DIFFBUS_C0201-DIFF BUS_0.22UF,6.3V,20%,X6S,SA    I88 @T6G_MB_LIB.T6G(SCH_1):PAGE418

P5E_CPU0_P2_TX_BUF_DN<1> @T6G_MB_LIB.T6G(SCH_1):P5E_CPU0_P2_TX_BUF_DN(1)
 C6568    2      2 Q_CAP_DIFFBUS_C0201-DIFF BUS_0.22UF,6.3V,20%,X6S,SA    I33 @T6G_MB_LIB.T6G(SCH_1):PAGE418
 U6012 EM10 B_PETN14 PT5161LRS-PT5161LRS,SMLF,IC,AJ051610U03   I142 @T6G_MB_LIB.T6G(SCH_1):PAGE418

P5E_CPU0_P2_TX_BUF_DN<2> @T6G_MB_LIB.T6G(SCH_1):P5E_CPU0_P2_TX_BUF_DN(2)
 C6570    2      2 Q_CAP_DIFFBUS_C0201-DIFF BUS_0.22UF,6.3V,20%,X6S,SA    I31 @T6G_MB_LIB.T6G(SCH_1):PAGE418
 U6012 EE10 B_PETN13 PT5161LRS-PT5161LRS,SMLF,IC,AJ051610U03   I142 @T6G_MB_LIB.T6G(SCH_1):PAGE418

P5E_CPU0_P2_TX_BUF_DN<3> @T6G_MB_LIB.T6G(SCH_1):P5E_CPU0_P2_TX_BUF_DN(3)
 C6572    2      2 Q_CAP_DIFFBUS_C0201-DIFF BUS_0.22UF,6.3V,20%,X6S,SA    I29 @T6G_MB_LIB.T6G(SCH_1):PAGE418
 U6012 DV10 B_PETN12 PT5161LRS-PT5161LRS,SMLF,IC,AJ051610U03   I142 @T6G_MB_LIB.T6G(SCH_1):PAGE418

P5E_CPU0_P2_TX_BUF_DN<4> @T6G_MB_LIB.T6G(SCH_1):P5E_CPU0_P2_TX_BUF_DN(4)
 C6574    2      2 Q_CAP_DIFFBUS_C0201-DIFF BUS_0.22UF,6.3V,20%,X6S,SA    I28 @T6G_MB_LIB.T6G(SCH_1):PAGE418
 U6012 DL10 B_PETN11 PT5161LRS-PT5161LRS,SMLF,IC,AJ051610U03   I142 @T6G_MB_LIB.T6G(SCH_1):PAGE418

P5E_CPU0_P2_TX_BUF_DN<5> @T6G_MB_LIB.T6G(SCH_1):P5E_CPU0_P2_TX_BUF_DN(5)
 C6576    2      2 Q_CAP_DIFFBUS_C0201-DIFF BUS_0.22UF,6.3V,20%,X6S,SA    I26 @T6G_MB_LIB.T6G(SCH_1):PAGE418
 U6012 DD10 B_PETN10 PT5161LRS-PT5161LRS,SMLF,IC,AJ051610U03   I142 @T6G_MB_LIB.T6G(SCH_1):PAGE418

P5E_CPU0_P2_TX_BUF_DN<6> @T6G_MB_LIB.T6G(SCH_1):P5E_CPU0_P2_TX_BUF_DN(6)
 C6578    2      2 Q_CAP_DIFFBUS_C0201-DIFF BUS_0.22UF,6.3V,20%,X6S,SA    I20 @T6G_MB_LIB.T6G(SCH_1):PAGE418
 U6012 CU10 B_PETN9 PT5161LRS-PT5161LRS,SMLF,IC,AJ051610U03   I142 @T6G_MB_LIB.T6G(SCH_1):PAGE418

P5E_CPU0_P2_TX_BUF_DN<7> @T6G_MB_LIB.T6G(SCH_1):P5E_CPU0_P2_TX_BUF_DN(7)
 C6580    2      2 Q_CAP_DIFFBUS_C0201-DIFF BUS_0.22UF,6.3V,20%,X6S,SA    I17 @T6G_MB_LIB.T6G(SCH_1):PAGE418
 U6012 CK10 B_PETN8 PT5161LRS-PT5161LRS,SMLF,IC,AJ051610U03   I142 @T6G_MB_LIB.T6G(SCH_1):PAGE418

P5E_CPU0_P2_TX_BUF_DN<8> @T6G_MB_LIB.T6G(SCH_1):P5E_CPU0_P2_TX_BUF_DN(8)
 U6012 CC10 B_PETN7 PT5161LRS-PT5161LRS,SMLF,IC,AJ051610U03    I47 @T6G_MB_LIB.T6G(SCH_1):PAGE418
 C6582    2      2 Q_CAP_DIFFBUS_C0201-DIFF BUS_0.22UF,6.3V,20%,X6S,SA   I105 @T6G_MB_LIB.T6G(SCH_1):PAGE418

P5E_CPU0_P2_TX_BUF_DN<9> @T6G_MB_LIB.T6G(SCH_1):P5E_CPU0_P2_TX_BUF_DN(9)
 U6012 BT10 B_PETN6 PT5161LRS-PT5161LRS,SMLF,IC,AJ051610U03    I47 @T6G_MB_LIB.T6G(SCH_1):PAGE418
 C6584    2      2 Q_CAP_DIFFBUS_C0201-DIFF BUS_0.22UF,6.3V,20%,X6S,SA   I100 @T6G_MB_LIB.T6G(SCH_1):PAGE418

P5E_CPU0_P2_TX_BUF_DP<0> @T6G_MB_LIB.T6G(SCH_1):P5E_CPU0_P2_TX_BUF_DP(0)
 C6565    2      2 Q_CAP_DIFFBUS_C0201-DIFF BUS_0.22UF,6.3V,20%,X6S,SA    I49 @T6G_MB_LIB.T6G(SCH_1):PAGE418
 U6012  EU7 B_PETP15 PT5161LRS-PT5161LRS,SMLF,IC,AJ051610U03   I142 @T6G_MB_LIB.T6G(SCH_1):PAGE418

P5E_CPU0_P2_TX_BUF_DP<10> @T6G_MB_LIB.T6G(SCH_1):P5E_CPU0_P2_TX_BUF_DP(10)
 U6012  BG7 B_PETP5 PT5161LRS-PT5161LRS,SMLF,IC,AJ051610U03    I47 @T6G_MB_LIB.T6G(SCH_1):PAGE418
 C6585    2      2 Q_CAP_DIFFBUS_C0201-DIFF BUS_0.22UF,6.3V,20%,X6S,SA    I99 @T6G_MB_LIB.T6G(SCH_1):PAGE418

P5E_CPU0_P2_TX_BUF_DP<11> @T6G_MB_LIB.T6G(SCH_1):P5E_CPU0_P2_TX_BUF_DP(11)
 U6012  AY7 B_PETP4 PT5161LRS-PT5161LRS,SMLF,IC,AJ051610U03    I47 @T6G_MB_LIB.T6G(SCH_1):PAGE418
 C6587    2      2 Q_CAP_DIFFBUS_C0201-DIFF BUS_0.22UF,6.3V,20%,X6S,SA    I97 @T6G_MB_LIB.T6G(SCH_1):PAGE418

P5E_CPU0_P2_TX_BUF_DP<12> @T6G_MB_LIB.T6G(SCH_1):P5E_CPU0_P2_TX_BUF_DP(12)
 U6012  AN7 B_PETP3 PT5161LRS-PT5161LRS,SMLF,IC,AJ051610U03    I47 @T6G_MB_LIB.T6G(SCH_1):PAGE418
 C6589    2      2 Q_CAP_DIFFBUS_C0201-DIFF BUS_0.22UF,6.3V,20%,X6S,SA    I95 @T6G_MB_LIB.T6G(SCH_1):PAGE418

P5E_CPU0_P2_TX_BUF_DP<13> @T6G_MB_LIB.T6G(SCH_1):P5E_CPU0_P2_TX_BUF_DP(13)
 U6012  AF7 B_PETP2 PT5161LRS-PT5161LRS,SMLF,IC,AJ051610U03    I47 @T6G_MB_LIB.T6G(SCH_1):PAGE418
 C6591    2      2 Q_CAP_DIFFBUS_C0201-DIFF BUS_0.22UF,6.3V,20%,X6S,SA    I93 @T6G_MB_LIB.T6G(SCH_1):PAGE418

P5E_CPU0_P2_TX_BUF_DP<14> @T6G_MB_LIB.T6G(SCH_1):P5E_CPU0_P2_TX_BUF_DP(14)
 U6012   W7 B_PETP1 PT5161LRS-PT5161LRS,SMLF,IC,AJ051610U03    I47 @T6G_MB_LIB.T6G(SCH_1):PAGE418
 C6593    2      2 Q_CAP_DIFFBUS_C0201-DIFF BUS_0.22UF,6.3V,20%,X6S,SA    I91 @T6G_MB_LIB.T6G(SCH_1):PAGE418

P5E_CPU0_P2_TX_BUF_DP<15> @T6G_MB_LIB.T6G(SCH_1):P5E_CPU0_P2_TX_BUF_DP(15)
 U6012   M7 B_PETP0 PT5161LRS-PT5161LRS,SMLF,IC,AJ051610U03    I47 @T6G_MB_LIB.T6G(SCH_1):PAGE418
 C6595    2      2 Q_CAP_DIFFBUS_C0201-DIFF BUS_0.22UF,6.3V,20%,X6S,SA    I89 @T6G_MB_LIB.T6G(SCH_1):PAGE418

P5E_CPU0_P2_TX_BUF_DP<1> @T6G_MB_LIB.T6G(SCH_1):P5E_CPU0_P2_TX_BUF_DP(1)
 C6567    2      2 Q_CAP_DIFFBUS_C0201-DIFF BUS_0.22UF,6.3V,20%,X6S,SA    I32 @T6G_MB_LIB.T6G(SCH_1):PAGE418
 U6012  EK7 B_PETP14 PT5161LRS-PT5161LRS,SMLF,IC,AJ051610U03   I142 @T6G_MB_LIB.T6G(SCH_1):PAGE418

P5E_CPU0_P2_TX_BUF_DP<2> @T6G_MB_LIB.T6G(SCH_1):P5E_CPU0_P2_TX_BUF_DP(2)
 C6569    2      2 Q_CAP_DIFFBUS_C0201-DIFF BUS_0.22UF,6.3V,20%,X6S,SA    I34 @T6G_MB_LIB.T6G(SCH_1):PAGE418
 U6012  EC7 B_PETP13 PT5161LRS-PT5161LRS,SMLF,IC,AJ051610U03   I142 @T6G_MB_LIB.T6G(SCH_1):PAGE418

P5E_CPU0_P2_TX_BUF_DP<3> @T6G_MB_LIB.T6G(SCH_1):P5E_CPU0_P2_TX_BUF_DP(3)
 C6571    2      2 Q_CAP_DIFFBUS_C0201-DIFF BUS_0.22UF,6.3V,20%,X6S,SA    I30 @T6G_MB_LIB.T6G(SCH_1):PAGE418
 U6012  DT7 B_PETP12 PT5161LRS-PT5161LRS,SMLF,IC,AJ051610U03   I142 @T6G_MB_LIB.T6G(SCH_1):PAGE418

P5E_CPU0_P2_TX_BUF_DP<4> @T6G_MB_LIB.T6G(SCH_1):P5E_CPU0_P2_TX_BUF_DP(4)
 C6573    2      2 Q_CAP_DIFFBUS_C0201-DIFF BUS_0.22UF,6.3V,20%,X6S,SA    I27 @T6G_MB_LIB.T6G(SCH_1):PAGE418
 U6012  DJ7 B_PETP11 PT5161LRS-PT5161LRS,SMLF,IC,AJ051610U03   I142 @T6G_MB_LIB.T6G(SCH_1):PAGE418

P5E_CPU0_P2_TX_BUF_DP<5> @T6G_MB_LIB.T6G(SCH_1):P5E_CPU0_P2_TX_BUF_DP(5)
 C6575    2      2 Q_CAP_DIFFBUS_C0201-DIFF BUS_0.22UF,6.3V,20%,X6S,SA    I25 @T6G_MB_LIB.T6G(SCH_1):PAGE418
 U6012  DB7 B_PETP10 PT5161LRS-PT5161LRS,SMLF,IC,AJ051610U03   I142 @T6G_MB_LIB.T6G(SCH_1):PAGE418

P5E_CPU0_P2_TX_BUF_DP<6> @T6G_MB_LIB.T6G(SCH_1):P5E_CPU0_P2_TX_BUF_DP(6)
 C6577    2      2 Q_CAP_DIFFBUS_C0201-DIFF BUS_0.22UF,6.3V,20%,X6S,SA    I19 @T6G_MB_LIB.T6G(SCH_1):PAGE418
 U6012  CR7 B_PETP9 PT5161LRS-PT5161LRS,SMLF,IC,AJ051610U03   I142 @T6G_MB_LIB.T6G(SCH_1):PAGE418

P5E_CPU0_P2_TX_BUF_DP<7> @T6G_MB_LIB.T6G(SCH_1):P5E_CPU0_P2_TX_BUF_DP(7)
 C6579    2      2 Q_CAP_DIFFBUS_C0201-DIFF BUS_0.22UF,6.3V,20%,X6S,SA    I18 @T6G_MB_LIB.T6G(SCH_1):PAGE418
 U6012  CH7 B_PETP8 PT5161LRS-PT5161LRS,SMLF,IC,AJ051610U03   I142 @T6G_MB_LIB.T6G(SCH_1):PAGE418

P5E_CPU0_P2_TX_BUF_DP<8> @T6G_MB_LIB.T6G(SCH_1):P5E_CPU0_P2_TX_BUF_DP(8)
 U6012  CA7 B_PETP7 PT5161LRS-PT5161LRS,SMLF,IC,AJ051610U03    I47 @T6G_MB_LIB.T6G(SCH_1):PAGE418
 C6581    2      2 Q_CAP_DIFFBUS_C0201-DIFF BUS_0.22UF,6.3V,20%,X6S,SA   I104 @T6G_MB_LIB.T6G(SCH_1):PAGE418

P5E_CPU0_P2_TX_BUF_DP<9> @T6G_MB_LIB.T6G(SCH_1):P5E_CPU0_P2_TX_BUF_DP(9)
 U6012  BP7 B_PETP6 PT5161LRS-PT5161LRS,SMLF,IC,AJ051610U03    I47 @T6G_MB_LIB.T6G(SCH_1):PAGE418
 C6583    2      2 Q_CAP_DIFFBUS_C0201-DIFF BUS_0.22UF,6.3V,20%,X6S,SA   I101 @T6G_MB_LIB.T6G(SCH_1):PAGE418

P5E_CPU0_P2_TX_C_DN<0> @T6G_MB_LIB.T6G(SCH_1):P5E_CPU0_P2_TX_C_DN(0)
  C868    1      1 Q_CAP_DIFFBUS_C0201-DIFF BUS_0.22UF,6.3V,20%,X6S,SA    I22 @T6G_MB_LIB.T6G(SCH_1):PAGE352
 U6012 EV34 B_PERP15 PT5161LRS-PT5161LRS,SMLF,IC,AJ051610U03    I37 @T6G_MB_LIB.T6G(SCH_1):PAGE415

P5E_CPU0_P2_TX_C_DN<10> @T6G_MB_LIB.T6G(SCH_1):P5E_CPU0_P2_TX_C_DN(10)
  C848    1      1 Q_CAP_DIFFBUS_C0201-DIFF BUS_0.22UF,6.3V,20%,X6S,SA    I66 @T6G_MB_LIB.T6G(SCH_1):PAGE352
 U6012 BH34 B_PERP5 PT5161LRS-PT5161LRS,SMLF,IC,AJ051610U03    I38 @T6G_MB_LIB.T6G(SCH_1):PAGE415

P5E_CPU0_P2_TX_C_DN<11> @T6G_MB_LIB.T6G(SCH_1):P5E_CPU0_P2_TX_C_DN(11)
  C846    1      1 Q_CAP_DIFFBUS_C0201-DIFF BUS_0.22UF,6.3V,20%,X6S,SA    I68 @T6G_MB_LIB.T6G(SCH_1):PAGE352
 U6012 BA34 B_PERP4 PT5161LRS-PT5161LRS,SMLF,IC,AJ051610U03    I38 @T6G_MB_LIB.T6G(SCH_1):PAGE415

P5E_CPU0_P2_TX_C_DN<12> @T6G_MB_LIB.T6G(SCH_1):P5E_CPU0_P2_TX_C_DN(12)
  C844    1      1 Q_CAP_DIFFBUS_C0201-DIFF BUS_0.22UF,6.3V,20%,X6S,SA    I70 @T6G_MB_LIB.T6G(SCH_1):PAGE352
 U6012 AP34 B_PERP3 PT5161LRS-PT5161LRS,SMLF,IC,AJ051610U03    I38 @T6G_MB_LIB.T6G(SCH_1):PAGE415

P5E_CPU0_P2_TX_C_DN<13> @T6G_MB_LIB.T6G(SCH_1):P5E_CPU0_P2_TX_C_DN(13)
  C842    1      1 Q_CAP_DIFFBUS_C0201-DIFF BUS_0.22UF,6.3V,20%,X6S,SA    I76 @T6G_MB_LIB.T6G(SCH_1):PAGE352
 U6012 AG34 B_PERP2 PT5161LRS-PT5161LRS,SMLF,IC,AJ051610U03    I38 @T6G_MB_LIB.T6G(SCH_1):PAGE415

P5E_CPU0_P2_TX_C_DN<14> @T6G_MB_LIB.T6G(SCH_1):P5E_CPU0_P2_TX_C_DN(14)
  C840    1      1 Q_CAP_DIFFBUS_C0201-DIFF BUS_0.22UF,6.3V,20%,X6S,SA    I79 @T6G_MB_LIB.T6G(SCH_1):PAGE352
 U6012  Y34 B_PERP1 PT5161LRS-PT5161LRS,SMLF,IC,AJ051610U03    I38 @T6G_MB_LIB.T6G(SCH_1):PAGE415

P5E_CPU0_P2_TX_C_DN<15> @T6G_MB_LIB.T6G(SCH_1):P5E_CPU0_P2_TX_C_DN(15)
  C838    1      1 Q_CAP_DIFFBUS_C0201-DIFF BUS_0.22UF,6.3V,20%,X6S,SA    I80 @T6G_MB_LIB.T6G(SCH_1):PAGE352
 U6012  N34 B_PERP0 PT5161LRS-PT5161LRS,SMLF,IC,AJ051610U03    I38 @T6G_MB_LIB.T6G(SCH_1):PAGE415

P5E_CPU0_P2_TX_C_DN<1> @T6G_MB_LIB.T6G(SCH_1):P5E_CPU0_P2_TX_C_DN(1)
  C866    1      1 Q_CAP_DIFFBUS_C0201-DIFF BUS_0.22UF,6.3V,20%,X6S,SA    I24 @T6G_MB_LIB.T6G(SCH_1):PAGE352
 U6012 EN35 B_PERN14 PT5161LRS-PT5161LRS,SMLF,IC,AJ051610U03    I37 @T6G_MB_LIB.T6G(SCH_1):PAGE415

P5E_CPU0_P2_TX_C_DN<2> @T6G_MB_LIB.T6G(SCH_1):P5E_CPU0_P2_TX_C_DN(2)
  C864    1      1 Q_CAP_DIFFBUS_C0201-DIFF BUS_0.22UF,6.3V,20%,X6S,SA    I25 @T6G_MB_LIB.T6G(SCH_1):PAGE352
 U6012 ED34 B_PERP13 PT5161LRS-PT5161LRS,SMLF,IC,AJ051610U03    I37 @T6G_MB_LIB.T6G(SCH_1):PAGE415

P5E_CPU0_P2_TX_C_DN<3> @T6G_MB_LIB.T6G(SCH_1):P5E_CPU0_P2_TX_C_DN(3)
  C862    1      1 Q_CAP_DIFFBUS_C0201-DIFF BUS_0.22UF,6.3V,20%,X6S,SA    I28 @T6G_MB_LIB.T6G(SCH_1):PAGE352
 U6012 DU34 B_PERP12 PT5161LRS-PT5161LRS,SMLF,IC,AJ051610U03    I37 @T6G_MB_LIB.T6G(SCH_1):PAGE415

P5E_CPU0_P2_TX_C_DN<4> @T6G_MB_LIB.T6G(SCH_1):P5E_CPU0_P2_TX_C_DN(4)
  C860    1      1 Q_CAP_DIFFBUS_C0201-DIFF BUS_0.22UF,6.3V,20%,X6S,SA    I30 @T6G_MB_LIB.T6G(SCH_1):PAGE352
 U6012 DK34 B_PERP11 PT5161LRS-PT5161LRS,SMLF,IC,AJ051610U03    I37 @T6G_MB_LIB.T6G(SCH_1):PAGE415

P5E_CPU0_P2_TX_C_DN<5> @T6G_MB_LIB.T6G(SCH_1):P5E_CPU0_P2_TX_C_DN(5)
  C858    1      1 Q_CAP_DIFFBUS_C0201-DIFF BUS_0.22UF,6.3V,20%,X6S,SA    I37 @T6G_MB_LIB.T6G(SCH_1):PAGE352
 U6012 DC34 B_PERP10 PT5161LRS-PT5161LRS,SMLF,IC,AJ051610U03    I37 @T6G_MB_LIB.T6G(SCH_1):PAGE415

P5E_CPU0_P2_TX_C_DN<6> @T6G_MB_LIB.T6G(SCH_1):P5E_CPU0_P2_TX_C_DN(6)
  C856    1      1 Q_CAP_DIFFBUS_C0201-DIFF BUS_0.22UF,6.3V,20%,X6S,SA    I39 @T6G_MB_LIB.T6G(SCH_1):PAGE352
 U6012 CT34 B_PERP9 PT5161LRS-PT5161LRS,SMLF,IC,AJ051610U03    I37 @T6G_MB_LIB.T6G(SCH_1):PAGE415

P5E_CPU0_P2_TX_C_DN<7> @T6G_MB_LIB.T6G(SCH_1):P5E_CPU0_P2_TX_C_DN(7)
  C854    1      1 Q_CAP_DIFFBUS_C0201-DIFF BUS_0.22UF,6.3V,20%,X6S,SA    I41 @T6G_MB_LIB.T6G(SCH_1):PAGE352
 U6012 CJ34 B_PERP8 PT5161LRS-PT5161LRS,SMLF,IC,AJ051610U03    I37 @T6G_MB_LIB.T6G(SCH_1):PAGE415

P5E_CPU0_P2_TX_C_DN<8> @T6G_MB_LIB.T6G(SCH_1):P5E_CPU0_P2_TX_C_DN(8)
  C852    1      1 Q_CAP_DIFFBUS_C0201-DIFF BUS_0.22UF,6.3V,20%,X6S,SA    I61 @T6G_MB_LIB.T6G(SCH_1):PAGE352
 U6012 CB34 B_PERP7 PT5161LRS-PT5161LRS,SMLF,IC,AJ051610U03    I38 @T6G_MB_LIB.T6G(SCH_1):PAGE415

P5E_CPU0_P2_TX_C_DN<9> @T6G_MB_LIB.T6G(SCH_1):P5E_CPU0_P2_TX_C_DN(9)
  C850    1      1 Q_CAP_DIFFBUS_C0201-DIFF BUS_0.22UF,6.3V,20%,X6S,SA    I64 @T6G_MB_LIB.T6G(SCH_1):PAGE352
 U6012 BR34 B_PERP6 PT5161LRS-PT5161LRS,SMLF,IC,AJ051610U03    I38 @T6G_MB_LIB.T6G(SCH_1):PAGE415

P5E_CPU0_P2_TX_C_DP<0> @T6G_MB_LIB.T6G(SCH_1):P5E_CPU0_P2_TX_C_DP(0)
  C869    1      1 Q_CAP_DIFFBUS_C0201-DIFF BUS_0.22UF,6.3V,20%,X6S,SA    I21 @T6G_MB_LIB.T6G(SCH_1):PAGE352
 U6012 EY35 B_PERN15 PT5161LRS-PT5161LRS,SMLF,IC,AJ051610U03    I37 @T6G_MB_LIB.T6G(SCH_1):PAGE415

P5E_CPU0_P2_TX_C_DP<10> @T6G_MB_LIB.T6G(SCH_1):P5E_CPU0_P2_TX_C_DP(10)
  C849    1      1 Q_CAP_DIFFBUS_C0201-DIFF BUS_0.22UF,6.3V,20%,X6S,SA    I65 @T6G_MB_LIB.T6G(SCH_1):PAGE352
 U6012 BK35 B_PERN5 PT5161LRS-PT5161LRS,SMLF,IC,AJ051610U03    I38 @T6G_MB_LIB.T6G(SCH_1):PAGE415

P5E_CPU0_P2_TX_C_DP<11> @T6G_MB_LIB.T6G(SCH_1):P5E_CPU0_P2_TX_C_DP(11)
  C847    1      1 Q_CAP_DIFFBUS_C0201-DIFF BUS_0.22UF,6.3V,20%,X6S,SA    I67 @T6G_MB_LIB.T6G(SCH_1):PAGE352
 U6012 BC35 B_PERN4 PT5161LRS-PT5161LRS,SMLF,IC,AJ051610U03    I38 @T6G_MB_LIB.T6G(SCH_1):PAGE415

P5E_CPU0_P2_TX_C_DP<12> @T6G_MB_LIB.T6G(SCH_1):P5E_CPU0_P2_TX_C_DP(12)
  C845    1      1 Q_CAP_DIFFBUS_C0201-DIFF BUS_0.22UF,6.3V,20%,X6S,SA    I69 @T6G_MB_LIB.T6G(SCH_1):PAGE352
 U6012 AT35 B_PERN3 PT5161LRS-PT5161LRS,SMLF,IC,AJ051610U03    I38 @T6G_MB_LIB.T6G(SCH_1):PAGE415

P5E_CPU0_P2_TX_C_DP<13> @T6G_MB_LIB.T6G(SCH_1):P5E_CPU0_P2_TX_C_DP(13)
  C843    1      1 Q_CAP_DIFFBUS_C0201-DIFF BUS_0.22UF,6.3V,20%,X6S,SA    I77 @T6G_MB_LIB.T6G(SCH_1):PAGE352
 U6012 AJ35 B_PERN2 PT5161LRS-PT5161LRS,SMLF,IC,AJ051610U03    I38 @T6G_MB_LIB.T6G(SCH_1):PAGE415

P5E_CPU0_P2_TX_C_DP<14> @T6G_MB_LIB.T6G(SCH_1):P5E_CPU0_P2_TX_C_DP(14)
  C841    1      1 Q_CAP_DIFFBUS_C0201-DIFF BUS_0.22UF,6.3V,20%,X6S,SA    I78 @T6G_MB_LIB.T6G(SCH_1):PAGE352
 U6012 AB35 B_PERN1 PT5161LRS-PT5161LRS,SMLF,IC,AJ051610U03    I38 @T6G_MB_LIB.T6G(SCH_1):PAGE415

P5E_CPU0_P2_TX_C_DP<15> @T6G_MB_LIB.T6G(SCH_1):P5E_CPU0_P2_TX_C_DP(15)
  C839    1      1 Q_CAP_DIFFBUS_C0201-DIFF BUS_0.22UF,6.3V,20%,X6S,SA    I81 @T6G_MB_LIB.T6G(SCH_1):PAGE352
 U6012  R35 B_PERN0 PT5161LRS-PT5161LRS,SMLF,IC,AJ051610U03    I38 @T6G_MB_LIB.T6G(SCH_1):PAGE415

P5E_CPU0_P2_TX_C_DP<1> @T6G_MB_LIB.T6G(SCH_1):P5E_CPU0_P2_TX_C_DP(1)
  C867    1      1 Q_CAP_DIFFBUS_C0201-DIFF BUS_0.22UF,6.3V,20%,X6S,SA    I23 @T6G_MB_LIB.T6G(SCH_1):PAGE352
 U6012 EL34 B_PERP14 PT5161LRS-PT5161LRS,SMLF,IC,AJ051610U03    I37 @T6G_MB_LIB.T6G(SCH_1):PAGE415

P5E_CPU0_P2_TX_C_DP<2> @T6G_MB_LIB.T6G(SCH_1):P5E_CPU0_P2_TX_C_DP(2)
  C865    1      1 Q_CAP_DIFFBUS_C0201-DIFF BUS_0.22UF,6.3V,20%,X6S,SA    I26 @T6G_MB_LIB.T6G(SCH_1):PAGE352
 U6012 EF35 B_PERN13 PT5161LRS-PT5161LRS,SMLF,IC,AJ051610U03    I37 @T6G_MB_LIB.T6G(SCH_1):PAGE415

P5E_CPU0_P2_TX_C_DP<3> @T6G_MB_LIB.T6G(SCH_1):P5E_CPU0_P2_TX_C_DP(3)
  C863    1      1 Q_CAP_DIFFBUS_C0201-DIFF BUS_0.22UF,6.3V,20%,X6S,SA    I27 @T6G_MB_LIB.T6G(SCH_1):PAGE352
 U6012 DW35 B_PERN12 PT5161LRS-PT5161LRS,SMLF,IC,AJ051610U03    I37 @T6G_MB_LIB.T6G(SCH_1):PAGE415

P5E_CPU0_P2_TX_C_DP<4> @T6G_MB_LIB.T6G(SCH_1):P5E_CPU0_P2_TX_C_DP(4)
  C861    1      1 Q_CAP_DIFFBUS_C0201-DIFF BUS_0.22UF,6.3V,20%,X6S,SA    I29 @T6G_MB_LIB.T6G(SCH_1):PAGE352
 U6012 DM35 B_PERN11 PT5161LRS-PT5161LRS,SMLF,IC,AJ051610U03    I37 @T6G_MB_LIB.T6G(SCH_1):PAGE415

P5E_CPU0_P2_TX_C_DP<5> @T6G_MB_LIB.T6G(SCH_1):P5E_CPU0_P2_TX_C_DP(5)
  C859    1      1 Q_CAP_DIFFBUS_C0201-DIFF BUS_0.22UF,6.3V,20%,X6S,SA    I36 @T6G_MB_LIB.T6G(SCH_1):PAGE352
 U6012 DE35 B_PERN10 PT5161LRS-PT5161LRS,SMLF,IC,AJ051610U03    I37 @T6G_MB_LIB.T6G(SCH_1):PAGE415

P5E_CPU0_P2_TX_C_DP<6> @T6G_MB_LIB.T6G(SCH_1):P5E_CPU0_P2_TX_C_DP(6)
  C857    1      1 Q_CAP_DIFFBUS_C0201-DIFF BUS_0.22UF,6.3V,20%,X6S,SA    I38 @T6G_MB_LIB.T6G(SCH_1):PAGE352
 U6012 CV35 B_PERN9 PT5161LRS-PT5161LRS,SMLF,IC,AJ051610U03    I37 @T6G_MB_LIB.T6G(SCH_1):PAGE415

P5E_CPU0_P2_TX_C_DP<7> @T6G_MB_LIB.T6G(SCH_1):P5E_CPU0_P2_TX_C_DP(7)
  C855    1      1 Q_CAP_DIFFBUS_C0201-DIFF BUS_0.22UF,6.3V,20%,X6S,SA    I40 @T6G_MB_LIB.T6G(SCH_1):PAGE352
 U6012 CL35 B_PERN8 PT5161LRS-PT5161LRS,SMLF,IC,AJ051610U03    I37 @T6G_MB_LIB.T6G(SCH_1):PAGE415

P5E_CPU0_P2_TX_C_DP<8> @T6G_MB_LIB.T6G(SCH_1):P5E_CPU0_P2_TX_C_DP(8)
  C853    1      1 Q_CAP_DIFFBUS_C0201-DIFF BUS_0.22UF,6.3V,20%,X6S,SA    I62 @T6G_MB_LIB.T6G(SCH_1):PAGE352
 U6012 CD35 B_PERN7 PT5161LRS-PT5161LRS,SMLF,IC,AJ051610U03    I38 @T6G_MB_LIB.T6G(SCH_1):PAGE415

P5E_CPU0_P2_TX_C_DP<9> @T6G_MB_LIB.T6G(SCH_1):P5E_CPU0_P2_TX_C_DP(9)
  C851    1      1 Q_CAP_DIFFBUS_C0201-DIFF BUS_0.22UF,6.3V,20%,X6S,SA    I63 @T6G_MB_LIB.T6G(SCH_1):PAGE352
 U6012 BU35 B_PERN6 PT5161LRS-PT5161LRS,SMLF,IC,AJ051610U03    I38 @T6G_MB_LIB.T6G(SCH_1):PAGE415

P5E_CPU0_P2_TX_DN<0> @T6G_MB_LIB.T6G(SCH_1):P5E_CPU0_P2_TX_DN(0)
   U25 BT35 P2_TXN0 GENOA_SP5-SOCKET6096_13568-001,SMLF,IO,DGA^6000030   I147 @T6G_MB_LIB.T6G(SCH_1):PAGE25
  C868    2      2 Q_CAP_DIFFBUS_C0201-DIFF BUS_0.22UF,6.3V,20%,X6S,SA    I22 @T6G_MB_LIB.T6G(SCH_1):PAGE352

P5E_CPU0_P2_TX_DN<10> @T6G_MB_LIB.T6G(SCH_1):P5E_CPU0_P2_TX_DN(10)
   U25 BU26 P2_TXN10 GENOA_SP5-SOCKET6096_13568-001,SMLF,IO,DGA^6000030   I147 @T6G_MB_LIB.T6G(SCH_1):PAGE25
  C848    2      2 Q_CAP_DIFFBUS_C0201-DIFF BUS_0.22UF,6.3V,20%,X6S,SA    I66 @T6G_MB_LIB.T6G(SCH_1):PAGE352

P5E_CPU0_P2_TX_DN<11> @T6G_MB_LIB.T6G(SCH_1):P5E_CPU0_P2_TX_DN(11)
   U25 CA26 P2_TXN11 GENOA_SP5-SOCKET6096_13568-001,SMLF,IO,DGA^6000030   I147 @T6G_MB_LIB.T6G(SCH_1):PAGE25
  C846    2      2 Q_CAP_DIFFBUS_C0201-DIFF BUS_0.22UF,6.3V,20%,X6S,SA    I68 @T6G_MB_LIB.T6G(SCH_1):PAGE352

P5E_CPU0_P2_TX_DN<12> @T6G_MB_LIB.T6G(SCH_1):P5E_CPU0_P2_TX_DN(12)
   U25 BW26 P2_TXN12 GENOA_SP5-SOCKET6096_13568-001,SMLF,IO,DGA^6000030   I147 @T6G_MB_LIB.T6G(SCH_1):PAGE25
  C844    2      2 Q_CAP_DIFFBUS_C0201-DIFF BUS_0.22UF,6.3V,20%,X6S,SA    I70 @T6G_MB_LIB.T6G(SCH_1):PAGE352

P5E_CPU0_P2_TX_DN<13> @T6G_MB_LIB.T6G(SCH_1):P5E_CPU0_P2_TX_DN(13)
   U25 BU23 P2_TXN13 GENOA_SP5-SOCKET6096_13568-001,SMLF,IO,DGA^6000030   I147 @T6G_MB_LIB.T6G(SCH_1):PAGE25
  C842    2      2 Q_CAP_DIFFBUS_C0201-DIFF BUS_0.22UF,6.3V,20%,X6S,SA    I76 @T6G_MB_LIB.T6G(SCH_1):PAGE352

P5E_CPU0_P2_TX_DN<14> @T6G_MB_LIB.T6G(SCH_1):P5E_CPU0_P2_TX_DN(14)
   U25 CA23 P2_TXN14 GENOA_SP5-SOCKET6096_13568-001,SMLF,IO,DGA^6000030   I147 @T6G_MB_LIB.T6G(SCH_1):PAGE25
  C840    2      2 Q_CAP_DIFFBUS_C0201-DIFF BUS_0.22UF,6.3V,20%,X6S,SA    I79 @T6G_MB_LIB.T6G(SCH_1):PAGE352

P5E_CPU0_P2_TX_DN<15> @T6G_MB_LIB.T6G(SCH_1):P5E_CPU0_P2_TX_DN(15)
   U25 BW23 P2_TXN15 GENOA_SP5-SOCKET6096_13568-001,SMLF,IO,DGA^6000030   I147 @T6G_MB_LIB.T6G(SCH_1):PAGE25
  C838    2      2 Q_CAP_DIFFBUS_C0201-DIFF BUS_0.22UF,6.3V,20%,X6S,SA    I80 @T6G_MB_LIB.T6G(SCH_1):PAGE352

P5E_CPU0_P2_TX_DN<1> @T6G_MB_LIB.T6G(SCH_1):P5E_CPU0_P2_TX_DN(1)
   U25 BV35 P2_TXN1 GENOA_SP5-SOCKET6096_13568-001,SMLF,IO,DGA^6000030   I147 @T6G_MB_LIB.T6G(SCH_1):PAGE25
  C866    2      2 Q_CAP_DIFFBUS_C0201-DIFF BUS_0.22UF,6.3V,20%,X6S,SA    I24 @T6G_MB_LIB.T6G(SCH_1):PAGE352

P5E_CPU0_P2_TX_DN<2> @T6G_MB_LIB.T6G(SCH_1):P5E_CPU0_P2_TX_DN(2)
   U25 CB35 P2_TXN2 GENOA_SP5-SOCKET6096_13568-001,SMLF,IO,DGA^6000030   I147 @T6G_MB_LIB.T6G(SCH_1):PAGE25
  C864    2      2 Q_CAP_DIFFBUS_C0201-DIFF BUS_0.22UF,6.3V,20%,X6S,SA    I25 @T6G_MB_LIB.T6G(SCH_1):PAGE352

P5E_CPU0_P2_TX_DN<3> @T6G_MB_LIB.T6G(SCH_1):P5E_CPU0_P2_TX_DN(3)
   U25 BY35 P2_TXN3 GENOA_SP5-SOCKET6096_13568-001,SMLF,IO,DGA^6000030   I147 @T6G_MB_LIB.T6G(SCH_1):PAGE25
  C862    2      2 Q_CAP_DIFFBUS_C0201-DIFF BUS_0.22UF,6.3V,20%,X6S,SA    I28 @T6G_MB_LIB.T6G(SCH_1):PAGE352

P5E_CPU0_P2_TX_DN<4> @T6G_MB_LIB.T6G(SCH_1):P5E_CPU0_P2_TX_DN(4)
   U25 BU32 P2_TXN4 GENOA_SP5-SOCKET6096_13568-001,SMLF,IO,DGA^6000030   I147 @T6G_MB_LIB.T6G(SCH_1):PAGE25
  C860    2      2 Q_CAP_DIFFBUS_C0201-DIFF BUS_0.22UF,6.3V,20%,X6S,SA    I30 @T6G_MB_LIB.T6G(SCH_1):PAGE352

P5E_CPU0_P2_TX_DN<5> @T6G_MB_LIB.T6G(SCH_1):P5E_CPU0_P2_TX_DN(5)
   U25 CA32 P2_TXN5 GENOA_SP5-SOCKET6096_13568-001,SMLF,IO,DGA^6000030   I147 @T6G_MB_LIB.T6G(SCH_1):PAGE25
  C858    2      2 Q_CAP_DIFFBUS_C0201-DIFF BUS_0.22UF,6.3V,20%,X6S,SA    I37 @T6G_MB_LIB.T6G(SCH_1):PAGE352

P5E_CPU0_P2_TX_DN<6> @T6G_MB_LIB.T6G(SCH_1):P5E_CPU0_P2_TX_DN(6)
   U25 BW32 P2_TXN6 GENOA_SP5-SOCKET6096_13568-001,SMLF,IO,DGA^6000030   I147 @T6G_MB_LIB.T6G(SCH_1):PAGE25
  C856    2      2 Q_CAP_DIFFBUS_C0201-DIFF BUS_0.22UF,6.3V,20%,X6S,SA    I39 @T6G_MB_LIB.T6G(SCH_1):PAGE352

P5E_CPU0_P2_TX_DN<7> @T6G_MB_LIB.T6G(SCH_1):P5E_CPU0_P2_TX_DN(7)
   U25 BU29 P2_TXN7 GENOA_SP5-SOCKET6096_13568-001,SMLF,IO,DGA^6000030   I147 @T6G_MB_LIB.T6G(SCH_1):PAGE25
  C854    2      2 Q_CAP_DIFFBUS_C0201-DIFF BUS_0.22UF,6.3V,20%,X6S,SA    I41 @T6G_MB_LIB.T6G(SCH_1):PAGE352

P5E_CPU0_P2_TX_DN<8> @T6G_MB_LIB.T6G(SCH_1):P5E_CPU0_P2_TX_DN(8)
   U25 CA29 P2_TXN8 GENOA_SP5-SOCKET6096_13568-001,SMLF,IO,DGA^6000030   I147 @T6G_MB_LIB.T6G(SCH_1):PAGE25
  C852    2      2 Q_CAP_DIFFBUS_C0201-DIFF BUS_0.22UF,6.3V,20%,X6S,SA    I61 @T6G_MB_LIB.T6G(SCH_1):PAGE352

P5E_CPU0_P2_TX_DN<9> @T6G_MB_LIB.T6G(SCH_1):P5E_CPU0_P2_TX_DN(9)
   U25 BW29 P2_TXN9 GENOA_SP5-SOCKET6096_13568-001,SMLF,IO,DGA^6000030   I147 @T6G_MB_LIB.T6G(SCH_1):PAGE25
  C850    2      2 Q_CAP_DIFFBUS_C0201-DIFF BUS_0.22UF,6.3V,20%,X6S,SA    I64 @T6G_MB_LIB.T6G(SCH_1):PAGE352

P5E_CPU0_P2_TX_DP<0> @T6G_MB_LIB.T6G(SCH_1):P5E_CPU0_P2_TX_DP(0)
   U25 BT36 P2_TXP0 GENOA_SP5-SOCKET6096_13568-001,SMLF,IO,DGA^6000030   I147 @T6G_MB_LIB.T6G(SCH_1):PAGE25
  C869    2      2 Q_CAP_DIFFBUS_C0201-DIFF BUS_0.22UF,6.3V,20%,X6S,SA    I21 @T6G_MB_LIB.T6G(SCH_1):PAGE352

P5E_CPU0_P2_TX_DP<10> @T6G_MB_LIB.T6G(SCH_1):P5E_CPU0_P2_TX_DP(10)
   U25 BU27 P2_TXP10 GENOA_SP5-SOCKET6096_13568-001,SMLF,IO,DGA^6000030   I147 @T6G_MB_LIB.T6G(SCH_1):PAGE25
  C849    2      2 Q_CAP_DIFFBUS_C0201-DIFF BUS_0.22UF,6.3V,20%,X6S,SA    I65 @T6G_MB_LIB.T6G(SCH_1):PAGE352

P5E_CPU0_P2_TX_DP<11> @T6G_MB_LIB.T6G(SCH_1):P5E_CPU0_P2_TX_DP(11)
   U25 CA27 P2_TXP11 GENOA_SP5-SOCKET6096_13568-001,SMLF,IO,DGA^6000030   I147 @T6G_MB_LIB.T6G(SCH_1):PAGE25
  C847    2      2 Q_CAP_DIFFBUS_C0201-DIFF BUS_0.22UF,6.3V,20%,X6S,SA    I67 @T6G_MB_LIB.T6G(SCH_1):PAGE352

P5E_CPU0_P2_TX_DP<12> @T6G_MB_LIB.T6G(SCH_1):P5E_CPU0_P2_TX_DP(12)
   U25 BW27 P2_TXP12 GENOA_SP5-SOCKET6096_13568-001,SMLF,IO,DGA^6000030   I147 @T6G_MB_LIB.T6G(SCH_1):PAGE25
  C845    2      2 Q_CAP_DIFFBUS_C0201-DIFF BUS_0.22UF,6.3V,20%,X6S,SA    I69 @T6G_MB_LIB.T6G(SCH_1):PAGE352

P5E_CPU0_P2_TX_DP<13> @T6G_MB_LIB.T6G(SCH_1):P5E_CPU0_P2_TX_DP(13)
   U25 BU24 P2_TXP13 GENOA_SP5-SOCKET6096_13568-001,SMLF,IO,DGA^6000030   I147 @T6G_MB_LIB.T6G(SCH_1):PAGE25
  C843    2      2 Q_CAP_DIFFBUS_C0201-DIFF BUS_0.22UF,6.3V,20%,X6S,SA    I77 @T6G_MB_LIB.T6G(SCH_1):PAGE352

P5E_CPU0_P2_TX_DP<14> @T6G_MB_LIB.T6G(SCH_1):P5E_CPU0_P2_TX_DP(14)
   U25 CA24 P2_TXP14 GENOA_SP5-SOCKET6096_13568-001,SMLF,IO,DGA^6000030   I147 @T6G_MB_LIB.T6G(SCH_1):PAGE25
  C841    2      2 Q_CAP_DIFFBUS_C0201-DIFF BUS_0.22UF,6.3V,20%,X6S,SA    I78 @T6G_MB_LIB.T6G(SCH_1):PAGE352

P5E_CPU0_P2_TX_DP<15> @T6G_MB_LIB.T6G(SCH_1):P5E_CPU0_P2_TX_DP(15)
   U25 BW24 P2_TXP15 GENOA_SP5-SOCKET6096_13568-001,SMLF,IO,DGA^6000030   I147 @T6G_MB_LIB.T6G(SCH_1):PAGE25
  C839    2      2 Q_CAP_DIFFBUS_C0201-DIFF BUS_0.22UF,6.3V,20%,X6S,SA    I81 @T6G_MB_LIB.T6G(SCH_1):PAGE352

P5E_CPU0_P2_TX_DP<1> @T6G_MB_LIB.T6G(SCH_1):P5E_CPU0_P2_TX_DP(1)
   U25 BV36 P2_TXP1 GENOA_SP5-SOCKET6096_13568-001,SMLF,IO,DGA^6000030   I147 @T6G_MB_LIB.T6G(SCH_1):PAGE25
  C867    2      2 Q_CAP_DIFFBUS_C0201-DIFF BUS_0.22UF,6.3V,20%,X6S,SA    I23 @T6G_MB_LIB.T6G(SCH_1):PAGE352

P5E_CPU0_P2_TX_DP<2> @T6G_MB_LIB.T6G(SCH_1):P5E_CPU0_P2_TX_DP(2)
   U25 CB36 P2_TXP2 GENOA_SP5-SOCKET6096_13568-001,SMLF,IO,DGA^6000030   I147 @T6G_MB_LIB.T6G(SCH_1):PAGE25
  C865    2      2 Q_CAP_DIFFBUS_C0201-DIFF BUS_0.22UF,6.3V,20%,X6S,SA    I26 @T6G_MB_LIB.T6G(SCH_1):PAGE352

P5E_CPU0_P2_TX_DP<3> @T6G_MB_LIB.T6G(SCH_1):P5E_CPU0_P2_TX_DP(3)
   U25 BY36 P2_TXP3 GENOA_SP5-SOCKET6096_13568-001,SMLF,IO,DGA^6000030   I147 @T6G_MB_LIB.T6G(SCH_1):PAGE25
  C863    2      2 Q_CAP_DIFFBUS_C0201-DIFF BUS_0.22UF,6.3V,20%,X6S,SA    I27 @T6G_MB_LIB.T6G(SCH_1):PAGE352

P5E_CPU0_P2_TX_DP<4> @T6G_MB_LIB.T6G(SCH_1):P5E_CPU0_P2_TX_DP(4)
   U25 BU33 P2_TXP4 GENOA_SP5-SOCKET6096_13568-001,SMLF,IO,DGA^6000030   I147 @T6G_MB_LIB.T6G(SCH_1):PAGE25
  C861    2      2 Q_CAP_DIFFBUS_C0201-DIFF BUS_0.22UF,6.3V,20%,X6S,SA    I29 @T6G_MB_LIB.T6G(SCH_1):PAGE352

P5E_CPU0_P2_TX_DP<5> @T6G_MB_LIB.T6G(SCH_1):P5E_CPU0_P2_TX_DP(5)
   U25 CA33 P2_TXP5 GENOA_SP5-SOCKET6096_13568-001,SMLF,IO,DGA^6000030   I147 @T6G_MB_LIB.T6G(SCH_1):PAGE25
  C859    2      2 Q_CAP_DIFFBUS_C0201-DIFF BUS_0.22UF,6.3V,20%,X6S,SA    I36 @T6G_MB_LIB.T6G(SCH_1):PAGE352

P5E_CPU0_P2_TX_DP<6> @T6G_MB_LIB.T6G(SCH_1):P5E_CPU0_P2_TX_DP(6)
   U25 BW33 P2_TXP6 GENOA_SP5-SOCKET6096_13568-001,SMLF,IO,DGA^6000030   I147 @T6G_MB_LIB.T6G(SCH_1):PAGE25
  C857    2      2 Q_CAP_DIFFBUS_C0201-DIFF BUS_0.22UF,6.3V,20%,X6S,SA    I38 @T6G_MB_LIB.T6G(SCH_1):PAGE352

P5E_CPU0_P2_TX_DP<7> @T6G_MB_LIB.T6G(SCH_1):P5E_CPU0_P2_TX_DP(7)
   U25 BU30 P2_TXP7 GENOA_SP5-SOCKET6096_13568-001,SMLF,IO,DGA^6000030   I147 @T6G_MB_LIB.T6G(SCH_1):PAGE25
  C855    2      2 Q_CAP_DIFFBUS_C0201-DIFF BUS_0.22UF,6.3V,20%,X6S,SA    I40 @T6G_MB_LIB.T6G(SCH_1):PAGE352

P5E_CPU0_P2_TX_DP<8> @T6G_MB_LIB.T6G(SCH_1):P5E_CPU0_P2_TX_DP(8)
   U25 CA30 P2_TXP8 GENOA_SP5-SOCKET6096_13568-001,SMLF,IO,DGA^6000030   I147 @T6G_MB_LIB.T6G(SCH_1):PAGE25
  C853    2      2 Q_CAP_DIFFBUS_C0201-DIFF BUS_0.22UF,6.3V,20%,X6S,SA    I62 @T6G_MB_LIB.T6G(SCH_1):PAGE352

P5E_CPU0_P2_TX_DP<9> @T6G_MB_LIB.T6G(SCH_1):P5E_CPU0_P2_TX_DP(9)
   U25 BW30 P2_TXP9 GENOA_SP5-SOCKET6096_13568-001,SMLF,IO,DGA^6000030   I147 @T6G_MB_LIB.T6G(SCH_1):PAGE25
  C851    2      2 Q_CAP_DIFFBUS_C0201-DIFF BUS_0.22UF,6.3V,20%,X6S,SA    I63 @T6G_MB_LIB.T6G(SCH_1):PAGE352

P5E_CPU0_P3_RX_BUF_DN<0> @T6G_MB_LIB.T6G(SCH_1):P5E_CPU0_P3_RX_BUF_DN(0)
 U6013  EV2 A_PERN15 PT5161LRS-PT5161LRS,SMLF,IC,AJ051610U03    I38 @T6G_MB_LIB.T6G(SCH_1):PAGE428
  J106   F1     F1 CONN112_10137002101LF-CONN112_10137002-101LF,THLF,A    I74 @T6G_MB_LIB.T6G(SCH_1):PAGE327

P5E_CPU0_P3_RX_BUF_DN<10> @T6G_MB_LIB.T6G(SCH_1):P5E_CPU0_P3_RX_BUF_DN(10)
 U6013  BH2 A_PERN5 PT5161LRS-PT5161LRS,SMLF,IC,AJ051610U03     I1 @T6G_MB_LIB.T6G(SCH_1):PAGE428
  J105   F3     F3 CONN112_10137002101LF-CONN112_10137002-101LF,THLF,A    I75 @T6G_MB_LIB.T6G(SCH_1):PAGE326

P5E_CPU0_P3_RX_BUF_DN<11> @T6G_MB_LIB.T6G(SCH_1):P5E_CPU0_P3_RX_BUF_DN(11)
 U6013  BA2 A_PERN4 PT5161LRS-PT5161LRS,SMLF,IC,AJ051610U03     I1 @T6G_MB_LIB.T6G(SCH_1):PAGE428
  J105   E4     E4 CONN112_10137002101LF-CONN112_10137002-101LF,THLF,A    I75 @T6G_MB_LIB.T6G(SCH_1):PAGE326

P5E_CPU0_P3_RX_BUF_DN<12> @T6G_MB_LIB.T6G(SCH_1):P5E_CPU0_P3_RX_BUF_DN(12)
 U6013  AP2 A_PERN3 PT5161LRS-PT5161LRS,SMLF,IC,AJ051610U03     I1 @T6G_MB_LIB.T6G(SCH_1):PAGE428
  J105   F5     F5 CONN112_10137002101LF-CONN112_10137002-101LF,THLF,A    I76 @T6G_MB_LIB.T6G(SCH_1):PAGE326

P5E_CPU0_P3_RX_BUF_DN<13> @T6G_MB_LIB.T6G(SCH_1):P5E_CPU0_P3_RX_BUF_DN(13)
 U6013  AG2 A_PERN2 PT5161LRS-PT5161LRS,SMLF,IC,AJ051610U03     I1 @T6G_MB_LIB.T6G(SCH_1):PAGE428
  J105   E6     E6 CONN112_10137002101LF-CONN112_10137002-101LF,THLF,A    I76 @T6G_MB_LIB.T6G(SCH_1):PAGE326

P5E_CPU0_P3_RX_BUF_DN<14> @T6G_MB_LIB.T6G(SCH_1):P5E_CPU0_P3_RX_BUF_DN(14)
 U6013   Y2 A_PERN1 PT5161LRS-PT5161LRS,SMLF,IC,AJ051610U03     I1 @T6G_MB_LIB.T6G(SCH_1):PAGE428
  J105   F7     F7 CONN112_10137002101LF-CONN112_10137002-101LF,THLF,A    I76 @T6G_MB_LIB.T6G(SCH_1):PAGE326

P5E_CPU0_P3_RX_BUF_DN<15> @T6G_MB_LIB.T6G(SCH_1):P5E_CPU0_P3_RX_BUF_DN(15)
 U6013   N2 A_PERN0 PT5161LRS-PT5161LRS,SMLF,IC,AJ051610U03     I1 @T6G_MB_LIB.T6G(SCH_1):PAGE428
  J105   E8     E8 CONN112_10137002101LF-CONN112_10137002-101LF,THLF,A    I76 @T6G_MB_LIB.T6G(SCH_1):PAGE326

P5E_CPU0_P3_RX_BUF_DN<1> @T6G_MB_LIB.T6G(SCH_1):P5E_CPU0_P3_RX_BUF_DN(1)
 U6013  EL2 A_PERN14 PT5161LRS-PT5161LRS,SMLF,IC,AJ051610U03    I38 @T6G_MB_LIB.T6G(SCH_1):PAGE428
  J106   E2     E2 CONN112_10137002101LF-CONN112_10137002-101LF,THLF,A    I74 @T6G_MB_LIB.T6G(SCH_1):PAGE327

P5E_CPU0_P3_RX_BUF_DN<2> @T6G_MB_LIB.T6G(SCH_1):P5E_CPU0_P3_RX_BUF_DN(2)
 U6013  ED2 A_PERN13 PT5161LRS-PT5161LRS,SMLF,IC,AJ051610U03    I38 @T6G_MB_LIB.T6G(SCH_1):PAGE428
  J106   F3     F3 CONN112_10137002101LF-CONN112_10137002-101LF,THLF,A    I74 @T6G_MB_LIB.T6G(SCH_1):PAGE327

P5E_CPU0_P3_RX_BUF_DN<3> @T6G_MB_LIB.T6G(SCH_1):P5E_CPU0_P3_RX_BUF_DN(3)
 U6013  DU2 A_PERN12 PT5161LRS-PT5161LRS,SMLF,IC,AJ051610U03    I38 @T6G_MB_LIB.T6G(SCH_1):PAGE428
  J106   E4     E4 CONN112_10137002101LF-CONN112_10137002-101LF,THLF,A    I74 @T6G_MB_LIB.T6G(SCH_1):PAGE327

P5E_CPU0_P3_RX_BUF_DN<4> @T6G_MB_LIB.T6G(SCH_1):P5E_CPU0_P3_RX_BUF_DN(4)
 U6013  DK2 A_PERN11 PT5161LRS-PT5161LRS,SMLF,IC,AJ051610U03    I38 @T6G_MB_LIB.T6G(SCH_1):PAGE428
  J106   F5     F5 CONN112_10137002101LF-CONN112_10137002-101LF,THLF,A    I19 @T6G_MB_LIB.T6G(SCH_1):PAGE327

P5E_CPU0_P3_RX_BUF_DN<5> @T6G_MB_LIB.T6G(SCH_1):P5E_CPU0_P3_RX_BUF_DN(5)
 U6013  DC2 A_PERN10 PT5161LRS-PT5161LRS,SMLF,IC,AJ051610U03    I38 @T6G_MB_LIB.T6G(SCH_1):PAGE428
  J106   E6     E6 CONN112_10137002101LF-CONN112_10137002-101LF,THLF,A    I19 @T6G_MB_LIB.T6G(SCH_1):PAGE327

P5E_CPU0_P3_RX_BUF_DN<6> @T6G_MB_LIB.T6G(SCH_1):P5E_CPU0_P3_RX_BUF_DN(6)
 U6013  CT2 A_PERN9 PT5161LRS-PT5161LRS,SMLF,IC,AJ051610U03    I38 @T6G_MB_LIB.T6G(SCH_1):PAGE428
  J106   F7     F7 CONN112_10137002101LF-CONN112_10137002-101LF,THLF,A    I19 @T6G_MB_LIB.T6G(SCH_1):PAGE327

P5E_CPU0_P3_RX_BUF_DN<7> @T6G_MB_LIB.T6G(SCH_1):P5E_CPU0_P3_RX_BUF_DN(7)
 U6013  CJ2 A_PERN8 PT5161LRS-PT5161LRS,SMLF,IC,AJ051610U03    I38 @T6G_MB_LIB.T6G(SCH_1):PAGE428
  J106   E8     E8 CONN112_10137002101LF-CONN112_10137002-101LF,THLF,A    I19 @T6G_MB_LIB.T6G(SCH_1):PAGE327

P5E_CPU0_P3_RX_BUF_DN<8> @T6G_MB_LIB.T6G(SCH_1):P5E_CPU0_P3_RX_BUF_DN(8)
 U6013  CB2 A_PERN7 PT5161LRS-PT5161LRS,SMLF,IC,AJ051610U03     I1 @T6G_MB_LIB.T6G(SCH_1):PAGE428
  J105   F1     F1 CONN112_10137002101LF-CONN112_10137002-101LF,THLF,A    I75 @T6G_MB_LIB.T6G(SCH_1):PAGE326

P5E_CPU0_P3_RX_BUF_DN<9> @T6G_MB_LIB.T6G(SCH_1):P5E_CPU0_P3_RX_BUF_DN(9)
 U6013  BR2 A_PERN6 PT5161LRS-PT5161LRS,SMLF,IC,AJ051610U03     I1 @T6G_MB_LIB.T6G(SCH_1):PAGE428
  J105   E2     E2 CONN112_10137002101LF-CONN112_10137002-101LF,THLF,A    I75 @T6G_MB_LIB.T6G(SCH_1):PAGE326

P5E_CPU0_P3_RX_BUF_DP<0> @T6G_MB_LIB.T6G(SCH_1):P5E_CPU0_P3_RX_BUF_DP(0)
 U6013  EY1 A_PERP15 PT5161LRS-PT5161LRS,SMLF,IC,AJ051610U03    I38 @T6G_MB_LIB.T6G(SCH_1):PAGE428
  J106   G1     G1 CONN112_10137002101LF-CONN112_10137002-101LF,THLF,A    I74 @T6G_MB_LIB.T6G(SCH_1):PAGE327

P5E_CPU0_P3_RX_BUF_DP<10> @T6G_MB_LIB.T6G(SCH_1):P5E_CPU0_P3_RX_BUF_DP(10)
 U6013  BK1 A_PERP5 PT5161LRS-PT5161LRS,SMLF,IC,AJ051610U03     I1 @T6G_MB_LIB.T6G(SCH_1):PAGE428
  J105   G3     G3 CONN112_10137002101LF-CONN112_10137002-101LF,THLF,A    I75 @T6G_MB_LIB.T6G(SCH_1):PAGE326

P5E_CPU0_P3_RX_BUF_DP<11> @T6G_MB_LIB.T6G(SCH_1):P5E_CPU0_P3_RX_BUF_DP(11)
 U6013  BC1 A_PERP4 PT5161LRS-PT5161LRS,SMLF,IC,AJ051610U03     I1 @T6G_MB_LIB.T6G(SCH_1):PAGE428
  J105   F4     F4 CONN112_10137002101LF-CONN112_10137002-101LF,THLF,A    I75 @T6G_MB_LIB.T6G(SCH_1):PAGE326

P5E_CPU0_P3_RX_BUF_DP<12> @T6G_MB_LIB.T6G(SCH_1):P5E_CPU0_P3_RX_BUF_DP(12)
 U6013  AT1 A_PERP3 PT5161LRS-PT5161LRS,SMLF,IC,AJ051610U03     I1 @T6G_MB_LIB.T6G(SCH_1):PAGE428
  J105   G5     G5 CONN112_10137002101LF-CONN112_10137002-101LF,THLF,A    I76 @T6G_MB_LIB.T6G(SCH_1):PAGE326

P5E_CPU0_P3_RX_BUF_DP<13> @T6G_MB_LIB.T6G(SCH_1):P5E_CPU0_P3_RX_BUF_DP(13)
 U6013  AJ1 A_PERP2 PT5161LRS-PT5161LRS,SMLF,IC,AJ051610U03     I1 @T6G_MB_LIB.T6G(SCH_1):PAGE428
  J105   F6     F6 CONN112_10137002101LF-CONN112_10137002-101LF,THLF,A    I76 @T6G_MB_LIB.T6G(SCH_1):PAGE326

P5E_CPU0_P3_RX_BUF_DP<14> @T6G_MB_LIB.T6G(SCH_1):P5E_CPU0_P3_RX_BUF_DP(14)
 U6013  AB1 A_PERP1 PT5161LRS-PT5161LRS,SMLF,IC,AJ051610U03     I1 @T6G_MB_LIB.T6G(SCH_1):PAGE428
  J105   G7     G7 CONN112_10137002101LF-CONN112_10137002-101LF,THLF,A    I76 @T6G_MB_LIB.T6G(SCH_1):PAGE326

P5E_CPU0_P3_RX_BUF_DP<15> @T6G_MB_LIB.T6G(SCH_1):P5E_CPU0_P3_RX_BUF_DP(15)
 U6013   R1 A_PERP0 PT5161LRS-PT5161LRS,SMLF,IC,AJ051610U03     I1 @T6G_MB_LIB.T6G(SCH_1):PAGE428
  J105   F8     F8 CONN112_10137002101LF-CONN112_10137002-101LF,THLF,A    I76 @T6G_MB_LIB.T6G(SCH_1):PAGE326

P5E_CPU0_P3_RX_BUF_DP<1> @T6G_MB_LIB.T6G(SCH_1):P5E_CPU0_P3_RX_BUF_DP(1)
 U6013  EN1 A_PERP14 PT5161LRS-PT5161LRS,SMLF,IC,AJ051610U03    I38 @T6G_MB_LIB.T6G(SCH_1):PAGE428
  J106   F2     F2 CONN112_10137002101LF-CONN112_10137002-101LF,THLF,A    I74 @T6G_MB_LIB.T6G(SCH_1):PAGE327

P5E_CPU0_P3_RX_BUF_DP<2> @T6G_MB_LIB.T6G(SCH_1):P5E_CPU0_P3_RX_BUF_DP(2)
 U6013  EF1 A_PERP13 PT5161LRS-PT5161LRS,SMLF,IC,AJ051610U03    I38 @T6G_MB_LIB.T6G(SCH_1):PAGE428
  J106   G3     G3 CONN112_10137002101LF-CONN112_10137002-101LF,THLF,A    I74 @T6G_MB_LIB.T6G(SCH_1):PAGE327

P5E_CPU0_P3_RX_BUF_DP<3> @T6G_MB_LIB.T6G(SCH_1):P5E_CPU0_P3_RX_BUF_DP(3)
 U6013  DW1 A_PERP12 PT5161LRS-PT5161LRS,SMLF,IC,AJ051610U03    I38 @T6G_MB_LIB.T6G(SCH_1):PAGE428
  J106   F4     F4 CONN112_10137002101LF-CONN112_10137002-101LF,THLF,A    I74 @T6G_MB_LIB.T6G(SCH_1):PAGE327

P5E_CPU0_P3_RX_BUF_DP<4> @T6G_MB_LIB.T6G(SCH_1):P5E_CPU0_P3_RX_BUF_DP(4)
 U6013  DM1 A_PERP11 PT5161LRS-PT5161LRS,SMLF,IC,AJ051610U03    I38 @T6G_MB_LIB.T6G(SCH_1):PAGE428
  J106   G5     G5 CONN112_10137002101LF-CONN112_10137002-101LF,THLF,A    I19 @T6G_MB_LIB.T6G(SCH_1):PAGE327

P5E_CPU0_P3_RX_BUF_DP<5> @T6G_MB_LIB.T6G(SCH_1):P5E_CPU0_P3_RX_BUF_DP(5)
 U6013  DE1 A_PERP10 PT5161LRS-PT5161LRS,SMLF,IC,AJ051610U03    I38 @T6G_MB_LIB.T6G(SCH_1):PAGE428
  J106   F6     F6 CONN112_10137002101LF-CONN112_10137002-101LF,THLF,A    I19 @T6G_MB_LIB.T6G(SCH_1):PAGE327

P5E_CPU0_P3_RX_BUF_DP<6> @T6G_MB_LIB.T6G(SCH_1):P5E_CPU0_P3_RX_BUF_DP(6)
 U6013  CV1 A_PERP9 PT5161LRS-PT5161LRS,SMLF,IC,AJ051610U03    I38 @T6G_MB_LIB.T6G(SCH_1):PAGE428
  J106   G7     G7 CONN112_10137002101LF-CONN112_10137002-101LF,THLF,A    I19 @T6G_MB_LIB.T6G(SCH_1):PAGE327

P5E_CPU0_P3_RX_BUF_DP<7> @T6G_MB_LIB.T6G(SCH_1):P5E_CPU0_P3_RX_BUF_DP(7)
 U6013  CL1 A_PERP8 PT5161LRS-PT5161LRS,SMLF,IC,AJ051610U03    I38 @T6G_MB_LIB.T6G(SCH_1):PAGE428
  J106   F8     F8 CONN112_10137002101LF-CONN112_10137002-101LF,THLF,A    I19 @T6G_MB_LIB.T6G(SCH_1):PAGE327

P5E_CPU0_P3_RX_BUF_DP<8> @T6G_MB_LIB.T6G(SCH_1):P5E_CPU0_P3_RX_BUF_DP(8)
 U6013  CD1 A_PERP7 PT5161LRS-PT5161LRS,SMLF,IC,AJ051610U03     I1 @T6G_MB_LIB.T6G(SCH_1):PAGE428
  J105   G1     G1 CONN112_10137002101LF-CONN112_10137002-101LF,THLF,A    I75 @T6G_MB_LIB.T6G(SCH_1):PAGE326

P5E_CPU0_P3_RX_BUF_DP<9> @T6G_MB_LIB.T6G(SCH_1):P5E_CPU0_P3_RX_BUF_DP(9)
 U6013  BU1 A_PERP6 PT5161LRS-PT5161LRS,SMLF,IC,AJ051610U03     I1 @T6G_MB_LIB.T6G(SCH_1):PAGE428
  J105   F2     F2 CONN112_10137002101LF-CONN112_10137002-101LF,THLF,A    I75 @T6G_MB_LIB.T6G(SCH_1):PAGE326

P5E_CPU0_P3_RX_DN<0> @T6G_MB_LIB.T6G(SCH_1):P5E_CPU0_P3_RX_DN(0)
   U25 CV36 P3_RXN0 GENOA_SP5-SOCKET6096_13568-001,SMLF,IO,DGA^6000030   I148 @T6G_MB_LIB.T6G(SCH_1):PAGE25
 U6013 EW29 A_PETN15 PT5161LRS-PT5161LRS,SMLF,IC,AJ051610U03    I38 @T6G_MB_LIB.T6G(SCH_1):PAGE427

P5E_CPU0_P3_RX_DN<10> @T6G_MB_LIB.T6G(SCH_1):P5E_CPU0_P3_RX_DN(10)
   U25 DC27 P3_RXN10 GENOA_SP5-SOCKET6096_13568-001,SMLF,IO,DGA^6000030   I148 @T6G_MB_LIB.T6G(SCH_1):PAGE25
 U6013 BJ29 A_PETN5 PT5161LRS-PT5161LRS,SMLF,IC,AJ051610U03     I1 @T6G_MB_LIB.T6G(SCH_1):PAGE427

P5E_CPU0_P3_RX_DN<11> @T6G_MB_LIB.T6G(SCH_1):P5E_CPU0_P3_RX_DN(11)
   U25 DA27 P3_RXN11 GENOA_SP5-SOCKET6096_13568-001,SMLF,IO,DGA^6000030   I148 @T6G_MB_LIB.T6G(SCH_1):PAGE25
 U6013 BB29 A_PETN4 PT5161LRS-PT5161LRS,SMLF,IC,AJ051610U03     I1 @T6G_MB_LIB.T6G(SCH_1):PAGE427

P5E_CPU0_P3_RX_DN<12> @T6G_MB_LIB.T6G(SCH_1):P5E_CPU0_P3_RX_DN(12)
   U25 CW24 P3_RXN12 GENOA_SP5-SOCKET6096_13568-001,SMLF,IO,DGA^6000030   I148 @T6G_MB_LIB.T6G(SCH_1):PAGE25
 U6013 AR29 A_PETN3 PT5161LRS-PT5161LRS,SMLF,IC,AJ051610U03     I1 @T6G_MB_LIB.T6G(SCH_1):PAGE427

P5E_CPU0_P3_RX_DN<13> @T6G_MB_LIB.T6G(SCH_1):P5E_CPU0_P3_RX_DN(13)
   U25 DC24 P3_RXN13 GENOA_SP5-SOCKET6096_13568-001,SMLF,IO,DGA^6000030   I148 @T6G_MB_LIB.T6G(SCH_1):PAGE25
 U6013 AH29 A_PETN2 PT5161LRS-PT5161LRS,SMLF,IC,AJ051610U03     I1 @T6G_MB_LIB.T6G(SCH_1):PAGE427

P5E_CPU0_P3_RX_DN<14> @T6G_MB_LIB.T6G(SCH_1):P5E_CPU0_P3_RX_DN(14)
   U25 DA24 P3_RXN14 GENOA_SP5-SOCKET6096_13568-001,SMLF,IO,DGA^6000030   I148 @T6G_MB_LIB.T6G(SCH_1):PAGE25
 U6013 AA29 A_PETN1 PT5161LRS-PT5161LRS,SMLF,IC,AJ051610U03     I1 @T6G_MB_LIB.T6G(SCH_1):PAGE427

P5E_CPU0_P3_RX_DN<15> @T6G_MB_LIB.T6G(SCH_1):P5E_CPU0_P3_RX_DN(15)
   U25 CU24 P3_RXN15 GENOA_SP5-SOCKET6096_13568-001,SMLF,IO,DGA^6000030   I148 @T6G_MB_LIB.T6G(SCH_1):PAGE25
 U6013  P29 A_PETN0 PT5161LRS-PT5161LRS,SMLF,IC,AJ051610U03     I1 @T6G_MB_LIB.T6G(SCH_1):PAGE427

P5E_CPU0_P3_RX_DN<1> @T6G_MB_LIB.T6G(SCH_1):P5E_CPU0_P3_RX_DN(1)
   U25 CY36 P3_RXN1 GENOA_SP5-SOCKET6096_13568-001,SMLF,IO,DGA^6000030   I148 @T6G_MB_LIB.T6G(SCH_1):PAGE25
 U6013 EM29 A_PETN14 PT5161LRS-PT5161LRS,SMLF,IC,AJ051610U03    I38 @T6G_MB_LIB.T6G(SCH_1):PAGE427

P5E_CPU0_P3_RX_DN<2> @T6G_MB_LIB.T6G(SCH_1):P5E_CPU0_P3_RX_DN(2)
   U25 DB36 P3_RXN2 GENOA_SP5-SOCKET6096_13568-001,SMLF,IO,DGA^6000030   I148 @T6G_MB_LIB.T6G(SCH_1):PAGE25
 U6013 EE29 A_PETN13 PT5161LRS-PT5161LRS,SMLF,IC,AJ051610U03    I38 @T6G_MB_LIB.T6G(SCH_1):PAGE427

P5E_CPU0_P3_RX_DN<3> @T6G_MB_LIB.T6G(SCH_1):P5E_CPU0_P3_RX_DN(3)
   U25 CW33 P3_RXN3 GENOA_SP5-SOCKET6096_13568-001,SMLF,IO,DGA^6000030   I148 @T6G_MB_LIB.T6G(SCH_1):PAGE25
 U6013 DV29 A_PETN12 PT5161LRS-PT5161LRS,SMLF,IC,AJ051610U03    I38 @T6G_MB_LIB.T6G(SCH_1):PAGE427

P5E_CPU0_P3_RX_DN<4> @T6G_MB_LIB.T6G(SCH_1):P5E_CPU0_P3_RX_DN(4)
   U25 DC33 P3_RXN4 GENOA_SP5-SOCKET6096_13568-001,SMLF,IO,DGA^6000030   I148 @T6G_MB_LIB.T6G(SCH_1):PAGE25
 U6013 DL29 A_PETN11 PT5161LRS-PT5161LRS,SMLF,IC,AJ051610U03    I38 @T6G_MB_LIB.T6G(SCH_1):PAGE427

P5E_CPU0_P3_RX_DN<5> @T6G_MB_LIB.T6G(SCH_1):P5E_CPU0_P3_RX_DN(5)
   U25 DA33 P3_RXN5 GENOA_SP5-SOCKET6096_13568-001,SMLF,IO,DGA^6000030   I148 @T6G_MB_LIB.T6G(SCH_1):PAGE25
 U6013 DD29 A_PETN10 PT5161LRS-PT5161LRS,SMLF,IC,AJ051610U03    I38 @T6G_MB_LIB.T6G(SCH_1):PAGE427

P5E_CPU0_P3_RX_DN<6> @T6G_MB_LIB.T6G(SCH_1):P5E_CPU0_P3_RX_DN(6)
   U25 CW30 P3_RXN6 GENOA_SP5-SOCKET6096_13568-001,SMLF,IO,DGA^6000030   I148 @T6G_MB_LIB.T6G(SCH_1):PAGE25
 U6013 CU29 A_PETN9 PT5161LRS-PT5161LRS,SMLF,IC,AJ051610U03    I38 @T6G_MB_LIB.T6G(SCH_1):PAGE427

P5E_CPU0_P3_RX_DN<7> @T6G_MB_LIB.T6G(SCH_1):P5E_CPU0_P3_RX_DN(7)
   U25 DC30 P3_RXN7 GENOA_SP5-SOCKET6096_13568-001,SMLF,IO,DGA^6000030   I148 @T6G_MB_LIB.T6G(SCH_1):PAGE25
 U6013 CK29 A_PETN8 PT5161LRS-PT5161LRS,SMLF,IC,AJ051610U03    I38 @T6G_MB_LIB.T6G(SCH_1):PAGE427

P5E_CPU0_P3_RX_DN<8> @T6G_MB_LIB.T6G(SCH_1):P5E_CPU0_P3_RX_DN(8)
   U25 DA30 P3_RXN8 GENOA_SP5-SOCKET6096_13568-001,SMLF,IO,DGA^6000030   I148 @T6G_MB_LIB.T6G(SCH_1):PAGE25
 U6013 CC29 A_PETN7 PT5161LRS-PT5161LRS,SMLF,IC,AJ051610U03     I1 @T6G_MB_LIB.T6G(SCH_1):PAGE427

P5E_CPU0_P3_RX_DN<9> @T6G_MB_LIB.T6G(SCH_1):P5E_CPU0_P3_RX_DN(9)
   U25 CW27 P3_RXN9 GENOA_SP5-SOCKET6096_13568-001,SMLF,IO,DGA^6000030   I148 @T6G_MB_LIB.T6G(SCH_1):PAGE25
 U6013 BT29 A_PETN6 PT5161LRS-PT5161LRS,SMLF,IC,AJ051610U03     I1 @T6G_MB_LIB.T6G(SCH_1):PAGE427

P5E_CPU0_P3_RX_DP<0> @T6G_MB_LIB.T6G(SCH_1):P5E_CPU0_P3_RX_DP(0)
   U25 CV35 P3_RXP0 GENOA_SP5-SOCKET6096_13568-001,SMLF,IO,DGA^6000030   I148 @T6G_MB_LIB.T6G(SCH_1):PAGE25
 U6013 EU26 A_PETP15 PT5161LRS-PT5161LRS,SMLF,IC,AJ051610U03    I38 @T6G_MB_LIB.T6G(SCH_1):PAGE427

P5E_CPU0_P3_RX_DP<10> @T6G_MB_LIB.T6G(SCH_1):P5E_CPU0_P3_RX_DP(10)
   U25 DC26 P3_RXP10 GENOA_SP5-SOCKET6096_13568-001,SMLF,IO,DGA^6000030   I148 @T6G_MB_LIB.T6G(SCH_1):PAGE25
 U6013 BG26 A_PETP5 PT5161LRS-PT5161LRS,SMLF,IC,AJ051610U03     I1 @T6G_MB_LIB.T6G(SCH_1):PAGE427

P5E_CPU0_P3_RX_DP<11> @T6G_MB_LIB.T6G(SCH_1):P5E_CPU0_P3_RX_DP(11)
   U25 DA26 P3_RXP11 GENOA_SP5-SOCKET6096_13568-001,SMLF,IO,DGA^6000030   I148 @T6G_MB_LIB.T6G(SCH_1):PAGE25
 U6013 AY26 A_PETP4 PT5161LRS-PT5161LRS,SMLF,IC,AJ051610U03     I1 @T6G_MB_LIB.T6G(SCH_1):PAGE427

P5E_CPU0_P3_RX_DP<12> @T6G_MB_LIB.T6G(SCH_1):P5E_CPU0_P3_RX_DP(12)
   U25 CW23 P3_RXP12 GENOA_SP5-SOCKET6096_13568-001,SMLF,IO,DGA^6000030   I148 @T6G_MB_LIB.T6G(SCH_1):PAGE25
 U6013 AN26 A_PETP3 PT5161LRS-PT5161LRS,SMLF,IC,AJ051610U03     I1 @T6G_MB_LIB.T6G(SCH_1):PAGE427

P5E_CPU0_P3_RX_DP<13> @T6G_MB_LIB.T6G(SCH_1):P5E_CPU0_P3_RX_DP(13)
   U25 DC23 P3_RXP13 GENOA_SP5-SOCKET6096_13568-001,SMLF,IO,DGA^6000030   I148 @T6G_MB_LIB.T6G(SCH_1):PAGE25
 U6013 AF26 A_PETP2 PT5161LRS-PT5161LRS,SMLF,IC,AJ051610U03     I1 @T6G_MB_LIB.T6G(SCH_1):PAGE427

P5E_CPU0_P3_RX_DP<14> @T6G_MB_LIB.T6G(SCH_1):P5E_CPU0_P3_RX_DP(14)
   U25 DA23 P3_RXP14 GENOA_SP5-SOCKET6096_13568-001,SMLF,IO,DGA^6000030   I148 @T6G_MB_LIB.T6G(SCH_1):PAGE25
 U6013  W26 A_PETP1 PT5161LRS-PT5161LRS,SMLF,IC,AJ051610U03     I1 @T6G_MB_LIB.T6G(SCH_1):PAGE427

P5E_CPU0_P3_RX_DP<15> @T6G_MB_LIB.T6G(SCH_1):P5E_CPU0_P3_RX_DP(15)
   U25 CU23 P3_RXP15 GENOA_SP5-SOCKET6096_13568-001,SMLF,IO,DGA^6000030   I148 @T6G_MB_LIB.T6G(SCH_1):PAGE25
 U6013  M26 A_PETP0 PT5161LRS-PT5161LRS,SMLF,IC,AJ051610U03     I1 @T6G_MB_LIB.T6G(SCH_1):PAGE427

P5E_CPU0_P3_RX_DP<1> @T6G_MB_LIB.T6G(SCH_1):P5E_CPU0_P3_RX_DP(1)
   U25 CY35 P3_RXP1 GENOA_SP5-SOCKET6096_13568-001,SMLF,IO,DGA^6000030   I148 @T6G_MB_LIB.T6G(SCH_1):PAGE25
 U6013 EK26 A_PETP14 PT5161LRS-PT5161LRS,SMLF,IC,AJ051610U03    I38 @T6G_MB_LIB.T6G(SCH_1):PAGE427

P5E_CPU0_P3_RX_DP<2> @T6G_MB_LIB.T6G(SCH_1):P5E_CPU0_P3_RX_DP(2)
   U25 DB35 P3_RXP2 GENOA_SP5-SOCKET6096_13568-001,SMLF,IO,DGA^6000030   I148 @T6G_MB_LIB.T6G(SCH_1):PAGE25
 U6013 EC26 A_PETP13 PT5161LRS-PT5161LRS,SMLF,IC,AJ051610U03    I38 @T6G_MB_LIB.T6G(SCH_1):PAGE427

P5E_CPU0_P3_RX_DP<3> @T6G_MB_LIB.T6G(SCH_1):P5E_CPU0_P3_RX_DP(3)
   U25 CW32 P3_RXP3 GENOA_SP5-SOCKET6096_13568-001,SMLF,IO,DGA^6000030   I148 @T6G_MB_LIB.T6G(SCH_1):PAGE25
 U6013 DT26 A_PETP12 PT5161LRS-PT5161LRS,SMLF,IC,AJ051610U03    I38 @T6G_MB_LIB.T6G(SCH_1):PAGE427

P5E_CPU0_P3_RX_DP<4> @T6G_MB_LIB.T6G(SCH_1):P5E_CPU0_P3_RX_DP(4)
   U25 DC32 P3_RXP4 GENOA_SP5-SOCKET6096_13568-001,SMLF,IO,DGA^6000030   I148 @T6G_MB_LIB.T6G(SCH_1):PAGE25
 U6013 DJ26 A_PETP11 PT5161LRS-PT5161LRS,SMLF,IC,AJ051610U03    I38 @T6G_MB_LIB.T6G(SCH_1):PAGE427

P5E_CPU0_P3_RX_DP<5> @T6G_MB_LIB.T6G(SCH_1):P5E_CPU0_P3_RX_DP(5)
   U25 DA32 P3_RXP5 GENOA_SP5-SOCKET6096_13568-001,SMLF,IO,DGA^6000030   I148 @T6G_MB_LIB.T6G(SCH_1):PAGE25
 U6013 DB26 A_PETP10 PT5161LRS-PT5161LRS,SMLF,IC,AJ051610U03    I38 @T6G_MB_LIB.T6G(SCH_1):PAGE427

P5E_CPU0_P3_RX_DP<6> @T6G_MB_LIB.T6G(SCH_1):P5E_CPU0_P3_RX_DP(6)
   U25 CW29 P3_RXP6 GENOA_SP5-SOCKET6096_13568-001,SMLF,IO,DGA^6000030   I148 @T6G_MB_LIB.T6G(SCH_1):PAGE25
 U6013 CR26 A_PETP9 PT5161LRS-PT5161LRS,SMLF,IC,AJ051610U03    I38 @T6G_MB_LIB.T6G(SCH_1):PAGE427

P5E_CPU0_P3_RX_DP<7> @T6G_MB_LIB.T6G(SCH_1):P5E_CPU0_P3_RX_DP(7)
   U25 DC29 P3_RXP7 GENOA_SP5-SOCKET6096_13568-001,SMLF,IO,DGA^6000030   I148 @T6G_MB_LIB.T6G(SCH_1):PAGE25
 U6013 CH26 A_PETP8 PT5161LRS-PT5161LRS,SMLF,IC,AJ051610U03    I38 @T6G_MB_LIB.T6G(SCH_1):PAGE427

P5E_CPU0_P3_RX_DP<8> @T6G_MB_LIB.T6G(SCH_1):P5E_CPU0_P3_RX_DP(8)
   U25 DA29 P3_RXP8 GENOA_SP5-SOCKET6096_13568-001,SMLF,IO,DGA^6000030   I148 @T6G_MB_LIB.T6G(SCH_1):PAGE25
 U6013 CA26 A_PETP7 PT5161LRS-PT5161LRS,SMLF,IC,AJ051610U03     I1 @T6G_MB_LIB.T6G(SCH_1):PAGE427

P5E_CPU0_P3_RX_DP<9> @T6G_MB_LIB.T6G(SCH_1):P5E_CPU0_P3_RX_DP(9)
   U25 CW26 P3_RXP9 GENOA_SP5-SOCKET6096_13568-001,SMLF,IO,DGA^6000030   I148 @T6G_MB_LIB.T6G(SCH_1):PAGE25
 U6013 BP26 A_PETP6 PT5161LRS-PT5161LRS,SMLF,IC,AJ051610U03     I1 @T6G_MB_LIB.T6G(SCH_1):PAGE427

P5E_CPU0_P3_TX_BUF_C_DN<0> @T6G_MB_LIB.T6G(SCH_1):P5E_CPU0_P3_TX_BUF_C_DN(0)
 C6598    1      1 Q_CAP_DIFFBUS_C0201-DIFF BUS_0.22UF,6.3V,20%,X6S,SA    I39 @T6G_MB_LIB.T6G(SCH_1):PAGE429
  J106   L1     L1 CONN112_10137002101LF-CONN112_10137002-101LF,THLF,A    I74 @T6G_MB_LIB.T6G(SCH_1):PAGE327

P5E_CPU0_P3_TX_BUF_C_DN<10> @T6G_MB_LIB.T6G(SCH_1):P5E_CPU0_P3_TX_BUF_C_DN(10)
 C6618    1      1 Q_CAP_DIFFBUS_C0201-DIFF BUS_0.22UF,6.3V,20%,X6S,SA    I99 @T6G_MB_LIB.T6G(SCH_1):PAGE429
  J105   L3     L3 CONN112_10137002101LF-CONN112_10137002-101LF,THLF,A    I75 @T6G_MB_LIB.T6G(SCH_1):PAGE326

P5E_CPU0_P3_TX_BUF_C_DN<11> @T6G_MB_LIB.T6G(SCH_1):P5E_CPU0_P3_TX_BUF_C_DN(11)
 C6620    1      1 Q_CAP_DIFFBUS_C0201-DIFF BUS_0.22UF,6.3V,20%,X6S,SA    I98 @T6G_MB_LIB.T6G(SCH_1):PAGE429
  J105   K4     K4 CONN112_10137002101LF-CONN112_10137002-101LF,THLF,A    I75 @T6G_MB_LIB.T6G(SCH_1):PAGE326

P5E_CPU0_P3_TX_BUF_C_DN<12> @T6G_MB_LIB.T6G(SCH_1):P5E_CPU0_P3_TX_BUF_C_DN(12)
 C6622    1      1 Q_CAP_DIFFBUS_C0201-DIFF BUS_0.22UF,6.3V,20%,X6S,SA    I97 @T6G_MB_LIB.T6G(SCH_1):PAGE429
  J105   L5     L5 CONN112_10137002101LF-CONN112_10137002-101LF,THLF,A    I76 @T6G_MB_LIB.T6G(SCH_1):PAGE326

P5E_CPU0_P3_TX_BUF_C_DN<13> @T6G_MB_LIB.T6G(SCH_1):P5E_CPU0_P3_TX_BUF_C_DN(13)
 C6624    1      1 Q_CAP_DIFFBUS_C0201-DIFF BUS_0.22UF,6.3V,20%,X6S,SA    I95 @T6G_MB_LIB.T6G(SCH_1):PAGE429
  J105   K6     K6 CONN112_10137002101LF-CONN112_10137002-101LF,THLF,A    I76 @T6G_MB_LIB.T6G(SCH_1):PAGE326

P5E_CPU0_P3_TX_BUF_C_DN<14> @T6G_MB_LIB.T6G(SCH_1):P5E_CPU0_P3_TX_BUF_C_DN(14)
 C6626    1      1 Q_CAP_DIFFBUS_C0201-DIFF BUS_0.22UF,6.3V,20%,X6S,SA    I92 @T6G_MB_LIB.T6G(SCH_1):PAGE429
  J105   L7     L7 CONN112_10137002101LF-CONN112_10137002-101LF,THLF,A    I76 @T6G_MB_LIB.T6G(SCH_1):PAGE326

P5E_CPU0_P3_TX_BUF_C_DN<15> @T6G_MB_LIB.T6G(SCH_1):P5E_CPU0_P3_TX_BUF_C_DN(15)
 C6628    1      1 Q_CAP_DIFFBUS_C0201-DIFF BUS_0.22UF,6.3V,20%,X6S,SA    I90 @T6G_MB_LIB.T6G(SCH_1):PAGE429
  J105   K8     K8 CONN112_10137002101LF-CONN112_10137002-101LF,THLF,A    I76 @T6G_MB_LIB.T6G(SCH_1):PAGE326

P5E_CPU0_P3_TX_BUF_C_DN<1> @T6G_MB_LIB.T6G(SCH_1):P5E_CPU0_P3_TX_BUF_C_DN(1)
 C6600    1      1 Q_CAP_DIFFBUS_C0201-DIFF BUS_0.22UF,6.3V,20%,X6S,SA    I37 @T6G_MB_LIB.T6G(SCH_1):PAGE429
  J106   K2     K2 CONN112_10137002101LF-CONN112_10137002-101LF,THLF,A    I74 @T6G_MB_LIB.T6G(SCH_1):PAGE327

P5E_CPU0_P3_TX_BUF_C_DN<2> @T6G_MB_LIB.T6G(SCH_1):P5E_CPU0_P3_TX_BUF_C_DN(2)
 C6602    1      1 Q_CAP_DIFFBUS_C0201-DIFF BUS_0.22UF,6.3V,20%,X6S,SA    I35 @T6G_MB_LIB.T6G(SCH_1):PAGE429
  J106   L3     L3 CONN112_10137002101LF-CONN112_10137002-101LF,THLF,A    I74 @T6G_MB_LIB.T6G(SCH_1):PAGE327

P5E_CPU0_P3_TX_BUF_C_DN<3> @T6G_MB_LIB.T6G(SCH_1):P5E_CPU0_P3_TX_BUF_C_DN(3)
 C6604    1      1 Q_CAP_DIFFBUS_C0201-DIFF BUS_0.22UF,6.3V,20%,X6S,SA    I33 @T6G_MB_LIB.T6G(SCH_1):PAGE429
  J106   K4     K4 CONN112_10137002101LF-CONN112_10137002-101LF,THLF,A    I74 @T6G_MB_LIB.T6G(SCH_1):PAGE327

P5E_CPU0_P3_TX_BUF_C_DN<4> @T6G_MB_LIB.T6G(SCH_1):P5E_CPU0_P3_TX_BUF_C_DN(4)
 C6606    1      1 Q_CAP_DIFFBUS_C0201-DIFF BUS_0.22UF,6.3V,20%,X6S,SA    I31 @T6G_MB_LIB.T6G(SCH_1):PAGE429
  J106   L5     L5 CONN112_10137002101LF-CONN112_10137002-101LF,THLF,A    I19 @T6G_MB_LIB.T6G(SCH_1):PAGE327

P5E_CPU0_P3_TX_BUF_C_DN<5> @T6G_MB_LIB.T6G(SCH_1):P5E_CPU0_P3_TX_BUF_C_DN(5)
 C6608    1      1 Q_CAP_DIFFBUS_C0201-DIFF BUS_0.22UF,6.3V,20%,X6S,SA    I23 @T6G_MB_LIB.T6G(SCH_1):PAGE429
  J106   K6     K6 CONN112_10137002101LF-CONN112_10137002-101LF,THLF,A    I19 @T6G_MB_LIB.T6G(SCH_1):PAGE327

P5E_CPU0_P3_TX_BUF_C_DN<6> @T6G_MB_LIB.T6G(SCH_1):P5E_CPU0_P3_TX_BUF_C_DN(6)
 C6610    1      1 Q_CAP_DIFFBUS_C0201-DIFF BUS_0.22UF,6.3V,20%,X6S,SA    I21 @T6G_MB_LIB.T6G(SCH_1):PAGE429
  J106   L7     L7 CONN112_10137002101LF-CONN112_10137002-101LF,THLF,A    I19 @T6G_MB_LIB.T6G(SCH_1):PAGE327

P5E_CPU0_P3_TX_BUF_C_DN<7> @T6G_MB_LIB.T6G(SCH_1):P5E_CPU0_P3_TX_BUF_C_DN(7)
 C6612    1      1 Q_CAP_DIFFBUS_C0201-DIFF BUS_0.22UF,6.3V,20%,X6S,SA    I20 @T6G_MB_LIB.T6G(SCH_1):PAGE429
  J106   K8     K8 CONN112_10137002101LF-CONN112_10137002-101LF,THLF,A    I19 @T6G_MB_LIB.T6G(SCH_1):PAGE327

P5E_CPU0_P3_TX_BUF_C_DN<8> @T6G_MB_LIB.T6G(SCH_1):P5E_CPU0_P3_TX_BUF_C_DN(8)
 C6614    1      1 Q_CAP_DIFFBUS_C0201-DIFF BUS_0.22UF,6.3V,20%,X6S,SA   I104 @T6G_MB_LIB.T6G(SCH_1):PAGE429
  J105   L1     L1 CONN112_10137002101LF-CONN112_10137002-101LF,THLF,A    I75 @T6G_MB_LIB.T6G(SCH_1):PAGE326

P5E_CPU0_P3_TX_BUF_C_DN<9> @T6G_MB_LIB.T6G(SCH_1):P5E_CPU0_P3_TX_BUF_C_DN(9)
 C6616    1      1 Q_CAP_DIFFBUS_C0201-DIFF BUS_0.22UF,6.3V,20%,X6S,SA   I103 @T6G_MB_LIB.T6G(SCH_1):PAGE429
  J105   K2     K2 CONN112_10137002101LF-CONN112_10137002-101LF,THLF,A    I75 @T6G_MB_LIB.T6G(SCH_1):PAGE326

P5E_CPU0_P3_TX_BUF_C_DP<0> @T6G_MB_LIB.T6G(SCH_1):P5E_CPU0_P3_TX_BUF_C_DP(0)
 C6597    1      1 Q_CAP_DIFFBUS_C0201-DIFF BUS_0.22UF,6.3V,20%,X6S,SA    I40 @T6G_MB_LIB.T6G(SCH_1):PAGE429
  J106   M1     M1 CONN112_10137002101LF-CONN112_10137002-101LF,THLF,A    I74 @T6G_MB_LIB.T6G(SCH_1):PAGE327

P5E_CPU0_P3_TX_BUF_C_DP<10> @T6G_MB_LIB.T6G(SCH_1):P5E_CPU0_P3_TX_BUF_C_DP(10)
 C6617    1      1 Q_CAP_DIFFBUS_C0201-DIFF BUS_0.22UF,6.3V,20%,X6S,SA   I101 @T6G_MB_LIB.T6G(SCH_1):PAGE429
  J105   M3     M3 CONN112_10137002101LF-CONN112_10137002-101LF,THLF,A    I75 @T6G_MB_LIB.T6G(SCH_1):PAGE326

P5E_CPU0_P3_TX_BUF_C_DP<11> @T6G_MB_LIB.T6G(SCH_1):P5E_CPU0_P3_TX_BUF_C_DP(11)
 C6619    1      1 Q_CAP_DIFFBUS_C0201-DIFF BUS_0.22UF,6.3V,20%,X6S,SA   I100 @T6G_MB_LIB.T6G(SCH_1):PAGE429
  J105   L4     L4 CONN112_10137002101LF-CONN112_10137002-101LF,THLF,A    I75 @T6G_MB_LIB.T6G(SCH_1):PAGE326

P5E_CPU0_P3_TX_BUF_C_DP<12> @T6G_MB_LIB.T6G(SCH_1):P5E_CPU0_P3_TX_BUF_C_DP(12)
 C6621    1      1 Q_CAP_DIFFBUS_C0201-DIFF BUS_0.22UF,6.3V,20%,X6S,SA    I96 @T6G_MB_LIB.T6G(SCH_1):PAGE429
  J105   M5     M5 CONN112_10137002101LF-CONN112_10137002-101LF,THLF,A    I76 @T6G_MB_LIB.T6G(SCH_1):PAGE326

P5E_CPU0_P3_TX_BUF_C_DP<13> @T6G_MB_LIB.T6G(SCH_1):P5E_CPU0_P3_TX_BUF_C_DP(13)
 C6623    1      1 Q_CAP_DIFFBUS_C0201-DIFF BUS_0.22UF,6.3V,20%,X6S,SA    I94 @T6G_MB_LIB.T6G(SCH_1):PAGE429
  J105   L6     L6 CONN112_10137002101LF-CONN112_10137002-101LF,THLF,A    I76 @T6G_MB_LIB.T6G(SCH_1):PAGE326

P5E_CPU0_P3_TX_BUF_C_DP<14> @T6G_MB_LIB.T6G(SCH_1):P5E_CPU0_P3_TX_BUF_C_DP(14)
 C6625    1      1 Q_CAP_DIFFBUS_C0201-DIFF BUS_0.22UF,6.3V,20%,X6S,SA    I91 @T6G_MB_LIB.T6G(SCH_1):PAGE429
  J105   M7     M7 CONN112_10137002101LF-CONN112_10137002-101LF,THLF,A    I76 @T6G_MB_LIB.T6G(SCH_1):PAGE326

P5E_CPU0_P3_TX_BUF_C_DP<15> @T6G_MB_LIB.T6G(SCH_1):P5E_CPU0_P3_TX_BUF_C_DP(15)
 C6627    1      1 Q_CAP_DIFFBUS_C0201-DIFF BUS_0.22UF,6.3V,20%,X6S,SA    I93 @T6G_MB_LIB.T6G(SCH_1):PAGE429
  J105   L8     L8 CONN112_10137002101LF-CONN112_10137002-101LF,THLF,A    I76 @T6G_MB_LIB.T6G(SCH_1):PAGE326

P5E_CPU0_P3_TX_BUF_C_DP<1> @T6G_MB_LIB.T6G(SCH_1):P5E_CPU0_P3_TX_BUF_C_DP(1)
 C6599    1      1 Q_CAP_DIFFBUS_C0201-DIFF BUS_0.22UF,6.3V,20%,X6S,SA    I38 @T6G_MB_LIB.T6G(SCH_1):PAGE429
  J106   L2     L2 CONN112_10137002101LF-CONN112_10137002-101LF,THLF,A    I74 @T6G_MB_LIB.T6G(SCH_1):PAGE327

P5E_CPU0_P3_TX_BUF_C_DP<2> @T6G_MB_LIB.T6G(SCH_1):P5E_CPU0_P3_TX_BUF_C_DP(2)
 C6601    1      1 Q_CAP_DIFFBUS_C0201-DIFF BUS_0.22UF,6.3V,20%,X6S,SA    I36 @T6G_MB_LIB.T6G(SCH_1):PAGE429
  J106   M3     M3 CONN112_10137002101LF-CONN112_10137002-101LF,THLF,A    I74 @T6G_MB_LIB.T6G(SCH_1):PAGE327

P5E_CPU0_P3_TX_BUF_C_DP<3> @T6G_MB_LIB.T6G(SCH_1):P5E_CPU0_P3_TX_BUF_C_DP(3)
 C6603    1      1 Q_CAP_DIFFBUS_C0201-DIFF BUS_0.22UF,6.3V,20%,X6S,SA    I34 @T6G_MB_LIB.T6G(SCH_1):PAGE429
  J106   L4     L4 CONN112_10137002101LF-CONN112_10137002-101LF,THLF,A    I74 @T6G_MB_LIB.T6G(SCH_1):PAGE327

P5E_CPU0_P3_TX_BUF_C_DP<4> @T6G_MB_LIB.T6G(SCH_1):P5E_CPU0_P3_TX_BUF_C_DP(4)
 C6605    1      1 Q_CAP_DIFFBUS_C0201-DIFF BUS_0.22UF,6.3V,20%,X6S,SA    I32 @T6G_MB_LIB.T6G(SCH_1):PAGE429
  J106   M5     M5 CONN112_10137002101LF-CONN112_10137002-101LF,THLF,A    I19 @T6G_MB_LIB.T6G(SCH_1):PAGE327

P5E_CPU0_P3_TX_BUF_C_DP<5> @T6G_MB_LIB.T6G(SCH_1):P5E_CPU0_P3_TX_BUF_C_DP(5)
 C6607    1      1 Q_CAP_DIFFBUS_C0201-DIFF BUS_0.22UF,6.3V,20%,X6S,SA    I24 @T6G_MB_LIB.T6G(SCH_1):PAGE429
  J106   L6     L6 CONN112_10137002101LF-CONN112_10137002-101LF,THLF,A    I19 @T6G_MB_LIB.T6G(SCH_1):PAGE327

P5E_CPU0_P3_TX_BUF_C_DP<6> @T6G_MB_LIB.T6G(SCH_1):P5E_CPU0_P3_TX_BUF_C_DP(6)
 C6609    1      1 Q_CAP_DIFFBUS_C0201-DIFF BUS_0.22UF,6.3V,20%,X6S,SA    I22 @T6G_MB_LIB.T6G(SCH_1):PAGE429
  J106   M7     M7 CONN112_10137002101LF-CONN112_10137002-101LF,THLF,A    I19 @T6G_MB_LIB.T6G(SCH_1):PAGE327

P5E_CPU0_P3_TX_BUF_C_DP<7> @T6G_MB_LIB.T6G(SCH_1):P5E_CPU0_P3_TX_BUF_C_DP(7)
 C6611    1      1 Q_CAP_DIFFBUS_C0201-DIFF BUS_0.22UF,6.3V,20%,X6S,SA    I19 @T6G_MB_LIB.T6G(SCH_1):PAGE429
  J106   L8     L8 CONN112_10137002101LF-CONN112_10137002-101LF,THLF,A    I19 @T6G_MB_LIB.T6G(SCH_1):PAGE327

P5E_CPU0_P3_TX_BUF_C_DP<8> @T6G_MB_LIB.T6G(SCH_1):P5E_CPU0_P3_TX_BUF_C_DP(8)
 C6613    1      1 Q_CAP_DIFFBUS_C0201-DIFF BUS_0.22UF,6.3V,20%,X6S,SA   I105 @T6G_MB_LIB.T6G(SCH_1):PAGE429
  J105   M1     M1 CONN112_10137002101LF-CONN112_10137002-101LF,THLF,A    I75 @T6G_MB_LIB.T6G(SCH_1):PAGE326

P5E_CPU0_P3_TX_BUF_C_DP<9> @T6G_MB_LIB.T6G(SCH_1):P5E_CPU0_P3_TX_BUF_C_DP(9)
 C6615    1      1 Q_CAP_DIFFBUS_C0201-DIFF BUS_0.22UF,6.3V,20%,X6S,SA   I102 @T6G_MB_LIB.T6G(SCH_1):PAGE429
  J105   L2     L2 CONN112_10137002101LF-CONN112_10137002-101LF,THLF,A    I75 @T6G_MB_LIB.T6G(SCH_1):PAGE326

P5E_CPU0_P3_TX_BUF_DN<0> @T6G_MB_LIB.T6G(SCH_1):P5E_CPU0_P3_TX_BUF_DN(0)
 C6598    2      2 Q_CAP_DIFFBUS_C0201-DIFF BUS_0.22UF,6.3V,20%,X6S,SA    I39 @T6G_MB_LIB.T6G(SCH_1):PAGE429
 U6013 EW10 B_PETN15 PT5161LRS-PT5161LRS,SMLF,IC,AJ051610U03   I142 @T6G_MB_LIB.T6G(SCH_1):PAGE429

P5E_CPU0_P3_TX_BUF_DN<10> @T6G_MB_LIB.T6G(SCH_1):P5E_CPU0_P3_TX_BUF_DN(10)
 U6013 BJ10 B_PETN5 PT5161LRS-PT5161LRS,SMLF,IC,AJ051610U03    I51 @T6G_MB_LIB.T6G(SCH_1):PAGE429
 C6618    2      2 Q_CAP_DIFFBUS_C0201-DIFF BUS_0.22UF,6.3V,20%,X6S,SA    I99 @T6G_MB_LIB.T6G(SCH_1):PAGE429

P5E_CPU0_P3_TX_BUF_DN<11> @T6G_MB_LIB.T6G(SCH_1):P5E_CPU0_P3_TX_BUF_DN(11)
 U6013 BB10 B_PETN4 PT5161LRS-PT5161LRS,SMLF,IC,AJ051610U03    I51 @T6G_MB_LIB.T6G(SCH_1):PAGE429
 C6620    2      2 Q_CAP_DIFFBUS_C0201-DIFF BUS_0.22UF,6.3V,20%,X6S,SA    I98 @T6G_MB_LIB.T6G(SCH_1):PAGE429

P5E_CPU0_P3_TX_BUF_DN<12> @T6G_MB_LIB.T6G(SCH_1):P5E_CPU0_P3_TX_BUF_DN(12)
 U6013 AR10 B_PETN3 PT5161LRS-PT5161LRS,SMLF,IC,AJ051610U03    I51 @T6G_MB_LIB.T6G(SCH_1):PAGE429
 C6622    2      2 Q_CAP_DIFFBUS_C0201-DIFF BUS_0.22UF,6.3V,20%,X6S,SA    I97 @T6G_MB_LIB.T6G(SCH_1):PAGE429

P5E_CPU0_P3_TX_BUF_DN<13> @T6G_MB_LIB.T6G(SCH_1):P5E_CPU0_P3_TX_BUF_DN(13)
 U6013 AH10 B_PETN2 PT5161LRS-PT5161LRS,SMLF,IC,AJ051610U03    I51 @T6G_MB_LIB.T6G(SCH_1):PAGE429
 C6624    2      2 Q_CAP_DIFFBUS_C0201-DIFF BUS_0.22UF,6.3V,20%,X6S,SA    I95 @T6G_MB_LIB.T6G(SCH_1):PAGE429

P5E_CPU0_P3_TX_BUF_DN<14> @T6G_MB_LIB.T6G(SCH_1):P5E_CPU0_P3_TX_BUF_DN(14)
 U6013 AA10 B_PETN1 PT5161LRS-PT5161LRS,SMLF,IC,AJ051610U03    I51 @T6G_MB_LIB.T6G(SCH_1):PAGE429
 C6626    2      2 Q_CAP_DIFFBUS_C0201-DIFF BUS_0.22UF,6.3V,20%,X6S,SA    I92 @T6G_MB_LIB.T6G(SCH_1):PAGE429

P5E_CPU0_P3_TX_BUF_DN<15> @T6G_MB_LIB.T6G(SCH_1):P5E_CPU0_P3_TX_BUF_DN(15)
 U6013  P10 B_PETN0 PT5161LRS-PT5161LRS,SMLF,IC,AJ051610U03    I51 @T6G_MB_LIB.T6G(SCH_1):PAGE429
 C6628    2      2 Q_CAP_DIFFBUS_C0201-DIFF BUS_0.22UF,6.3V,20%,X6S,SA    I90 @T6G_MB_LIB.T6G(SCH_1):PAGE429

P5E_CPU0_P3_TX_BUF_DN<1> @T6G_MB_LIB.T6G(SCH_1):P5E_CPU0_P3_TX_BUF_DN(1)
 C6600    2      2 Q_CAP_DIFFBUS_C0201-DIFF BUS_0.22UF,6.3V,20%,X6S,SA    I37 @T6G_MB_LIB.T6G(SCH_1):PAGE429
 U6013 EM10 B_PETN14 PT5161LRS-PT5161LRS,SMLF,IC,AJ051610U03   I142 @T6G_MB_LIB.T6G(SCH_1):PAGE429

P5E_CPU0_P3_TX_BUF_DN<2> @T6G_MB_LIB.T6G(SCH_1):P5E_CPU0_P3_TX_BUF_DN(2)
 C6602    2      2 Q_CAP_DIFFBUS_C0201-DIFF BUS_0.22UF,6.3V,20%,X6S,SA    I35 @T6G_MB_LIB.T6G(SCH_1):PAGE429
 U6013 EE10 B_PETN13 PT5161LRS-PT5161LRS,SMLF,IC,AJ051610U03   I142 @T6G_MB_LIB.T6G(SCH_1):PAGE429

P5E_CPU0_P3_TX_BUF_DN<3> @T6G_MB_LIB.T6G(SCH_1):P5E_CPU0_P3_TX_BUF_DN(3)
 C6604    2      2 Q_CAP_DIFFBUS_C0201-DIFF BUS_0.22UF,6.3V,20%,X6S,SA    I33 @T6G_MB_LIB.T6G(SCH_1):PAGE429
 U6013 DV10 B_PETN12 PT5161LRS-PT5161LRS,SMLF,IC,AJ051610U03   I142 @T6G_MB_LIB.T6G(SCH_1):PAGE429

P5E_CPU0_P3_TX_BUF_DN<4> @T6G_MB_LIB.T6G(SCH_1):P5E_CPU0_P3_TX_BUF_DN(4)
 C6606    2      2 Q_CAP_DIFFBUS_C0201-DIFF BUS_0.22UF,6.3V,20%,X6S,SA    I31 @T6G_MB_LIB.T6G(SCH_1):PAGE429
 U6013 DL10 B_PETN11 PT5161LRS-PT5161LRS,SMLF,IC,AJ051610U03   I142 @T6G_MB_LIB.T6G(SCH_1):PAGE429

P5E_CPU0_P3_TX_BUF_DN<5> @T6G_MB_LIB.T6G(SCH_1):P5E_CPU0_P3_TX_BUF_DN(5)
 C6608    2      2 Q_CAP_DIFFBUS_C0201-DIFF BUS_0.22UF,6.3V,20%,X6S,SA    I23 @T6G_MB_LIB.T6G(SCH_1):PAGE429
 U6013 DD10 B_PETN10 PT5161LRS-PT5161LRS,SMLF,IC,AJ051610U03   I142 @T6G_MB_LIB.T6G(SCH_1):PAGE429

P5E_CPU0_P3_TX_BUF_DN<6> @T6G_MB_LIB.T6G(SCH_1):P5E_CPU0_P3_TX_BUF_DN(6)
 C6610    2      2 Q_CAP_DIFFBUS_C0201-DIFF BUS_0.22UF,6.3V,20%,X6S,SA    I21 @T6G_MB_LIB.T6G(SCH_1):PAGE429
 U6013 CU10 B_PETN9 PT5161LRS-PT5161LRS,SMLF,IC,AJ051610U03   I142 @T6G_MB_LIB.T6G(SCH_1):PAGE429

P5E_CPU0_P3_TX_BUF_DN<7> @T6G_MB_LIB.T6G(SCH_1):P5E_CPU0_P3_TX_BUF_DN(7)
 C6612    2      2 Q_CAP_DIFFBUS_C0201-DIFF BUS_0.22UF,6.3V,20%,X6S,SA    I20 @T6G_MB_LIB.T6G(SCH_1):PAGE429
 U6013 CK10 B_PETN8 PT5161LRS-PT5161LRS,SMLF,IC,AJ051610U03   I142 @T6G_MB_LIB.T6G(SCH_1):PAGE429

P5E_CPU0_P3_TX_BUF_DN<8> @T6G_MB_LIB.T6G(SCH_1):P5E_CPU0_P3_TX_BUF_DN(8)
 U6013 CC10 B_PETN7 PT5161LRS-PT5161LRS,SMLF,IC,AJ051610U03    I51 @T6G_MB_LIB.T6G(SCH_1):PAGE429
 C6614    2      2 Q_CAP_DIFFBUS_C0201-DIFF BUS_0.22UF,6.3V,20%,X6S,SA   I104 @T6G_MB_LIB.T6G(SCH_1):PAGE429

P5E_CPU0_P3_TX_BUF_DN<9> @T6G_MB_LIB.T6G(SCH_1):P5E_CPU0_P3_TX_BUF_DN(9)
 U6013 BT10 B_PETN6 PT5161LRS-PT5161LRS,SMLF,IC,AJ051610U03    I51 @T6G_MB_LIB.T6G(SCH_1):PAGE429
 C6616    2      2 Q_CAP_DIFFBUS_C0201-DIFF BUS_0.22UF,6.3V,20%,X6S,SA   I103 @T6G_MB_LIB.T6G(SCH_1):PAGE429

P5E_CPU0_P3_TX_BUF_DP<0> @T6G_MB_LIB.T6G(SCH_1):P5E_CPU0_P3_TX_BUF_DP(0)
 C6597    2      2 Q_CAP_DIFFBUS_C0201-DIFF BUS_0.22UF,6.3V,20%,X6S,SA    I40 @T6G_MB_LIB.T6G(SCH_1):PAGE429
 U6013  EU7 B_PETP15 PT5161LRS-PT5161LRS,SMLF,IC,AJ051610U03   I142 @T6G_MB_LIB.T6G(SCH_1):PAGE429

P5E_CPU0_P3_TX_BUF_DP<10> @T6G_MB_LIB.T6G(SCH_1):P5E_CPU0_P3_TX_BUF_DP(10)
 U6013  BG7 B_PETP5 PT5161LRS-PT5161LRS,SMLF,IC,AJ051610U03    I51 @T6G_MB_LIB.T6G(SCH_1):PAGE429
 C6617    2      2 Q_CAP_DIFFBUS_C0201-DIFF BUS_0.22UF,6.3V,20%,X6S,SA   I101 @T6G_MB_LIB.T6G(SCH_1):PAGE429

P5E_CPU0_P3_TX_BUF_DP<11> @T6G_MB_LIB.T6G(SCH_1):P5E_CPU0_P3_TX_BUF_DP(11)
 U6013  AY7 B_PETP4 PT5161LRS-PT5161LRS,SMLF,IC,AJ051610U03    I51 @T6G_MB_LIB.T6G(SCH_1):PAGE429
 C6619    2      2 Q_CAP_DIFFBUS_C0201-DIFF BUS_0.22UF,6.3V,20%,X6S,SA   I100 @T6G_MB_LIB.T6G(SCH_1):PAGE429

P5E_CPU0_P3_TX_BUF_DP<12> @T6G_MB_LIB.T6G(SCH_1):P5E_CPU0_P3_TX_BUF_DP(12)
 U6013  AN7 B_PETP3 PT5161LRS-PT5161LRS,SMLF,IC,AJ051610U03    I51 @T6G_MB_LIB.T6G(SCH_1):PAGE429
 C6621    2      2 Q_CAP_DIFFBUS_C0201-DIFF BUS_0.22UF,6.3V,20%,X6S,SA    I96 @T6G_MB_LIB.T6G(SCH_1):PAGE429

P5E_CPU0_P3_TX_BUF_DP<13> @T6G_MB_LIB.T6G(SCH_1):P5E_CPU0_P3_TX_BUF_DP(13)
 U6013  AF7 B_PETP2 PT5161LRS-PT5161LRS,SMLF,IC,AJ051610U03    I51 @T6G_MB_LIB.T6G(SCH_1):PAGE429
 C6623    2      2 Q_CAP_DIFFBUS_C0201-DIFF BUS_0.22UF,6.3V,20%,X6S,SA    I94 @T6G_MB_LIB.T6G(SCH_1):PAGE429

P5E_CPU0_P3_TX_BUF_DP<14> @T6G_MB_LIB.T6G(SCH_1):P5E_CPU0_P3_TX_BUF_DP(14)
 U6013   W7 B_PETP1 PT5161LRS-PT5161LRS,SMLF,IC,AJ051610U03    I51 @T6G_MB_LIB.T6G(SCH_1):PAGE429
 C6625    2      2 Q_CAP_DIFFBUS_C0201-DIFF BUS_0.22UF,6.3V,20%,X6S,SA    I91 @T6G_MB_LIB.T6G(SCH_1):PAGE429

P5E_CPU0_P3_TX_BUF_DP<15> @T6G_MB_LIB.T6G(SCH_1):P5E_CPU0_P3_TX_BUF_DP(15)
 U6013   M7 B_PETP0 PT5161LRS-PT5161LRS,SMLF,IC,AJ051610U03    I51 @T6G_MB_LIB.T6G(SCH_1):PAGE429
 C6627    2      2 Q_CAP_DIFFBUS_C0201-DIFF BUS_0.22UF,6.3V,20%,X6S,SA    I93 @T6G_MB_LIB.T6G(SCH_1):PAGE429

P5E_CPU0_P3_TX_BUF_DP<1> @T6G_MB_LIB.T6G(SCH_1):P5E_CPU0_P3_TX_BUF_DP(1)
 C6599    2      2 Q_CAP_DIFFBUS_C0201-DIFF BUS_0.22UF,6.3V,20%,X6S,SA    I38 @T6G_MB_LIB.T6G(SCH_1):PAGE429
 U6013  EK7 B_PETP14 PT5161LRS-PT5161LRS,SMLF,IC,AJ051610U03   I142 @T6G_MB_LIB.T6G(SCH_1):PAGE429

P5E_CPU0_P3_TX_BUF_DP<2> @T6G_MB_LIB.T6G(SCH_1):P5E_CPU0_P3_TX_BUF_DP(2)
 C6601    2      2 Q_CAP_DIFFBUS_C0201-DIFF BUS_0.22UF,6.3V,20%,X6S,SA    I36 @T6G_MB_LIB.T6G(SCH_1):PAGE429
 U6013  EC7 B_PETP13 PT5161LRS-PT5161LRS,SMLF,IC,AJ051610U03   I142 @T6G_MB_LIB.T6G(SCH_1):PAGE429

P5E_CPU0_P3_TX_BUF_DP<3> @T6G_MB_LIB.T6G(SCH_1):P5E_CPU0_P3_TX_BUF_DP(3)
 C6603    2      2 Q_CAP_DIFFBUS_C0201-DIFF BUS_0.22UF,6.3V,20%,X6S,SA    I34 @T6G_MB_LIB.T6G(SCH_1):PAGE429
 U6013  DT7 B_PETP12 PT5161LRS-PT5161LRS,SMLF,IC,AJ051610U03   I142 @T6G_MB_LIB.T6G(SCH_1):PAGE429

P5E_CPU0_P3_TX_BUF_DP<4> @T6G_MB_LIB.T6G(SCH_1):P5E_CPU0_P3_TX_BUF_DP(4)
 C6605    2      2 Q_CAP_DIFFBUS_C0201-DIFF BUS_0.22UF,6.3V,20%,X6S,SA    I32 @T6G_MB_LIB.T6G(SCH_1):PAGE429
 U6013  DJ7 B_PETP11 PT5161LRS-PT5161LRS,SMLF,IC,AJ051610U03   I142 @T6G_MB_LIB.T6G(SCH_1):PAGE429

P5E_CPU0_P3_TX_BUF_DP<5> @T6G_MB_LIB.T6G(SCH_1):P5E_CPU0_P3_TX_BUF_DP(5)
 C6607    2      2 Q_CAP_DIFFBUS_C0201-DIFF BUS_0.22UF,6.3V,20%,X6S,SA    I24 @T6G_MB_LIB.T6G(SCH_1):PAGE429
 U6013  DB7 B_PETP10 PT5161LRS-PT5161LRS,SMLF,IC,AJ051610U03   I142 @T6G_MB_LIB.T6G(SCH_1):PAGE429

P5E_CPU0_P3_TX_BUF_DP<6> @T6G_MB_LIB.T6G(SCH_1):P5E_CPU0_P3_TX_BUF_DP(6)
 C6609    2      2 Q_CAP_DIFFBUS_C0201-DIFF BUS_0.22UF,6.3V,20%,X6S,SA    I22 @T6G_MB_LIB.T6G(SCH_1):PAGE429
 U6013  CR7 B_PETP9 PT5161LRS-PT5161LRS,SMLF,IC,AJ051610U03   I142 @T6G_MB_LIB.T6G(SCH_1):PAGE429

P5E_CPU0_P3_TX_BUF_DP<7> @T6G_MB_LIB.T6G(SCH_1):P5E_CPU0_P3_TX_BUF_DP(7)
 C6611    2      2 Q_CAP_DIFFBUS_C0201-DIFF BUS_0.22UF,6.3V,20%,X6S,SA    I19 @T6G_MB_LIB.T6G(SCH_1):PAGE429
 U6013  CH7 B_PETP8 PT5161LRS-PT5161LRS,SMLF,IC,AJ051610U03   I142 @T6G_MB_LIB.T6G(SCH_1):PAGE429

P5E_CPU0_P3_TX_BUF_DP<8> @T6G_MB_LIB.T6G(SCH_1):P5E_CPU0_P3_TX_BUF_DP(8)
 U6013  CA7 B_PETP7 PT5161LRS-PT5161LRS,SMLF,IC,AJ051610U03    I51 @T6G_MB_LIB.T6G(SCH_1):PAGE429
 C6613    2      2 Q_CAP_DIFFBUS_C0201-DIFF BUS_0.22UF,6.3V,20%,X6S,SA   I105 @T6G_MB_LIB.T6G(SCH_1):PAGE429

P5E_CPU0_P3_TX_BUF_DP<9> @T6G_MB_LIB.T6G(SCH_1):P5E_CPU0_P3_TX_BUF_DP(9)
 U6013  BP7 B_PETP6 PT5161LRS-PT5161LRS,SMLF,IC,AJ051610U03    I51 @T6G_MB_LIB.T6G(SCH_1):PAGE429
 C6615    2      2 Q_CAP_DIFFBUS_C0201-DIFF BUS_0.22UF,6.3V,20%,X6S,SA   I102 @T6G_MB_LIB.T6G(SCH_1):PAGE429

P5E_CPU0_P3_TX_C_DN<0> @T6G_MB_LIB.T6G(SCH_1):P5E_CPU0_P3_TX_C_DN(0)
  C900    1      1 Q_CAP_DIFFBUS_C0201-DIFF BUS_0.22UF,6.3V,20%,X6S,SA   I121 @T6G_MB_LIB.T6G(SCH_1):PAGE352
 U6013 EV34 B_PERP15 PT5161LRS-PT5161LRS,SMLF,IC,AJ051610U03    I38 @T6G_MB_LIB.T6G(SCH_1):PAGE426

P5E_CPU0_P3_TX_C_DN<10> @T6G_MB_LIB.T6G(SCH_1):P5E_CPU0_P3_TX_C_DN(10)
  C880    1      1 Q_CAP_DIFFBUS_C0201-DIFF BUS_0.22UF,6.3V,20%,X6S,SA   I156 @T6G_MB_LIB.T6G(SCH_1):PAGE352
 U6013 BH34 B_PERP5 PT5161LRS-PT5161LRS,SMLF,IC,AJ051610U03     I1 @T6G_MB_LIB.T6G(SCH_1):PAGE426

P5E_CPU0_P3_TX_C_DN<11> @T6G_MB_LIB.T6G(SCH_1):P5E_CPU0_P3_TX_C_DN(11)
  C878    1      1 Q_CAP_DIFFBUS_C0201-DIFF BUS_0.22UF,6.3V,20%,X6S,SA   I157 @T6G_MB_LIB.T6G(SCH_1):PAGE352
 U6013 BA34 B_PERP4 PT5161LRS-PT5161LRS,SMLF,IC,AJ051610U03     I1 @T6G_MB_LIB.T6G(SCH_1):PAGE426

P5E_CPU0_P3_TX_C_DN<12> @T6G_MB_LIB.T6G(SCH_1):P5E_CPU0_P3_TX_C_DN(12)
  C876    1      1 Q_CAP_DIFFBUS_C0201-DIFF BUS_0.22UF,6.3V,20%,X6S,SA   I160 @T6G_MB_LIB.T6G(SCH_1):PAGE352
 U6013 AP34 B_PERP3 PT5161LRS-PT5161LRS,SMLF,IC,AJ051610U03     I1 @T6G_MB_LIB.T6G(SCH_1):PAGE426

P5E_CPU0_P3_TX_C_DN<13> @T6G_MB_LIB.T6G(SCH_1):P5E_CPU0_P3_TX_C_DN(13)
  C874    1      1 Q_CAP_DIFFBUS_C0201-DIFF BUS_0.22UF,6.3V,20%,X6S,SA   I165 @T6G_MB_LIB.T6G(SCH_1):PAGE352
 U6013 AG34 B_PERP2 PT5161LRS-PT5161LRS,SMLF,IC,AJ051610U03     I1 @T6G_MB_LIB.T6G(SCH_1):PAGE426

P5E_CPU0_P3_TX_C_DN<14> @T6G_MB_LIB.T6G(SCH_1):P5E_CPU0_P3_TX_C_DN(14)
  C872    1      1 Q_CAP_DIFFBUS_C0201-DIFF BUS_0.22UF,6.3V,20%,X6S,SA   I167 @T6G_MB_LIB.T6G(SCH_1):PAGE352
 U6013 AB35 B_PERN1 PT5161LRS-PT5161LRS,SMLF,IC,AJ051610U03     I1 @T6G_MB_LIB.T6G(SCH_1):PAGE426

P5E_CPU0_P3_TX_C_DN<15> @T6G_MB_LIB.T6G(SCH_1):P5E_CPU0_P3_TX_C_DN(15)
  C870    1      1 Q_CAP_DIFFBUS_C0201-DIFF BUS_0.22UF,6.3V,20%,X6S,SA   I169 @T6G_MB_LIB.T6G(SCH_1):PAGE352
 U6013  N34 B_PERP0 PT5161LRS-PT5161LRS,SMLF,IC,AJ051610U03     I1 @T6G_MB_LIB.T6G(SCH_1):PAGE426

P5E_CPU0_P3_TX_C_DN<1> @T6G_MB_LIB.T6G(SCH_1):P5E_CPU0_P3_TX_C_DN(1)
  C898    1      1 Q_CAP_DIFFBUS_C0201-DIFF BUS_0.22UF,6.3V,20%,X6S,SA   I206 @T6G_MB_LIB.T6G(SCH_1):PAGE352
 U6013 EN35 B_PERN14 PT5161LRS-PT5161LRS,SMLF,IC,AJ051610U03    I38 @T6G_MB_LIB.T6G(SCH_1):PAGE426

P5E_CPU0_P3_TX_C_DN<2> @T6G_MB_LIB.T6G(SCH_1):P5E_CPU0_P3_TX_C_DN(2)
  C896    1      1 Q_CAP_DIFFBUS_C0201-DIFF BUS_0.22UF,6.3V,20%,X6S,SA   I124 @T6G_MB_LIB.T6G(SCH_1):PAGE352
 U6013 ED34 B_PERP13 PT5161LRS-PT5161LRS,SMLF,IC,AJ051610U03    I38 @T6G_MB_LIB.T6G(SCH_1):PAGE426

P5E_CPU0_P3_TX_C_DN<3> @T6G_MB_LIB.T6G(SCH_1):P5E_CPU0_P3_TX_C_DN(3)
  C894    1      1 Q_CAP_DIFFBUS_C0201-DIFF BUS_0.22UF,6.3V,20%,X6S,SA   I126 @T6G_MB_LIB.T6G(SCH_1):PAGE352
 U6013 DU34 B_PERP12 PT5161LRS-PT5161LRS,SMLF,IC,AJ051610U03    I38 @T6G_MB_LIB.T6G(SCH_1):PAGE426

P5E_CPU0_P3_TX_C_DN<4> @T6G_MB_LIB.T6G(SCH_1):P5E_CPU0_P3_TX_C_DN(4)
  C892    1      1 Q_CAP_DIFFBUS_C0201-DIFF BUS_0.22UF,6.3V,20%,X6S,SA   I127 @T6G_MB_LIB.T6G(SCH_1):PAGE352
 U6013 DK34 B_PERP11 PT5161LRS-PT5161LRS,SMLF,IC,AJ051610U03    I38 @T6G_MB_LIB.T6G(SCH_1):PAGE426

P5E_CPU0_P3_TX_C_DN<5> @T6G_MB_LIB.T6G(SCH_1):P5E_CPU0_P3_TX_C_DN(5)
  C890    1      1 Q_CAP_DIFFBUS_C0201-DIFF BUS_0.22UF,6.3V,20%,X6S,SA   I133 @T6G_MB_LIB.T6G(SCH_1):PAGE352
 U6013 DC34 B_PERP10 PT5161LRS-PT5161LRS,SMLF,IC,AJ051610U03    I38 @T6G_MB_LIB.T6G(SCH_1):PAGE426

P5E_CPU0_P3_TX_C_DN<6> @T6G_MB_LIB.T6G(SCH_1):P5E_CPU0_P3_TX_C_DN(6)
  C888    1      1 Q_CAP_DIFFBUS_C0201-DIFF BUS_0.22UF,6.3V,20%,X6S,SA   I135 @T6G_MB_LIB.T6G(SCH_1):PAGE352
 U6013 CT34 B_PERP9 PT5161LRS-PT5161LRS,SMLF,IC,AJ051610U03    I38 @T6G_MB_LIB.T6G(SCH_1):PAGE426

P5E_CPU0_P3_TX_C_DN<7> @T6G_MB_LIB.T6G(SCH_1):P5E_CPU0_P3_TX_C_DN(7)
  C886    1      1 Q_CAP_DIFFBUS_C0201-DIFF BUS_0.22UF,6.3V,20%,X6S,SA   I137 @T6G_MB_LIB.T6G(SCH_1):PAGE352
 U6013 CJ34 B_PERP8 PT5161LRS-PT5161LRS,SMLF,IC,AJ051610U03    I38 @T6G_MB_LIB.T6G(SCH_1):PAGE426

P5E_CPU0_P3_TX_C_DN<8> @T6G_MB_LIB.T6G(SCH_1):P5E_CPU0_P3_TX_C_DN(8)
  C884    1      1 Q_CAP_DIFFBUS_C0201-DIFF BUS_0.22UF,6.3V,20%,X6S,SA   I151 @T6G_MB_LIB.T6G(SCH_1):PAGE352
 U6013 CB34 B_PERP7 PT5161LRS-PT5161LRS,SMLF,IC,AJ051610U03     I1 @T6G_MB_LIB.T6G(SCH_1):PAGE426

P5E_CPU0_P3_TX_C_DN<9> @T6G_MB_LIB.T6G(SCH_1):P5E_CPU0_P3_TX_C_DN(9)
  C882    1      1 Q_CAP_DIFFBUS_C0201-DIFF BUS_0.22UF,6.3V,20%,X6S,SA   I154 @T6G_MB_LIB.T6G(SCH_1):PAGE352
 U6013 BR34 B_PERP6 PT5161LRS-PT5161LRS,SMLF,IC,AJ051610U03     I1 @T6G_MB_LIB.T6G(SCH_1):PAGE426

P5E_CPU0_P3_TX_C_DP<0> @T6G_MB_LIB.T6G(SCH_1):P5E_CPU0_P3_TX_C_DP(0)
  C901    1      1 Q_CAP_DIFFBUS_C0201-DIFF BUS_0.22UF,6.3V,20%,X6S,SA   I120 @T6G_MB_LIB.T6G(SCH_1):PAGE352
 U6013 EY35 B_PERN15 PT5161LRS-PT5161LRS,SMLF,IC,AJ051610U03    I38 @T6G_MB_LIB.T6G(SCH_1):PAGE426

P5E_CPU0_P3_TX_C_DP<10> @T6G_MB_LIB.T6G(SCH_1):P5E_CPU0_P3_TX_C_DP(10)
  C881    1      1 Q_CAP_DIFFBUS_C0201-DIFF BUS_0.22UF,6.3V,20%,X6S,SA   I155 @T6G_MB_LIB.T6G(SCH_1):PAGE352
 U6013 BK35 B_PERN5 PT5161LRS-PT5161LRS,SMLF,IC,AJ051610U03     I1 @T6G_MB_LIB.T6G(SCH_1):PAGE426

P5E_CPU0_P3_TX_C_DP<11> @T6G_MB_LIB.T6G(SCH_1):P5E_CPU0_P3_TX_C_DP(11)
  C879    1      1 Q_CAP_DIFFBUS_C0201-DIFF BUS_0.22UF,6.3V,20%,X6S,SA   I158 @T6G_MB_LIB.T6G(SCH_1):PAGE352
 U6013 BC35 B_PERN4 PT5161LRS-PT5161LRS,SMLF,IC,AJ051610U03     I1 @T6G_MB_LIB.T6G(SCH_1):PAGE426

P5E_CPU0_P3_TX_C_DP<12> @T6G_MB_LIB.T6G(SCH_1):P5E_CPU0_P3_TX_C_DP(12)
  C877    1      1 Q_CAP_DIFFBUS_C0201-DIFF BUS_0.22UF,6.3V,20%,X6S,SA   I159 @T6G_MB_LIB.T6G(SCH_1):PAGE352
 U6013 AT35 B_PERN3 PT5161LRS-PT5161LRS,SMLF,IC,AJ051610U03     I1 @T6G_MB_LIB.T6G(SCH_1):PAGE426

P5E_CPU0_P3_TX_C_DP<13> @T6G_MB_LIB.T6G(SCH_1):P5E_CPU0_P3_TX_C_DP(13)
  C875    1      1 Q_CAP_DIFFBUS_C0201-DIFF BUS_0.22UF,6.3V,20%,X6S,SA   I164 @T6G_MB_LIB.T6G(SCH_1):PAGE352
 U6013 AJ35 B_PERN2 PT5161LRS-PT5161LRS,SMLF,IC,AJ051610U03     I1 @T6G_MB_LIB.T6G(SCH_1):PAGE426

P5E_CPU0_P3_TX_C_DP<14> @T6G_MB_LIB.T6G(SCH_1):P5E_CPU0_P3_TX_C_DP(14)
  C873    1      1 Q_CAP_DIFFBUS_C0201-DIFF BUS_0.22UF,6.3V,20%,X6S,SA   I166 @T6G_MB_LIB.T6G(SCH_1):PAGE352
 U6013  Y34 B_PERP1 PT5161LRS-PT5161LRS,SMLF,IC,AJ051610U03     I1 @T6G_MB_LIB.T6G(SCH_1):PAGE426

P5E_CPU0_P3_TX_C_DP<15> @T6G_MB_LIB.T6G(SCH_1):P5E_CPU0_P3_TX_C_DP(15)
  C871    1      1 Q_CAP_DIFFBUS_C0201-DIFF BUS_0.22UF,6.3V,20%,X6S,SA   I168 @T6G_MB_LIB.T6G(SCH_1):PAGE352
 U6013  R35 B_PERN0 PT5161LRS-PT5161LRS,SMLF,IC,AJ051610U03     I1 @T6G_MB_LIB.T6G(SCH_1):PAGE426

P5E_CPU0_P3_TX_C_DP<1> @T6G_MB_LIB.T6G(SCH_1):P5E_CPU0_P3_TX_C_DP(1)
  C899    1      1 Q_CAP_DIFFBUS_C0201-DIFF BUS_0.22UF,6.3V,20%,X6S,SA   I122 @T6G_MB_LIB.T6G(SCH_1):PAGE352
 U6013 EL34 B_PERP14 PT5161LRS-PT5161LRS,SMLF,IC,AJ051610U03    I38 @T6G_MB_LIB.T6G(SCH_1):PAGE426

P5E_CPU0_P3_TX_C_DP<2> @T6G_MB_LIB.T6G(SCH_1):P5E_CPU0_P3_TX_C_DP(2)
  C897    1      1 Q_CAP_DIFFBUS_C0201-DIFF BUS_0.22UF,6.3V,20%,X6S,SA   I123 @T6G_MB_LIB.T6G(SCH_1):PAGE352
 U6013 EF35 B_PERN13 PT5161LRS-PT5161LRS,SMLF,IC,AJ051610U03    I38 @T6G_MB_LIB.T6G(SCH_1):PAGE426

P5E_CPU0_P3_TX_C_DP<3> @T6G_MB_LIB.T6G(SCH_1):P5E_CPU0_P3_TX_C_DP(3)
  C895    1      1 Q_CAP_DIFFBUS_C0201-DIFF BUS_0.22UF,6.3V,20%,X6S,SA   I125 @T6G_MB_LIB.T6G(SCH_1):PAGE352
 U6013 DW35 B_PERN12 PT5161LRS-PT5161LRS,SMLF,IC,AJ051610U03    I38 @T6G_MB_LIB.T6G(SCH_1):PAGE426

P5E_CPU0_P3_TX_C_DP<4> @T6G_MB_LIB.T6G(SCH_1):P5E_CPU0_P3_TX_C_DP(4)
  C893    1      1 Q_CAP_DIFFBUS_C0201-DIFF BUS_0.22UF,6.3V,20%,X6S,SA   I128 @T6G_MB_LIB.T6G(SCH_1):PAGE352
 U6013 DM35 B_PERN11 PT5161LRS-PT5161LRS,SMLF,IC,AJ051610U03    I38 @T6G_MB_LIB.T6G(SCH_1):PAGE426

P5E_CPU0_P3_TX_C_DP<5> @T6G_MB_LIB.T6G(SCH_1):P5E_CPU0_P3_TX_C_DP(5)
  C891    1      1 Q_CAP_DIFFBUS_C0201-DIFF BUS_0.22UF,6.3V,20%,X6S,SA   I132 @T6G_MB_LIB.T6G(SCH_1):PAGE352
 U6013 DE35 B_PERN10 PT5161LRS-PT5161LRS,SMLF,IC,AJ051610U03    I38 @T6G_MB_LIB.T6G(SCH_1):PAGE426

P5E_CPU0_P3_TX_C_DP<6> @T6G_MB_LIB.T6G(SCH_1):P5E_CPU0_P3_TX_C_DP(6)
  C889    1      1 Q_CAP_DIFFBUS_C0201-DIFF BUS_0.22UF,6.3V,20%,X6S,SA   I134 @T6G_MB_LIB.T6G(SCH_1):PAGE352
 U6013 CV35 B_PERN9 PT5161LRS-PT5161LRS,SMLF,IC,AJ051610U03    I38 @T6G_MB_LIB.T6G(SCH_1):PAGE426

P5E_CPU0_P3_TX_C_DP<7> @T6G_MB_LIB.T6G(SCH_1):P5E_CPU0_P3_TX_C_DP(7)
  C887    1      1 Q_CAP_DIFFBUS_C0201-DIFF BUS_0.22UF,6.3V,20%,X6S,SA   I136 @T6G_MB_LIB.T6G(SCH_1):PAGE352
 U6013 CL35 B_PERN8 PT5161LRS-PT5161LRS,SMLF,IC,AJ051610U03    I38 @T6G_MB_LIB.T6G(SCH_1):PAGE426

P5E_CPU0_P3_TX_C_DP<8> @T6G_MB_LIB.T6G(SCH_1):P5E_CPU0_P3_TX_C_DP(8)
  C885    1      1 Q_CAP_DIFFBUS_C0201-DIFF BUS_0.22UF,6.3V,20%,X6S,SA   I152 @T6G_MB_LIB.T6G(SCH_1):PAGE352
 U6013 CD35 B_PERN7 PT5161LRS-PT5161LRS,SMLF,IC,AJ051610U03     I1 @T6G_MB_LIB.T6G(SCH_1):PAGE426

P5E_CPU0_P3_TX_C_DP<9> @T6G_MB_LIB.T6G(SCH_1):P5E_CPU0_P3_TX_C_DP(9)
  C883    1      1 Q_CAP_DIFFBUS_C0201-DIFF BUS_0.22UF,6.3V,20%,X6S,SA   I153 @T6G_MB_LIB.T6G(SCH_1):PAGE352
 U6013 BU35 B_PERN6 PT5161LRS-PT5161LRS,SMLF,IC,AJ051610U03     I1 @T6G_MB_LIB.T6G(SCH_1):PAGE426

P5E_CPU0_P3_TX_DN<0> @T6G_MB_LIB.T6G(SCH_1):P5E_CPU0_P3_TX_DN(0)
   U25 CD35 P3_TXN0 GENOA_SP5-SOCKET6096_13568-001,SMLF,IO,DGA^6000030   I148 @T6G_MB_LIB.T6G(SCH_1):PAGE25
  C900    2      2 Q_CAP_DIFFBUS_C0201-DIFF BUS_0.22UF,6.3V,20%,X6S,SA   I121 @T6G_MB_LIB.T6G(SCH_1):PAGE352

P5E_CPU0_P3_TX_DN<10> @T6G_MB_LIB.T6G(SCH_1):P5E_CPU0_P3_TX_DN(10)
   U25 CC26 P3_TXN10 GENOA_SP5-SOCKET6096_13568-001,SMLF,IO,DGA^6000030   I148 @T6G_MB_LIB.T6G(SCH_1):PAGE25
  C880    2      2 Q_CAP_DIFFBUS_C0201-DIFF BUS_0.22UF,6.3V,20%,X6S,SA   I156 @T6G_MB_LIB.T6G(SCH_1):PAGE352

P5E_CPU0_P3_TX_DN<11> @T6G_MB_LIB.T6G(SCH_1):P5E_CPU0_P3_TX_DN(11)
   U25 CG26 P3_TXN11 GENOA_SP5-SOCKET6096_13568-001,SMLF,IO,DGA^6000030   I148 @T6G_MB_LIB.T6G(SCH_1):PAGE25
  C878    2      2 Q_CAP_DIFFBUS_C0201-DIFF BUS_0.22UF,6.3V,20%,X6S,SA   I157 @T6G_MB_LIB.T6G(SCH_1):PAGE352

P5E_CPU0_P3_TX_DN<12> @T6G_MB_LIB.T6G(SCH_1):P5E_CPU0_P3_TX_DN(12)
   U25 CE26 P3_TXN12 GENOA_SP5-SOCKET6096_13568-001,SMLF,IO,DGA^6000030   I148 @T6G_MB_LIB.T6G(SCH_1):PAGE25
  C876    2      2 Q_CAP_DIFFBUS_C0201-DIFF BUS_0.22UF,6.3V,20%,X6S,SA   I160 @T6G_MB_LIB.T6G(SCH_1):PAGE352

P5E_CPU0_P3_TX_DN<13> @T6G_MB_LIB.T6G(SCH_1):P5E_CPU0_P3_TX_DN(13)
   U25 CC23 P3_TXN13 GENOA_SP5-SOCKET6096_13568-001,SMLF,IO,DGA^6000030   I148 @T6G_MB_LIB.T6G(SCH_1):PAGE25
  C874    2      2 Q_CAP_DIFFBUS_C0201-DIFF BUS_0.22UF,6.3V,20%,X6S,SA   I165 @T6G_MB_LIB.T6G(SCH_1):PAGE352

P5E_CPU0_P3_TX_DN<14> @T6G_MB_LIB.T6G(SCH_1):P5E_CPU0_P3_TX_DN(14)
   U25 CG23 P3_TXN14 GENOA_SP5-SOCKET6096_13568-001,SMLF,IO,DGA^6000030   I148 @T6G_MB_LIB.T6G(SCH_1):PAGE25
  C872    2      2 Q_CAP_DIFFBUS_C0201-DIFF BUS_0.22UF,6.3V,20%,X6S,SA   I167 @T6G_MB_LIB.T6G(SCH_1):PAGE352

P5E_CPU0_P3_TX_DN<15> @T6G_MB_LIB.T6G(SCH_1):P5E_CPU0_P3_TX_DN(15)
   U25 CE23 P3_TXN15 GENOA_SP5-SOCKET6096_13568-001,SMLF,IO,DGA^6000030   I148 @T6G_MB_LIB.T6G(SCH_1):PAGE25
  C870    2      2 Q_CAP_DIFFBUS_C0201-DIFF BUS_0.22UF,6.3V,20%,X6S,SA   I169 @T6G_MB_LIB.T6G(SCH_1):PAGE352

P5E_CPU0_P3_TX_DN<1> @T6G_MB_LIB.T6G(SCH_1):P5E_CPU0_P3_TX_DN(1)
   U25 CF35 P3_TXN1 GENOA_SP5-SOCKET6096_13568-001,SMLF,IO,DGA^6000030   I148 @T6G_MB_LIB.T6G(SCH_1):PAGE25
  C898    2      2 Q_CAP_DIFFBUS_C0201-DIFF BUS_0.22UF,6.3V,20%,X6S,SA   I206 @T6G_MB_LIB.T6G(SCH_1):PAGE352

P5E_CPU0_P3_TX_DN<2> @T6G_MB_LIB.T6G(SCH_1):P5E_CPU0_P3_TX_DN(2)
   U25 CH35 P3_TXN2 GENOA_SP5-SOCKET6096_13568-001,SMLF,IO,DGA^6000030   I148 @T6G_MB_LIB.T6G(SCH_1):PAGE25
  C896    2      2 Q_CAP_DIFFBUS_C0201-DIFF BUS_0.22UF,6.3V,20%,X6S,SA   I124 @T6G_MB_LIB.T6G(SCH_1):PAGE352

P5E_CPU0_P3_TX_DN<3> @T6G_MB_LIB.T6G(SCH_1):P5E_CPU0_P3_TX_DN(3)
   U25 CC32 P3_TXN3 GENOA_SP5-SOCKET6096_13568-001,SMLF,IO,DGA^6000030   I148 @T6G_MB_LIB.T6G(SCH_1):PAGE25
  C894    2      2 Q_CAP_DIFFBUS_C0201-DIFF BUS_0.22UF,6.3V,20%,X6S,SA   I126 @T6G_MB_LIB.T6G(SCH_1):PAGE352

P5E_CPU0_P3_TX_DN<4> @T6G_MB_LIB.T6G(SCH_1):P5E_CPU0_P3_TX_DN(4)
   U25 CJ32 P3_TXN4 GENOA_SP5-SOCKET6096_13568-001,SMLF,IO,DGA^6000030   I148 @T6G_MB_LIB.T6G(SCH_1):PAGE25
  C892    2      2 Q_CAP_DIFFBUS_C0201-DIFF BUS_0.22UF,6.3V,20%,X6S,SA   I127 @T6G_MB_LIB.T6G(SCH_1):PAGE352

P5E_CPU0_P3_TX_DN<5> @T6G_MB_LIB.T6G(SCH_1):P5E_CPU0_P3_TX_DN(5)
   U25 CG32 P3_TXN5 GENOA_SP5-SOCKET6096_13568-001,SMLF,IO,DGA^6000030   I148 @T6G_MB_LIB.T6G(SCH_1):PAGE25
  C890    2      2 Q_CAP_DIFFBUS_C0201-DIFF BUS_0.22UF,6.3V,20%,X6S,SA   I133 @T6G_MB_LIB.T6G(SCH_1):PAGE352

P5E_CPU0_P3_TX_DN<6> @T6G_MB_LIB.T6G(SCH_1):P5E_CPU0_P3_TX_DN(6)
   U25 CE32 P3_TXN6 GENOA_SP5-SOCKET6096_13568-001,SMLF,IO,DGA^6000030   I148 @T6G_MB_LIB.T6G(SCH_1):PAGE25
  C888    2      2 Q_CAP_DIFFBUS_C0201-DIFF BUS_0.22UF,6.3V,20%,X6S,SA   I135 @T6G_MB_LIB.T6G(SCH_1):PAGE352

P5E_CPU0_P3_TX_DN<7> @T6G_MB_LIB.T6G(SCH_1):P5E_CPU0_P3_TX_DN(7)
   U25 CC29 P3_TXN7 GENOA_SP5-SOCKET6096_13568-001,SMLF,IO,DGA^6000030   I148 @T6G_MB_LIB.T6G(SCH_1):PAGE25
  C886    2      2 Q_CAP_DIFFBUS_C0201-DIFF BUS_0.22UF,6.3V,20%,X6S,SA   I137 @T6G_MB_LIB.T6G(SCH_1):PAGE352

P5E_CPU0_P3_TX_DN<8> @T6G_MB_LIB.T6G(SCH_1):P5E_CPU0_P3_TX_DN(8)
   U25 CG29 P3_TXN8 GENOA_SP5-SOCKET6096_13568-001,SMLF,IO,DGA^6000030   I148 @T6G_MB_LIB.T6G(SCH_1):PAGE25
  C884    2      2 Q_CAP_DIFFBUS_C0201-DIFF BUS_0.22UF,6.3V,20%,X6S,SA   I151 @T6G_MB_LIB.T6G(SCH_1):PAGE352

P5E_CPU0_P3_TX_DN<9> @T6G_MB_LIB.T6G(SCH_1):P5E_CPU0_P3_TX_DN(9)
   U25 CE29 P3_TXN9 GENOA_SP5-SOCKET6096_13568-001,SMLF,IO,DGA^6000030   I148 @T6G_MB_LIB.T6G(SCH_1):PAGE25
  C882    2      2 Q_CAP_DIFFBUS_C0201-DIFF BUS_0.22UF,6.3V,20%,X6S,SA   I154 @T6G_MB_LIB.T6G(SCH_1):PAGE352

P5E_CPU0_P3_TX_DP<0> @T6G_MB_LIB.T6G(SCH_1):P5E_CPU0_P3_TX_DP(0)
   U25 CD36 P3_TXP0 GENOA_SP5-SOCKET6096_13568-001,SMLF,IO,DGA^6000030   I148 @T6G_MB_LIB.T6G(SCH_1):PAGE25
  C901    2      2 Q_CAP_DIFFBUS_C0201-DIFF BUS_0.22UF,6.3V,20%,X6S,SA   I120 @T6G_MB_LIB.T6G(SCH_1):PAGE352

P5E_CPU0_P3_TX_DP<10> @T6G_MB_LIB.T6G(SCH_1):P5E_CPU0_P3_TX_DP(10)
   U25 CC27 P3_TXP10 GENOA_SP5-SOCKET6096_13568-001,SMLF,IO,DGA^6000030   I148 @T6G_MB_LIB.T6G(SCH_1):PAGE25
  C881    2      2 Q_CAP_DIFFBUS_C0201-DIFF BUS_0.22UF,6.3V,20%,X6S,SA   I155 @T6G_MB_LIB.T6G(SCH_1):PAGE352

P5E_CPU0_P3_TX_DP<11> @T6G_MB_LIB.T6G(SCH_1):P5E_CPU0_P3_TX_DP(11)
   U25 CG27 P3_TXP11 GENOA_SP5-SOCKET6096_13568-001,SMLF,IO,DGA^6000030   I148 @T6G_MB_LIB.T6G(SCH_1):PAGE25
  C879    2      2 Q_CAP_DIFFBUS_C0201-DIFF BUS_0.22UF,6.3V,20%,X6S,SA   I158 @T6G_MB_LIB.T6G(SCH_1):PAGE352

P5E_CPU0_P3_TX_DP<12> @T6G_MB_LIB.T6G(SCH_1):P5E_CPU0_P3_TX_DP(12)
   U25 CE27 P3_TXP12 GENOA_SP5-SOCKET6096_13568-001,SMLF,IO,DGA^6000030   I148 @T6G_MB_LIB.T6G(SCH_1):PAGE25
  C877    2      2 Q_CAP_DIFFBUS_C0201-DIFF BUS_0.22UF,6.3V,20%,X6S,SA   I159 @T6G_MB_LIB.T6G(SCH_1):PAGE352

P5E_CPU0_P3_TX_DP<13> @T6G_MB_LIB.T6G(SCH_1):P5E_CPU0_P3_TX_DP(13)
   U25 CC24 P3_TXP13 GENOA_SP5-SOCKET6096_13568-001,SMLF,IO,DGA^6000030   I148 @T6G_MB_LIB.T6G(SCH_1):PAGE25
  C875    2      2 Q_CAP_DIFFBUS_C0201-DIFF BUS_0.22UF,6.3V,20%,X6S,SA   I164 @T6G_MB_LIB.T6G(SCH_1):PAGE352

P5E_CPU0_P3_TX_DP<14> @T6G_MB_LIB.T6G(SCH_1):P5E_CPU0_P3_TX_DP(14)
   U25 CG24 P3_TXP14 GENOA_SP5-SOCKET6096_13568-001,SMLF,IO,DGA^6000030   I148 @T6G_MB_LIB.T6G(SCH_1):PAGE25
  C873    2      2 Q_CAP_DIFFBUS_C0201-DIFF BUS_0.22UF,6.3V,20%,X6S,SA   I166 @T6G_MB_LIB.T6G(SCH_1):PAGE352

P5E_CPU0_P3_TX_DP<15> @T6G_MB_LIB.T6G(SCH_1):P5E_CPU0_P3_TX_DP(15)
   U25 CE24 P3_TXP15 GENOA_SP5-SOCKET6096_13568-001,SMLF,IO,DGA^6000030   I148 @T6G_MB_LIB.T6G(SCH_1):PAGE25
  C871    2      2 Q_CAP_DIFFBUS_C0201-DIFF BUS_0.22UF,6.3V,20%,X6S,SA   I168 @T6G_MB_LIB.T6G(SCH_1):PAGE352

P5E_CPU0_P3_TX_DP<1> @T6G_MB_LIB.T6G(SCH_1):P5E_CPU0_P3_TX_DP(1)
   U25 CF36 P3_TXP1 GENOA_SP5-SOCKET6096_13568-001,SMLF,IO,DGA^6000030   I148 @T6G_MB_LIB.T6G(SCH_1):PAGE25
  C899    2      2 Q_CAP_DIFFBUS_C0201-DIFF BUS_0.22UF,6.3V,20%,X6S,SA   I122 @T6G_MB_LIB.T6G(SCH_1):PAGE352

P5E_CPU0_P3_TX_DP<2> @T6G_MB_LIB.T6G(SCH_1):P5E_CPU0_P3_TX_DP(2)
   U25 CH36 P3_TXP2 GENOA_SP5-SOCKET6096_13568-001,SMLF,IO,DGA^6000030   I148 @T6G_MB_LIB.T6G(SCH_1):PAGE25
  C897    2      2 Q_CAP_DIFFBUS_C0201-DIFF BUS_0.22UF,6.3V,20%,X6S,SA   I123 @T6G_MB_LIB.T6G(SCH_1):PAGE352

P5E_CPU0_P3_TX_DP<3> @T6G_MB_LIB.T6G(SCH_1):P5E_CPU0_P3_TX_DP(3)
   U25 CC33 P3_TXP3 GENOA_SP5-SOCKET6096_13568-001,SMLF,IO,DGA^6000030   I148 @T6G_MB_LIB.T6G(SCH_1):PAGE25
  C895    2      2 Q_CAP_DIFFBUS_C0201-DIFF BUS_0.22UF,6.3V,20%,X6S,SA   I125 @T6G_MB_LIB.T6G(SCH_1):PAGE352

P5E_CPU0_P3_TX_DP<4> @T6G_MB_LIB.T6G(SCH_1):P5E_CPU0_P3_TX_DP(4)
   U25 CJ33 P3_TXP4 GENOA_SP5-SOCKET6096_13568-001,SMLF,IO,DGA^6000030   I148 @T6G_MB_LIB.T6G(SCH_1):PAGE25
  C893    2      2 Q_CAP_DIFFBUS_C0201-DIFF BUS_0.22UF,6.3V,20%,X6S,SA   I128 @T6G_MB_LIB.T6G(SCH_1):PAGE352

P5E_CPU0_P3_TX_DP<5> @T6G_MB_LIB.T6G(SCH_1):P5E_CPU0_P3_TX_DP(5)
   U25 CG33 P3_TXP5 GENOA_SP5-SOCKET6096_13568-001,SMLF,IO,DGA^6000030   I148 @T6G_MB_LIB.T6G(SCH_1):PAGE25
  C891    2      2 Q_CAP_DIFFBUS_C0201-DIFF BUS_0.22UF,6.3V,20%,X6S,SA   I132 @T6G_MB_LIB.T6G(SCH_1):PAGE352

P5E_CPU0_P3_TX_DP<6> @T6G_MB_LIB.T6G(SCH_1):P5E_CPU0_P3_TX_DP(6)
   U25 CE33 P3_TXP6 GENOA_SP5-SOCKET6096_13568-001,SMLF,IO,DGA^6000030   I148 @T6G_MB_LIB.T6G(SCH_1):PAGE25
  C889    2      2 Q_CAP_DIFFBUS_C0201-DIFF BUS_0.22UF,6.3V,20%,X6S,SA   I134 @T6G_MB_LIB.T6G(SCH_1):PAGE352

P5E_CPU0_P3_TX_DP<7> @T6G_MB_LIB.T6G(SCH_1):P5E_CPU0_P3_TX_DP(7)
   U25 CC30 P3_TXP7 GENOA_SP5-SOCKET6096_13568-001,SMLF,IO,DGA^6000030   I148 @T6G_MB_LIB.T6G(SCH_1):PAGE25
  C887    2      2 Q_CAP_DIFFBUS_C0201-DIFF BUS_0.22UF,6.3V,20%,X6S,SA   I136 @T6G_MB_LIB.T6G(SCH_1):PAGE352

P5E_CPU0_P3_TX_DP<8> @T6G_MB_LIB.T6G(SCH_1):P5E_CPU0_P3_TX_DP(8)
   U25 CG30 P3_TXP8 GENOA_SP5-SOCKET6096_13568-001,SMLF,IO,DGA^6000030   I148 @T6G_MB_LIB.T6G(SCH_1):PAGE25
  C885    2      2 Q_CAP_DIFFBUS_C0201-DIFF BUS_0.22UF,6.3V,20%,X6S,SA   I152 @T6G_MB_LIB.T6G(SCH_1):PAGE352

P5E_CPU0_P3_TX_DP<9> @T6G_MB_LIB.T6G(SCH_1):P5E_CPU0_P3_TX_DP(9)
   U25 CE30 P3_TXP9 GENOA_SP5-SOCKET6096_13568-001,SMLF,IO,DGA^6000030   I148 @T6G_MB_LIB.T6G(SCH_1):PAGE25
  C883    2      2 Q_CAP_DIFFBUS_C0201-DIFF BUS_0.22UF,6.3V,20%,X6S,SA   I153 @T6G_MB_LIB.T6G(SCH_1):PAGE352

P5E_CPU1_G1_RX_DN<0> @T6G_MB_LIB.T6G(SCH_1):P5E_CPU1_G1_RX_DN(0)
   U26  V40 G1_RXN0 GENOA_SP5-SOCKET6096_13568-001,SMLF,IO,DGA^6000030   I214 @T6G_MB_LIB.T6G(SCH_1):PAGE49
   J35  A17  PERN0 SCONN168_ME1016810202011-SCONN168_ME1016810202011,A   I168 @T6G_MB_LIB.T6G(SCH_1):PAGE341

P5E_CPU1_G1_RX_DN<10> @T6G_MB_LIB.T6G(SCH_1):P5E_CPU1_G1_RX_DN(10)
   U26  N49 G1_RXN10 GENOA_SP5-SOCKET6096_13568-001,SMLF,IO,DGA^6000030   I214 @T6G_MB_LIB.T6G(SCH_1):PAGE49
   J35  A50 PERN10 SCONN168_ME1016810202011-SCONN168_ME1016810202011,A   I168 @T6G_MB_LIB.T6G(SCH_1):PAGE341

P5E_CPU1_G1_RX_DN<11> @T6G_MB_LIB.T6G(SCH_1):P5E_CPU1_G1_RX_DN(11)
   U26  R49 G1_RXN11 GENOA_SP5-SOCKET6096_13568-001,SMLF,IO,DGA^6000030   I214 @T6G_MB_LIB.T6G(SCH_1):PAGE49
   J35  A53 PERN11 SCONN168_ME1016810202011-SCONN168_ME1016810202011,A   I168 @T6G_MB_LIB.T6G(SCH_1):PAGE341

P5E_CPU1_G1_RX_DN<12> @T6G_MB_LIB.T6G(SCH_1):P5E_CPU1_G1_RX_DN(12)
   U26  U49 G1_RXN12 GENOA_SP5-SOCKET6096_13568-001,SMLF,IO,DGA^6000030   I214 @T6G_MB_LIB.T6G(SCH_1):PAGE49
   J35  A56 PERN12 SCONN168_ME1016810202011-SCONN168_ME1016810202011,A   I168 @T6G_MB_LIB.T6G(SCH_1):PAGE341

P5E_CPU1_G1_RX_DN<13> @T6G_MB_LIB.T6G(SCH_1):P5E_CPU1_G1_RX_DN(13)
   U26  W52 G1_RXN13 GENOA_SP5-SOCKET6096_13568-001,SMLF,IO,DGA^6000030   I214 @T6G_MB_LIB.T6G(SCH_1):PAGE49
   J35  A59 PERN13 SCONN168_ME1016810202011-SCONN168_ME1016810202011,A   I168 @T6G_MB_LIB.T6G(SCH_1):PAGE341

P5E_CPU1_G1_RX_DN<14> @T6G_MB_LIB.T6G(SCH_1):P5E_CPU1_G1_RX_DN(14)
   U26  R52 G1_RXN14 GENOA_SP5-SOCKET6096_13568-001,SMLF,IO,DGA^6000030   I214 @T6G_MB_LIB.T6G(SCH_1):PAGE49
   J35  A62 PERN14 SCONN168_ME1016810202011-SCONN168_ME1016810202011,A   I168 @T6G_MB_LIB.T6G(SCH_1):PAGE341

P5E_CPU1_G1_RX_DN<15> @T6G_MB_LIB.T6G(SCH_1):P5E_CPU1_G1_RX_DN(15)
   U26  U52 G1_RXN15 GENOA_SP5-SOCKET6096_13568-001,SMLF,IO,DGA^6000030   I214 @T6G_MB_LIB.T6G(SCH_1):PAGE49
   J35  A65 PERN15 SCONN168_ME1016810202011-SCONN168_ME1016810202011,A   I168 @T6G_MB_LIB.T6G(SCH_1):PAGE341

P5E_CPU1_G1_RX_DN<1> @T6G_MB_LIB.T6G(SCH_1):P5E_CPU1_G1_RX_DN(1)
   U26  T40 G1_RXN1 GENOA_SP5-SOCKET6096_13568-001,SMLF,IO,DGA^6000030   I214 @T6G_MB_LIB.T6G(SCH_1):PAGE49
   J35  A20  PERN1 SCONN168_ME1016810202011-SCONN168_ME1016810202011,A   I168 @T6G_MB_LIB.T6G(SCH_1):PAGE341

P5E_CPU1_G1_RX_DN<2> @T6G_MB_LIB.T6G(SCH_1):P5E_CPU1_G1_RX_DN(2)
   U26  P40 G1_RXN2 GENOA_SP5-SOCKET6096_13568-001,SMLF,IO,DGA^6000030   I214 @T6G_MB_LIB.T6G(SCH_1):PAGE49
   J35  A23  PERN2 SCONN168_ME1016810202011-SCONN168_ME1016810202011,A   I168 @T6G_MB_LIB.T6G(SCH_1):PAGE341

P5E_CPU1_G1_RX_DN<3> @T6G_MB_LIB.T6G(SCH_1):P5E_CPU1_G1_RX_DN(3)
   U26  U43 G1_RXN3 GENOA_SP5-SOCKET6096_13568-001,SMLF,IO,DGA^6000030   I214 @T6G_MB_LIB.T6G(SCH_1):PAGE49
   J35  A26  PERN3 SCONN168_ME1016810202011-SCONN168_ME1016810202011,A   I168 @T6G_MB_LIB.T6G(SCH_1):PAGE341

P5E_CPU1_G1_RX_DN<4> @T6G_MB_LIB.T6G(SCH_1):P5E_CPU1_G1_RX_DN(4)
   U26  N43 G1_RXN4 GENOA_SP5-SOCKET6096_13568-001,SMLF,IO,DGA^6000030   I214 @T6G_MB_LIB.T6G(SCH_1):PAGE49
   J35  A30  PERN4 SCONN168_ME1016810202011-SCONN168_ME1016810202011,A   I168 @T6G_MB_LIB.T6G(SCH_1):PAGE341

P5E_CPU1_G1_RX_DN<5> @T6G_MB_LIB.T6G(SCH_1):P5E_CPU1_G1_RX_DN(5)
   U26  R43 G1_RXN5 GENOA_SP5-SOCKET6096_13568-001,SMLF,IO,DGA^6000030   I214 @T6G_MB_LIB.T6G(SCH_1):PAGE49
   J35  A33  PERN5 SCONN168_ME1016810202011-SCONN168_ME1016810202011,A   I168 @T6G_MB_LIB.T6G(SCH_1):PAGE341

P5E_CPU1_G1_RX_DN<6> @T6G_MB_LIB.T6G(SCH_1):P5E_CPU1_G1_RX_DN(6)
   U26  U46 G1_RXN6 GENOA_SP5-SOCKET6096_13568-001,SMLF,IO,DGA^6000030   I214 @T6G_MB_LIB.T6G(SCH_1):PAGE49
   J35  A36  PERN6 SCONN168_ME1016810202011-SCONN168_ME1016810202011,A   I168 @T6G_MB_LIB.T6G(SCH_1):PAGE341

P5E_CPU1_G1_RX_DN<7> @T6G_MB_LIB.T6G(SCH_1):P5E_CPU1_G1_RX_DN(7)
   U26  N46 G1_RXN7 GENOA_SP5-SOCKET6096_13568-001,SMLF,IO,DGA^6000030   I214 @T6G_MB_LIB.T6G(SCH_1):PAGE49
   J35  A39  PERN7 SCONN168_ME1016810202011-SCONN168_ME1016810202011,A   I168 @T6G_MB_LIB.T6G(SCH_1):PAGE341

P5E_CPU1_G1_RX_DN<8> @T6G_MB_LIB.T6G(SCH_1):P5E_CPU1_G1_RX_DN(8)
   U26  R46 G1_RXN8 GENOA_SP5-SOCKET6096_13568-001,SMLF,IO,DGA^6000030   I214 @T6G_MB_LIB.T6G(SCH_1):PAGE49
   J35  A44  PERN8 SCONN168_ME1016810202011-SCONN168_ME1016810202011,A   I168 @T6G_MB_LIB.T6G(SCH_1):PAGE341

P5E_CPU1_G1_RX_DN<9> @T6G_MB_LIB.T6G(SCH_1):P5E_CPU1_G1_RX_DN(9)
   U26  W49 G1_RXN9 GENOA_SP5-SOCKET6096_13568-001,SMLF,IO,DGA^6000030   I214 @T6G_MB_LIB.T6G(SCH_1):PAGE49
   J35  A47  PERN9 SCONN168_ME1016810202011-SCONN168_ME1016810202011,A   I168 @T6G_MB_LIB.T6G(SCH_1):PAGE341

P5E_CPU1_G1_RX_DP<0> @T6G_MB_LIB.T6G(SCH_1):P5E_CPU1_G1_RX_DP(0)
   U26  V41 G1_RXP0 GENOA_SP5-SOCKET6096_13568-001,SMLF,IO,DGA^6000030   I214 @T6G_MB_LIB.T6G(SCH_1):PAGE49
   J35  A18  PERP0 SCONN168_ME1016810202011-SCONN168_ME1016810202011,A   I168 @T6G_MB_LIB.T6G(SCH_1):PAGE341

P5E_CPU1_G1_RX_DP<10> @T6G_MB_LIB.T6G(SCH_1):P5E_CPU1_G1_RX_DP(10)
   U26  N50 G1_RXP10 GENOA_SP5-SOCKET6096_13568-001,SMLF,IO,DGA^6000030   I214 @T6G_MB_LIB.T6G(SCH_1):PAGE49
   J35  A51 PERP10 SCONN168_ME1016810202011-SCONN168_ME1016810202011,A   I168 @T6G_MB_LIB.T6G(SCH_1):PAGE341

P5E_CPU1_G1_RX_DP<11> @T6G_MB_LIB.T6G(SCH_1):P5E_CPU1_G1_RX_DP(11)
   U26  R50 G1_RXP11 GENOA_SP5-SOCKET6096_13568-001,SMLF,IO,DGA^6000030   I214 @T6G_MB_LIB.T6G(SCH_1):PAGE49
   J35  A54 PERP11 SCONN168_ME1016810202011-SCONN168_ME1016810202011,A   I168 @T6G_MB_LIB.T6G(SCH_1):PAGE341

P5E_CPU1_G1_RX_DP<12> @T6G_MB_LIB.T6G(SCH_1):P5E_CPU1_G1_RX_DP(12)
   U26  U50 G1_RXP12 GENOA_SP5-SOCKET6096_13568-001,SMLF,IO,DGA^6000030   I214 @T6G_MB_LIB.T6G(SCH_1):PAGE49
   J35  A57 PERP12 SCONN168_ME1016810202011-SCONN168_ME1016810202011,A   I168 @T6G_MB_LIB.T6G(SCH_1):PAGE341

P5E_CPU1_G1_RX_DP<13> @T6G_MB_LIB.T6G(SCH_1):P5E_CPU1_G1_RX_DP(13)
   U26  W53 G1_RXP13 GENOA_SP5-SOCKET6096_13568-001,SMLF,IO,DGA^6000030   I214 @T6G_MB_LIB.T6G(SCH_1):PAGE49
   J35  A60 PERP13 SCONN168_ME1016810202011-SCONN168_ME1016810202011,A   I168 @T6G_MB_LIB.T6G(SCH_1):PAGE341

P5E_CPU1_G1_RX_DP<14> @T6G_MB_LIB.T6G(SCH_1):P5E_CPU1_G1_RX_DP(14)
   U26  R53 G1_RXP14 GENOA_SP5-SOCKET6096_13568-001,SMLF,IO,DGA^6000030   I214 @T6G_MB_LIB.T6G(SCH_1):PAGE49
   J35  A63 PERP14 SCONN168_ME1016810202011-SCONN168_ME1016810202011,A   I168 @T6G_MB_LIB.T6G(SCH_1):PAGE341

P5E_CPU1_G1_RX_DP<15> @T6G_MB_LIB.T6G(SCH_1):P5E_CPU1_G1_RX_DP(15)
   U26  U53 G1_RXP15 GENOA_SP5-SOCKET6096_13568-001,SMLF,IO,DGA^6000030   I214 @T6G_MB_LIB.T6G(SCH_1):PAGE49
   J35  A66 PERP15 SCONN168_ME1016810202011-SCONN168_ME1016810202011,A   I168 @T6G_MB_LIB.T6G(SCH_1):PAGE341

P5E_CPU1_G1_RX_DP<1> @T6G_MB_LIB.T6G(SCH_1):P5E_CPU1_G1_RX_DP(1)
   U26  T41 G1_RXP1 GENOA_SP5-SOCKET6096_13568-001,SMLF,IO,DGA^6000030   I214 @T6G_MB_LIB.T6G(SCH_1):PAGE49
   J35  A21  PERP1 SCONN168_ME1016810202011-SCONN168_ME1016810202011,A   I168 @T6G_MB_LIB.T6G(SCH_1):PAGE341

P5E_CPU1_G1_RX_DP<2> @T6G_MB_LIB.T6G(SCH_1):P5E_CPU1_G1_RX_DP(2)
   U26  P41 G1_RXP2 GENOA_SP5-SOCKET6096_13568-001,SMLF,IO,DGA^6000030   I214 @T6G_MB_LIB.T6G(SCH_1):PAGE49
   J35  A24  PERP2 SCONN168_ME1016810202011-SCONN168_ME1016810202011,A   I168 @T6G_MB_LIB.T6G(SCH_1):PAGE341

P5E_CPU1_G1_RX_DP<3> @T6G_MB_LIB.T6G(SCH_1):P5E_CPU1_G1_RX_DP(3)
   U26  U44 G1_RXP3 GENOA_SP5-SOCKET6096_13568-001,SMLF,IO,DGA^6000030   I214 @T6G_MB_LIB.T6G(SCH_1):PAGE49
   J35  A27  PERP3 SCONN168_ME1016810202011-SCONN168_ME1016810202011,A   I168 @T6G_MB_LIB.T6G(SCH_1):PAGE341

P5E_CPU1_G1_RX_DP<4> @T6G_MB_LIB.T6G(SCH_1):P5E_CPU1_G1_RX_DP(4)
   U26  N44 G1_RXP4 GENOA_SP5-SOCKET6096_13568-001,SMLF,IO,DGA^6000030   I214 @T6G_MB_LIB.T6G(SCH_1):PAGE49
   J35  A31  PERP4 SCONN168_ME1016810202011-SCONN168_ME1016810202011,A   I168 @T6G_MB_LIB.T6G(SCH_1):PAGE341

P5E_CPU1_G1_RX_DP<5> @T6G_MB_LIB.T6G(SCH_1):P5E_CPU1_G1_RX_DP(5)
   U26  R44 G1_RXP5 GENOA_SP5-SOCKET6096_13568-001,SMLF,IO,DGA^6000030   I214 @T6G_MB_LIB.T6G(SCH_1):PAGE49
   J35  A34  PERP5 SCONN168_ME1016810202011-SCONN168_ME1016810202011,A   I168 @T6G_MB_LIB.T6G(SCH_1):PAGE341

P5E_CPU1_G1_RX_DP<6> @T6G_MB_LIB.T6G(SCH_1):P5E_CPU1_G1_RX_DP(6)
   U26  U47 G1_RXP6 GENOA_SP5-SOCKET6096_13568-001,SMLF,IO,DGA^6000030   I214 @T6G_MB_LIB.T6G(SCH_1):PAGE49
   J35  A37  PERP6 SCONN168_ME1016810202011-SCONN168_ME1016810202011,A   I168 @T6G_MB_LIB.T6G(SCH_1):PAGE341

P5E_CPU1_G1_RX_DP<7> @T6G_MB_LIB.T6G(SCH_1):P5E_CPU1_G1_RX_DP(7)
   U26  N47 G1_RXP7 GENOA_SP5-SOCKET6096_13568-001,SMLF,IO,DGA^6000030   I214 @T6G_MB_LIB.T6G(SCH_1):PAGE49
   J35  A40  PERP7 SCONN168_ME1016810202011-SCONN168_ME1016810202011,A   I168 @T6G_MB_LIB.T6G(SCH_1):PAGE341

P5E_CPU1_G1_RX_DP<8> @T6G_MB_LIB.T6G(SCH_1):P5E_CPU1_G1_RX_DP(8)
   U26  R47 G1_RXP8 GENOA_SP5-SOCKET6096_13568-001,SMLF,IO,DGA^6000030   I214 @T6G_MB_LIB.T6G(SCH_1):PAGE49
   J35  A45  PERP8 SCONN168_ME1016810202011-SCONN168_ME1016810202011,A   I168 @T6G_MB_LIB.T6G(SCH_1):PAGE341

P5E_CPU1_G1_RX_DP<9> @T6G_MB_LIB.T6G(SCH_1):P5E_CPU1_G1_RX_DP(9)
   U26  W50 G1_RXP9 GENOA_SP5-SOCKET6096_13568-001,SMLF,IO,DGA^6000030   I214 @T6G_MB_LIB.T6G(SCH_1):PAGE49
   J35  A48  PERP9 SCONN168_ME1016810202011-SCONN168_ME1016810202011,A   I168 @T6G_MB_LIB.T6G(SCH_1):PAGE341

P5E_CPU1_G1_TX_C_DN<0> @T6G_MB_LIB.T6G(SCH_1):P5E_CPU1_G1_TX_C_DN(0)
   J35  B18  PETP0 SCONN168_ME1016810202011-SCONN168_ME1016810202011,A   I168 @T6G_MB_LIB.T6G(SCH_1):PAGE341
  C708    1      1 Q_CAP_DIFFBUS_C0201-DIFF BUS_0.22UF,6.3V,20%,X6S,SA   I166 @T6G_MB_LIB.T6G(SCH_1):PAGE355

P5E_CPU1_G1_TX_C_DN<10> @T6G_MB_LIB.T6G(SCH_1):P5E_CPU1_G1_TX_C_DN(10)
   J35  B51 PETP10 SCONN168_ME1016810202011-SCONN168_ME1016810202011,A   I168 @T6G_MB_LIB.T6G(SCH_1):PAGE341
  C688    1      1 Q_CAP_DIFFBUS_C0201-DIFF BUS_0.22UF,6.3V,20%,X6S,SA   I220 @T6G_MB_LIB.T6G(SCH_1):PAGE355

P5E_CPU1_G1_TX_C_DN<11> @T6G_MB_LIB.T6G(SCH_1):P5E_CPU1_G1_TX_C_DN(11)
   J35  B54 PETP11 SCONN168_ME1016810202011-SCONN168_ME1016810202011,A   I168 @T6G_MB_LIB.T6G(SCH_1):PAGE341
  C686    1      1 Q_CAP_DIFFBUS_C0201-DIFF BUS_0.22UF,6.3V,20%,X6S,SA   I223 @T6G_MB_LIB.T6G(SCH_1):PAGE355

P5E_CPU1_G1_TX_C_DN<12> @T6G_MB_LIB.T6G(SCH_1):P5E_CPU1_G1_TX_C_DN(12)
   J35  B57 PETP12 SCONN168_ME1016810202011-SCONN168_ME1016810202011,A   I168 @T6G_MB_LIB.T6G(SCH_1):PAGE341
  C684    1      1 Q_CAP_DIFFBUS_C0201-DIFF BUS_0.22UF,6.3V,20%,X6S,SA   I225 @T6G_MB_LIB.T6G(SCH_1):PAGE355

P5E_CPU1_G1_TX_C_DN<13> @T6G_MB_LIB.T6G(SCH_1):P5E_CPU1_G1_TX_C_DN(13)
   J35  B60 PETP13 SCONN168_ME1016810202011-SCONN168_ME1016810202011,A   I168 @T6G_MB_LIB.T6G(SCH_1):PAGE341
  C682    1      1 Q_CAP_DIFFBUS_C0201-DIFF BUS_0.22UF,6.3V,20%,X6S,SA   I247 @T6G_MB_LIB.T6G(SCH_1):PAGE355

P5E_CPU1_G1_TX_C_DN<14> @T6G_MB_LIB.T6G(SCH_1):P5E_CPU1_G1_TX_C_DN(14)
   J35  B63 PETP14 SCONN168_ME1016810202011-SCONN168_ME1016810202011,A   I168 @T6G_MB_LIB.T6G(SCH_1):PAGE341
  C680    1      1 Q_CAP_DIFFBUS_C0201-DIFF BUS_0.22UF,6.3V,20%,X6S,SA   I249 @T6G_MB_LIB.T6G(SCH_1):PAGE355

P5E_CPU1_G1_TX_C_DN<15> @T6G_MB_LIB.T6G(SCH_1):P5E_CPU1_G1_TX_C_DN(15)
   J35  B66 PETP15 SCONN168_ME1016810202011-SCONN168_ME1016810202011,A   I168 @T6G_MB_LIB.T6G(SCH_1):PAGE341
  C678    1      1 Q_CAP_DIFFBUS_C0201-DIFF BUS_0.22UF,6.3V,20%,X6S,SA   I251 @T6G_MB_LIB.T6G(SCH_1):PAGE355

P5E_CPU1_G1_TX_C_DN<1> @T6G_MB_LIB.T6G(SCH_1):P5E_CPU1_G1_TX_C_DN(1)
   J35  B21  PETP1 SCONN168_ME1016810202011-SCONN168_ME1016810202011,A   I168 @T6G_MB_LIB.T6G(SCH_1):PAGE341
  C706    1      1 Q_CAP_DIFFBUS_C0201-DIFF BUS_0.22UF,6.3V,20%,X6S,SA   I167 @T6G_MB_LIB.T6G(SCH_1):PAGE355

P5E_CPU1_G1_TX_C_DN<2> @T6G_MB_LIB.T6G(SCH_1):P5E_CPU1_G1_TX_C_DN(2)
   J35  B24  PETP2 SCONN168_ME1016810202011-SCONN168_ME1016810202011,A   I168 @T6G_MB_LIB.T6G(SCH_1):PAGE341
  C704    1      1 Q_CAP_DIFFBUS_C0201-DIFF BUS_0.22UF,6.3V,20%,X6S,SA   I170 @T6G_MB_LIB.T6G(SCH_1):PAGE355

P5E_CPU1_G1_TX_C_DN<3> @T6G_MB_LIB.T6G(SCH_1):P5E_CPU1_G1_TX_C_DN(3)
   J35  B27  PETP3 SCONN168_ME1016810202011-SCONN168_ME1016810202011,A   I168 @T6G_MB_LIB.T6G(SCH_1):PAGE341
  C702    1      1 Q_CAP_DIFFBUS_C0201-DIFF BUS_0.22UF,6.3V,20%,X6S,SA   I197 @T6G_MB_LIB.T6G(SCH_1):PAGE355

P5E_CPU1_G1_TX_C_DN<4> @T6G_MB_LIB.T6G(SCH_1):P5E_CPU1_G1_TX_C_DN(4)
   J35  B31  PETP4 SCONN168_ME1016810202011-SCONN168_ME1016810202011,A   I168 @T6G_MB_LIB.T6G(SCH_1):PAGE341
  C700    1      1 Q_CAP_DIFFBUS_C0201-DIFF BUS_0.22UF,6.3V,20%,X6S,SA   I200 @T6G_MB_LIB.T6G(SCH_1):PAGE355

P5E_CPU1_G1_TX_C_DN<5> @T6G_MB_LIB.T6G(SCH_1):P5E_CPU1_G1_TX_C_DN(5)
   J35  B34  PETP5 SCONN168_ME1016810202011-SCONN168_ME1016810202011,A   I168 @T6G_MB_LIB.T6G(SCH_1):PAGE341
  C698    1      1 Q_CAP_DIFFBUS_C0201-DIFF BUS_0.22UF,6.3V,20%,X6S,SA   I201 @T6G_MB_LIB.T6G(SCH_1):PAGE355

P5E_CPU1_G1_TX_C_DN<6> @T6G_MB_LIB.T6G(SCH_1):P5E_CPU1_G1_TX_C_DN(6)
   J35  B37  PETP6 SCONN168_ME1016810202011-SCONN168_ME1016810202011,A   I168 @T6G_MB_LIB.T6G(SCH_1):PAGE341
  C696    1      1 Q_CAP_DIFFBUS_C0201-DIFF BUS_0.22UF,6.3V,20%,X6S,SA   I204 @T6G_MB_LIB.T6G(SCH_1):PAGE355

P5E_CPU1_G1_TX_C_DN<7> @T6G_MB_LIB.T6G(SCH_1):P5E_CPU1_G1_TX_C_DN(7)
   J35  B40  PETP7 SCONN168_ME1016810202011-SCONN168_ME1016810202011,A   I168 @T6G_MB_LIB.T6G(SCH_1):PAGE341
  C694    1      1 Q_CAP_DIFFBUS_C0201-DIFF BUS_0.22UF,6.3V,20%,X6S,SA   I206 @T6G_MB_LIB.T6G(SCH_1):PAGE355

P5E_CPU1_G1_TX_C_DN<8> @T6G_MB_LIB.T6G(SCH_1):P5E_CPU1_G1_TX_C_DN(8)
   J35  B45  PETP8 SCONN168_ME1016810202011-SCONN168_ME1016810202011,A   I168 @T6G_MB_LIB.T6G(SCH_1):PAGE341
  C692    1      1 Q_CAP_DIFFBUS_C0201-DIFF BUS_0.22UF,6.3V,20%,X6S,SA   I217 @T6G_MB_LIB.T6G(SCH_1):PAGE355

P5E_CPU1_G1_TX_C_DN<9> @T6G_MB_LIB.T6G(SCH_1):P5E_CPU1_G1_TX_C_DN(9)
   J35  B48  PETP9 SCONN168_ME1016810202011-SCONN168_ME1016810202011,A   I168 @T6G_MB_LIB.T6G(SCH_1):PAGE341
  C690    1      1 Q_CAP_DIFFBUS_C0201-DIFF BUS_0.22UF,6.3V,20%,X6S,SA   I219 @T6G_MB_LIB.T6G(SCH_1):PAGE355

P5E_CPU1_G1_TX_C_DP<0> @T6G_MB_LIB.T6G(SCH_1):P5E_CPU1_G1_TX_C_DP(0)
   J35  B17  PETN0 SCONN168_ME1016810202011-SCONN168_ME1016810202011,A   I168 @T6G_MB_LIB.T6G(SCH_1):PAGE341
  C709    1      1 Q_CAP_DIFFBUS_C0201-DIFF BUS_0.22UF,6.3V,20%,X6S,SA   I165 @T6G_MB_LIB.T6G(SCH_1):PAGE355

P5E_CPU1_G1_TX_C_DP<10> @T6G_MB_LIB.T6G(SCH_1):P5E_CPU1_G1_TX_C_DP(10)
   J35  B50 PETN10 SCONN168_ME1016810202011-SCONN168_ME1016810202011,A   I168 @T6G_MB_LIB.T6G(SCH_1):PAGE341
  C689    1      1 Q_CAP_DIFFBUS_C0201-DIFF BUS_0.22UF,6.3V,20%,X6S,SA   I221 @T6G_MB_LIB.T6G(SCH_1):PAGE355

P5E_CPU1_G1_TX_C_DP<11> @T6G_MB_LIB.T6G(SCH_1):P5E_CPU1_G1_TX_C_DP(11)
   J35  B53 PETN11 SCONN168_ME1016810202011-SCONN168_ME1016810202011,A   I168 @T6G_MB_LIB.T6G(SCH_1):PAGE341
  C687    1      1 Q_CAP_DIFFBUS_C0201-DIFF BUS_0.22UF,6.3V,20%,X6S,SA   I222 @T6G_MB_LIB.T6G(SCH_1):PAGE355

P5E_CPU1_G1_TX_C_DP<12> @T6G_MB_LIB.T6G(SCH_1):P5E_CPU1_G1_TX_C_DP(12)
   J35  B56 PETN12 SCONN168_ME1016810202011-SCONN168_ME1016810202011,A   I168 @T6G_MB_LIB.T6G(SCH_1):PAGE341
  C685    1      1 Q_CAP_DIFFBUS_C0201-DIFF BUS_0.22UF,6.3V,20%,X6S,SA   I224 @T6G_MB_LIB.T6G(SCH_1):PAGE355

P5E_CPU1_G1_TX_C_DP<13> @T6G_MB_LIB.T6G(SCH_1):P5E_CPU1_G1_TX_C_DP(13)
   J35  B59 PETN13 SCONN168_ME1016810202011-SCONN168_ME1016810202011,A   I168 @T6G_MB_LIB.T6G(SCH_1):PAGE341
  C683    1      1 Q_CAP_DIFFBUS_C0201-DIFF BUS_0.22UF,6.3V,20%,X6S,SA   I236 @T6G_MB_LIB.T6G(SCH_1):PAGE355

P5E_CPU1_G1_TX_C_DP<14> @T6G_MB_LIB.T6G(SCH_1):P5E_CPU1_G1_TX_C_DP(14)
   J35  B62 PETN14 SCONN168_ME1016810202011-SCONN168_ME1016810202011,A   I168 @T6G_MB_LIB.T6G(SCH_1):PAGE341
  C681    1      1 Q_CAP_DIFFBUS_C0201-DIFF BUS_0.22UF,6.3V,20%,X6S,SA   I248 @T6G_MB_LIB.T6G(SCH_1):PAGE355

P5E_CPU1_G1_TX_C_DP<15> @T6G_MB_LIB.T6G(SCH_1):P5E_CPU1_G1_TX_C_DP(15)
   J35  B65 PETN15 SCONN168_ME1016810202011-SCONN168_ME1016810202011,A   I168 @T6G_MB_LIB.T6G(SCH_1):PAGE341
  C679    1      1 Q_CAP_DIFFBUS_C0201-DIFF BUS_0.22UF,6.3V,20%,X6S,SA   I250 @T6G_MB_LIB.T6G(SCH_1):PAGE355

P5E_CPU1_G1_TX_C_DP<1> @T6G_MB_LIB.T6G(SCH_1):P5E_CPU1_G1_TX_C_DP(1)
   J35  B20  PETN1 SCONN168_ME1016810202011-SCONN168_ME1016810202011,A   I168 @T6G_MB_LIB.T6G(SCH_1):PAGE341
  C707    1      1 Q_CAP_DIFFBUS_C0201-DIFF BUS_0.22UF,6.3V,20%,X6S,SA   I168 @T6G_MB_LIB.T6G(SCH_1):PAGE355

P5E_CPU1_G1_TX_C_DP<2> @T6G_MB_LIB.T6G(SCH_1):P5E_CPU1_G1_TX_C_DP(2)
   J35  B23  PETN2 SCONN168_ME1016810202011-SCONN168_ME1016810202011,A   I168 @T6G_MB_LIB.T6G(SCH_1):PAGE341
  C705    1      1 Q_CAP_DIFFBUS_C0201-DIFF BUS_0.22UF,6.3V,20%,X6S,SA   I169 @T6G_MB_LIB.T6G(SCH_1):PAGE355

P5E_CPU1_G1_TX_C_DP<3> @T6G_MB_LIB.T6G(SCH_1):P5E_CPU1_G1_TX_C_DP(3)
   J35  B26  PETN3 SCONN168_ME1016810202011-SCONN168_ME1016810202011,A   I168 @T6G_MB_LIB.T6G(SCH_1):PAGE341
  C703    1      1 Q_CAP_DIFFBUS_C0201-DIFF BUS_0.22UF,6.3V,20%,X6S,SA   I198 @T6G_MB_LIB.T6G(SCH_1):PAGE355

P5E_CPU1_G1_TX_C_DP<4> @T6G_MB_LIB.T6G(SCH_1):P5E_CPU1_G1_TX_C_DP(4)
   J35  B30  PETN4 SCONN168_ME1016810202011-SCONN168_ME1016810202011,A   I168 @T6G_MB_LIB.T6G(SCH_1):PAGE341
  C701    1      1 Q_CAP_DIFFBUS_C0201-DIFF BUS_0.22UF,6.3V,20%,X6S,SA   I199 @T6G_MB_LIB.T6G(SCH_1):PAGE355

P5E_CPU1_G1_TX_C_DP<5> @T6G_MB_LIB.T6G(SCH_1):P5E_CPU1_G1_TX_C_DP(5)
   J35  B33  PETN5 SCONN168_ME1016810202011-SCONN168_ME1016810202011,A   I168 @T6G_MB_LIB.T6G(SCH_1):PAGE341
  C699    1      1 Q_CAP_DIFFBUS_C0201-DIFF BUS_0.22UF,6.3V,20%,X6S,SA   I202 @T6G_MB_LIB.T6G(SCH_1):PAGE355

P5E_CPU1_G1_TX_C_DP<6> @T6G_MB_LIB.T6G(SCH_1):P5E_CPU1_G1_TX_C_DP(6)
   J35  B36  PETN6 SCONN168_ME1016810202011-SCONN168_ME1016810202011,A   I168 @T6G_MB_LIB.T6G(SCH_1):PAGE341
  C697    1      1 Q_CAP_DIFFBUS_C0201-DIFF BUS_0.22UF,6.3V,20%,X6S,SA   I203 @T6G_MB_LIB.T6G(SCH_1):PAGE355

P5E_CPU1_G1_TX_C_DP<7> @T6G_MB_LIB.T6G(SCH_1):P5E_CPU1_G1_TX_C_DP(7)
   J35  B39  PETN7 SCONN168_ME1016810202011-SCONN168_ME1016810202011,A   I168 @T6G_MB_LIB.T6G(SCH_1):PAGE341
  C695    1      1 Q_CAP_DIFFBUS_C0201-DIFF BUS_0.22UF,6.3V,20%,X6S,SA   I205 @T6G_MB_LIB.T6G(SCH_1):PAGE355

P5E_CPU1_G1_TX_C_DP<8> @T6G_MB_LIB.T6G(SCH_1):P5E_CPU1_G1_TX_C_DP(8)
   J35  B44  PETN8 SCONN168_ME1016810202011-SCONN168_ME1016810202011,A   I168 @T6G_MB_LIB.T6G(SCH_1):PAGE341
   C56    1      1 Q_CAP_DIFFBUS_C0201-DIFF BUS_0.22UF,6.3V,20%,X6S,SA   I216 @T6G_MB_LIB.T6G(SCH_1):PAGE355

P5E_CPU1_G1_TX_C_DP<9> @T6G_MB_LIB.T6G(SCH_1):P5E_CPU1_G1_TX_C_DP(9)
   J35  B47  PETN9 SCONN168_ME1016810202011-SCONN168_ME1016810202011,A   I168 @T6G_MB_LIB.T6G(SCH_1):PAGE341
  C691    1      1 Q_CAP_DIFFBUS_C0201-DIFF BUS_0.22UF,6.3V,20%,X6S,SA   I218 @T6G_MB_LIB.T6G(SCH_1):PAGE355

P5E_CPU1_G1_TX_DN<0> @T6G_MB_LIB.T6G(SCH_1):P5E_CPU1_G1_TX_DN(0)
   U26 AP41 G1_TXN0 GENOA_SP5-SOCKET6096_13568-001,SMLF,IO,DGA^6000030   I214 @T6G_MB_LIB.T6G(SCH_1):PAGE49
  C708    2      2 Q_CAP_DIFFBUS_C0201-DIFF BUS_0.22UF,6.3V,20%,X6S,SA   I166 @T6G_MB_LIB.T6G(SCH_1):PAGE355

P5E_CPU1_G1_TX_DN<10> @T6G_MB_LIB.T6G(SCH_1):P5E_CPU1_G1_TX_DN(10)
   U26 AN50 G1_TXN10 GENOA_SP5-SOCKET6096_13568-001,SMLF,IO,DGA^6000030   I214 @T6G_MB_LIB.T6G(SCH_1):PAGE49
  C688    2      2 Q_CAP_DIFFBUS_C0201-DIFF BUS_0.22UF,6.3V,20%,X6S,SA   I220 @T6G_MB_LIB.T6G(SCH_1):PAGE355

P5E_CPU1_G1_TX_DN<11> @T6G_MB_LIB.T6G(SCH_1):P5E_CPU1_G1_TX_DN(11)
   U26 AJ50 G1_TXN11 GENOA_SP5-SOCKET6096_13568-001,SMLF,IO,DGA^6000030   I214 @T6G_MB_LIB.T6G(SCH_1):PAGE49
  C686    2      2 Q_CAP_DIFFBUS_C0201-DIFF BUS_0.22UF,6.3V,20%,X6S,SA   I223 @T6G_MB_LIB.T6G(SCH_1):PAGE355

P5E_CPU1_G1_TX_DN<12> @T6G_MB_LIB.T6G(SCH_1):P5E_CPU1_G1_TX_DN(12)
   U26 AL50 G1_TXN12 GENOA_SP5-SOCKET6096_13568-001,SMLF,IO,DGA^6000030   I214 @T6G_MB_LIB.T6G(SCH_1):PAGE49
  C684    2      2 Q_CAP_DIFFBUS_C0201-DIFF BUS_0.22UF,6.3V,20%,X6S,SA   I225 @T6G_MB_LIB.T6G(SCH_1):PAGE355

P5E_CPU1_G1_TX_DN<13> @T6G_MB_LIB.T6G(SCH_1):P5E_CPU1_G1_TX_DN(13)
   U26 AN53 G1_TXN13 GENOA_SP5-SOCKET6096_13568-001,SMLF,IO,DGA^6000030   I214 @T6G_MB_LIB.T6G(SCH_1):PAGE49
  C682    2      2 Q_CAP_DIFFBUS_C0201-DIFF BUS_0.22UF,6.3V,20%,X6S,SA   I247 @T6G_MB_LIB.T6G(SCH_1):PAGE355

P5E_CPU1_G1_TX_DN<14> @T6G_MB_LIB.T6G(SCH_1):P5E_CPU1_G1_TX_DN(14)
   U26 AJ53 G1_TXN14 GENOA_SP5-SOCKET6096_13568-001,SMLF,IO,DGA^6000030   I214 @T6G_MB_LIB.T6G(SCH_1):PAGE49
  C680    2      2 Q_CAP_DIFFBUS_C0201-DIFF BUS_0.22UF,6.3V,20%,X6S,SA   I249 @T6G_MB_LIB.T6G(SCH_1):PAGE355

P5E_CPU1_G1_TX_DN<15> @T6G_MB_LIB.T6G(SCH_1):P5E_CPU1_G1_TX_DN(15)
   U26 AL53 G1_TXN15 GENOA_SP5-SOCKET6096_13568-001,SMLF,IO,DGA^6000030   I214 @T6G_MB_LIB.T6G(SCH_1):PAGE49
  C678    2      2 Q_CAP_DIFFBUS_C0201-DIFF BUS_0.22UF,6.3V,20%,X6S,SA   I251 @T6G_MB_LIB.T6G(SCH_1):PAGE355

P5E_CPU1_G1_TX_DN<1> @T6G_MB_LIB.T6G(SCH_1):P5E_CPU1_G1_TX_DN(1)
   U26 AM41 G1_TXN1 GENOA_SP5-SOCKET6096_13568-001,SMLF,IO,DGA^6000030   I214 @T6G_MB_LIB.T6G(SCH_1):PAGE49
  C706    2      2 Q_CAP_DIFFBUS_C0201-DIFF BUS_0.22UF,6.3V,20%,X6S,SA   I167 @T6G_MB_LIB.T6G(SCH_1):PAGE355

P5E_CPU1_G1_TX_DN<2> @T6G_MB_LIB.T6G(SCH_1):P5E_CPU1_G1_TX_DN(2)
   U26 AH41 G1_TXN2 GENOA_SP5-SOCKET6096_13568-001,SMLF,IO,DGA^6000030   I214 @T6G_MB_LIB.T6G(SCH_1):PAGE49
  C704    2      2 Q_CAP_DIFFBUS_C0201-DIFF BUS_0.22UF,6.3V,20%,X6S,SA   I170 @T6G_MB_LIB.T6G(SCH_1):PAGE355

P5E_CPU1_G1_TX_DN<3> @T6G_MB_LIB.T6G(SCH_1):P5E_CPU1_G1_TX_DN(3)
   U26 AK41 G1_TXN3 GENOA_SP5-SOCKET6096_13568-001,SMLF,IO,DGA^6000030   I214 @T6G_MB_LIB.T6G(SCH_1):PAGE49
  C702    2      2 Q_CAP_DIFFBUS_C0201-DIFF BUS_0.22UF,6.3V,20%,X6S,SA   I197 @T6G_MB_LIB.T6G(SCH_1):PAGE355

P5E_CPU1_G1_TX_DN<4> @T6G_MB_LIB.T6G(SCH_1):P5E_CPU1_G1_TX_DN(4)
   U26 AN44 G1_TXN4 GENOA_SP5-SOCKET6096_13568-001,SMLF,IO,DGA^6000030   I214 @T6G_MB_LIB.T6G(SCH_1):PAGE49
  C700    2      2 Q_CAP_DIFFBUS_C0201-DIFF BUS_0.22UF,6.3V,20%,X6S,SA   I200 @T6G_MB_LIB.T6G(SCH_1):PAGE355

P5E_CPU1_G1_TX_DN<5> @T6G_MB_LIB.T6G(SCH_1):P5E_CPU1_G1_TX_DN(5)
   U26 AJ44 G1_TXN5 GENOA_SP5-SOCKET6096_13568-001,SMLF,IO,DGA^6000030   I214 @T6G_MB_LIB.T6G(SCH_1):PAGE49
  C698    2      2 Q_CAP_DIFFBUS_C0201-DIFF BUS_0.22UF,6.3V,20%,X6S,SA   I201 @T6G_MB_LIB.T6G(SCH_1):PAGE355

P5E_CPU1_G1_TX_DN<6> @T6G_MB_LIB.T6G(SCH_1):P5E_CPU1_G1_TX_DN(6)
   U26 AL44 G1_TXN6 GENOA_SP5-SOCKET6096_13568-001,SMLF,IO,DGA^6000030   I214 @T6G_MB_LIB.T6G(SCH_1):PAGE49
  C696    2      2 Q_CAP_DIFFBUS_C0201-DIFF BUS_0.22UF,6.3V,20%,X6S,SA   I204 @T6G_MB_LIB.T6G(SCH_1):PAGE355

P5E_CPU1_G1_TX_DN<7> @T6G_MB_LIB.T6G(SCH_1):P5E_CPU1_G1_TX_DN(7)
   U26 AN47 G1_TXN7 GENOA_SP5-SOCKET6096_13568-001,SMLF,IO,DGA^6000030   I214 @T6G_MB_LIB.T6G(SCH_1):PAGE49
  C694    2      2 Q_CAP_DIFFBUS_C0201-DIFF BUS_0.22UF,6.3V,20%,X6S,SA   I206 @T6G_MB_LIB.T6G(SCH_1):PAGE355

P5E_CPU1_G1_TX_DN<8> @T6G_MB_LIB.T6G(SCH_1):P5E_CPU1_G1_TX_DN(8)
   U26 AJ47 G1_TXN8 GENOA_SP5-SOCKET6096_13568-001,SMLF,IO,DGA^6000030   I214 @T6G_MB_LIB.T6G(SCH_1):PAGE49
  C692    2      2 Q_CAP_DIFFBUS_C0201-DIFF BUS_0.22UF,6.3V,20%,X6S,SA   I217 @T6G_MB_LIB.T6G(SCH_1):PAGE355

P5E_CPU1_G1_TX_DN<9> @T6G_MB_LIB.T6G(SCH_1):P5E_CPU1_G1_TX_DN(9)
   U26 AL47 G1_TXN9 GENOA_SP5-SOCKET6096_13568-001,SMLF,IO,DGA^6000030   I214 @T6G_MB_LIB.T6G(SCH_1):PAGE49
  C690    2      2 Q_CAP_DIFFBUS_C0201-DIFF BUS_0.22UF,6.3V,20%,X6S,SA   I219 @T6G_MB_LIB.T6G(SCH_1):PAGE355

P5E_CPU1_G1_TX_DP<0> @T6G_MB_LIB.T6G(SCH_1):P5E_CPU1_G1_TX_DP(0)
   U26 AP40 G1_TXP0 GENOA_SP5-SOCKET6096_13568-001,SMLF,IO,DGA^6000030   I214 @T6G_MB_LIB.T6G(SCH_1):PAGE49
  C709    2      2 Q_CAP_DIFFBUS_C0201-DIFF BUS_0.22UF,6.3V,20%,X6S,SA   I165 @T6G_MB_LIB.T6G(SCH_1):PAGE355

P5E_CPU1_G1_TX_DP<10> @T6G_MB_LIB.T6G(SCH_1):P5E_CPU1_G1_TX_DP(10)
   U26 AN49 G1_TXP10 GENOA_SP5-SOCKET6096_13568-001,SMLF,IO,DGA^6000030   I214 @T6G_MB_LIB.T6G(SCH_1):PAGE49
  C689    2      2 Q_CAP_DIFFBUS_C0201-DIFF BUS_0.22UF,6.3V,20%,X6S,SA   I221 @T6G_MB_LIB.T6G(SCH_1):PAGE355

P5E_CPU1_G1_TX_DP<11> @T6G_MB_LIB.T6G(SCH_1):P5E_CPU1_G1_TX_DP(11)
   U26 AJ49 G1_TXP11 GENOA_SP5-SOCKET6096_13568-001,SMLF,IO,DGA^6000030   I214 @T6G_MB_LIB.T6G(SCH_1):PAGE49
  C687    2      2 Q_CAP_DIFFBUS_C0201-DIFF BUS_0.22UF,6.3V,20%,X6S,SA   I222 @T6G_MB_LIB.T6G(SCH_1):PAGE355

P5E_CPU1_G1_TX_DP<12> @T6G_MB_LIB.T6G(SCH_1):P5E_CPU1_G1_TX_DP(12)
   U26 AL49 G1_TXP12 GENOA_SP5-SOCKET6096_13568-001,SMLF,IO,DGA^6000030   I214 @T6G_MB_LIB.T6G(SCH_1):PAGE49
  C685    2      2 Q_CAP_DIFFBUS_C0201-DIFF BUS_0.22UF,6.3V,20%,X6S,SA   I224 @T6G_MB_LIB.T6G(SCH_1):PAGE355

P5E_CPU1_G1_TX_DP<13> @T6G_MB_LIB.T6G(SCH_1):P5E_CPU1_G1_TX_DP(13)
   U26 AN52 G1_TXP13 GENOA_SP5-SOCKET6096_13568-001,SMLF,IO,DGA^6000030   I214 @T6G_MB_LIB.T6G(SCH_1):PAGE49
  C683    2      2 Q_CAP_DIFFBUS_C0201-DIFF BUS_0.22UF,6.3V,20%,X6S,SA   I236 @T6G_MB_LIB.T6G(SCH_1):PAGE355

P5E_CPU1_G1_TX_DP<14> @T6G_MB_LIB.T6G(SCH_1):P5E_CPU1_G1_TX_DP(14)
   U26 AJ52 G1_TXP14 GENOA_SP5-SOCKET6096_13568-001,SMLF,IO,DGA^6000030   I214 @T6G_MB_LIB.T6G(SCH_1):PAGE49
  C681    2      2 Q_CAP_DIFFBUS_C0201-DIFF BUS_0.22UF,6.3V,20%,X6S,SA   I248 @T6G_MB_LIB.T6G(SCH_1):PAGE355

P5E_CPU1_G1_TX_DP<15> @T6G_MB_LIB.T6G(SCH_1):P5E_CPU1_G1_TX_DP(15)
   U26 AL52 G1_TXP15 GENOA_SP5-SOCKET6096_13568-001,SMLF,IO,DGA^6000030   I214 @T6G_MB_LIB.T6G(SCH_1):PAGE49
  C679    2      2 Q_CAP_DIFFBUS_C0201-DIFF BUS_0.22UF,6.3V,20%,X6S,SA   I250 @T6G_MB_LIB.T6G(SCH_1):PAGE355

P5E_CPU1_G1_TX_DP<1> @T6G_MB_LIB.T6G(SCH_1):P5E_CPU1_G1_TX_DP(1)
   U26 AM40 G1_TXP1 GENOA_SP5-SOCKET6096_13568-001,SMLF,IO,DGA^6000030   I214 @T6G_MB_LIB.T6G(SCH_1):PAGE49
  C707    2      2 Q_CAP_DIFFBUS_C0201-DIFF BUS_0.22UF,6.3V,20%,X6S,SA   I168 @T6G_MB_LIB.T6G(SCH_1):PAGE355

P5E_CPU1_G1_TX_DP<2> @T6G_MB_LIB.T6G(SCH_1):P5E_CPU1_G1_TX_DP(2)
   U26 AH40 G1_TXP2 GENOA_SP5-SOCKET6096_13568-001,SMLF,IO,DGA^6000030   I214 @T6G_MB_LIB.T6G(SCH_1):PAGE49
  C705    2      2 Q_CAP_DIFFBUS_C0201-DIFF BUS_0.22UF,6.3V,20%,X6S,SA   I169 @T6G_MB_LIB.T6G(SCH_1):PAGE355

P5E_CPU1_G1_TX_DP<3> @T6G_MB_LIB.T6G(SCH_1):P5E_CPU1_G1_TX_DP(3)
   U26 AK40 G1_TXP3 GENOA_SP5-SOCKET6096_13568-001,SMLF,IO,DGA^6000030   I214 @T6G_MB_LIB.T6G(SCH_1):PAGE49
  C703    2      2 Q_CAP_DIFFBUS_C0201-DIFF BUS_0.22UF,6.3V,20%,X6S,SA   I198 @T6G_MB_LIB.T6G(SCH_1):PAGE355

P5E_CPU1_G1_TX_DP<4> @T6G_MB_LIB.T6G(SCH_1):P5E_CPU1_G1_TX_DP(4)
   U26 AN43 G1_TXP4 GENOA_SP5-SOCKET6096_13568-001,SMLF,IO,DGA^6000030   I214 @T6G_MB_LIB.T6G(SCH_1):PAGE49
  C701    2      2 Q_CAP_DIFFBUS_C0201-DIFF BUS_0.22UF,6.3V,20%,X6S,SA   I199 @T6G_MB_LIB.T6G(SCH_1):PAGE355

P5E_CPU1_G1_TX_DP<5> @T6G_MB_LIB.T6G(SCH_1):P5E_CPU1_G1_TX_DP(5)
   U26 AJ43 G1_TXP5 GENOA_SP5-SOCKET6096_13568-001,SMLF,IO,DGA^6000030   I214 @T6G_MB_LIB.T6G(SCH_1):PAGE49
  C699    2      2 Q_CAP_DIFFBUS_C0201-DIFF BUS_0.22UF,6.3V,20%,X6S,SA   I202 @T6G_MB_LIB.T6G(SCH_1):PAGE355

P5E_CPU1_G1_TX_DP<6> @T6G_MB_LIB.T6G(SCH_1):P5E_CPU1_G1_TX_DP(6)
   U26 AL43 G1_TXP6 GENOA_SP5-SOCKET6096_13568-001,SMLF,IO,DGA^6000030   I214 @T6G_MB_LIB.T6G(SCH_1):PAGE49
  C697    2      2 Q_CAP_DIFFBUS_C0201-DIFF BUS_0.22UF,6.3V,20%,X6S,SA   I203 @T6G_MB_LIB.T6G(SCH_1):PAGE355

P5E_CPU1_G1_TX_DP<7> @T6G_MB_LIB.T6G(SCH_1):P5E_CPU1_G1_TX_DP(7)
   U26 AN46 G1_TXP7 GENOA_SP5-SOCKET6096_13568-001,SMLF,IO,DGA^6000030   I214 @T6G_MB_LIB.T6G(SCH_1):PAGE49
  C695    2      2 Q_CAP_DIFFBUS_C0201-DIFF BUS_0.22UF,6.3V,20%,X6S,SA   I205 @T6G_MB_LIB.T6G(SCH_1):PAGE355

P5E_CPU1_G1_TX_DP<8> @T6G_MB_LIB.T6G(SCH_1):P5E_CPU1_G1_TX_DP(8)
   U26 AJ46 G1_TXP8 GENOA_SP5-SOCKET6096_13568-001,SMLF,IO,DGA^6000030   I214 @T6G_MB_LIB.T6G(SCH_1):PAGE49
   C56    2      2 Q_CAP_DIFFBUS_C0201-DIFF BUS_0.22UF,6.3V,20%,X6S,SA   I216 @T6G_MB_LIB.T6G(SCH_1):PAGE355

P5E_CPU1_G1_TX_DP<9> @T6G_MB_LIB.T6G(SCH_1):P5E_CPU1_G1_TX_DP(9)
   U26 AL46 G1_TXP9 GENOA_SP5-SOCKET6096_13568-001,SMLF,IO,DGA^6000030   I214 @T6G_MB_LIB.T6G(SCH_1):PAGE49
  C691    2      2 Q_CAP_DIFFBUS_C0201-DIFF BUS_0.22UF,6.3V,20%,X6S,SA   I218 @T6G_MB_LIB.T6G(SCH_1):PAGE355

P5E_CPU1_P0_RX_BUF_DN<0> @T6G_MB_LIB.T6G(SCH_1):P5E_CPU1_P0_RX_BUF_DN(0)
 U6014  EV2 A_PERN15 PT5161LRS-PT5161LRS,SMLF,IC,AJ051610U03    I38 @T6G_MB_LIB.T6G(SCH_1):PAGE402
  J112   C1     C1 CONN160_10131762101LF-CONN160_10131762-101LF,THLF,A   I102 @T6G_MB_LIB.T6G(SCH_1):PAGE329

P5E_CPU1_P0_RX_BUF_DN<10> @T6G_MB_LIB.T6G(SCH_1):P5E_CPU1_P0_RX_BUF_DN(10)
 U6014  BH2 A_PERN5 PT5161LRS-PT5161LRS,SMLF,IC,AJ051610U03     I1 @T6G_MB_LIB.T6G(SCH_1):PAGE402
  J111   C3     C3 CONN112_10137002101LF-CONN112_10137002-101LF,THLF,A    I76 @T6G_MB_LIB.T6G(SCH_1):PAGE328

P5E_CPU1_P0_RX_BUF_DN<11> @T6G_MB_LIB.T6G(SCH_1):P5E_CPU1_P0_RX_BUF_DN(11)
 U6014  BA2 A_PERN4 PT5161LRS-PT5161LRS,SMLF,IC,AJ051610U03     I1 @T6G_MB_LIB.T6G(SCH_1):PAGE402
  J111   B4     B4 CONN112_10137002101LF-CONN112_10137002-101LF,THLF,A    I76 @T6G_MB_LIB.T6G(SCH_1):PAGE328

P5E_CPU1_P0_RX_BUF_DN<12> @T6G_MB_LIB.T6G(SCH_1):P5E_CPU1_P0_RX_BUF_DN(12)
 U6014  AP2 A_PERN3 PT5161LRS-PT5161LRS,SMLF,IC,AJ051610U03     I1 @T6G_MB_LIB.T6G(SCH_1):PAGE402
  J111   C5     C5 CONN112_10137002101LF-CONN112_10137002-101LF,THLF,A    I38 @T6G_MB_LIB.T6G(SCH_1):PAGE328

P5E_CPU1_P0_RX_BUF_DN<13> @T6G_MB_LIB.T6G(SCH_1):P5E_CPU1_P0_RX_BUF_DN(13)
 U6014  AG2 A_PERN2 PT5161LRS-PT5161LRS,SMLF,IC,AJ051610U03     I1 @T6G_MB_LIB.T6G(SCH_1):PAGE402
  J111   B6     B6 CONN112_10137002101LF-CONN112_10137002-101LF,THLF,A    I38 @T6G_MB_LIB.T6G(SCH_1):PAGE328

P5E_CPU1_P0_RX_BUF_DN<14> @T6G_MB_LIB.T6G(SCH_1):P5E_CPU1_P0_RX_BUF_DN(14)
 U6014   Y2 A_PERN1 PT5161LRS-PT5161LRS,SMLF,IC,AJ051610U03     I1 @T6G_MB_LIB.T6G(SCH_1):PAGE402
  J111   C7     C7 CONN112_10137002101LF-CONN112_10137002-101LF,THLF,A    I38 @T6G_MB_LIB.T6G(SCH_1):PAGE328

P5E_CPU1_P0_RX_BUF_DN<15> @T6G_MB_LIB.T6G(SCH_1):P5E_CPU1_P0_RX_BUF_DN(15)
 U6014   N2 A_PERN0 PT5161LRS-PT5161LRS,SMLF,IC,AJ051610U03     I1 @T6G_MB_LIB.T6G(SCH_1):PAGE402
  J111   B8     B8 CONN112_10137002101LF-CONN112_10137002-101LF,THLF,A    I38 @T6G_MB_LIB.T6G(SCH_1):PAGE328

P5E_CPU1_P0_RX_BUF_DN<1> @T6G_MB_LIB.T6G(SCH_1):P5E_CPU1_P0_RX_BUF_DN(1)
 U6014  EL2 A_PERN14 PT5161LRS-PT5161LRS,SMLF,IC,AJ051610U03    I38 @T6G_MB_LIB.T6G(SCH_1):PAGE402
  J112   B2     B2 CONN160_10131762101LF-CONN160_10131762-101LF,THLF,A   I102 @T6G_MB_LIB.T6G(SCH_1):PAGE329

P5E_CPU1_P0_RX_BUF_DN<2> @T6G_MB_LIB.T6G(SCH_1):P5E_CPU1_P0_RX_BUF_DN(2)
 U6014  ED2 A_PERN13 PT5161LRS-PT5161LRS,SMLF,IC,AJ051610U03    I38 @T6G_MB_LIB.T6G(SCH_1):PAGE402
  J112   C3     C3 CONN160_10131762101LF-CONN160_10131762-101LF,THLF,A   I102 @T6G_MB_LIB.T6G(SCH_1):PAGE329

P5E_CPU1_P0_RX_BUF_DN<3> @T6G_MB_LIB.T6G(SCH_1):P5E_CPU1_P0_RX_BUF_DN(3)
 U6014  DU2 A_PERN12 PT5161LRS-PT5161LRS,SMLF,IC,AJ051610U03    I38 @T6G_MB_LIB.T6G(SCH_1):PAGE402
  J112   B4     B4 CONN160_10131762101LF-CONN160_10131762-101LF,THLF,A   I102 @T6G_MB_LIB.T6G(SCH_1):PAGE329

P5E_CPU1_P0_RX_BUF_DN<4> @T6G_MB_LIB.T6G(SCH_1):P5E_CPU1_P0_RX_BUF_DN(4)
 U6014  DK2 A_PERN11 PT5161LRS-PT5161LRS,SMLF,IC,AJ051610U03    I38 @T6G_MB_LIB.T6G(SCH_1):PAGE402
  J112   C5     C5 CONN160_10131762101LF-CONN160_10131762-101LF,THLF,A     I7 @T6G_MB_LIB.T6G(SCH_1):PAGE329

P5E_CPU1_P0_RX_BUF_DN<5> @T6G_MB_LIB.T6G(SCH_1):P5E_CPU1_P0_RX_BUF_DN(5)
 U6014  DC2 A_PERN10 PT5161LRS-PT5161LRS,SMLF,IC,AJ051610U03    I38 @T6G_MB_LIB.T6G(SCH_1):PAGE402
  J112   B6     B6 CONN160_10131762101LF-CONN160_10131762-101LF,THLF,A     I7 @T6G_MB_LIB.T6G(SCH_1):PAGE329

P5E_CPU1_P0_RX_BUF_DN<6> @T6G_MB_LIB.T6G(SCH_1):P5E_CPU1_P0_RX_BUF_DN(6)
 U6014  CT2 A_PERN9 PT5161LRS-PT5161LRS,SMLF,IC,AJ051610U03    I38 @T6G_MB_LIB.T6G(SCH_1):PAGE402
  J112   C7     C7 CONN160_10131762101LF-CONN160_10131762-101LF,THLF,A     I7 @T6G_MB_LIB.T6G(SCH_1):PAGE329

P5E_CPU1_P0_RX_BUF_DN<7> @T6G_MB_LIB.T6G(SCH_1):P5E_CPU1_P0_RX_BUF_DN(7)
 U6014  CJ2 A_PERN8 PT5161LRS-PT5161LRS,SMLF,IC,AJ051610U03    I38 @T6G_MB_LIB.T6G(SCH_1):PAGE402
  J112   B8     B8 CONN160_10131762101LF-CONN160_10131762-101LF,THLF,A     I7 @T6G_MB_LIB.T6G(SCH_1):PAGE329

P5E_CPU1_P0_RX_BUF_DN<8> @T6G_MB_LIB.T6G(SCH_1):P5E_CPU1_P0_RX_BUF_DN(8)
 U6014  CB2 A_PERN7 PT5161LRS-PT5161LRS,SMLF,IC,AJ051610U03     I1 @T6G_MB_LIB.T6G(SCH_1):PAGE402
  J111   C1     C1 CONN112_10137002101LF-CONN112_10137002-101LF,THLF,A    I76 @T6G_MB_LIB.T6G(SCH_1):PAGE328

P5E_CPU1_P0_RX_BUF_DN<9> @T6G_MB_LIB.T6G(SCH_1):P5E_CPU1_P0_RX_BUF_DN(9)
 U6014  BR2 A_PERN6 PT5161LRS-PT5161LRS,SMLF,IC,AJ051610U03     I1 @T6G_MB_LIB.T6G(SCH_1):PAGE402
  J111   B2     B2 CONN112_10137002101LF-CONN112_10137002-101LF,THLF,A    I76 @T6G_MB_LIB.T6G(SCH_1):PAGE328

P5E_CPU1_P0_RX_BUF_DP<0> @T6G_MB_LIB.T6G(SCH_1):P5E_CPU1_P0_RX_BUF_DP(0)
 U6014  EY1 A_PERP15 PT5161LRS-PT5161LRS,SMLF,IC,AJ051610U03    I38 @T6G_MB_LIB.T6G(SCH_1):PAGE402
  J112   D1     D1 CONN160_10131762101LF-CONN160_10131762-101LF,THLF,A   I102 @T6G_MB_LIB.T6G(SCH_1):PAGE329

P5E_CPU1_P0_RX_BUF_DP<10> @T6G_MB_LIB.T6G(SCH_1):P5E_CPU1_P0_RX_BUF_DP(10)
 U6014  BK1 A_PERP5 PT5161LRS-PT5161LRS,SMLF,IC,AJ051610U03     I1 @T6G_MB_LIB.T6G(SCH_1):PAGE402
  J111   D3     D3 CONN112_10137002101LF-CONN112_10137002-101LF,THLF,A    I76 @T6G_MB_LIB.T6G(SCH_1):PAGE328

P5E_CPU1_P0_RX_BUF_DP<11> @T6G_MB_LIB.T6G(SCH_1):P5E_CPU1_P0_RX_BUF_DP(11)
 U6014  BC1 A_PERP4 PT5161LRS-PT5161LRS,SMLF,IC,AJ051610U03     I1 @T6G_MB_LIB.T6G(SCH_1):PAGE402
  J111   C4     C4 CONN112_10137002101LF-CONN112_10137002-101LF,THLF,A    I76 @T6G_MB_LIB.T6G(SCH_1):PAGE328

P5E_CPU1_P0_RX_BUF_DP<12> @T6G_MB_LIB.T6G(SCH_1):P5E_CPU1_P0_RX_BUF_DP(12)
 U6014  AT1 A_PERP3 PT5161LRS-PT5161LRS,SMLF,IC,AJ051610U03     I1 @T6G_MB_LIB.T6G(SCH_1):PAGE402
  J111   D5     D5 CONN112_10137002101LF-CONN112_10137002-101LF,THLF,A    I38 @T6G_MB_LIB.T6G(SCH_1):PAGE328

P5E_CPU1_P0_RX_BUF_DP<13> @T6G_MB_LIB.T6G(SCH_1):P5E_CPU1_P0_RX_BUF_DP(13)
 U6014  AJ1 A_PERP2 PT5161LRS-PT5161LRS,SMLF,IC,AJ051610U03     I1 @T6G_MB_LIB.T6G(SCH_1):PAGE402
  J111   C6     C6 CONN112_10137002101LF-CONN112_10137002-101LF,THLF,A    I38 @T6G_MB_LIB.T6G(SCH_1):PAGE328

P5E_CPU1_P0_RX_BUF_DP<14> @T6G_MB_LIB.T6G(SCH_1):P5E_CPU1_P0_RX_BUF_DP(14)
 U6014  AB1 A_PERP1 PT5161LRS-PT5161LRS,SMLF,IC,AJ051610U03     I1 @T6G_MB_LIB.T6G(SCH_1):PAGE402
  J111   D7     D7 CONN112_10137002101LF-CONN112_10137002-101LF,THLF,A    I38 @T6G_MB_LIB.T6G(SCH_1):PAGE328

P5E_CPU1_P0_RX_BUF_DP<15> @T6G_MB_LIB.T6G(SCH_1):P5E_CPU1_P0_RX_BUF_DP(15)
 U6014   R1 A_PERP0 PT5161LRS-PT5161LRS,SMLF,IC,AJ051610U03     I1 @T6G_MB_LIB.T6G(SCH_1):PAGE402
  J111   C8     C8 CONN112_10137002101LF-CONN112_10137002-101LF,THLF,A    I38 @T6G_MB_LIB.T6G(SCH_1):PAGE328

P5E_CPU1_P0_RX_BUF_DP<1> @T6G_MB_LIB.T6G(SCH_1):P5E_CPU1_P0_RX_BUF_DP(1)
 U6014  EN1 A_PERP14 PT5161LRS-PT5161LRS,SMLF,IC,AJ051610U03    I38 @T6G_MB_LIB.T6G(SCH_1):PAGE402
  J112   C2     C2 CONN160_10131762101LF-CONN160_10131762-101LF,THLF,A   I102 @T6G_MB_LIB.T6G(SCH_1):PAGE329

P5E_CPU1_P0_RX_BUF_DP<2> @T6G_MB_LIB.T6G(SCH_1):P5E_CPU1_P0_RX_BUF_DP(2)
 U6014  EF1 A_PERP13 PT5161LRS-PT5161LRS,SMLF,IC,AJ051610U03    I38 @T6G_MB_LIB.T6G(SCH_1):PAGE402
  J112   D3     D3 CONN160_10131762101LF-CONN160_10131762-101LF,THLF,A   I102 @T6G_MB_LIB.T6G(SCH_1):PAGE329

P5E_CPU1_P0_RX_BUF_DP<3> @T6G_MB_LIB.T6G(SCH_1):P5E_CPU1_P0_RX_BUF_DP(3)
 U6014  DW1 A_PERP12 PT5161LRS-PT5161LRS,SMLF,IC,AJ051610U03    I38 @T6G_MB_LIB.T6G(SCH_1):PAGE402
  J112   C4     C4 CONN160_10131762101LF-CONN160_10131762-101LF,THLF,A   I102 @T6G_MB_LIB.T6G(SCH_1):PAGE329

P5E_CPU1_P0_RX_BUF_DP<4> @T6G_MB_LIB.T6G(SCH_1):P5E_CPU1_P0_RX_BUF_DP(4)
 U6014  DM1 A_PERP11 PT5161LRS-PT5161LRS,SMLF,IC,AJ051610U03    I38 @T6G_MB_LIB.T6G(SCH_1):PAGE402
  J112   D5     D5 CONN160_10131762101LF-CONN160_10131762-101LF,THLF,A     I7 @T6G_MB_LIB.T6G(SCH_1):PAGE329

P5E_CPU1_P0_RX_BUF_DP<5> @T6G_MB_LIB.T6G(SCH_1):P5E_CPU1_P0_RX_BUF_DP(5)
 U6014  DE1 A_PERP10 PT5161LRS-PT5161LRS,SMLF,IC,AJ051610U03    I38 @T6G_MB_LIB.T6G(SCH_1):PAGE402
  J112   C6     C6 CONN160_10131762101LF-CONN160_10131762-101LF,THLF,A     I7 @T6G_MB_LIB.T6G(SCH_1):PAGE329

P5E_CPU1_P0_RX_BUF_DP<6> @T6G_MB_LIB.T6G(SCH_1):P5E_CPU1_P0_RX_BUF_DP(6)
 U6014  CV1 A_PERP9 PT5161LRS-PT5161LRS,SMLF,IC,AJ051610U03    I38 @T6G_MB_LIB.T6G(SCH_1):PAGE402
  J112   D7     D7 CONN160_10131762101LF-CONN160_10131762-101LF,THLF,A     I7 @T6G_MB_LIB.T6G(SCH_1):PAGE329

P5E_CPU1_P0_RX_BUF_DP<7> @T6G_MB_LIB.T6G(SCH_1):P5E_CPU1_P0_RX_BUF_DP(7)
 U6014  CL1 A_PERP8 PT5161LRS-PT5161LRS,SMLF,IC,AJ051610U03    I38 @T6G_MB_LIB.T6G(SCH_1):PAGE402
  J112   C8     C8 CONN160_10131762101LF-CONN160_10131762-101LF,THLF,A     I7 @T6G_MB_LIB.T6G(SCH_1):PAGE329

P5E_CPU1_P0_RX_BUF_DP<8> @T6G_MB_LIB.T6G(SCH_1):P5E_CPU1_P0_RX_BUF_DP(8)
 U6014  CD1 A_PERP7 PT5161LRS-PT5161LRS,SMLF,IC,AJ051610U03     I1 @T6G_MB_LIB.T6G(SCH_1):PAGE402
  J111   D1     D1 CONN112_10137002101LF-CONN112_10137002-101LF,THLF,A    I76 @T6G_MB_LIB.T6G(SCH_1):PAGE328

P5E_CPU1_P0_RX_BUF_DP<9> @T6G_MB_LIB.T6G(SCH_1):P5E_CPU1_P0_RX_BUF_DP(9)
 U6014  BU1 A_PERP6 PT5161LRS-PT5161LRS,SMLF,IC,AJ051610U03     I1 @T6G_MB_LIB.T6G(SCH_1):PAGE402
  J111   C2     C2 CONN112_10137002101LF-CONN112_10137002-101LF,THLF,A    I76 @T6G_MB_LIB.T6G(SCH_1):PAGE328

P5E_CPU1_P0_RX_DN<0> @T6G_MB_LIB.T6G(SCH_1):P5E_CPU1_P0_RX_DN(0)
   U26 BW53 P0_RXN0||SATA00_RXN GENOA_SP5-SOCKET6096_13568-001,SMLF,IO,DGA^6000030   I147 @T6G_MB_LIB.T6G(SCH_1):PAGE51
 U6014 EW29 A_PETN15 PT5161LRS-PT5161LRS,SMLF,IC,AJ051610U03    I38 @T6G_MB_LIB.T6G(SCH_1):PAGE438

P5E_CPU1_P0_RX_DN<10> @T6G_MB_LIB.T6G(SCH_1):P5E_CPU1_P0_RX_DN(10)
   U26 CA44 P0_RXN10||SATA12_RXN GENOA_SP5-SOCKET6096_13568-001,SMLF,IO,DGA^6000030   I147 @T6G_MB_LIB.T6G(SCH_1):PAGE51
 U6014 BJ29 A_PETN5 PT5161LRS-PT5161LRS,SMLF,IC,AJ051610U03     I1 @T6G_MB_LIB.T6G(SCH_1):PAGE438

P5E_CPU1_P0_RX_DN<11> @T6G_MB_LIB.T6G(SCH_1):P5E_CPU1_P0_RX_DN(11)
   U26 BU44 P0_RXN11||SATA13_RXN GENOA_SP5-SOCKET6096_13568-001,SMLF,IO,DGA^6000030   I147 @T6G_MB_LIB.T6G(SCH_1):PAGE51
 U6014 BB29 A_PETN4 PT5161LRS-PT5161LRS,SMLF,IC,AJ051610U03     I1 @T6G_MB_LIB.T6G(SCH_1):PAGE438

P5E_CPU1_P0_RX_DN<12> @T6G_MB_LIB.T6G(SCH_1):P5E_CPU1_P0_RX_DN(12)
   U26 BY41 P0_RXN12||SATA14_RXN GENOA_SP5-SOCKET6096_13568-001,SMLF,IO,DGA^6000030   I147 @T6G_MB_LIB.T6G(SCH_1):PAGE51
 U6014 AR29 A_PETN3 PT5161LRS-PT5161LRS,SMLF,IC,AJ051610U03     I1 @T6G_MB_LIB.T6G(SCH_1):PAGE438

P5E_CPU1_P0_RX_DN<13> @T6G_MB_LIB.T6G(SCH_1):P5E_CPU1_P0_RX_DN(13)
   U26 CB41 P0_RXN13||SATA15_RXN GENOA_SP5-SOCKET6096_13568-001,SMLF,IO,DGA^6000030   I147 @T6G_MB_LIB.T6G(SCH_1):PAGE51
 U6014 AH29 A_PETN2 PT5161LRS-PT5161LRS,SMLF,IC,AJ051610U03     I1 @T6G_MB_LIB.T6G(SCH_1):PAGE438

P5E_CPU1_P0_RX_DN<14> @T6G_MB_LIB.T6G(SCH_1):P5E_CPU1_P0_RX_DN(14)
   U26 BV41 P0_RXN14||SATA16_RXN GENOA_SP5-SOCKET6096_13568-001,SMLF,IO,DGA^6000030   I147 @T6G_MB_LIB.T6G(SCH_1):PAGE51
 U6014 AA29 A_PETN1 PT5161LRS-PT5161LRS,SMLF,IC,AJ051610U03     I1 @T6G_MB_LIB.T6G(SCH_1):PAGE438

P5E_CPU1_P0_RX_DN<15> @T6G_MB_LIB.T6G(SCH_1):P5E_CPU1_P0_RX_DN(15)
   U26 BT41 P0_RXN15||SATA17_RXN GENOA_SP5-SOCKET6096_13568-001,SMLF,IO,DGA^6000030   I147 @T6G_MB_LIB.T6G(SCH_1):PAGE51
 U6014  P29 A_PETN0 PT5161LRS-PT5161LRS,SMLF,IC,AJ051610U03     I1 @T6G_MB_LIB.T6G(SCH_1):PAGE438

P5E_CPU1_P0_RX_DN<1> @T6G_MB_LIB.T6G(SCH_1):P5E_CPU1_P0_RX_DN(1)
   U26 CA53 P0_RXN1||SATA01_RXN GENOA_SP5-SOCKET6096_13568-001,SMLF,IO,DGA^6000030   I147 @T6G_MB_LIB.T6G(SCH_1):PAGE51
 U6014 EM29 A_PETN14 PT5161LRS-PT5161LRS,SMLF,IC,AJ051610U03    I38 @T6G_MB_LIB.T6G(SCH_1):PAGE438

P5E_CPU1_P0_RX_DN<2> @T6G_MB_LIB.T6G(SCH_1):P5E_CPU1_P0_RX_DN(2)
   U26 BU53 P0_RXN2||SATA02_RXN GENOA_SP5-SOCKET6096_13568-001,SMLF,IO,DGA^6000030   I147 @T6G_MB_LIB.T6G(SCH_1):PAGE51
 U6014 EE29 A_PETN13 PT5161LRS-PT5161LRS,SMLF,IC,AJ051610U03    I38 @T6G_MB_LIB.T6G(SCH_1):PAGE438

P5E_CPU1_P0_RX_DN<3> @T6G_MB_LIB.T6G(SCH_1):P5E_CPU1_P0_RX_DN(3)
   U26 BW50 P0_RXN3||SATA03_RXN GENOA_SP5-SOCKET6096_13568-001,SMLF,IO,DGA^6000030   I147 @T6G_MB_LIB.T6G(SCH_1):PAGE51
 U6014 DV29 A_PETN12 PT5161LRS-PT5161LRS,SMLF,IC,AJ051610U03    I38 @T6G_MB_LIB.T6G(SCH_1):PAGE438

P5E_CPU1_P0_RX_DN<4> @T6G_MB_LIB.T6G(SCH_1):P5E_CPU1_P0_RX_DN(4)
   U26 CA50 P0_RXN4||SATA04_RXN GENOA_SP5-SOCKET6096_13568-001,SMLF,IO,DGA^6000030   I147 @T6G_MB_LIB.T6G(SCH_1):PAGE51
 U6014 DL29 A_PETN11 PT5161LRS-PT5161LRS,SMLF,IC,AJ051610U03    I38 @T6G_MB_LIB.T6G(SCH_1):PAGE438

P5E_CPU1_P0_RX_DN<5> @T6G_MB_LIB.T6G(SCH_1):P5E_CPU1_P0_RX_DN(5)
   U26 BU50 P0_RXN5||SATA05_RXN GENOA_SP5-SOCKET6096_13568-001,SMLF,IO,DGA^6000030   I147 @T6G_MB_LIB.T6G(SCH_1):PAGE51
 U6014 DD29 A_PETN10 PT5161LRS-PT5161LRS,SMLF,IC,AJ051610U03    I38 @T6G_MB_LIB.T6G(SCH_1):PAGE438

P5E_CPU1_P0_RX_DN<6> @T6G_MB_LIB.T6G(SCH_1):P5E_CPU1_P0_RX_DN(6)
   U26 BW47 P0_RXN6||SATA06_RXN GENOA_SP5-SOCKET6096_13568-001,SMLF,IO,DGA^6000030   I147 @T6G_MB_LIB.T6G(SCH_1):PAGE51
 U6014 CU29 A_PETN9 PT5161LRS-PT5161LRS,SMLF,IC,AJ051610U03    I38 @T6G_MB_LIB.T6G(SCH_1):PAGE438

P5E_CPU1_P0_RX_DN<7> @T6G_MB_LIB.T6G(SCH_1):P5E_CPU1_P0_RX_DN(7)
   U26 CA47 P0_RXN7||SATA07_RXN GENOA_SP5-SOCKET6096_13568-001,SMLF,IO,DGA^6000030   I147 @T6G_MB_LIB.T6G(SCH_1):PAGE51
 U6014 CK29 A_PETN8 PT5161LRS-PT5161LRS,SMLF,IC,AJ051610U03    I38 @T6G_MB_LIB.T6G(SCH_1):PAGE438

P5E_CPU1_P0_RX_DN<8> @T6G_MB_LIB.T6G(SCH_1):P5E_CPU1_P0_RX_DN(8)
   U26 BU47 P0_RXN8||SATA10_RXN GENOA_SP5-SOCKET6096_13568-001,SMLF,IO,DGA^6000030   I147 @T6G_MB_LIB.T6G(SCH_1):PAGE51
 U6014 CC29 A_PETN7 PT5161LRS-PT5161LRS,SMLF,IC,AJ051610U03     I1 @T6G_MB_LIB.T6G(SCH_1):PAGE438

P5E_CPU1_P0_RX_DN<9> @T6G_MB_LIB.T6G(SCH_1):P5E_CPU1_P0_RX_DN(9)
   U26 BW44 P0_RXN9||SATA11_RXN GENOA_SP5-SOCKET6096_13568-001,SMLF,IO,DGA^6000030   I147 @T6G_MB_LIB.T6G(SCH_1):PAGE51
 U6014 BT29 A_PETN6 PT5161LRS-PT5161LRS,SMLF,IC,AJ051610U03     I1 @T6G_MB_LIB.T6G(SCH_1):PAGE438

P5E_CPU1_P0_RX_DP<0> @T6G_MB_LIB.T6G(SCH_1):P5E_CPU1_P0_RX_DP(0)
   U26 BW52 P0_RXP0||SATA00_RXP GENOA_SP5-SOCKET6096_13568-001,SMLF,IO,DGA^6000030   I147 @T6G_MB_LIB.T6G(SCH_1):PAGE51
 U6014 EU26 A_PETP15 PT5161LRS-PT5161LRS,SMLF,IC,AJ051610U03    I38 @T6G_MB_LIB.T6G(SCH_1):PAGE438

P5E_CPU1_P0_RX_DP<10> @T6G_MB_LIB.T6G(SCH_1):P5E_CPU1_P0_RX_DP(10)
   U26 CA43 P0_RXP10||SATA12_RXP GENOA_SP5-SOCKET6096_13568-001,SMLF,IO,DGA^6000030   I147 @T6G_MB_LIB.T6G(SCH_1):PAGE51
 U6014 BG26 A_PETP5 PT5161LRS-PT5161LRS,SMLF,IC,AJ051610U03     I1 @T6G_MB_LIB.T6G(SCH_1):PAGE438

P5E_CPU1_P0_RX_DP<11> @T6G_MB_LIB.T6G(SCH_1):P5E_CPU1_P0_RX_DP(11)
   U26 BU43 P0_RXP11||SATA13_RXP GENOA_SP5-SOCKET6096_13568-001,SMLF,IO,DGA^6000030   I147 @T6G_MB_LIB.T6G(SCH_1):PAGE51
 U6014 AY26 A_PETP4 PT5161LRS-PT5161LRS,SMLF,IC,AJ051610U03     I1 @T6G_MB_LIB.T6G(SCH_1):PAGE438

P5E_CPU1_P0_RX_DP<12> @T6G_MB_LIB.T6G(SCH_1):P5E_CPU1_P0_RX_DP(12)
   U26 BY40 P0_RXP12||SATA14_RXP GENOA_SP5-SOCKET6096_13568-001,SMLF,IO,DGA^6000030   I147 @T6G_MB_LIB.T6G(SCH_1):PAGE51
 U6014 AN26 A_PETP3 PT5161LRS-PT5161LRS,SMLF,IC,AJ051610U03     I1 @T6G_MB_LIB.T6G(SCH_1):PAGE438

P5E_CPU1_P0_RX_DP<13> @T6G_MB_LIB.T6G(SCH_1):P5E_CPU1_P0_RX_DP(13)
   U26 CB40 P0_RXP13||SATA15_RXP GENOA_SP5-SOCKET6096_13568-001,SMLF,IO,DGA^6000030   I147 @T6G_MB_LIB.T6G(SCH_1):PAGE51
 U6014 AF26 A_PETP2 PT5161LRS-PT5161LRS,SMLF,IC,AJ051610U03     I1 @T6G_MB_LIB.T6G(SCH_1):PAGE438

P5E_CPU1_P0_RX_DP<14> @T6G_MB_LIB.T6G(SCH_1):P5E_CPU1_P0_RX_DP(14)
   U26 BV40 P0_RXP14||SATA16_RXP GENOA_SP5-SOCKET6096_13568-001,SMLF,IO,DGA^6000030   I147 @T6G_MB_LIB.T6G(SCH_1):PAGE51
 U6014  W26 A_PETP1 PT5161LRS-PT5161LRS,SMLF,IC,AJ051610U03     I1 @T6G_MB_LIB.T6G(SCH_1):PAGE438

P5E_CPU1_P0_RX_DP<15> @T6G_MB_LIB.T6G(SCH_1):P5E_CPU1_P0_RX_DP(15)
   U26 BT40 P0_RXP15||SATA17_RXP GENOA_SP5-SOCKET6096_13568-001,SMLF,IO,DGA^6000030   I147 @T6G_MB_LIB.T6G(SCH_1):PAGE51
 U6014  M26 A_PETP0 PT5161LRS-PT5161LRS,SMLF,IC,AJ051610U03     I1 @T6G_MB_LIB.T6G(SCH_1):PAGE438

P5E_CPU1_P0_RX_DP<1> @T6G_MB_LIB.T6G(SCH_1):P5E_CPU1_P0_RX_DP(1)
   U26 CA52 P0_RXP1||SATA01_RXP GENOA_SP5-SOCKET6096_13568-001,SMLF,IO,DGA^6000030   I147 @T6G_MB_LIB.T6G(SCH_1):PAGE51
 U6014 EK26 A_PETP14 PT5161LRS-PT5161LRS,SMLF,IC,AJ051610U03    I38 @T6G_MB_LIB.T6G(SCH_1):PAGE438

P5E_CPU1_P0_RX_DP<2> @T6G_MB_LIB.T6G(SCH_1):P5E_CPU1_P0_RX_DP(2)
   U26 BU52 P0_RXP2||SATA02_RXP GENOA_SP5-SOCKET6096_13568-001,SMLF,IO,DGA^6000030   I147 @T6G_MB_LIB.T6G(SCH_1):PAGE51
 U6014 EC26 A_PETP13 PT5161LRS-PT5161LRS,SMLF,IC,AJ051610U03    I38 @T6G_MB_LIB.T6G(SCH_1):PAGE438

P5E_CPU1_P0_RX_DP<3> @T6G_MB_LIB.T6G(SCH_1):P5E_CPU1_P0_RX_DP(3)
   U26 BW49 P0_RXP3||SATA03_RXP GENOA_SP5-SOCKET6096_13568-001,SMLF,IO,DGA^6000030   I147 @T6G_MB_LIB.T6G(SCH_1):PAGE51
 U6014 DT26 A_PETP12 PT5161LRS-PT5161LRS,SMLF,IC,AJ051610U03    I38 @T6G_MB_LIB.T6G(SCH_1):PAGE438

P5E_CPU1_P0_RX_DP<4> @T6G_MB_LIB.T6G(SCH_1):P5E_CPU1_P0_RX_DP(4)
   U26 CA49 P0_RXP4||SATA04_RXP GENOA_SP5-SOCKET6096_13568-001,SMLF,IO,DGA^6000030   I147 @T6G_MB_LIB.T6G(SCH_1):PAGE51
 U6014 DJ26 A_PETP11 PT5161LRS-PT5161LRS,SMLF,IC,AJ051610U03    I38 @T6G_MB_LIB.T6G(SCH_1):PAGE438

P5E_CPU1_P0_RX_DP<5> @T6G_MB_LIB.T6G(SCH_1):P5E_CPU1_P0_RX_DP(5)
   U26 BU49 P0_RXP5||SATA05_RXP GENOA_SP5-SOCKET6096_13568-001,SMLF,IO,DGA^6000030   I147 @T6G_MB_LIB.T6G(SCH_1):PAGE51
 U6014 DB26 A_PETP10 PT5161LRS-PT5161LRS,SMLF,IC,AJ051610U03    I38 @T6G_MB_LIB.T6G(SCH_1):PAGE438

P5E_CPU1_P0_RX_DP<6> @T6G_MB_LIB.T6G(SCH_1):P5E_CPU1_P0_RX_DP(6)
   U26 BW46 P0_RXP6||SATA06_RXP GENOA_SP5-SOCKET6096_13568-001,SMLF,IO,DGA^6000030   I147 @T6G_MB_LIB.T6G(SCH_1):PAGE51
 U6014 CR26 A_PETP9 PT5161LRS-PT5161LRS,SMLF,IC,AJ051610U03    I38 @T6G_MB_LIB.T6G(SCH_1):PAGE438

P5E_CPU1_P0_RX_DP<7> @T6G_MB_LIB.T6G(SCH_1):P5E_CPU1_P0_RX_DP(7)
   U26 CA46 P0_RXP7||SATA07_RXP GENOA_SP5-SOCKET6096_13568-001,SMLF,IO,DGA^6000030   I147 @T6G_MB_LIB.T6G(SCH_1):PAGE51
 U6014 CH26 A_PETP8 PT5161LRS-PT5161LRS,SMLF,IC,AJ051610U03    I38 @T6G_MB_LIB.T6G(SCH_1):PAGE438

P5E_CPU1_P0_RX_DP<8> @T6G_MB_LIB.T6G(SCH_1):P5E_CPU1_P0_RX_DP(8)
   U26 BU46 P0_RXP8||SATA10_RXP GENOA_SP5-SOCKET6096_13568-001,SMLF,IO,DGA^6000030   I147 @T6G_MB_LIB.T6G(SCH_1):PAGE51
 U6014 CA26 A_PETP7 PT5161LRS-PT5161LRS,SMLF,IC,AJ051610U03     I1 @T6G_MB_LIB.T6G(SCH_1):PAGE438

P5E_CPU1_P0_RX_DP<9> @T6G_MB_LIB.T6G(SCH_1):P5E_CPU1_P0_RX_DP(9)
   U26 BW43 P0_RXP9||SATA11_RXP GENOA_SP5-SOCKET6096_13568-001,SMLF,IO,DGA^6000030   I147 @T6G_MB_LIB.T6G(SCH_1):PAGE51
 U6014 BP26 A_PETP6 PT5161LRS-PT5161LRS,SMLF,IC,AJ051610U03     I1 @T6G_MB_LIB.T6G(SCH_1):PAGE438

P5E_CPU1_P0_TX_BUF_C_DN<0> @T6G_MB_LIB.T6G(SCH_1):P5E_CPU1_P0_TX_BUF_C_DN(0)
 C6630    1      1 Q_CAP_DIFFBUS_C0201-DIFF BUS_0.22UF,6.3V,20%,X6S,SA    I47 @T6G_MB_LIB.T6G(SCH_1):PAGE439
  J112   I1     I1 CONN160_10131762101LF-CONN160_10131762-101LF,THLF,A   I102 @T6G_MB_LIB.T6G(SCH_1):PAGE329

P5E_CPU1_P0_TX_BUF_C_DN<10> @T6G_MB_LIB.T6G(SCH_1):P5E_CPU1_P0_TX_BUF_C_DN(10)
 C6650    1      1 Q_CAP_DIFFBUS_C0201-DIFF BUS_0.22UF,6.3V,20%,X6S,SA    I97 @T6G_MB_LIB.T6G(SCH_1):PAGE439
  J111   I3     I3 CONN112_10137002101LF-CONN112_10137002-101LF,THLF,A    I76 @T6G_MB_LIB.T6G(SCH_1):PAGE328

P5E_CPU1_P0_TX_BUF_C_DN<11> @T6G_MB_LIB.T6G(SCH_1):P5E_CPU1_P0_TX_BUF_C_DN(11)
 C6652    1      1 Q_CAP_DIFFBUS_C0201-DIFF BUS_0.22UF,6.3V,20%,X6S,SA    I94 @T6G_MB_LIB.T6G(SCH_1):PAGE439
  J111   H4     H4 CONN112_10137002101LF-CONN112_10137002-101LF,THLF,A    I76 @T6G_MB_LIB.T6G(SCH_1):PAGE328

P5E_CPU1_P0_TX_BUF_C_DN<12> @T6G_MB_LIB.T6G(SCH_1):P5E_CPU1_P0_TX_BUF_C_DN(12)
 C6654    1      1 Q_CAP_DIFFBUS_C0201-DIFF BUS_0.22UF,6.3V,20%,X6S,SA    I92 @T6G_MB_LIB.T6G(SCH_1):PAGE439
  J111   I5     I5 CONN112_10137002101LF-CONN112_10137002-101LF,THLF,A    I38 @T6G_MB_LIB.T6G(SCH_1):PAGE328

P5E_CPU1_P0_TX_BUF_C_DN<13> @T6G_MB_LIB.T6G(SCH_1):P5E_CPU1_P0_TX_BUF_C_DN(13)
 C6656    1      1 Q_CAP_DIFFBUS_C0201-DIFF BUS_0.22UF,6.3V,20%,X6S,SA    I90 @T6G_MB_LIB.T6G(SCH_1):PAGE439
  J111   H6     H6 CONN112_10137002101LF-CONN112_10137002-101LF,THLF,A    I38 @T6G_MB_LIB.T6G(SCH_1):PAGE328

P5E_CPU1_P0_TX_BUF_C_DN<14> @T6G_MB_LIB.T6G(SCH_1):P5E_CPU1_P0_TX_BUF_C_DN(14)
 C6658    1      1 Q_CAP_DIFFBUS_C0201-DIFF BUS_0.22UF,6.3V,20%,X6S,SA    I88 @T6G_MB_LIB.T6G(SCH_1):PAGE439
  J111   I7     I7 CONN112_10137002101LF-CONN112_10137002-101LF,THLF,A    I38 @T6G_MB_LIB.T6G(SCH_1):PAGE328

P5E_CPU1_P0_TX_BUF_C_DN<15> @T6G_MB_LIB.T6G(SCH_1):P5E_CPU1_P0_TX_BUF_C_DN(15)
 C6660    1      1 Q_CAP_DIFFBUS_C0201-DIFF BUS_0.22UF,6.3V,20%,X6S,SA    I86 @T6G_MB_LIB.T6G(SCH_1):PAGE439
  J111   H8     H8 CONN112_10137002101LF-CONN112_10137002-101LF,THLF,A    I38 @T6G_MB_LIB.T6G(SCH_1):PAGE328

P5E_CPU1_P0_TX_BUF_C_DN<1> @T6G_MB_LIB.T6G(SCH_1):P5E_CPU1_P0_TX_BUF_C_DN(1)
 C6632    1      1 Q_CAP_DIFFBUS_C0201-DIFF BUS_0.22UF,6.3V,20%,X6S,SA    I44 @T6G_MB_LIB.T6G(SCH_1):PAGE439
  J112   H2     H2 CONN160_10131762101LF-CONN160_10131762-101LF,THLF,A   I102 @T6G_MB_LIB.T6G(SCH_1):PAGE329

P5E_CPU1_P0_TX_BUF_C_DN<2> @T6G_MB_LIB.T6G(SCH_1):P5E_CPU1_P0_TX_BUF_C_DN(2)
 C6634    1      1 Q_CAP_DIFFBUS_C0201-DIFF BUS_0.22UF,6.3V,20%,X6S,SA    I26 @T6G_MB_LIB.T6G(SCH_1):PAGE439
  J112   I3     I3 CONN160_10131762101LF-CONN160_10131762-101LF,THLF,A   I102 @T6G_MB_LIB.T6G(SCH_1):PAGE329

P5E_CPU1_P0_TX_BUF_C_DN<3> @T6G_MB_LIB.T6G(SCH_1):P5E_CPU1_P0_TX_BUF_C_DN(3)
 C6636    1      1 Q_CAP_DIFFBUS_C0201-DIFF BUS_0.22UF,6.3V,20%,X6S,SA    I24 @T6G_MB_LIB.T6G(SCH_1):PAGE439
  J112   H4     H4 CONN160_10131762101LF-CONN160_10131762-101LF,THLF,A   I102 @T6G_MB_LIB.T6G(SCH_1):PAGE329

P5E_CPU1_P0_TX_BUF_C_DN<4> @T6G_MB_LIB.T6G(SCH_1):P5E_CPU1_P0_TX_BUF_C_DN(4)
 C6638    1      1 Q_CAP_DIFFBUS_C0201-DIFF BUS_0.22UF,6.3V,20%,X6S,SA    I23 @T6G_MB_LIB.T6G(SCH_1):PAGE439
  J112   I5     I5 CONN160_10131762101LF-CONN160_10131762-101LF,THLF,A     I7 @T6G_MB_LIB.T6G(SCH_1):PAGE329

P5E_CPU1_P0_TX_BUF_C_DN<5> @T6G_MB_LIB.T6G(SCH_1):P5E_CPU1_P0_TX_BUF_C_DN(5)
 C6640    1      1 Q_CAP_DIFFBUS_C0201-DIFF BUS_0.22UF,6.3V,20%,X6S,SA    I21 @T6G_MB_LIB.T6G(SCH_1):PAGE439
  J112   H6     H6 CONN160_10131762101LF-CONN160_10131762-101LF,THLF,A     I7 @T6G_MB_LIB.T6G(SCH_1):PAGE329

P5E_CPU1_P0_TX_BUF_C_DN<6> @T6G_MB_LIB.T6G(SCH_1):P5E_CPU1_P0_TX_BUF_C_DN(6)
 C6642    1      1 Q_CAP_DIFFBUS_C0201-DIFF BUS_0.22UF,6.3V,20%,X6S,SA    I19 @T6G_MB_LIB.T6G(SCH_1):PAGE439
  J112   I7     I7 CONN160_10131762101LF-CONN160_10131762-101LF,THLF,A     I7 @T6G_MB_LIB.T6G(SCH_1):PAGE329

P5E_CPU1_P0_TX_BUF_C_DN<7> @T6G_MB_LIB.T6G(SCH_1):P5E_CPU1_P0_TX_BUF_C_DN(7)
 C6644    1      1 Q_CAP_DIFFBUS_C0201-DIFF BUS_0.22UF,6.3V,20%,X6S,SA    I15 @T6G_MB_LIB.T6G(SCH_1):PAGE439
  J112   H8     H8 CONN160_10131762101LF-CONN160_10131762-101LF,THLF,A     I7 @T6G_MB_LIB.T6G(SCH_1):PAGE329

P5E_CPU1_P0_TX_BUF_C_DN<8> @T6G_MB_LIB.T6G(SCH_1):P5E_CPU1_P0_TX_BUF_C_DN(8)
 C6646    1      1 Q_CAP_DIFFBUS_C0201-DIFF BUS_0.22UF,6.3V,20%,X6S,SA   I104 @T6G_MB_LIB.T6G(SCH_1):PAGE439
  J111   I1     I1 CONN112_10137002101LF-CONN112_10137002-101LF,THLF,A    I76 @T6G_MB_LIB.T6G(SCH_1):PAGE328

P5E_CPU1_P0_TX_BUF_C_DN<9> @T6G_MB_LIB.T6G(SCH_1):P5E_CPU1_P0_TX_BUF_C_DN(9)
 C6648    1      1 Q_CAP_DIFFBUS_C0201-DIFF BUS_0.22UF,6.3V,20%,X6S,SA   I103 @T6G_MB_LIB.T6G(SCH_1):PAGE439
  J111   H2     H2 CONN112_10137002101LF-CONN112_10137002-101LF,THLF,A    I76 @T6G_MB_LIB.T6G(SCH_1):PAGE328

P5E_CPU1_P0_TX_BUF_C_DP<0> @T6G_MB_LIB.T6G(SCH_1):P5E_CPU1_P0_TX_BUF_C_DP(0)
 C6629    1      1 Q_CAP_DIFFBUS_C0201-DIFF BUS_0.22UF,6.3V,20%,X6S,SA    I46 @T6G_MB_LIB.T6G(SCH_1):PAGE439
  J112   J1     J1 CONN160_10131762101LF-CONN160_10131762-101LF,THLF,A   I102 @T6G_MB_LIB.T6G(SCH_1):PAGE329

P5E_CPU1_P0_TX_BUF_C_DP<10> @T6G_MB_LIB.T6G(SCH_1):P5E_CPU1_P0_TX_BUF_C_DP(10)
 C6649    1      1 Q_CAP_DIFFBUS_C0201-DIFF BUS_0.22UF,6.3V,20%,X6S,SA    I96 @T6G_MB_LIB.T6G(SCH_1):PAGE439
  J111   J3     J3 CONN112_10137002101LF-CONN112_10137002-101LF,THLF,A    I76 @T6G_MB_LIB.T6G(SCH_1):PAGE328

P5E_CPU1_P0_TX_BUF_C_DP<11> @T6G_MB_LIB.T6G(SCH_1):P5E_CPU1_P0_TX_BUF_C_DP(11)
 C6651    1      1 Q_CAP_DIFFBUS_C0201-DIFF BUS_0.22UF,6.3V,20%,X6S,SA    I95 @T6G_MB_LIB.T6G(SCH_1):PAGE439
  J111   I4     I4 CONN112_10137002101LF-CONN112_10137002-101LF,THLF,A    I76 @T6G_MB_LIB.T6G(SCH_1):PAGE328

P5E_CPU1_P0_TX_BUF_C_DP<12> @T6G_MB_LIB.T6G(SCH_1):P5E_CPU1_P0_TX_BUF_C_DP(12)
 C6653    1      1 Q_CAP_DIFFBUS_C0201-DIFF BUS_0.22UF,6.3V,20%,X6S,SA    I93 @T6G_MB_LIB.T6G(SCH_1):PAGE439
  J111   J5     J5 CONN112_10137002101LF-CONN112_10137002-101LF,THLF,A    I38 @T6G_MB_LIB.T6G(SCH_1):PAGE328

P5E_CPU1_P0_TX_BUF_C_DP<13> @T6G_MB_LIB.T6G(SCH_1):P5E_CPU1_P0_TX_BUF_C_DP(13)
 C6655    1      1 Q_CAP_DIFFBUS_C0201-DIFF BUS_0.22UF,6.3V,20%,X6S,SA    I91 @T6G_MB_LIB.T6G(SCH_1):PAGE439
  J111   I6     I6 CONN112_10137002101LF-CONN112_10137002-101LF,THLF,A    I38 @T6G_MB_LIB.T6G(SCH_1):PAGE328

P5E_CPU1_P0_TX_BUF_C_DP<14> @T6G_MB_LIB.T6G(SCH_1):P5E_CPU1_P0_TX_BUF_C_DP(14)
 C6657    1      1 Q_CAP_DIFFBUS_C0201-DIFF BUS_0.22UF,6.3V,20%,X6S,SA    I89 @T6G_MB_LIB.T6G(SCH_1):PAGE439
  J111   J7     J7 CONN112_10137002101LF-CONN112_10137002-101LF,THLF,A    I38 @T6G_MB_LIB.T6G(SCH_1):PAGE328

P5E_CPU1_P0_TX_BUF_C_DP<15> @T6G_MB_LIB.T6G(SCH_1):P5E_CPU1_P0_TX_BUF_C_DP(15)
 C6659    1      1 Q_CAP_DIFFBUS_C0201-DIFF BUS_0.22UF,6.3V,20%,X6S,SA    I87 @T6G_MB_LIB.T6G(SCH_1):PAGE439
  J111   I8     I8 CONN112_10137002101LF-CONN112_10137002-101LF,THLF,A    I38 @T6G_MB_LIB.T6G(SCH_1):PAGE328

P5E_CPU1_P0_TX_BUF_C_DP<1> @T6G_MB_LIB.T6G(SCH_1):P5E_CPU1_P0_TX_BUF_C_DP(1)
 C6631    1      1 Q_CAP_DIFFBUS_C0201-DIFF BUS_0.22UF,6.3V,20%,X6S,SA    I45 @T6G_MB_LIB.T6G(SCH_1):PAGE439
  J112   I2     I2 CONN160_10131762101LF-CONN160_10131762-101LF,THLF,A   I102 @T6G_MB_LIB.T6G(SCH_1):PAGE329

P5E_CPU1_P0_TX_BUF_C_DP<2> @T6G_MB_LIB.T6G(SCH_1):P5E_CPU1_P0_TX_BUF_C_DP(2)
 C6633    1      1 Q_CAP_DIFFBUS_C0201-DIFF BUS_0.22UF,6.3V,20%,X6S,SA    I27 @T6G_MB_LIB.T6G(SCH_1):PAGE439
  J112   J3     J3 CONN160_10131762101LF-CONN160_10131762-101LF,THLF,A   I102 @T6G_MB_LIB.T6G(SCH_1):PAGE329

P5E_CPU1_P0_TX_BUF_C_DP<3> @T6G_MB_LIB.T6G(SCH_1):P5E_CPU1_P0_TX_BUF_C_DP(3)
 C6635    1      1 Q_CAP_DIFFBUS_C0201-DIFF BUS_0.22UF,6.3V,20%,X6S,SA    I25 @T6G_MB_LIB.T6G(SCH_1):PAGE439
  J112   I4     I4 CONN160_10131762101LF-CONN160_10131762-101LF,THLF,A   I102 @T6G_MB_LIB.T6G(SCH_1):PAGE329

P5E_CPU1_P0_TX_BUF_C_DP<4> @T6G_MB_LIB.T6G(SCH_1):P5E_CPU1_P0_TX_BUF_C_DP(4)
 C6637    1      1 Q_CAP_DIFFBUS_C0201-DIFF BUS_0.22UF,6.3V,20%,X6S,SA    I22 @T6G_MB_LIB.T6G(SCH_1):PAGE439
  J112   J5     J5 CONN160_10131762101LF-CONN160_10131762-101LF,THLF,A     I7 @T6G_MB_LIB.T6G(SCH_1):PAGE329

P5E_CPU1_P0_TX_BUF_C_DP<5> @T6G_MB_LIB.T6G(SCH_1):P5E_CPU1_P0_TX_BUF_C_DP(5)
 C6639    1      1 Q_CAP_DIFFBUS_C0201-DIFF BUS_0.22UF,6.3V,20%,X6S,SA    I20 @T6G_MB_LIB.T6G(SCH_1):PAGE439
  J112   I6     I6 CONN160_10131762101LF-CONN160_10131762-101LF,THLF,A     I7 @T6G_MB_LIB.T6G(SCH_1):PAGE329

P5E_CPU1_P0_TX_BUF_C_DP<6> @T6G_MB_LIB.T6G(SCH_1):P5E_CPU1_P0_TX_BUF_C_DP(6)
 C6641    1      1 Q_CAP_DIFFBUS_C0201-DIFF BUS_0.22UF,6.3V,20%,X6S,SA    I18 @T6G_MB_LIB.T6G(SCH_1):PAGE439
  J112   J7     J7 CONN160_10131762101LF-CONN160_10131762-101LF,THLF,A     I7 @T6G_MB_LIB.T6G(SCH_1):PAGE329

P5E_CPU1_P0_TX_BUF_C_DP<7> @T6G_MB_LIB.T6G(SCH_1):P5E_CPU1_P0_TX_BUF_C_DP(7)
 C6643    1      1 Q_CAP_DIFFBUS_C0201-DIFF BUS_0.22UF,6.3V,20%,X6S,SA    I16 @T6G_MB_LIB.T6G(SCH_1):PAGE439
  J112   I8     I8 CONN160_10131762101LF-CONN160_10131762-101LF,THLF,A     I7 @T6G_MB_LIB.T6G(SCH_1):PAGE329

P5E_CPU1_P0_TX_BUF_C_DP<8> @T6G_MB_LIB.T6G(SCH_1):P5E_CPU1_P0_TX_BUF_C_DP(8)
 C6645    1      1 Q_CAP_DIFFBUS_C0201-DIFF BUS_0.22UF,6.3V,20%,X6S,SA   I105 @T6G_MB_LIB.T6G(SCH_1):PAGE439
  J111   J1     J1 CONN112_10137002101LF-CONN112_10137002-101LF,THLF,A    I76 @T6G_MB_LIB.T6G(SCH_1):PAGE328

P5E_CPU1_P0_TX_BUF_C_DP<9> @T6G_MB_LIB.T6G(SCH_1):P5E_CPU1_P0_TX_BUF_C_DP(9)
 C6647    1      1 Q_CAP_DIFFBUS_C0201-DIFF BUS_0.22UF,6.3V,20%,X6S,SA   I102 @T6G_MB_LIB.T6G(SCH_1):PAGE439
  J111   I2     I2 CONN112_10137002101LF-CONN112_10137002-101LF,THLF,A    I76 @T6G_MB_LIB.T6G(SCH_1):PAGE328

P5E_CPU1_P0_TX_BUF_DN<0> @T6G_MB_LIB.T6G(SCH_1):P5E_CPU1_P0_TX_BUF_DN(0)
 C6630    2      2 Q_CAP_DIFFBUS_C0201-DIFF BUS_0.22UF,6.3V,20%,X6S,SA    I47 @T6G_MB_LIB.T6G(SCH_1):PAGE439
 U6014 EW10 B_PETN15 PT5161LRS-PT5161LRS,SMLF,IC,AJ051610U03   I142 @T6G_MB_LIB.T6G(SCH_1):PAGE439

P5E_CPU1_P0_TX_BUF_DN<10> @T6G_MB_LIB.T6G(SCH_1):P5E_CPU1_P0_TX_BUF_DN(10)
 U6014 BJ10 B_PETN5 PT5161LRS-PT5161LRS,SMLF,IC,AJ051610U03    I43 @T6G_MB_LIB.T6G(SCH_1):PAGE439
 C6650    2      2 Q_CAP_DIFFBUS_C0201-DIFF BUS_0.22UF,6.3V,20%,X6S,SA    I97 @T6G_MB_LIB.T6G(SCH_1):PAGE439

P5E_CPU1_P0_TX_BUF_DN<11> @T6G_MB_LIB.T6G(SCH_1):P5E_CPU1_P0_TX_BUF_DN(11)
 U6014 BB10 B_PETN4 PT5161LRS-PT5161LRS,SMLF,IC,AJ051610U03    I43 @T6G_MB_LIB.T6G(SCH_1):PAGE439
 C6652    2      2 Q_CAP_DIFFBUS_C0201-DIFF BUS_0.22UF,6.3V,20%,X6S,SA    I94 @T6G_MB_LIB.T6G(SCH_1):PAGE439

P5E_CPU1_P0_TX_BUF_DN<12> @T6G_MB_LIB.T6G(SCH_1):P5E_CPU1_P0_TX_BUF_DN(12)
 U6014 AR10 B_PETN3 PT5161LRS-PT5161LRS,SMLF,IC,AJ051610U03    I43 @T6G_MB_LIB.T6G(SCH_1):PAGE439
 C6654    2      2 Q_CAP_DIFFBUS_C0201-DIFF BUS_0.22UF,6.3V,20%,X6S,SA    I92 @T6G_MB_LIB.T6G(SCH_1):PAGE439

P5E_CPU1_P0_TX_BUF_DN<13> @T6G_MB_LIB.T6G(SCH_1):P5E_CPU1_P0_TX_BUF_DN(13)
 U6014 AH10 B_PETN2 PT5161LRS-PT5161LRS,SMLF,IC,AJ051610U03    I43 @T6G_MB_LIB.T6G(SCH_1):PAGE439
 C6656    2      2 Q_CAP_DIFFBUS_C0201-DIFF BUS_0.22UF,6.3V,20%,X6S,SA    I90 @T6G_MB_LIB.T6G(SCH_1):PAGE439

P5E_CPU1_P0_TX_BUF_DN<14> @T6G_MB_LIB.T6G(SCH_1):P5E_CPU1_P0_TX_BUF_DN(14)
 U6014 AA10 B_PETN1 PT5161LRS-PT5161LRS,SMLF,IC,AJ051610U03    I43 @T6G_MB_LIB.T6G(SCH_1):PAGE439
 C6658    2      2 Q_CAP_DIFFBUS_C0201-DIFF BUS_0.22UF,6.3V,20%,X6S,SA    I88 @T6G_MB_LIB.T6G(SCH_1):PAGE439

P5E_CPU1_P0_TX_BUF_DN<15> @T6G_MB_LIB.T6G(SCH_1):P5E_CPU1_P0_TX_BUF_DN(15)
 U6014  P10 B_PETN0 PT5161LRS-PT5161LRS,SMLF,IC,AJ051610U03    I43 @T6G_MB_LIB.T6G(SCH_1):PAGE439
 C6660    2      2 Q_CAP_DIFFBUS_C0201-DIFF BUS_0.22UF,6.3V,20%,X6S,SA    I86 @T6G_MB_LIB.T6G(SCH_1):PAGE439

P5E_CPU1_P0_TX_BUF_DN<1> @T6G_MB_LIB.T6G(SCH_1):P5E_CPU1_P0_TX_BUF_DN(1)
 C6632    2      2 Q_CAP_DIFFBUS_C0201-DIFF BUS_0.22UF,6.3V,20%,X6S,SA    I44 @T6G_MB_LIB.T6G(SCH_1):PAGE439
 U6014 EM10 B_PETN14 PT5161LRS-PT5161LRS,SMLF,IC,AJ051610U03   I142 @T6G_MB_LIB.T6G(SCH_1):PAGE439

P5E_CPU1_P0_TX_BUF_DN<2> @T6G_MB_LIB.T6G(SCH_1):P5E_CPU1_P0_TX_BUF_DN(2)
 C6634    2      2 Q_CAP_DIFFBUS_C0201-DIFF BUS_0.22UF,6.3V,20%,X6S,SA    I26 @T6G_MB_LIB.T6G(SCH_1):PAGE439
 U6014 EE10 B_PETN13 PT5161LRS-PT5161LRS,SMLF,IC,AJ051610U03   I142 @T6G_MB_LIB.T6G(SCH_1):PAGE439

P5E_CPU1_P0_TX_BUF_DN<3> @T6G_MB_LIB.T6G(SCH_1):P5E_CPU1_P0_TX_BUF_DN(3)
 C6636    2      2 Q_CAP_DIFFBUS_C0201-DIFF BUS_0.22UF,6.3V,20%,X6S,SA    I24 @T6G_MB_LIB.T6G(SCH_1):PAGE439
 U6014 DV10 B_PETN12 PT5161LRS-PT5161LRS,SMLF,IC,AJ051610U03   I142 @T6G_MB_LIB.T6G(SCH_1):PAGE439

P5E_CPU1_P0_TX_BUF_DN<4> @T6G_MB_LIB.T6G(SCH_1):P5E_CPU1_P0_TX_BUF_DN(4)
 C6638    2      2 Q_CAP_DIFFBUS_C0201-DIFF BUS_0.22UF,6.3V,20%,X6S,SA    I23 @T6G_MB_LIB.T6G(SCH_1):PAGE439
 U6014 DL10 B_PETN11 PT5161LRS-PT5161LRS,SMLF,IC,AJ051610U03   I142 @T6G_MB_LIB.T6G(SCH_1):PAGE439

P5E_CPU1_P0_TX_BUF_DN<5> @T6G_MB_LIB.T6G(SCH_1):P5E_CPU1_P0_TX_BUF_DN(5)
 C6640    2      2 Q_CAP_DIFFBUS_C0201-DIFF BUS_0.22UF,6.3V,20%,X6S,SA    I21 @T6G_MB_LIB.T6G(SCH_1):PAGE439
 U6014 DD10 B_PETN10 PT5161LRS-PT5161LRS,SMLF,IC,AJ051610U03   I142 @T6G_MB_LIB.T6G(SCH_1):PAGE439

P5E_CPU1_P0_TX_BUF_DN<6> @T6G_MB_LIB.T6G(SCH_1):P5E_CPU1_P0_TX_BUF_DN(6)
 C6642    2      2 Q_CAP_DIFFBUS_C0201-DIFF BUS_0.22UF,6.3V,20%,X6S,SA    I19 @T6G_MB_LIB.T6G(SCH_1):PAGE439
 U6014 CU10 B_PETN9 PT5161LRS-PT5161LRS,SMLF,IC,AJ051610U03   I142 @T6G_MB_LIB.T6G(SCH_1):PAGE439

P5E_CPU1_P0_TX_BUF_DN<7> @T6G_MB_LIB.T6G(SCH_1):P5E_CPU1_P0_TX_BUF_DN(7)
 C6644    2      2 Q_CAP_DIFFBUS_C0201-DIFF BUS_0.22UF,6.3V,20%,X6S,SA    I15 @T6G_MB_LIB.T6G(SCH_1):PAGE439
 U6014 CK10 B_PETN8 PT5161LRS-PT5161LRS,SMLF,IC,AJ051610U03   I142 @T6G_MB_LIB.T6G(SCH_1):PAGE439

P5E_CPU1_P0_TX_BUF_DN<8> @T6G_MB_LIB.T6G(SCH_1):P5E_CPU1_P0_TX_BUF_DN(8)
 U6014 CC10 B_PETN7 PT5161LRS-PT5161LRS,SMLF,IC,AJ051610U03    I43 @T6G_MB_LIB.T6G(SCH_1):PAGE439
 C6646    2      2 Q_CAP_DIFFBUS_C0201-DIFF BUS_0.22UF,6.3V,20%,X6S,SA   I104 @T6G_MB_LIB.T6G(SCH_1):PAGE439

P5E_CPU1_P0_TX_BUF_DN<9> @T6G_MB_LIB.T6G(SCH_1):P5E_CPU1_P0_TX_BUF_DN(9)
 U6014 BT10 B_PETN6 PT5161LRS-PT5161LRS,SMLF,IC,AJ051610U03    I43 @T6G_MB_LIB.T6G(SCH_1):PAGE439
 C6648    2      2 Q_CAP_DIFFBUS_C0201-DIFF BUS_0.22UF,6.3V,20%,X6S,SA   I103 @T6G_MB_LIB.T6G(SCH_1):PAGE439

P5E_CPU1_P0_TX_BUF_DP<0> @T6G_MB_LIB.T6G(SCH_1):P5E_CPU1_P0_TX_BUF_DP(0)
 C6629    2      2 Q_CAP_DIFFBUS_C0201-DIFF BUS_0.22UF,6.3V,20%,X6S,SA    I46 @T6G_MB_LIB.T6G(SCH_1):PAGE439
 U6014  EU7 B_PETP15 PT5161LRS-PT5161LRS,SMLF,IC,AJ051610U03   I142 @T6G_MB_LIB.T6G(SCH_1):PAGE439

P5E_CPU1_P0_TX_BUF_DP<10> @T6G_MB_LIB.T6G(SCH_1):P5E_CPU1_P0_TX_BUF_DP(10)
 U6014  BG7 B_PETP5 PT5161LRS-PT5161LRS,SMLF,IC,AJ051610U03    I43 @T6G_MB_LIB.T6G(SCH_1):PAGE439
 C6649    2      2 Q_CAP_DIFFBUS_C0201-DIFF BUS_0.22UF,6.3V,20%,X6S,SA    I96 @T6G_MB_LIB.T6G(SCH_1):PAGE439

P5E_CPU1_P0_TX_BUF_DP<11> @T6G_MB_LIB.T6G(SCH_1):P5E_CPU1_P0_TX_BUF_DP(11)
 U6014  AY7 B_PETP4 PT5161LRS-PT5161LRS,SMLF,IC,AJ051610U03    I43 @T6G_MB_LIB.T6G(SCH_1):PAGE439
 C6651    2      2 Q_CAP_DIFFBUS_C0201-DIFF BUS_0.22UF,6.3V,20%,X6S,SA    I95 @T6G_MB_LIB.T6G(SCH_1):PAGE439

P5E_CPU1_P0_TX_BUF_DP<12> @T6G_MB_LIB.T6G(SCH_1):P5E_CPU1_P0_TX_BUF_DP(12)
 U6014  AN7 B_PETP3 PT5161LRS-PT5161LRS,SMLF,IC,AJ051610U03    I43 @T6G_MB_LIB.T6G(SCH_1):PAGE439
 C6653    2      2 Q_CAP_DIFFBUS_C0201-DIFF BUS_0.22UF,6.3V,20%,X6S,SA    I93 @T6G_MB_LIB.T6G(SCH_1):PAGE439

P5E_CPU1_P0_TX_BUF_DP<13> @T6G_MB_LIB.T6G(SCH_1):P5E_CPU1_P0_TX_BUF_DP(13)
 U6014  AF7 B_PETP2 PT5161LRS-PT5161LRS,SMLF,IC,AJ051610U03    I43 @T6G_MB_LIB.T6G(SCH_1):PAGE439
 C6655    2      2 Q_CAP_DIFFBUS_C0201-DIFF BUS_0.22UF,6.3V,20%,X6S,SA    I91 @T6G_MB_LIB.T6G(SCH_1):PAGE439

P5E_CPU1_P0_TX_BUF_DP<14> @T6G_MB_LIB.T6G(SCH_1):P5E_CPU1_P0_TX_BUF_DP(14)
 U6014   W7 B_PETP1 PT5161LRS-PT5161LRS,SMLF,IC,AJ051610U03    I43 @T6G_MB_LIB.T6G(SCH_1):PAGE439
 C6657    2      2 Q_CAP_DIFFBUS_C0201-DIFF BUS_0.22UF,6.3V,20%,X6S,SA    I89 @T6G_MB_LIB.T6G(SCH_1):PAGE439

P5E_CPU1_P0_TX_BUF_DP<15> @T6G_MB_LIB.T6G(SCH_1):P5E_CPU1_P0_TX_BUF_DP(15)
 U6014   M7 B_PETP0 PT5161LRS-PT5161LRS,SMLF,IC,AJ051610U03    I43 @T6G_MB_LIB.T6G(SCH_1):PAGE439
 C6659    2      2 Q_CAP_DIFFBUS_C0201-DIFF BUS_0.22UF,6.3V,20%,X6S,SA    I87 @T6G_MB_LIB.T6G(SCH_1):PAGE439

P5E_CPU1_P0_TX_BUF_DP<1> @T6G_MB_LIB.T6G(SCH_1):P5E_CPU1_P0_TX_BUF_DP(1)
 C6631    2      2 Q_CAP_DIFFBUS_C0201-DIFF BUS_0.22UF,6.3V,20%,X6S,SA    I45 @T6G_MB_LIB.T6G(SCH_1):PAGE439
 U6014  EK7 B_PETP14 PT5161LRS-PT5161LRS,SMLF,IC,AJ051610U03   I142 @T6G_MB_LIB.T6G(SCH_1):PAGE439

P5E_CPU1_P0_TX_BUF_DP<2> @T6G_MB_LIB.T6G(SCH_1):P5E_CPU1_P0_TX_BUF_DP(2)
 C6633    2      2 Q_CAP_DIFFBUS_C0201-DIFF BUS_0.22UF,6.3V,20%,X6S,SA    I27 @T6G_MB_LIB.T6G(SCH_1):PAGE439
 U6014  EC7 B_PETP13 PT5161LRS-PT5161LRS,SMLF,IC,AJ051610U03   I142 @T6G_MB_LIB.T6G(SCH_1):PAGE439

P5E_CPU1_P0_TX_BUF_DP<3> @T6G_MB_LIB.T6G(SCH_1):P5E_CPU1_P0_TX_BUF_DP(3)
 C6635    2      2 Q_CAP_DIFFBUS_C0201-DIFF BUS_0.22UF,6.3V,20%,X6S,SA    I25 @T6G_MB_LIB.T6G(SCH_1):PAGE439
 U6014  DT7 B_PETP12 PT5161LRS-PT5161LRS,SMLF,IC,AJ051610U03   I142 @T6G_MB_LIB.T6G(SCH_1):PAGE439

P5E_CPU1_P0_TX_BUF_DP<4> @T6G_MB_LIB.T6G(SCH_1):P5E_CPU1_P0_TX_BUF_DP(4)
 C6637    2      2 Q_CAP_DIFFBUS_C0201-DIFF BUS_0.22UF,6.3V,20%,X6S,SA    I22 @T6G_MB_LIB.T6G(SCH_1):PAGE439
 U6014  DJ7 B_PETP11 PT5161LRS-PT5161LRS,SMLF,IC,AJ051610U03   I142 @T6G_MB_LIB.T6G(SCH_1):PAGE439

P5E_CPU1_P0_TX_BUF_DP<5> @T6G_MB_LIB.T6G(SCH_1):P5E_CPU1_P0_TX_BUF_DP(5)
 C6639    2      2 Q_CAP_DIFFBUS_C0201-DIFF BUS_0.22UF,6.3V,20%,X6S,SA    I20 @T6G_MB_LIB.T6G(SCH_1):PAGE439
 U6014  DB7 B_PETP10 PT5161LRS-PT5161LRS,SMLF,IC,AJ051610U03   I142 @T6G_MB_LIB.T6G(SCH_1):PAGE439

P5E_CPU1_P0_TX_BUF_DP<6> @T6G_MB_LIB.T6G(SCH_1):P5E_CPU1_P0_TX_BUF_DP(6)
 C6641    2      2 Q_CAP_DIFFBUS_C0201-DIFF BUS_0.22UF,6.3V,20%,X6S,SA    I18 @T6G_MB_LIB.T6G(SCH_1):PAGE439
 U6014  CR7 B_PETP9 PT5161LRS-PT5161LRS,SMLF,IC,AJ051610U03   I142 @T6G_MB_LIB.T6G(SCH_1):PAGE439

P5E_CPU1_P0_TX_BUF_DP<7> @T6G_MB_LIB.T6G(SCH_1):P5E_CPU1_P0_TX_BUF_DP(7)
 C6643    2      2 Q_CAP_DIFFBUS_C0201-DIFF BUS_0.22UF,6.3V,20%,X6S,SA    I16 @T6G_MB_LIB.T6G(SCH_1):PAGE439
 U6014  CH7 B_PETP8 PT5161LRS-PT5161LRS,SMLF,IC,AJ051610U03   I142 @T6G_MB_LIB.T6G(SCH_1):PAGE439

P5E_CPU1_P0_TX_BUF_DP<8> @T6G_MB_LIB.T6G(SCH_1):P5E_CPU1_P0_TX_BUF_DP(8)
 U6014  CA7 B_PETP7 PT5161LRS-PT5161LRS,SMLF,IC,AJ051610U03    I43 @T6G_MB_LIB.T6G(SCH_1):PAGE439
 C6645    2      2 Q_CAP_DIFFBUS_C0201-DIFF BUS_0.22UF,6.3V,20%,X6S,SA   I105 @T6G_MB_LIB.T6G(SCH_1):PAGE439

P5E_CPU1_P0_TX_BUF_DP<9> @T6G_MB_LIB.T6G(SCH_1):P5E_CPU1_P0_TX_BUF_DP(9)
 U6014  BP7 B_PETP6 PT5161LRS-PT5161LRS,SMLF,IC,AJ051610U03    I43 @T6G_MB_LIB.T6G(SCH_1):PAGE439
 C6647    2      2 Q_CAP_DIFFBUS_C0201-DIFF BUS_0.22UF,6.3V,20%,X6S,SA   I102 @T6G_MB_LIB.T6G(SCH_1):PAGE439

P5E_CPU1_P0_TX_C_DN<0> @T6G_MB_LIB.T6G(SCH_1):P5E_CPU1_P0_TX_C_DN(0)
  C836    1      1 Q_CAP_DIFFBUS_C0201-DIFF BUS_0.22UF,6.3V,20%,X6S,SA   I333 @T6G_MB_LIB.T6G(SCH_1):PAGE353
 U6014 EV34 B_PERP15 PT5161LRS-PT5161LRS,SMLF,IC,AJ051610U03    I38 @T6G_MB_LIB.T6G(SCH_1):PAGE437

P5E_CPU1_P0_TX_C_DN<10> @T6G_MB_LIB.T6G(SCH_1):P5E_CPU1_P0_TX_C_DN(10)
  C816    1      1 Q_CAP_DIFFBUS_C0201-DIFF BUS_0.22UF,6.3V,20%,X6S,SA   I368 @T6G_MB_LIB.T6G(SCH_1):PAGE353
 U6014 BH34 B_PERP5 PT5161LRS-PT5161LRS,SMLF,IC,AJ051610U03     I1 @T6G_MB_LIB.T6G(SCH_1):PAGE437

P5E_CPU1_P0_TX_C_DN<11> @T6G_MB_LIB.T6G(SCH_1):P5E_CPU1_P0_TX_C_DN(11)
  C814    1      1 Q_CAP_DIFFBUS_C0201-DIFF BUS_0.22UF,6.3V,20%,X6S,SA   I370 @T6G_MB_LIB.T6G(SCH_1):PAGE353
 U6014 BA34 B_PERP4 PT5161LRS-PT5161LRS,SMLF,IC,AJ051610U03     I1 @T6G_MB_LIB.T6G(SCH_1):PAGE437

P5E_CPU1_P0_TX_C_DN<12> @T6G_MB_LIB.T6G(SCH_1):P5E_CPU1_P0_TX_C_DN(12)
  C812    1      1 Q_CAP_DIFFBUS_C0201-DIFF BUS_0.22UF,6.3V,20%,X6S,SA   I371 @T6G_MB_LIB.T6G(SCH_1):PAGE353
 U6014 AP34 B_PERP3 PT5161LRS-PT5161LRS,SMLF,IC,AJ051610U03     I1 @T6G_MB_LIB.T6G(SCH_1):PAGE437

P5E_CPU1_P0_TX_C_DN<13> @T6G_MB_LIB.T6G(SCH_1):P5E_CPU1_P0_TX_C_DN(13)
  C810    1      1 Q_CAP_DIFFBUS_C0201-DIFF BUS_0.22UF,6.3V,20%,X6S,SA   I374 @T6G_MB_LIB.T6G(SCH_1):PAGE353
 U6014 AJ35 B_PERN2 PT5161LRS-PT5161LRS,SMLF,IC,AJ051610U03     I1 @T6G_MB_LIB.T6G(SCH_1):PAGE437

P5E_CPU1_P0_TX_C_DN<14> @T6G_MB_LIB.T6G(SCH_1):P5E_CPU1_P0_TX_C_DN(14)
  C808    1      1 Q_CAP_DIFFBUS_C0201-DIFF BUS_0.22UF,6.3V,20%,X6S,SA   I376 @T6G_MB_LIB.T6G(SCH_1):PAGE353
 U6014  Y34 B_PERP1 PT5161LRS-PT5161LRS,SMLF,IC,AJ051610U03     I1 @T6G_MB_LIB.T6G(SCH_1):PAGE437

P5E_CPU1_P0_TX_C_DN<15> @T6G_MB_LIB.T6G(SCH_1):P5E_CPU1_P0_TX_C_DN(15)
  C806    1      1 Q_CAP_DIFFBUS_C0201-DIFF BUS_0.22UF,6.3V,20%,X6S,SA   I377 @T6G_MB_LIB.T6G(SCH_1):PAGE353
 U6014  N34 B_PERP0 PT5161LRS-PT5161LRS,SMLF,IC,AJ051610U03     I1 @T6G_MB_LIB.T6G(SCH_1):PAGE437

P5E_CPU1_P0_TX_C_DN<1> @T6G_MB_LIB.T6G(SCH_1):P5E_CPU1_P0_TX_C_DN(1)
  C834    1      1 Q_CAP_DIFFBUS_C0201-DIFF BUS_0.22UF,6.3V,20%,X6S,SA   I335 @T6G_MB_LIB.T6G(SCH_1):PAGE353
 U6014 EN35 B_PERN14 PT5161LRS-PT5161LRS,SMLF,IC,AJ051610U03    I38 @T6G_MB_LIB.T6G(SCH_1):PAGE437

P5E_CPU1_P0_TX_C_DN<2> @T6G_MB_LIB.T6G(SCH_1):P5E_CPU1_P0_TX_C_DN(2)
  C832    1      1 Q_CAP_DIFFBUS_C0201-DIFF BUS_0.22UF,6.3V,20%,X6S,SA   I338 @T6G_MB_LIB.T6G(SCH_1):PAGE353
 U6014 ED34 B_PERP13 PT5161LRS-PT5161LRS,SMLF,IC,AJ051610U03    I38 @T6G_MB_LIB.T6G(SCH_1):PAGE437

P5E_CPU1_P0_TX_C_DN<3> @T6G_MB_LIB.T6G(SCH_1):P5E_CPU1_P0_TX_C_DN(3)
  C830    1      1 Q_CAP_DIFFBUS_C0201-DIFF BUS_0.22UF,6.3V,20%,X6S,SA   I341 @T6G_MB_LIB.T6G(SCH_1):PAGE353
 U6014 DU34 B_PERP12 PT5161LRS-PT5161LRS,SMLF,IC,AJ051610U03    I38 @T6G_MB_LIB.T6G(SCH_1):PAGE437

P5E_CPU1_P0_TX_C_DN<4> @T6G_MB_LIB.T6G(SCH_1):P5E_CPU1_P0_TX_C_DN(4)
  C828    1      1 Q_CAP_DIFFBUS_C0201-DIFF BUS_0.22UF,6.3V,20%,X6S,SA   I340 @T6G_MB_LIB.T6G(SCH_1):PAGE353
 U6014 DK34 B_PERP11 PT5161LRS-PT5161LRS,SMLF,IC,AJ051610U03    I38 @T6G_MB_LIB.T6G(SCH_1):PAGE437

P5E_CPU1_P0_TX_C_DN<5> @T6G_MB_LIB.T6G(SCH_1):P5E_CPU1_P0_TX_C_DN(5)
  C826    1      1 Q_CAP_DIFFBUS_C0201-DIFF BUS_0.22UF,6.3V,20%,X6S,SA   I344 @T6G_MB_LIB.T6G(SCH_1):PAGE353
 U6014 DC34 B_PERP10 PT5161LRS-PT5161LRS,SMLF,IC,AJ051610U03    I38 @T6G_MB_LIB.T6G(SCH_1):PAGE437

P5E_CPU1_P0_TX_C_DN<6> @T6G_MB_LIB.T6G(SCH_1):P5E_CPU1_P0_TX_C_DN(6)
  C824    1      1 Q_CAP_DIFFBUS_C0201-DIFF BUS_0.22UF,6.3V,20%,X6S,SA   I416 @T6G_MB_LIB.T6G(SCH_1):PAGE353
 U6014 CT34 B_PERP9 PT5161LRS-PT5161LRS,SMLF,IC,AJ051610U03    I38 @T6G_MB_LIB.T6G(SCH_1):PAGE437

P5E_CPU1_P0_TX_C_DN<7> @T6G_MB_LIB.T6G(SCH_1):P5E_CPU1_P0_TX_C_DN(7)
  C822    1      1 Q_CAP_DIFFBUS_C0201-DIFF BUS_0.22UF,6.3V,20%,X6S,SA   I345 @T6G_MB_LIB.T6G(SCH_1):PAGE353
 U6014 CJ34 B_PERP8 PT5161LRS-PT5161LRS,SMLF,IC,AJ051610U03    I38 @T6G_MB_LIB.T6G(SCH_1):PAGE437

P5E_CPU1_P0_TX_C_DN<8> @T6G_MB_LIB.T6G(SCH_1):P5E_CPU1_P0_TX_C_DN(8)
  C820    1      1 Q_CAP_DIFFBUS_C0201-DIFF BUS_0.22UF,6.3V,20%,X6S,SA   I363 @T6G_MB_LIB.T6G(SCH_1):PAGE353
 U6014 CB34 B_PERP7 PT5161LRS-PT5161LRS,SMLF,IC,AJ051610U03     I1 @T6G_MB_LIB.T6G(SCH_1):PAGE437

P5E_CPU1_P0_TX_C_DN<9> @T6G_MB_LIB.T6G(SCH_1):P5E_CPU1_P0_TX_C_DN(9)
  C818    1      1 Q_CAP_DIFFBUS_C0201-DIFF BUS_0.22UF,6.3V,20%,X6S,SA   I365 @T6G_MB_LIB.T6G(SCH_1):PAGE353
 U6014 BR34 B_PERP6 PT5161LRS-PT5161LRS,SMLF,IC,AJ051610U03     I1 @T6G_MB_LIB.T6G(SCH_1):PAGE437

P5E_CPU1_P0_TX_C_DP<0> @T6G_MB_LIB.T6G(SCH_1):P5E_CPU1_P0_TX_C_DP(0)
  C837    1      1 Q_CAP_DIFFBUS_C0201-DIFF BUS_0.22UF,6.3V,20%,X6S,SA   I334 @T6G_MB_LIB.T6G(SCH_1):PAGE353
 U6014 EY35 B_PERN15 PT5161LRS-PT5161LRS,SMLF,IC,AJ051610U03    I38 @T6G_MB_LIB.T6G(SCH_1):PAGE437

P5E_CPU1_P0_TX_C_DP<10> @T6G_MB_LIB.T6G(SCH_1):P5E_CPU1_P0_TX_C_DP(10)
  C817    1      1 Q_CAP_DIFFBUS_C0201-DIFF BUS_0.22UF,6.3V,20%,X6S,SA   I367 @T6G_MB_LIB.T6G(SCH_1):PAGE353
 U6014 BK35 B_PERN5 PT5161LRS-PT5161LRS,SMLF,IC,AJ051610U03     I1 @T6G_MB_LIB.T6G(SCH_1):PAGE437

P5E_CPU1_P0_TX_C_DP<11> @T6G_MB_LIB.T6G(SCH_1):P5E_CPU1_P0_TX_C_DP(11)
  C815    1      1 Q_CAP_DIFFBUS_C0201-DIFF BUS_0.22UF,6.3V,20%,X6S,SA   I369 @T6G_MB_LIB.T6G(SCH_1):PAGE353
 U6014 BC35 B_PERN4 PT5161LRS-PT5161LRS,SMLF,IC,AJ051610U03     I1 @T6G_MB_LIB.T6G(SCH_1):PAGE437

P5E_CPU1_P0_TX_C_DP<12> @T6G_MB_LIB.T6G(SCH_1):P5E_CPU1_P0_TX_C_DP(12)
  C813    1      1 Q_CAP_DIFFBUS_C0201-DIFF BUS_0.22UF,6.3V,20%,X6S,SA   I372 @T6G_MB_LIB.T6G(SCH_1):PAGE353
 U6014 AT35 B_PERN3 PT5161LRS-PT5161LRS,SMLF,IC,AJ051610U03     I1 @T6G_MB_LIB.T6G(SCH_1):PAGE437

P5E_CPU1_P0_TX_C_DP<13> @T6G_MB_LIB.T6G(SCH_1):P5E_CPU1_P0_TX_C_DP(13)
  C811    1      1 Q_CAP_DIFFBUS_C0201-DIFF BUS_0.22UF,6.3V,20%,X6S,SA   I373 @T6G_MB_LIB.T6G(SCH_1):PAGE353
 U6014 AG34 B_PERP2 PT5161LRS-PT5161LRS,SMLF,IC,AJ051610U03     I1 @T6G_MB_LIB.T6G(SCH_1):PAGE437

P5E_CPU1_P0_TX_C_DP<14> @T6G_MB_LIB.T6G(SCH_1):P5E_CPU1_P0_TX_C_DP(14)
  C809    1      1 Q_CAP_DIFFBUS_C0201-DIFF BUS_0.22UF,6.3V,20%,X6S,SA   I375 @T6G_MB_LIB.T6G(SCH_1):PAGE353
 U6014 AB35 B_PERN1 PT5161LRS-PT5161LRS,SMLF,IC,AJ051610U03     I1 @T6G_MB_LIB.T6G(SCH_1):PAGE437

P5E_CPU1_P0_TX_C_DP<15> @T6G_MB_LIB.T6G(SCH_1):P5E_CPU1_P0_TX_C_DP(15)
  C807    1      1 Q_CAP_DIFFBUS_C0201-DIFF BUS_0.22UF,6.3V,20%,X6S,SA   I378 @T6G_MB_LIB.T6G(SCH_1):PAGE353
 U6014  R35 B_PERN0 PT5161LRS-PT5161LRS,SMLF,IC,AJ051610U03     I1 @T6G_MB_LIB.T6G(SCH_1):PAGE437

P5E_CPU1_P0_TX_C_DP<1> @T6G_MB_LIB.T6G(SCH_1):P5E_CPU1_P0_TX_C_DP(1)
  C835    1      1 Q_CAP_DIFFBUS_C0201-DIFF BUS_0.22UF,6.3V,20%,X6S,SA   I336 @T6G_MB_LIB.T6G(SCH_1):PAGE353
 U6014 EL34 B_PERP14 PT5161LRS-PT5161LRS,SMLF,IC,AJ051610U03    I38 @T6G_MB_LIB.T6G(SCH_1):PAGE437

P5E_CPU1_P0_TX_C_DP<2> @T6G_MB_LIB.T6G(SCH_1):P5E_CPU1_P0_TX_C_DP(2)
  C833    1      1 Q_CAP_DIFFBUS_C0201-DIFF BUS_0.22UF,6.3V,20%,X6S,SA   I339 @T6G_MB_LIB.T6G(SCH_1):PAGE353
 U6014 EF35 B_PERN13 PT5161LRS-PT5161LRS,SMLF,IC,AJ051610U03    I38 @T6G_MB_LIB.T6G(SCH_1):PAGE437

P5E_CPU1_P0_TX_C_DP<3> @T6G_MB_LIB.T6G(SCH_1):P5E_CPU1_P0_TX_C_DP(3)
  C831    1      1 Q_CAP_DIFFBUS_C0201-DIFF BUS_0.22UF,6.3V,20%,X6S,SA   I337 @T6G_MB_LIB.T6G(SCH_1):PAGE353
 U6014 DW35 B_PERN12 PT5161LRS-PT5161LRS,SMLF,IC,AJ051610U03    I38 @T6G_MB_LIB.T6G(SCH_1):PAGE437

P5E_CPU1_P0_TX_C_DP<4> @T6G_MB_LIB.T6G(SCH_1):P5E_CPU1_P0_TX_C_DP(4)
  C829    1      1 Q_CAP_DIFFBUS_C0201-DIFF BUS_0.22UF,6.3V,20%,X6S,SA   I342 @T6G_MB_LIB.T6G(SCH_1):PAGE353
 U6014 DM35 B_PERN11 PT5161LRS-PT5161LRS,SMLF,IC,AJ051610U03    I38 @T6G_MB_LIB.T6G(SCH_1):PAGE437

P5E_CPU1_P0_TX_C_DP<5> @T6G_MB_LIB.T6G(SCH_1):P5E_CPU1_P0_TX_C_DP(5)
  C827    1      1 Q_CAP_DIFFBUS_C0201-DIFF BUS_0.22UF,6.3V,20%,X6S,SA   I343 @T6G_MB_LIB.T6G(SCH_1):PAGE353
 U6014 DE35 B_PERN10 PT5161LRS-PT5161LRS,SMLF,IC,AJ051610U03    I38 @T6G_MB_LIB.T6G(SCH_1):PAGE437

P5E_CPU1_P0_TX_C_DP<6> @T6G_MB_LIB.T6G(SCH_1):P5E_CPU1_P0_TX_C_DP(6)
  C825    1      1 Q_CAP_DIFFBUS_C0201-DIFF BUS_0.22UF,6.3V,20%,X6S,SA   I415 @T6G_MB_LIB.T6G(SCH_1):PAGE353
 U6014 CV35 B_PERN9 PT5161LRS-PT5161LRS,SMLF,IC,AJ051610U03    I38 @T6G_MB_LIB.T6G(SCH_1):PAGE437

P5E_CPU1_P0_TX_C_DP<7> @T6G_MB_LIB.T6G(SCH_1):P5E_CPU1_P0_TX_C_DP(7)
  C823    1      1 Q_CAP_DIFFBUS_C0201-DIFF BUS_0.22UF,6.3V,20%,X6S,SA   I346 @T6G_MB_LIB.T6G(SCH_1):PAGE353
 U6014 CL35 B_PERN8 PT5161LRS-PT5161LRS,SMLF,IC,AJ051610U03    I38 @T6G_MB_LIB.T6G(SCH_1):PAGE437

P5E_CPU1_P0_TX_C_DP<8> @T6G_MB_LIB.T6G(SCH_1):P5E_CPU1_P0_TX_C_DP(8)
  C821    1      1 Q_CAP_DIFFBUS_C0201-DIFF BUS_0.22UF,6.3V,20%,X6S,SA   I364 @T6G_MB_LIB.T6G(SCH_1):PAGE353
 U6014 CD35 B_PERN7 PT5161LRS-PT5161LRS,SMLF,IC,AJ051610U03     I1 @T6G_MB_LIB.T6G(SCH_1):PAGE437

P5E_CPU1_P0_TX_C_DP<9> @T6G_MB_LIB.T6G(SCH_1):P5E_CPU1_P0_TX_C_DP(9)
  C819    1      1 Q_CAP_DIFFBUS_C0201-DIFF BUS_0.22UF,6.3V,20%,X6S,SA   I366 @T6G_MB_LIB.T6G(SCH_1):PAGE353
 U6014 BU35 B_PERN6 PT5161LRS-PT5161LRS,SMLF,IC,AJ051610U03     I1 @T6G_MB_LIB.T6G(SCH_1):PAGE437

P5E_CPU1_P0_TX_DN<0> @T6G_MB_LIB.T6G(SCH_1):P5E_CPU1_P0_TX_DN(0)
   U26 CN52 P0_TXN0||SATA00_TXN GENOA_SP5-SOCKET6096_13568-001,SMLF,IO,DGA^6000030   I147 @T6G_MB_LIB.T6G(SCH_1):PAGE51
  C836    2      2 Q_CAP_DIFFBUS_C0201-DIFF BUS_0.22UF,6.3V,20%,X6S,SA   I333 @T6G_MB_LIB.T6G(SCH_1):PAGE353

P5E_CPU1_P0_TX_DN<10> @T6G_MB_LIB.T6G(SCH_1):P5E_CPU1_P0_TX_DN(10)
   U26 CR43 P0_TXN10||SATA12_TXN GENOA_SP5-SOCKET6096_13568-001,SMLF,IO,DGA^6000030   I147 @T6G_MB_LIB.T6G(SCH_1):PAGE51
  C816    2      2 Q_CAP_DIFFBUS_C0201-DIFF BUS_0.22UF,6.3V,20%,X6S,SA   I368 @T6G_MB_LIB.T6G(SCH_1):PAGE353

P5E_CPU1_P0_TX_DN<11> @T6G_MB_LIB.T6G(SCH_1):P5E_CPU1_P0_TX_DN(11)
   U26 CU43 P0_TXN11||SATA13_TXN GENOA_SP5-SOCKET6096_13568-001,SMLF,IO,DGA^6000030   I147 @T6G_MB_LIB.T6G(SCH_1):PAGE51
  C814    2      2 Q_CAP_DIFFBUS_C0201-DIFF BUS_0.22UF,6.3V,20%,X6S,SA   I370 @T6G_MB_LIB.T6G(SCH_1):PAGE353

P5E_CPU1_P0_TX_DN<12> @T6G_MB_LIB.T6G(SCH_1):P5E_CPU1_P0_TX_DN(12)
   U26 CN43 P0_TXN12||SATA14_TXN GENOA_SP5-SOCKET6096_13568-001,SMLF,IO,DGA^6000030   I147 @T6G_MB_LIB.T6G(SCH_1):PAGE51
  C812    2      2 Q_CAP_DIFFBUS_C0201-DIFF BUS_0.22UF,6.3V,20%,X6S,SA   I371 @T6G_MB_LIB.T6G(SCH_1):PAGE353

P5E_CPU1_P0_TX_DN<13> @T6G_MB_LIB.T6G(SCH_1):P5E_CPU1_P0_TX_DN(13)
   U26 CT40 P0_TXN13||SATA15_TXN GENOA_SP5-SOCKET6096_13568-001,SMLF,IO,DGA^6000030   I147 @T6G_MB_LIB.T6G(SCH_1):PAGE51
  C810    2      2 Q_CAP_DIFFBUS_C0201-DIFF BUS_0.22UF,6.3V,20%,X6S,SA   I374 @T6G_MB_LIB.T6G(SCH_1):PAGE353

P5E_CPU1_P0_TX_DN<14> @T6G_MB_LIB.T6G(SCH_1):P5E_CPU1_P0_TX_DN(14)
   U26 CP40 P0_TXN14||SATA16_TXN GENOA_SP5-SOCKET6096_13568-001,SMLF,IO,DGA^6000030   I147 @T6G_MB_LIB.T6G(SCH_1):PAGE51
  C808    2      2 Q_CAP_DIFFBUS_C0201-DIFF BUS_0.22UF,6.3V,20%,X6S,SA   I376 @T6G_MB_LIB.T6G(SCH_1):PAGE353

P5E_CPU1_P0_TX_DN<15> @T6G_MB_LIB.T6G(SCH_1):P5E_CPU1_P0_TX_DN(15)
   U26 CM40 P0_TXN15||SATA17_TXN GENOA_SP5-SOCKET6096_13568-001,SMLF,IO,DGA^6000030   I147 @T6G_MB_LIB.T6G(SCH_1):PAGE51
  C806    2      2 Q_CAP_DIFFBUS_C0201-DIFF BUS_0.22UF,6.3V,20%,X6S,SA   I377 @T6G_MB_LIB.T6G(SCH_1):PAGE353

P5E_CPU1_P0_TX_DN<1> @T6G_MB_LIB.T6G(SCH_1):P5E_CPU1_P0_TX_DN(1)
   U26 CR52 P0_TXN1||SATA01_TXN GENOA_SP5-SOCKET6096_13568-001,SMLF,IO,DGA^6000030   I147 @T6G_MB_LIB.T6G(SCH_1):PAGE51
  C834    2      2 Q_CAP_DIFFBUS_C0201-DIFF BUS_0.22UF,6.3V,20%,X6S,SA   I335 @T6G_MB_LIB.T6G(SCH_1):PAGE353

P5E_CPU1_P0_TX_DN<2> @T6G_MB_LIB.T6G(SCH_1):P5E_CPU1_P0_TX_DN(2)
   U26 CL52 P0_TXN2||SATA02_TXN GENOA_SP5-SOCKET6096_13568-001,SMLF,IO,DGA^6000030   I147 @T6G_MB_LIB.T6G(SCH_1):PAGE51
  C832    2      2 Q_CAP_DIFFBUS_C0201-DIFF BUS_0.22UF,6.3V,20%,X6S,SA   I338 @T6G_MB_LIB.T6G(SCH_1):PAGE353

P5E_CPU1_P0_TX_DN<3> @T6G_MB_LIB.T6G(SCH_1):P5E_CPU1_P0_TX_DN(3)
   U26 CN49 P0_TXN3||SATA03_TXN GENOA_SP5-SOCKET6096_13568-001,SMLF,IO,DGA^6000030   I147 @T6G_MB_LIB.T6G(SCH_1):PAGE51
  C830    2      2 Q_CAP_DIFFBUS_C0201-DIFF BUS_0.22UF,6.3V,20%,X6S,SA   I341 @T6G_MB_LIB.T6G(SCH_1):PAGE353

P5E_CPU1_P0_TX_DN<4> @T6G_MB_LIB.T6G(SCH_1):P5E_CPU1_P0_TX_DN(4)
   U26 CR49 P0_TXN4||SATA04_TXN GENOA_SP5-SOCKET6096_13568-001,SMLF,IO,DGA^6000030   I147 @T6G_MB_LIB.T6G(SCH_1):PAGE51
  C828    2      2 Q_CAP_DIFFBUS_C0201-DIFF BUS_0.22UF,6.3V,20%,X6S,SA   I340 @T6G_MB_LIB.T6G(SCH_1):PAGE353

P5E_CPU1_P0_TX_DN<5> @T6G_MB_LIB.T6G(SCH_1):P5E_CPU1_P0_TX_DN(5)
   U26 CU49 P0_TXN5||SATA05_TXN GENOA_SP5-SOCKET6096_13568-001,SMLF,IO,DGA^6000030   I147 @T6G_MB_LIB.T6G(SCH_1):PAGE51
  C826    2      2 Q_CAP_DIFFBUS_C0201-DIFF BUS_0.22UF,6.3V,20%,X6S,SA   I344 @T6G_MB_LIB.T6G(SCH_1):PAGE353

P5E_CPU1_P0_TX_DN<6> @T6G_MB_LIB.T6G(SCH_1):P5E_CPU1_P0_TX_DN(6)
   U26 CL49 P0_TXN6||SATA06_TXN GENOA_SP5-SOCKET6096_13568-001,SMLF,IO,DGA^6000030   I147 @T6G_MB_LIB.T6G(SCH_1):PAGE51
  C824    2      2 Q_CAP_DIFFBUS_C0201-DIFF BUS_0.22UF,6.3V,20%,X6S,SA   I416 @T6G_MB_LIB.T6G(SCH_1):PAGE353

P5E_CPU1_P0_TX_DN<7> @T6G_MB_LIB.T6G(SCH_1):P5E_CPU1_P0_TX_DN(7)
   U26 CR46 P0_TXN7||SATA07_TXN GENOA_SP5-SOCKET6096_13568-001,SMLF,IO,DGA^6000030   I147 @T6G_MB_LIB.T6G(SCH_1):PAGE51
  C822    2      2 Q_CAP_DIFFBUS_C0201-DIFF BUS_0.22UF,6.3V,20%,X6S,SA   I345 @T6G_MB_LIB.T6G(SCH_1):PAGE353

P5E_CPU1_P0_TX_DN<8> @T6G_MB_LIB.T6G(SCH_1):P5E_CPU1_P0_TX_DN(8)
   U26 CU46 P0_TXN8||SATA10_TXN GENOA_SP5-SOCKET6096_13568-001,SMLF,IO,DGA^6000030   I147 @T6G_MB_LIB.T6G(SCH_1):PAGE51
  C820    2      2 Q_CAP_DIFFBUS_C0201-DIFF BUS_0.22UF,6.3V,20%,X6S,SA   I363 @T6G_MB_LIB.T6G(SCH_1):PAGE353

P5E_CPU1_P0_TX_DN<9> @T6G_MB_LIB.T6G(SCH_1):P5E_CPU1_P0_TX_DN(9)
   U26 CN46 P0_TXN9||SATA11_TXN GENOA_SP5-SOCKET6096_13568-001,SMLF,IO,DGA^6000030   I147 @T6G_MB_LIB.T6G(SCH_1):PAGE51
  C818    2      2 Q_CAP_DIFFBUS_C0201-DIFF BUS_0.22UF,6.3V,20%,X6S,SA   I365 @T6G_MB_LIB.T6G(SCH_1):PAGE353

P5E_CPU1_P0_TX_DP<0> @T6G_MB_LIB.T6G(SCH_1):P5E_CPU1_P0_TX_DP(0)
   U26 CN53 P0_TXP0||SATA00_TXP GENOA_SP5-SOCKET6096_13568-001,SMLF,IO,DGA^6000030   I147 @T6G_MB_LIB.T6G(SCH_1):PAGE51
  C837    2      2 Q_CAP_DIFFBUS_C0201-DIFF BUS_0.22UF,6.3V,20%,X6S,SA   I334 @T6G_MB_LIB.T6G(SCH_1):PAGE353

P5E_CPU1_P0_TX_DP<10> @T6G_MB_LIB.T6G(SCH_1):P5E_CPU1_P0_TX_DP(10)
   U26 CR44 P0_TXP10||SATA12_TXP GENOA_SP5-SOCKET6096_13568-001,SMLF,IO,DGA^6000030   I147 @T6G_MB_LIB.T6G(SCH_1):PAGE51
  C817    2      2 Q_CAP_DIFFBUS_C0201-DIFF BUS_0.22UF,6.3V,20%,X6S,SA   I367 @T6G_MB_LIB.T6G(SCH_1):PAGE353

P5E_CPU1_P0_TX_DP<11> @T6G_MB_LIB.T6G(SCH_1):P5E_CPU1_P0_TX_DP(11)
   U26 CU44 P0_TXP11||SATA13_TXP GENOA_SP5-SOCKET6096_13568-001,SMLF,IO,DGA^6000030   I147 @T6G_MB_LIB.T6G(SCH_1):PAGE51
  C815    2      2 Q_CAP_DIFFBUS_C0201-DIFF BUS_0.22UF,6.3V,20%,X6S,SA   I369 @T6G_MB_LIB.T6G(SCH_1):PAGE353

P5E_CPU1_P0_TX_DP<12> @T6G_MB_LIB.T6G(SCH_1):P5E_CPU1_P0_TX_DP(12)
   U26 CN44 P0_TXP12||SATA14_TXP GENOA_SP5-SOCKET6096_13568-001,SMLF,IO,DGA^6000030   I147 @T6G_MB_LIB.T6G(SCH_1):PAGE51
  C813    2      2 Q_CAP_DIFFBUS_C0201-DIFF BUS_0.22UF,6.3V,20%,X6S,SA   I372 @T6G_MB_LIB.T6G(SCH_1):PAGE353

P5E_CPU1_P0_TX_DP<13> @T6G_MB_LIB.T6G(SCH_1):P5E_CPU1_P0_TX_DP(13)
   U26 CT41 P0_TXP13||SATA15_TXP GENOA_SP5-SOCKET6096_13568-001,SMLF,IO,DGA^6000030   I147 @T6G_MB_LIB.T6G(SCH_1):PAGE51
  C811    2      2 Q_CAP_DIFFBUS_C0201-DIFF BUS_0.22UF,6.3V,20%,X6S,SA   I373 @T6G_MB_LIB.T6G(SCH_1):PAGE353

P5E_CPU1_P0_TX_DP<14> @T6G_MB_LIB.T6G(SCH_1):P5E_CPU1_P0_TX_DP(14)
   U26 CP41 P0_TXP14||SATA16_TXP GENOA_SP5-SOCKET6096_13568-001,SMLF,IO,DGA^6000030   I147 @T6G_MB_LIB.T6G(SCH_1):PAGE51
  C809    2      2 Q_CAP_DIFFBUS_C0201-DIFF BUS_0.22UF,6.3V,20%,X6S,SA   I375 @T6G_MB_LIB.T6G(SCH_1):PAGE353

P5E_CPU1_P0_TX_DP<15> @T6G_MB_LIB.T6G(SCH_1):P5E_CPU1_P0_TX_DP(15)
   U26 CM41 P0_TXP15||SATA17_TXP GENOA_SP5-SOCKET6096_13568-001,SMLF,IO,DGA^6000030   I147 @T6G_MB_LIB.T6G(SCH_1):PAGE51
  C807    2      2 Q_CAP_DIFFBUS_C0201-DIFF BUS_0.22UF,6.3V,20%,X6S,SA   I378 @T6G_MB_LIB.T6G(SCH_1):PAGE353

P5E_CPU1_P0_TX_DP<1> @T6G_MB_LIB.T6G(SCH_1):P5E_CPU1_P0_TX_DP(1)
   U26 CR53 P0_TXP1||SATA01_TXP GENOA_SP5-SOCKET6096_13568-001,SMLF,IO,DGA^6000030   I147 @T6G_MB_LIB.T6G(SCH_1):PAGE51
  C835    2      2 Q_CAP_DIFFBUS_C0201-DIFF BUS_0.22UF,6.3V,20%,X6S,SA   I336 @T6G_MB_LIB.T6G(SCH_1):PAGE353

P5E_CPU1_P0_TX_DP<2> @T6G_MB_LIB.T6G(SCH_1):P5E_CPU1_P0_TX_DP(2)
   U26 CL53 P0_TXP2||SATA02_TXP GENOA_SP5-SOCKET6096_13568-001,SMLF,IO,DGA^6000030   I147 @T6G_MB_LIB.T6G(SCH_1):PAGE51
  C833    2      2 Q_CAP_DIFFBUS_C0201-DIFF BUS_0.22UF,6.3V,20%,X6S,SA   I339 @T6G_MB_LIB.T6G(SCH_1):PAGE353

P5E_CPU1_P0_TX_DP<3> @T6G_MB_LIB.T6G(SCH_1):P5E_CPU1_P0_TX_DP(3)
   U26 CN50 P0_TXP3||SATA03_TXP GENOA_SP5-SOCKET6096_13568-001,SMLF,IO,DGA^6000030   I147 @T6G_MB_LIB.T6G(SCH_1):PAGE51
  C831    2      2 Q_CAP_DIFFBUS_C0201-DIFF BUS_0.22UF,6.3V,20%,X6S,SA   I337 @T6G_MB_LIB.T6G(SCH_1):PAGE353

P5E_CPU1_P0_TX_DP<4> @T6G_MB_LIB.T6G(SCH_1):P5E_CPU1_P0_TX_DP(4)
   U26 CR50 P0_TXP4||SATA04_TXP GENOA_SP5-SOCKET6096_13568-001,SMLF,IO,DGA^6000030   I147 @T6G_MB_LIB.T6G(SCH_1):PAGE51
  C829    2      2 Q_CAP_DIFFBUS_C0201-DIFF BUS_0.22UF,6.3V,20%,X6S,SA   I342 @T6G_MB_LIB.T6G(SCH_1):PAGE353

P5E_CPU1_P0_TX_DP<5> @T6G_MB_LIB.T6G(SCH_1):P5E_CPU1_P0_TX_DP(5)
   U26 CU50 P0_TXP5||SATA05_TXP GENOA_SP5-SOCKET6096_13568-001,SMLF,IO,DGA^6000030   I147 @T6G_MB_LIB.T6G(SCH_1):PAGE51
  C827    2      2 Q_CAP_DIFFBUS_C0201-DIFF BUS_0.22UF,6.3V,20%,X6S,SA   I343 @T6G_MB_LIB.T6G(SCH_1):PAGE353

P5E_CPU1_P0_TX_DP<6> @T6G_MB_LIB.T6G(SCH_1):P5E_CPU1_P0_TX_DP(6)
   U26 CL50 P0_TXP6||SATA06_TXP GENOA_SP5-SOCKET6096_13568-001,SMLF,IO,DGA^6000030   I147 @T6G_MB_LIB.T6G(SCH_1):PAGE51
  C825    2      2 Q_CAP_DIFFBUS_C0201-DIFF BUS_0.22UF,6.3V,20%,X6S,SA   I415 @T6G_MB_LIB.T6G(SCH_1):PAGE353

P5E_CPU1_P0_TX_DP<7> @T6G_MB_LIB.T6G(SCH_1):P5E_CPU1_P0_TX_DP(7)
   U26 CR47 P0_TXP7||SATA07_TXP GENOA_SP5-SOCKET6096_13568-001,SMLF,IO,DGA^6000030   I147 @T6G_MB_LIB.T6G(SCH_1):PAGE51
  C823    2      2 Q_CAP_DIFFBUS_C0201-DIFF BUS_0.22UF,6.3V,20%,X6S,SA   I346 @T6G_MB_LIB.T6G(SCH_1):PAGE353

P5E_CPU1_P0_TX_DP<8> @T6G_MB_LIB.T6G(SCH_1):P5E_CPU1_P0_TX_DP(8)
   U26 CU47 P0_TXP8||SATA10_TXP GENOA_SP5-SOCKET6096_13568-001,SMLF,IO,DGA^6000030   I147 @T6G_MB_LIB.T6G(SCH_1):PAGE51
  C821    2      2 Q_CAP_DIFFBUS_C0201-DIFF BUS_0.22UF,6.3V,20%,X6S,SA   I364 @T6G_MB_LIB.T6G(SCH_1):PAGE353

P5E_CPU1_P0_TX_DP<9> @T6G_MB_LIB.T6G(SCH_1):P5E_CPU1_P0_TX_DP(9)
   U26 CN47 P0_TXP9||SATA11_TXP GENOA_SP5-SOCKET6096_13568-001,SMLF,IO,DGA^6000030   I147 @T6G_MB_LIB.T6G(SCH_1):PAGE51
  C819    2      2 Q_CAP_DIFFBUS_C0201-DIFF BUS_0.22UF,6.3V,20%,X6S,SA   I366 @T6G_MB_LIB.T6G(SCH_1):PAGE353

P5E_CPU1_P1_RX_BUF_DN<0> @T6G_MB_LIB.T6G(SCH_1):P5E_CPU1_P1_RX_BUF_DN(0)
 U6015  EV2 A_PERN15 PT5161LRS-PT5161LRS,SMLF,IC,AJ051610U03    I38 @T6G_MB_LIB.T6G(SCH_1):PAGE394
  J112   F1     F1 CONN160_10131762101LF-CONN160_10131762-101LF,THLF,A   I102 @T6G_MB_LIB.T6G(SCH_1):PAGE329

P5E_CPU1_P1_RX_BUF_DN<10> @T6G_MB_LIB.T6G(SCH_1):P5E_CPU1_P1_RX_BUF_DN(10)
 U6015  BH2 A_PERN5 PT5161LRS-PT5161LRS,SMLF,IC,AJ051610U03     I1 @T6G_MB_LIB.T6G(SCH_1):PAGE394
  J111   F3     F3 CONN112_10137002101LF-CONN112_10137002-101LF,THLF,A    I76 @T6G_MB_LIB.T6G(SCH_1):PAGE328

P5E_CPU1_P1_RX_BUF_DN<11> @T6G_MB_LIB.T6G(SCH_1):P5E_CPU1_P1_RX_BUF_DN(11)
 U6015  BA2 A_PERN4 PT5161LRS-PT5161LRS,SMLF,IC,AJ051610U03     I1 @T6G_MB_LIB.T6G(SCH_1):PAGE394
  J111   E4     E4 CONN112_10137002101LF-CONN112_10137002-101LF,THLF,A    I76 @T6G_MB_LIB.T6G(SCH_1):PAGE328

P5E_CPU1_P1_RX_BUF_DN<12> @T6G_MB_LIB.T6G(SCH_1):P5E_CPU1_P1_RX_BUF_DN(12)
 U6015  AP2 A_PERN3 PT5161LRS-PT5161LRS,SMLF,IC,AJ051610U03     I1 @T6G_MB_LIB.T6G(SCH_1):PAGE394
  J111   F5     F5 CONN112_10137002101LF-CONN112_10137002-101LF,THLF,A    I38 @T6G_MB_LIB.T6G(SCH_1):PAGE328

P5E_CPU1_P1_RX_BUF_DN<13> @T6G_MB_LIB.T6G(SCH_1):P5E_CPU1_P1_RX_BUF_DN(13)
 U6015  AG2 A_PERN2 PT5161LRS-PT5161LRS,SMLF,IC,AJ051610U03     I1 @T6G_MB_LIB.T6G(SCH_1):PAGE394
  J111   E6     E6 CONN112_10137002101LF-CONN112_10137002-101LF,THLF,A    I38 @T6G_MB_LIB.T6G(SCH_1):PAGE328

P5E_CPU1_P1_RX_BUF_DN<14> @T6G_MB_LIB.T6G(SCH_1):P5E_CPU1_P1_RX_BUF_DN(14)
 U6015   Y2 A_PERN1 PT5161LRS-PT5161LRS,SMLF,IC,AJ051610U03     I1 @T6G_MB_LIB.T6G(SCH_1):PAGE394
  J111   F7     F7 CONN112_10137002101LF-CONN112_10137002-101LF,THLF,A    I38 @T6G_MB_LIB.T6G(SCH_1):PAGE328

P5E_CPU1_P1_RX_BUF_DN<15> @T6G_MB_LIB.T6G(SCH_1):P5E_CPU1_P1_RX_BUF_DN(15)
 U6015   N2 A_PERN0 PT5161LRS-PT5161LRS,SMLF,IC,AJ051610U03     I1 @T6G_MB_LIB.T6G(SCH_1):PAGE394
  J111   E8     E8 CONN112_10137002101LF-CONN112_10137002-101LF,THLF,A    I38 @T6G_MB_LIB.T6G(SCH_1):PAGE328

P5E_CPU1_P1_RX_BUF_DN<1> @T6G_MB_LIB.T6G(SCH_1):P5E_CPU1_P1_RX_BUF_DN(1)
 U6015  EL2 A_PERN14 PT5161LRS-PT5161LRS,SMLF,IC,AJ051610U03    I38 @T6G_MB_LIB.T6G(SCH_1):PAGE394
  J112   E2     E2 CONN160_10131762101LF-CONN160_10131762-101LF,THLF,A   I102 @T6G_MB_LIB.T6G(SCH_1):PAGE329

P5E_CPU1_P1_RX_BUF_DN<2> @T6G_MB_LIB.T6G(SCH_1):P5E_CPU1_P1_RX_BUF_DN(2)
 U6015  ED2 A_PERN13 PT5161LRS-PT5161LRS,SMLF,IC,AJ051610U03    I38 @T6G_MB_LIB.T6G(SCH_1):PAGE394
  J112   F3     F3 CONN160_10131762101LF-CONN160_10131762-101LF,THLF,A   I102 @T6G_MB_LIB.T6G(SCH_1):PAGE329

P5E_CPU1_P1_RX_BUF_DN<3> @T6G_MB_LIB.T6G(SCH_1):P5E_CPU1_P1_RX_BUF_DN(3)
 U6015  DU2 A_PERN12 PT5161LRS-PT5161LRS,SMLF,IC,AJ051610U03    I38 @T6G_MB_LIB.T6G(SCH_1):PAGE394
  J112   E4     E4 CONN160_10131762101LF-CONN160_10131762-101LF,THLF,A   I102 @T6G_MB_LIB.T6G(SCH_1):PAGE329

P5E_CPU1_P1_RX_BUF_DN<4> @T6G_MB_LIB.T6G(SCH_1):P5E_CPU1_P1_RX_BUF_DN(4)
 U6015  DK2 A_PERN11 PT5161LRS-PT5161LRS,SMLF,IC,AJ051610U03    I38 @T6G_MB_LIB.T6G(SCH_1):PAGE394
  J112   F5     F5 CONN160_10131762101LF-CONN160_10131762-101LF,THLF,A     I7 @T6G_MB_LIB.T6G(SCH_1):PAGE329

P5E_CPU1_P1_RX_BUF_DN<5> @T6G_MB_LIB.T6G(SCH_1):P5E_CPU1_P1_RX_BUF_DN(5)
 U6015  DC2 A_PERN10 PT5161LRS-PT5161LRS,SMLF,IC,AJ051610U03    I38 @T6G_MB_LIB.T6G(SCH_1):PAGE394
  J112   E6     E6 CONN160_10131762101LF-CONN160_10131762-101LF,THLF,A     I7 @T6G_MB_LIB.T6G(SCH_1):PAGE329

P5E_CPU1_P1_RX_BUF_DN<6> @T6G_MB_LIB.T6G(SCH_1):P5E_CPU1_P1_RX_BUF_DN(6)
 U6015  CT2 A_PERN9 PT5161LRS-PT5161LRS,SMLF,IC,AJ051610U03    I38 @T6G_MB_LIB.T6G(SCH_1):PAGE394
  J112   F7     F7 CONN160_10131762101LF-CONN160_10131762-101LF,THLF,A     I7 @T6G_MB_LIB.T6G(SCH_1):PAGE329

P5E_CPU1_P1_RX_BUF_DN<7> @T6G_MB_LIB.T6G(SCH_1):P5E_CPU1_P1_RX_BUF_DN(7)
 U6015  CJ2 A_PERN8 PT5161LRS-PT5161LRS,SMLF,IC,AJ051610U03    I38 @T6G_MB_LIB.T6G(SCH_1):PAGE394
  J112   E8     E8 CONN160_10131762101LF-CONN160_10131762-101LF,THLF,A     I7 @T6G_MB_LIB.T6G(SCH_1):PAGE329

P5E_CPU1_P1_RX_BUF_DN<8> @T6G_MB_LIB.T6G(SCH_1):P5E_CPU1_P1_RX_BUF_DN(8)
 U6015  CB2 A_PERN7 PT5161LRS-PT5161LRS,SMLF,IC,AJ051610U03     I1 @T6G_MB_LIB.T6G(SCH_1):PAGE394
  J111   F1     F1 CONN112_10137002101LF-CONN112_10137002-101LF,THLF,A    I76 @T6G_MB_LIB.T6G(SCH_1):PAGE328

P5E_CPU1_P1_RX_BUF_DN<9> @T6G_MB_LIB.T6G(SCH_1):P5E_CPU1_P1_RX_BUF_DN(9)
 U6015  BR2 A_PERN6 PT5161LRS-PT5161LRS,SMLF,IC,AJ051610U03     I1 @T6G_MB_LIB.T6G(SCH_1):PAGE394
  J111   E2     E2 CONN112_10137002101LF-CONN112_10137002-101LF,THLF,A    I76 @T6G_MB_LIB.T6G(SCH_1):PAGE328

P5E_CPU1_P1_RX_BUF_DP<0> @T6G_MB_LIB.T6G(SCH_1):P5E_CPU1_P1_RX_BUF_DP(0)
 U6015  EY1 A_PERP15 PT5161LRS-PT5161LRS,SMLF,IC,AJ051610U03    I38 @T6G_MB_LIB.T6G(SCH_1):PAGE394
  J112   G1     G1 CONN160_10131762101LF-CONN160_10131762-101LF,THLF,A   I102 @T6G_MB_LIB.T6G(SCH_1):PAGE329

P5E_CPU1_P1_RX_BUF_DP<10> @T6G_MB_LIB.T6G(SCH_1):P5E_CPU1_P1_RX_BUF_DP(10)
 U6015  BK1 A_PERP5 PT5161LRS-PT5161LRS,SMLF,IC,AJ051610U03     I1 @T6G_MB_LIB.T6G(SCH_1):PAGE394
  J111   G3     G3 CONN112_10137002101LF-CONN112_10137002-101LF,THLF,A    I76 @T6G_MB_LIB.T6G(SCH_1):PAGE328

P5E_CPU1_P1_RX_BUF_DP<11> @T6G_MB_LIB.T6G(SCH_1):P5E_CPU1_P1_RX_BUF_DP(11)
 U6015  BC1 A_PERP4 PT5161LRS-PT5161LRS,SMLF,IC,AJ051610U03     I1 @T6G_MB_LIB.T6G(SCH_1):PAGE394
  J111   F4     F4 CONN112_10137002101LF-CONN112_10137002-101LF,THLF,A    I76 @T6G_MB_LIB.T6G(SCH_1):PAGE328

P5E_CPU1_P1_RX_BUF_DP<12> @T6G_MB_LIB.T6G(SCH_1):P5E_CPU1_P1_RX_BUF_DP(12)
 U6015  AT1 A_PERP3 PT5161LRS-PT5161LRS,SMLF,IC,AJ051610U03     I1 @T6G_MB_LIB.T6G(SCH_1):PAGE394
  J111   G5     G5 CONN112_10137002101LF-CONN112_10137002-101LF,THLF,A    I38 @T6G_MB_LIB.T6G(SCH_1):PAGE328

P5E_CPU1_P1_RX_BUF_DP<13> @T6G_MB_LIB.T6G(SCH_1):P5E_CPU1_P1_RX_BUF_DP(13)
 U6015  AJ1 A_PERP2 PT5161LRS-PT5161LRS,SMLF,IC,AJ051610U03     I1 @T6G_MB_LIB.T6G(SCH_1):PAGE394
  J111   F6     F6 CONN112_10137002101LF-CONN112_10137002-101LF,THLF,A    I38 @T6G_MB_LIB.T6G(SCH_1):PAGE328

P5E_CPU1_P1_RX_BUF_DP<14> @T6G_MB_LIB.T6G(SCH_1):P5E_CPU1_P1_RX_BUF_DP(14)
 U6015  AB1 A_PERP1 PT5161LRS-PT5161LRS,SMLF,IC,AJ051610U03     I1 @T6G_MB_LIB.T6G(SCH_1):PAGE394
  J111   G7     G7 CONN112_10137002101LF-CONN112_10137002-101LF,THLF,A    I38 @T6G_MB_LIB.T6G(SCH_1):PAGE328

P5E_CPU1_P1_RX_BUF_DP<15> @T6G_MB_LIB.T6G(SCH_1):P5E_CPU1_P1_RX_BUF_DP(15)
 U6015   R1 A_PERP0 PT5161LRS-PT5161LRS,SMLF,IC,AJ051610U03     I1 @T6G_MB_LIB.T6G(SCH_1):PAGE394
  J111   F8     F8 CONN112_10137002101LF-CONN112_10137002-101LF,THLF,A    I38 @T6G_MB_LIB.T6G(SCH_1):PAGE328

P5E_CPU1_P1_RX_BUF_DP<1> @T6G_MB_LIB.T6G(SCH_1):P5E_CPU1_P1_RX_BUF_DP(1)
 U6015  EN1 A_PERP14 PT5161LRS-PT5161LRS,SMLF,IC,AJ051610U03    I38 @T6G_MB_LIB.T6G(SCH_1):PAGE394
  J112   F2     F2 CONN160_10131762101LF-CONN160_10131762-101LF,THLF,A   I102 @T6G_MB_LIB.T6G(SCH_1):PAGE329

P5E_CPU1_P1_RX_BUF_DP<2> @T6G_MB_LIB.T6G(SCH_1):P5E_CPU1_P1_RX_BUF_DP(2)
 U6015  EF1 A_PERP13 PT5161LRS-PT5161LRS,SMLF,IC,AJ051610U03    I38 @T6G_MB_LIB.T6G(SCH_1):PAGE394
  J112   G3     G3 CONN160_10131762101LF-CONN160_10131762-101LF,THLF,A   I102 @T6G_MB_LIB.T6G(SCH_1):PAGE329

P5E_CPU1_P1_RX_BUF_DP<3> @T6G_MB_LIB.T6G(SCH_1):P5E_CPU1_P1_RX_BUF_DP(3)
 U6015  DW1 A_PERP12 PT5161LRS-PT5161LRS,SMLF,IC,AJ051610U03    I38 @T6G_MB_LIB.T6G(SCH_1):PAGE394
  J112   F4     F4 CONN160_10131762101LF-CONN160_10131762-101LF,THLF,A   I102 @T6G_MB_LIB.T6G(SCH_1):PAGE329

P5E_CPU1_P1_RX_BUF_DP<4> @T6G_MB_LIB.T6G(SCH_1):P5E_CPU1_P1_RX_BUF_DP(4)
 U6015  DM1 A_PERP11 PT5161LRS-PT5161LRS,SMLF,IC,AJ051610U03    I38 @T6G_MB_LIB.T6G(SCH_1):PAGE394
  J112   G5     G5 CONN160_10131762101LF-CONN160_10131762-101LF,THLF,A     I7 @T6G_MB_LIB.T6G(SCH_1):PAGE329

P5E_CPU1_P1_RX_BUF_DP<5> @T6G_MB_LIB.T6G(SCH_1):P5E_CPU1_P1_RX_BUF_DP(5)
 U6015  DE1 A_PERP10 PT5161LRS-PT5161LRS,SMLF,IC,AJ051610U03    I38 @T6G_MB_LIB.T6G(SCH_1):PAGE394
  J112   F6     F6 CONN160_10131762101LF-CONN160_10131762-101LF,THLF,A     I7 @T6G_MB_LIB.T6G(SCH_1):PAGE329

P5E_CPU1_P1_RX_BUF_DP<6> @T6G_MB_LIB.T6G(SCH_1):P5E_CPU1_P1_RX_BUF_DP(6)
 U6015  CV1 A_PERP9 PT5161LRS-PT5161LRS,SMLF,IC,AJ051610U03    I38 @T6G_MB_LIB.T6G(SCH_1):PAGE394
  J112   G7     G7 CONN160_10131762101LF-CONN160_10131762-101LF,THLF,A     I7 @T6G_MB_LIB.T6G(SCH_1):PAGE329

P5E_CPU1_P1_RX_BUF_DP<7> @T6G_MB_LIB.T6G(SCH_1):P5E_CPU1_P1_RX_BUF_DP(7)
 U6015  CL1 A_PERP8 PT5161LRS-PT5161LRS,SMLF,IC,AJ051610U03    I38 @T6G_MB_LIB.T6G(SCH_1):PAGE394
  J112   F8     F8 CONN160_10131762101LF-CONN160_10131762-101LF,THLF,A     I7 @T6G_MB_LIB.T6G(SCH_1):PAGE329

P5E_CPU1_P1_RX_BUF_DP<8> @T6G_MB_LIB.T6G(SCH_1):P5E_CPU1_P1_RX_BUF_DP(8)
 U6015  CD1 A_PERP7 PT5161LRS-PT5161LRS,SMLF,IC,AJ051610U03     I1 @T6G_MB_LIB.T6G(SCH_1):PAGE394
  J111   G1     G1 CONN112_10137002101LF-CONN112_10137002-101LF,THLF,A    I76 @T6G_MB_LIB.T6G(SCH_1):PAGE328

P5E_CPU1_P1_RX_BUF_DP<9> @T6G_MB_LIB.T6G(SCH_1):P5E_CPU1_P1_RX_BUF_DP(9)
 U6015  BU1 A_PERP6 PT5161LRS-PT5161LRS,SMLF,IC,AJ051610U03     I1 @T6G_MB_LIB.T6G(SCH_1):PAGE394
  J111   F2     F2 CONN112_10137002101LF-CONN112_10137002-101LF,THLF,A    I76 @T6G_MB_LIB.T6G(SCH_1):PAGE328

P5E_CPU1_P1_RX_DN<0> @T6G_MB_LIB.T6G(SCH_1):P5E_CPU1_P1_RX_DN(0)
   U26 CE53 P1_RXN0 GENOA_SP5-SOCKET6096_13568-001,SMLF,IO,DGA^6000030   I148 @T6G_MB_LIB.T6G(SCH_1):PAGE51
 U6015 EW29 A_PETN15 PT5161LRS-PT5161LRS,SMLF,IC,AJ051610U03    I38 @T6G_MB_LIB.T6G(SCH_1):PAGE395

P5E_CPU1_P1_RX_DN<10> @T6G_MB_LIB.T6G(SCH_1):P5E_CPU1_P1_RX_DN(10)
   U26 CG44 P1_RXN10 GENOA_SP5-SOCKET6096_13568-001,SMLF,IO,DGA^6000030   I148 @T6G_MB_LIB.T6G(SCH_1):PAGE51
 U6015 BJ29 A_PETN5 PT5161LRS-PT5161LRS,SMLF,IC,AJ051610U03     I1 @T6G_MB_LIB.T6G(SCH_1):PAGE395

P5E_CPU1_P1_RX_DN<11> @T6G_MB_LIB.T6G(SCH_1):P5E_CPU1_P1_RX_DN(11)
   U26 CJ44 P1_RXN11 GENOA_SP5-SOCKET6096_13568-001,SMLF,IO,DGA^6000030   I148 @T6G_MB_LIB.T6G(SCH_1):PAGE51
 U6015 BB29 A_PETN4 PT5161LRS-PT5161LRS,SMLF,IC,AJ051610U03     I1 @T6G_MB_LIB.T6G(SCH_1):PAGE395

P5E_CPU1_P1_RX_DN<12> @T6G_MB_LIB.T6G(SCH_1):P5E_CPU1_P1_RX_DN(12)
   U26 CC44 P1_RXN12 GENOA_SP5-SOCKET6096_13568-001,SMLF,IO,DGA^6000030   I148 @T6G_MB_LIB.T6G(SCH_1):PAGE51
 U6015 AR29 A_PETN3 PT5161LRS-PT5161LRS,SMLF,IC,AJ051610U03     I1 @T6G_MB_LIB.T6G(SCH_1):PAGE395

P5E_CPU1_P1_RX_DN<13> @T6G_MB_LIB.T6G(SCH_1):P5E_CPU1_P1_RX_DN(13)
   U26 CH41 P1_RXN13 GENOA_SP5-SOCKET6096_13568-001,SMLF,IO,DGA^6000030   I148 @T6G_MB_LIB.T6G(SCH_1):PAGE51
 U6015 AH29 A_PETN2 PT5161LRS-PT5161LRS,SMLF,IC,AJ051610U03     I1 @T6G_MB_LIB.T6G(SCH_1):PAGE395

P5E_CPU1_P1_RX_DN<14> @T6G_MB_LIB.T6G(SCH_1):P5E_CPU1_P1_RX_DN(14)
   U26 CF41 P1_RXN14 GENOA_SP5-SOCKET6096_13568-001,SMLF,IO,DGA^6000030   I148 @T6G_MB_LIB.T6G(SCH_1):PAGE51
 U6015 AA29 A_PETN1 PT5161LRS-PT5161LRS,SMLF,IC,AJ051610U03     I1 @T6G_MB_LIB.T6G(SCH_1):PAGE395

P5E_CPU1_P1_RX_DN<15> @T6G_MB_LIB.T6G(SCH_1):P5E_CPU1_P1_RX_DN(15)
   U26 CD41 P1_RXN15 GENOA_SP5-SOCKET6096_13568-001,SMLF,IO,DGA^6000030   I148 @T6G_MB_LIB.T6G(SCH_1):PAGE51
 U6015  P29 A_PETN0 PT5161LRS-PT5161LRS,SMLF,IC,AJ051610U03     I1 @T6G_MB_LIB.T6G(SCH_1):PAGE395

P5E_CPU1_P1_RX_DN<1> @T6G_MB_LIB.T6G(SCH_1):P5E_CPU1_P1_RX_DN(1)
   U26 CG53 P1_RXN1 GENOA_SP5-SOCKET6096_13568-001,SMLF,IO,DGA^6000030   I148 @T6G_MB_LIB.T6G(SCH_1):PAGE51
 U6015 EM29 A_PETN14 PT5161LRS-PT5161LRS,SMLF,IC,AJ051610U03    I38 @T6G_MB_LIB.T6G(SCH_1):PAGE395

P5E_CPU1_P1_RX_DN<2> @T6G_MB_LIB.T6G(SCH_1):P5E_CPU1_P1_RX_DN(2)
   U26 CC53 P1_RXN2 GENOA_SP5-SOCKET6096_13568-001,SMLF,IO,DGA^6000030   I148 @T6G_MB_LIB.T6G(SCH_1):PAGE51
 U6015 EE29 A_PETN13 PT5161LRS-PT5161LRS,SMLF,IC,AJ051610U03    I38 @T6G_MB_LIB.T6G(SCH_1):PAGE395

P5E_CPU1_P1_RX_DN<3> @T6G_MB_LIB.T6G(SCH_1):P5E_CPU1_P1_RX_DN(3)
   U26 CE50 P1_RXN3 GENOA_SP5-SOCKET6096_13568-001,SMLF,IO,DGA^6000030   I148 @T6G_MB_LIB.T6G(SCH_1):PAGE51
 U6015 DV29 A_PETN12 PT5161LRS-PT5161LRS,SMLF,IC,AJ051610U03    I38 @T6G_MB_LIB.T6G(SCH_1):PAGE395

P5E_CPU1_P1_RX_DN<4> @T6G_MB_LIB.T6G(SCH_1):P5E_CPU1_P1_RX_DN(4)
   U26 CG50 P1_RXN4 GENOA_SP5-SOCKET6096_13568-001,SMLF,IO,DGA^6000030   I148 @T6G_MB_LIB.T6G(SCH_1):PAGE51
 U6015 DL29 A_PETN11 PT5161LRS-PT5161LRS,SMLF,IC,AJ051610U03    I38 @T6G_MB_LIB.T6G(SCH_1):PAGE395

P5E_CPU1_P1_RX_DN<5> @T6G_MB_LIB.T6G(SCH_1):P5E_CPU1_P1_RX_DN(5)
   U26 CC50 P1_RXN5 GENOA_SP5-SOCKET6096_13568-001,SMLF,IO,DGA^6000030   I148 @T6G_MB_LIB.T6G(SCH_1):PAGE51
 U6015 DD29 A_PETN10 PT5161LRS-PT5161LRS,SMLF,IC,AJ051610U03    I38 @T6G_MB_LIB.T6G(SCH_1):PAGE395

P5E_CPU1_P1_RX_DN<6> @T6G_MB_LIB.T6G(SCH_1):P5E_CPU1_P1_RX_DN(6)
   U26 CE47 P1_RXN6 GENOA_SP5-SOCKET6096_13568-001,SMLF,IO,DGA^6000030   I148 @T6G_MB_LIB.T6G(SCH_1):PAGE51
 U6015 CU29 A_PETN9 PT5161LRS-PT5161LRS,SMLF,IC,AJ051610U03    I38 @T6G_MB_LIB.T6G(SCH_1):PAGE395

P5E_CPU1_P1_RX_DN<7> @T6G_MB_LIB.T6G(SCH_1):P5E_CPU1_P1_RX_DN(7)
   U26 CG47 P1_RXN7 GENOA_SP5-SOCKET6096_13568-001,SMLF,IO,DGA^6000030   I148 @T6G_MB_LIB.T6G(SCH_1):PAGE51
 U6015 CK29 A_PETN8 PT5161LRS-PT5161LRS,SMLF,IC,AJ051610U03    I38 @T6G_MB_LIB.T6G(SCH_1):PAGE395

P5E_CPU1_P1_RX_DN<8> @T6G_MB_LIB.T6G(SCH_1):P5E_CPU1_P1_RX_DN(8)
   U26 CC47 P1_RXN8 GENOA_SP5-SOCKET6096_13568-001,SMLF,IO,DGA^6000030   I148 @T6G_MB_LIB.T6G(SCH_1):PAGE51
 U6015 CC29 A_PETN7 PT5161LRS-PT5161LRS,SMLF,IC,AJ051610U03     I1 @T6G_MB_LIB.T6G(SCH_1):PAGE395

P5E_CPU1_P1_RX_DN<9> @T6G_MB_LIB.T6G(SCH_1):P5E_CPU1_P1_RX_DN(9)
   U26 CE44 P1_RXN9 GENOA_SP5-SOCKET6096_13568-001,SMLF,IO,DGA^6000030   I148 @T6G_MB_LIB.T6G(SCH_1):PAGE51
 U6015 BT29 A_PETN6 PT5161LRS-PT5161LRS,SMLF,IC,AJ051610U03     I1 @T6G_MB_LIB.T6G(SCH_1):PAGE395

P5E_CPU1_P1_RX_DP<0> @T6G_MB_LIB.T6G(SCH_1):P5E_CPU1_P1_RX_DP(0)
   U26 CE52 P1_RXP0 GENOA_SP5-SOCKET6096_13568-001,SMLF,IO,DGA^6000030   I148 @T6G_MB_LIB.T6G(SCH_1):PAGE51
 U6015 EU26 A_PETP15 PT5161LRS-PT5161LRS,SMLF,IC,AJ051610U03    I38 @T6G_MB_LIB.T6G(SCH_1):PAGE395

P5E_CPU1_P1_RX_DP<10> @T6G_MB_LIB.T6G(SCH_1):P5E_CPU1_P1_RX_DP(10)
   U26 CG43 P1_RXP10 GENOA_SP5-SOCKET6096_13568-001,SMLF,IO,DGA^6000030   I148 @T6G_MB_LIB.T6G(SCH_1):PAGE51
 U6015 BG26 A_PETP5 PT5161LRS-PT5161LRS,SMLF,IC,AJ051610U03     I1 @T6G_MB_LIB.T6G(SCH_1):PAGE395

P5E_CPU1_P1_RX_DP<11> @T6G_MB_LIB.T6G(SCH_1):P5E_CPU1_P1_RX_DP(11)
   U26 CJ43 P1_RXP11 GENOA_SP5-SOCKET6096_13568-001,SMLF,IO,DGA^6000030   I148 @T6G_MB_LIB.T6G(SCH_1):PAGE51
 U6015 AY26 A_PETP4 PT5161LRS-PT5161LRS,SMLF,IC,AJ051610U03     I1 @T6G_MB_LIB.T6G(SCH_1):PAGE395

P5E_CPU1_P1_RX_DP<12> @T6G_MB_LIB.T6G(SCH_1):P5E_CPU1_P1_RX_DP(12)
   U26 CC43 P1_RXP12 GENOA_SP5-SOCKET6096_13568-001,SMLF,IO,DGA^6000030   I148 @T6G_MB_LIB.T6G(SCH_1):PAGE51
 U6015 AN26 A_PETP3 PT5161LRS-PT5161LRS,SMLF,IC,AJ051610U03     I1 @T6G_MB_LIB.T6G(SCH_1):PAGE395

P5E_CPU1_P1_RX_DP<13> @T6G_MB_LIB.T6G(SCH_1):P5E_CPU1_P1_RX_DP(13)
   U26 CH40 P1_RXP13 GENOA_SP5-SOCKET6096_13568-001,SMLF,IO,DGA^6000030   I148 @T6G_MB_LIB.T6G(SCH_1):PAGE51
 U6015 AF26 A_PETP2 PT5161LRS-PT5161LRS,SMLF,IC,AJ051610U03     I1 @T6G_MB_LIB.T6G(SCH_1):PAGE395

P5E_CPU1_P1_RX_DP<14> @T6G_MB_LIB.T6G(SCH_1):P5E_CPU1_P1_RX_DP(14)
   U26 CF40 P1_RXP14 GENOA_SP5-SOCKET6096_13568-001,SMLF,IO,DGA^6000030   I148 @T6G_MB_LIB.T6G(SCH_1):PAGE51
 U6015  W26 A_PETP1 PT5161LRS-PT5161LRS,SMLF,IC,AJ051610U03     I1 @T6G_MB_LIB.T6G(SCH_1):PAGE395

P5E_CPU1_P1_RX_DP<15> @T6G_MB_LIB.T6G(SCH_1):P5E_CPU1_P1_RX_DP(15)
   U26 CD40 P1_RXP15 GENOA_SP5-SOCKET6096_13568-001,SMLF,IO,DGA^6000030   I148 @T6G_MB_LIB.T6G(SCH_1):PAGE51
 U6015  M26 A_PETP0 PT5161LRS-PT5161LRS,SMLF,IC,AJ051610U03     I1 @T6G_MB_LIB.T6G(SCH_1):PAGE395

P5E_CPU1_P1_RX_DP<1> @T6G_MB_LIB.T6G(SCH_1):P5E_CPU1_P1_RX_DP(1)
   U26 CG52 P1_RXP1 GENOA_SP5-SOCKET6096_13568-001,SMLF,IO,DGA^6000030   I148 @T6G_MB_LIB.T6G(SCH_1):PAGE51
 U6015 EK26 A_PETP14 PT5161LRS-PT5161LRS,SMLF,IC,AJ051610U03    I38 @T6G_MB_LIB.T6G(SCH_1):PAGE395

P5E_CPU1_P1_RX_DP<2> @T6G_MB_LIB.T6G(SCH_1):P5E_CPU1_P1_RX_DP(2)
   U26 CC52 P1_RXP2 GENOA_SP5-SOCKET6096_13568-001,SMLF,IO,DGA^6000030   I148 @T6G_MB_LIB.T6G(SCH_1):PAGE51
 U6015 EC26 A_PETP13 PT5161LRS-PT5161LRS,SMLF,IC,AJ051610U03    I38 @T6G_MB_LIB.T6G(SCH_1):PAGE395

P5E_CPU1_P1_RX_DP<3> @T6G_MB_LIB.T6G(SCH_1):P5E_CPU1_P1_RX_DP(3)
   U26 CE49 P1_RXP3 GENOA_SP5-SOCKET6096_13568-001,SMLF,IO,DGA^6000030   I148 @T6G_MB_LIB.T6G(SCH_1):PAGE51
 U6015 DT26 A_PETP12 PT5161LRS-PT5161LRS,SMLF,IC,AJ051610U03    I38 @T6G_MB_LIB.T6G(SCH_1):PAGE395

P5E_CPU1_P1_RX_DP<4> @T6G_MB_LIB.T6G(SCH_1):P5E_CPU1_P1_RX_DP(4)
   U26 CG49 P1_RXP4 GENOA_SP5-SOCKET6096_13568-001,SMLF,IO,DGA^6000030   I148 @T6G_MB_LIB.T6G(SCH_1):PAGE51
 U6015 DJ26 A_PETP11 PT5161LRS-PT5161LRS,SMLF,IC,AJ051610U03    I38 @T6G_MB_LIB.T6G(SCH_1):PAGE395

P5E_CPU1_P1_RX_DP<5> @T6G_MB_LIB.T6G(SCH_1):P5E_CPU1_P1_RX_DP(5)
   U26 CC49 P1_RXP5 GENOA_SP5-SOCKET6096_13568-001,SMLF,IO,DGA^6000030   I148 @T6G_MB_LIB.T6G(SCH_1):PAGE51
 U6015 DB26 A_PETP10 PT5161LRS-PT5161LRS,SMLF,IC,AJ051610U03    I38 @T6G_MB_LIB.T6G(SCH_1):PAGE395

P5E_CPU1_P1_RX_DP<6> @T6G_MB_LIB.T6G(SCH_1):P5E_CPU1_P1_RX_DP(6)
   U26 CE46 P1_RXP6 GENOA_SP5-SOCKET6096_13568-001,SMLF,IO,DGA^6000030   I148 @T6G_MB_LIB.T6G(SCH_1):PAGE51
 U6015 CR26 A_PETP9 PT5161LRS-PT5161LRS,SMLF,IC,AJ051610U03    I38 @T6G_MB_LIB.T6G(SCH_1):PAGE395

P5E_CPU1_P1_RX_DP<7> @T6G_MB_LIB.T6G(SCH_1):P5E_CPU1_P1_RX_DP(7)
   U26 CG46 P1_RXP7 GENOA_SP5-SOCKET6096_13568-001,SMLF,IO,DGA^6000030   I148 @T6G_MB_LIB.T6G(SCH_1):PAGE51
 U6015 CH26 A_PETP8 PT5161LRS-PT5161LRS,SMLF,IC,AJ051610U03    I38 @T6G_MB_LIB.T6G(SCH_1):PAGE395

P5E_CPU1_P1_RX_DP<8> @T6G_MB_LIB.T6G(SCH_1):P5E_CPU1_P1_RX_DP(8)
   U26 CC46 P1_RXP8 GENOA_SP5-SOCKET6096_13568-001,SMLF,IO,DGA^6000030   I148 @T6G_MB_LIB.T6G(SCH_1):PAGE51
 U6015 CA26 A_PETP7 PT5161LRS-PT5161LRS,SMLF,IC,AJ051610U03     I1 @T6G_MB_LIB.T6G(SCH_1):PAGE395

P5E_CPU1_P1_RX_DP<9> @T6G_MB_LIB.T6G(SCH_1):P5E_CPU1_P1_RX_DP(9)
   U26 CE43 P1_RXP9 GENOA_SP5-SOCKET6096_13568-001,SMLF,IO,DGA^6000030   I148 @T6G_MB_LIB.T6G(SCH_1):PAGE51
 U6015 BP26 A_PETP6 PT5161LRS-PT5161LRS,SMLF,IC,AJ051610U03     I1 @T6G_MB_LIB.T6G(SCH_1):PAGE395

P5E_CPU1_P1_TX_BUF_C_DN<0> @T6G_MB_LIB.T6G(SCH_1):P5E_CPU1_P1_TX_BUF_C_DN(0)
 C6662    1      1 Q_CAP_DIFFBUS_C0201-DIFF BUS_0.22UF,6.3V,20%,X6S,SA    I33 @T6G_MB_LIB.T6G(SCH_1):PAGE393
  J112   L1     L1 CONN160_10131762101LF-CONN160_10131762-101LF,THLF,A   I102 @T6G_MB_LIB.T6G(SCH_1):PAGE329

P5E_CPU1_P1_TX_BUF_C_DN<10> @T6G_MB_LIB.T6G(SCH_1):P5E_CPU1_P1_TX_BUF_C_DN(10)
 C6682    1      1 Q_CAP_DIFFBUS_C0201-DIFF BUS_0.22UF,6.3V,20%,X6S,SA   I100 @T6G_MB_LIB.T6G(SCH_1):PAGE393
  J111   L3     L3 CONN112_10137002101LF-CONN112_10137002-101LF,THLF,A    I76 @T6G_MB_LIB.T6G(SCH_1):PAGE328

P5E_CPU1_P1_TX_BUF_C_DN<11> @T6G_MB_LIB.T6G(SCH_1):P5E_CPU1_P1_TX_BUF_C_DN(11)
 C6684    1      1 Q_CAP_DIFFBUS_C0201-DIFF BUS_0.22UF,6.3V,20%,X6S,SA    I97 @T6G_MB_LIB.T6G(SCH_1):PAGE393
  J111   K4     K4 CONN112_10137002101LF-CONN112_10137002-101LF,THLF,A    I76 @T6G_MB_LIB.T6G(SCH_1):PAGE328

P5E_CPU1_P1_TX_BUF_C_DN<12> @T6G_MB_LIB.T6G(SCH_1):P5E_CPU1_P1_TX_BUF_C_DN(12)
 C6686    1      1 Q_CAP_DIFFBUS_C0201-DIFF BUS_0.22UF,6.3V,20%,X6S,SA    I95 @T6G_MB_LIB.T6G(SCH_1):PAGE393
  J111   L5     L5 CONN112_10137002101LF-CONN112_10137002-101LF,THLF,A    I38 @T6G_MB_LIB.T6G(SCH_1):PAGE328

P5E_CPU1_P1_TX_BUF_C_DN<13> @T6G_MB_LIB.T6G(SCH_1):P5E_CPU1_P1_TX_BUF_C_DN(13)
 C6688    1      1 Q_CAP_DIFFBUS_C0201-DIFF BUS_0.22UF,6.3V,20%,X6S,SA    I88 @T6G_MB_LIB.T6G(SCH_1):PAGE393
  J111   K6     K6 CONN112_10137002101LF-CONN112_10137002-101LF,THLF,A    I38 @T6G_MB_LIB.T6G(SCH_1):PAGE328

P5E_CPU1_P1_TX_BUF_C_DN<14> @T6G_MB_LIB.T6G(SCH_1):P5E_CPU1_P1_TX_BUF_C_DN(14)
 C6690    1      1 Q_CAP_DIFFBUS_C0201-DIFF BUS_0.22UF,6.3V,20%,X6S,SA    I86 @T6G_MB_LIB.T6G(SCH_1):PAGE393
  J111   L7     L7 CONN112_10137002101LF-CONN112_10137002-101LF,THLF,A    I38 @T6G_MB_LIB.T6G(SCH_1):PAGE328

P5E_CPU1_P1_TX_BUF_C_DN<15> @T6G_MB_LIB.T6G(SCH_1):P5E_CPU1_P1_TX_BUF_C_DN(15)
 C6692    1      1 Q_CAP_DIFFBUS_C0201-DIFF BUS_0.22UF,6.3V,20%,X6S,SA    I84 @T6G_MB_LIB.T6G(SCH_1):PAGE393
  J111   K8     K8 CONN112_10137002101LF-CONN112_10137002-101LF,THLF,A    I38 @T6G_MB_LIB.T6G(SCH_1):PAGE328

P5E_CPU1_P1_TX_BUF_C_DN<1> @T6G_MB_LIB.T6G(SCH_1):P5E_CPU1_P1_TX_BUF_C_DN(1)
 C6664    1      1 Q_CAP_DIFFBUS_C0201-DIFF BUS_0.22UF,6.3V,20%,X6S,SA    I32 @T6G_MB_LIB.T6G(SCH_1):PAGE393
  J112   K2     K2 CONN160_10131762101LF-CONN160_10131762-101LF,THLF,A   I102 @T6G_MB_LIB.T6G(SCH_1):PAGE329

P5E_CPU1_P1_TX_BUF_C_DN<2> @T6G_MB_LIB.T6G(SCH_1):P5E_CPU1_P1_TX_BUF_C_DN(2)
 C6666    1      1 Q_CAP_DIFFBUS_C0201-DIFF BUS_0.22UF,6.3V,20%,X6S,SA    I29 @T6G_MB_LIB.T6G(SCH_1):PAGE393
  J112   L3     L3 CONN160_10131762101LF-CONN160_10131762-101LF,THLF,A   I102 @T6G_MB_LIB.T6G(SCH_1):PAGE329

P5E_CPU1_P1_TX_BUF_C_DN<3> @T6G_MB_LIB.T6G(SCH_1):P5E_CPU1_P1_TX_BUF_C_DN(3)
 C6668    1      1 Q_CAP_DIFFBUS_C0201-DIFF BUS_0.22UF,6.3V,20%,X6S,SA    I28 @T6G_MB_LIB.T6G(SCH_1):PAGE393
  J112   K4     K4 CONN160_10131762101LF-CONN160_10131762-101LF,THLF,A   I102 @T6G_MB_LIB.T6G(SCH_1):PAGE329

P5E_CPU1_P1_TX_BUF_C_DN<4> @T6G_MB_LIB.T6G(SCH_1):P5E_CPU1_P1_TX_BUF_C_DN(4)
 C6670    1      1 Q_CAP_DIFFBUS_C0201-DIFF BUS_0.22UF,6.3V,20%,X6S,SA    I25 @T6G_MB_LIB.T6G(SCH_1):PAGE393
  J112   L5     L5 CONN160_10131762101LF-CONN160_10131762-101LF,THLF,A     I7 @T6G_MB_LIB.T6G(SCH_1):PAGE329

P5E_CPU1_P1_TX_BUF_C_DN<5> @T6G_MB_LIB.T6G(SCH_1):P5E_CPU1_P1_TX_BUF_C_DN(5)
 C6672    1      1 Q_CAP_DIFFBUS_C0201-DIFF BUS_0.22UF,6.3V,20%,X6S,SA    I23 @T6G_MB_LIB.T6G(SCH_1):PAGE393
  J112   K6     K6 CONN160_10131762101LF-CONN160_10131762-101LF,THLF,A     I7 @T6G_MB_LIB.T6G(SCH_1):PAGE329

P5E_CPU1_P1_TX_BUF_C_DN<6> @T6G_MB_LIB.T6G(SCH_1):P5E_CPU1_P1_TX_BUF_C_DN(6)
 C6674    1      1 Q_CAP_DIFFBUS_C0201-DIFF BUS_0.22UF,6.3V,20%,X6S,SA    I19 @T6G_MB_LIB.T6G(SCH_1):PAGE393
  J112   L7     L7 CONN160_10131762101LF-CONN160_10131762-101LF,THLF,A     I7 @T6G_MB_LIB.T6G(SCH_1):PAGE329

P5E_CPU1_P1_TX_BUF_C_DN<7> @T6G_MB_LIB.T6G(SCH_1):P5E_CPU1_P1_TX_BUF_C_DN(7)
 C6676    1      1 Q_CAP_DIFFBUS_C0201-DIFF BUS_0.22UF,6.3V,20%,X6S,SA    I17 @T6G_MB_LIB.T6G(SCH_1):PAGE393
  J112   K8     K8 CONN160_10131762101LF-CONN160_10131762-101LF,THLF,A     I7 @T6G_MB_LIB.T6G(SCH_1):PAGE329

P5E_CPU1_P1_TX_BUF_C_DN<8> @T6G_MB_LIB.T6G(SCH_1):P5E_CPU1_P1_TX_BUF_C_DN(8)
 C6678    1      1 Q_CAP_DIFFBUS_C0201-DIFF BUS_0.22UF,6.3V,20%,X6S,SA   I103 @T6G_MB_LIB.T6G(SCH_1):PAGE393
  J111   L1     L1 CONN112_10137002101LF-CONN112_10137002-101LF,THLF,A    I76 @T6G_MB_LIB.T6G(SCH_1):PAGE328

P5E_CPU1_P1_TX_BUF_C_DN<9> @T6G_MB_LIB.T6G(SCH_1):P5E_CPU1_P1_TX_BUF_C_DN(9)
 C6680    1      1 Q_CAP_DIFFBUS_C0201-DIFF BUS_0.22UF,6.3V,20%,X6S,SA   I102 @T6G_MB_LIB.T6G(SCH_1):PAGE393
  J111   K2     K2 CONN112_10137002101LF-CONN112_10137002-101LF,THLF,A    I76 @T6G_MB_LIB.T6G(SCH_1):PAGE328

P5E_CPU1_P1_TX_BUF_C_DP<0> @T6G_MB_LIB.T6G(SCH_1):P5E_CPU1_P1_TX_BUF_C_DP(0)
 C6661    1      1 Q_CAP_DIFFBUS_C0201-DIFF BUS_0.22UF,6.3V,20%,X6S,SA    I42 @T6G_MB_LIB.T6G(SCH_1):PAGE393
  J112   M1     M1 CONN160_10131762101LF-CONN160_10131762-101LF,THLF,A   I102 @T6G_MB_LIB.T6G(SCH_1):PAGE329

P5E_CPU1_P1_TX_BUF_C_DP<10> @T6G_MB_LIB.T6G(SCH_1):P5E_CPU1_P1_TX_BUF_C_DP(10)
 C6681    1      1 Q_CAP_DIFFBUS_C0201-DIFF BUS_0.22UF,6.3V,20%,X6S,SA    I99 @T6G_MB_LIB.T6G(SCH_1):PAGE393
  J111   M3     M3 CONN112_10137002101LF-CONN112_10137002-101LF,THLF,A    I76 @T6G_MB_LIB.T6G(SCH_1):PAGE328

P5E_CPU1_P1_TX_BUF_C_DP<11> @T6G_MB_LIB.T6G(SCH_1):P5E_CPU1_P1_TX_BUF_C_DP(11)
 C6683    1      1 Q_CAP_DIFFBUS_C0201-DIFF BUS_0.22UF,6.3V,20%,X6S,SA    I98 @T6G_MB_LIB.T6G(SCH_1):PAGE393
  J111   L4     L4 CONN112_10137002101LF-CONN112_10137002-101LF,THLF,A    I76 @T6G_MB_LIB.T6G(SCH_1):PAGE328

P5E_CPU1_P1_TX_BUF_C_DP<12> @T6G_MB_LIB.T6G(SCH_1):P5E_CPU1_P1_TX_BUF_C_DP(12)
 C6685    1      1 Q_CAP_DIFFBUS_C0201-DIFF BUS_0.22UF,6.3V,20%,X6S,SA    I96 @T6G_MB_LIB.T6G(SCH_1):PAGE393
  J111   M5     M5 CONN112_10137002101LF-CONN112_10137002-101LF,THLF,A    I38 @T6G_MB_LIB.T6G(SCH_1):PAGE328

P5E_CPU1_P1_TX_BUF_C_DP<13> @T6G_MB_LIB.T6G(SCH_1):P5E_CPU1_P1_TX_BUF_C_DP(13)
 C6687    1      1 Q_CAP_DIFFBUS_C0201-DIFF BUS_0.22UF,6.3V,20%,X6S,SA    I89 @T6G_MB_LIB.T6G(SCH_1):PAGE393
  J111   L6     L6 CONN112_10137002101LF-CONN112_10137002-101LF,THLF,A    I38 @T6G_MB_LIB.T6G(SCH_1):PAGE328

P5E_CPU1_P1_TX_BUF_C_DP<14> @T6G_MB_LIB.T6G(SCH_1):P5E_CPU1_P1_TX_BUF_C_DP(14)
 C6689    1      1 Q_CAP_DIFFBUS_C0201-DIFF BUS_0.22UF,6.3V,20%,X6S,SA    I87 @T6G_MB_LIB.T6G(SCH_1):PAGE393
  J111   M7     M7 CONN112_10137002101LF-CONN112_10137002-101LF,THLF,A    I38 @T6G_MB_LIB.T6G(SCH_1):PAGE328

P5E_CPU1_P1_TX_BUF_C_DP<15> @T6G_MB_LIB.T6G(SCH_1):P5E_CPU1_P1_TX_BUF_C_DP(15)
 C6691    1      1 Q_CAP_DIFFBUS_C0201-DIFF BUS_0.22UF,6.3V,20%,X6S,SA    I85 @T6G_MB_LIB.T6G(SCH_1):PAGE393
  J111   L8     L8 CONN112_10137002101LF-CONN112_10137002-101LF,THLF,A    I38 @T6G_MB_LIB.T6G(SCH_1):PAGE328

P5E_CPU1_P1_TX_BUF_C_DP<1> @T6G_MB_LIB.T6G(SCH_1):P5E_CPU1_P1_TX_BUF_C_DP(1)
 C6663    1      1 Q_CAP_DIFFBUS_C0201-DIFF BUS_0.22UF,6.3V,20%,X6S,SA    I31 @T6G_MB_LIB.T6G(SCH_1):PAGE393
  J112   L2     L2 CONN160_10131762101LF-CONN160_10131762-101LF,THLF,A   I102 @T6G_MB_LIB.T6G(SCH_1):PAGE329

P5E_CPU1_P1_TX_BUF_C_DP<2> @T6G_MB_LIB.T6G(SCH_1):P5E_CPU1_P1_TX_BUF_C_DP(2)
 C6665    1      1 Q_CAP_DIFFBUS_C0201-DIFF BUS_0.22UF,6.3V,20%,X6S,SA    I30 @T6G_MB_LIB.T6G(SCH_1):PAGE393
  J112   M3     M3 CONN160_10131762101LF-CONN160_10131762-101LF,THLF,A   I102 @T6G_MB_LIB.T6G(SCH_1):PAGE329

P5E_CPU1_P1_TX_BUF_C_DP<3> @T6G_MB_LIB.T6G(SCH_1):P5E_CPU1_P1_TX_BUF_C_DP(3)
 C6667    1      1 Q_CAP_DIFFBUS_C0201-DIFF BUS_0.22UF,6.3V,20%,X6S,SA    I27 @T6G_MB_LIB.T6G(SCH_1):PAGE393
  J112   L4     L4 CONN160_10131762101LF-CONN160_10131762-101LF,THLF,A   I102 @T6G_MB_LIB.T6G(SCH_1):PAGE329

P5E_CPU1_P1_TX_BUF_C_DP<4> @T6G_MB_LIB.T6G(SCH_1):P5E_CPU1_P1_TX_BUF_C_DP(4)
 C6669    1      1 Q_CAP_DIFFBUS_C0201-DIFF BUS_0.22UF,6.3V,20%,X6S,SA    I26 @T6G_MB_LIB.T6G(SCH_1):PAGE393
  J112   M5     M5 CONN160_10131762101LF-CONN160_10131762-101LF,THLF,A     I7 @T6G_MB_LIB.T6G(SCH_1):PAGE329

P5E_CPU1_P1_TX_BUF_C_DP<5> @T6G_MB_LIB.T6G(SCH_1):P5E_CPU1_P1_TX_BUF_C_DP(5)
 C6671    1      1 Q_CAP_DIFFBUS_C0201-DIFF BUS_0.22UF,6.3V,20%,X6S,SA    I24 @T6G_MB_LIB.T6G(SCH_1):PAGE393
  J112   L6     L6 CONN160_10131762101LF-CONN160_10131762-101LF,THLF,A     I7 @T6G_MB_LIB.T6G(SCH_1):PAGE329

P5E_CPU1_P1_TX_BUF_C_DP<6> @T6G_MB_LIB.T6G(SCH_1):P5E_CPU1_P1_TX_BUF_C_DP(6)
 C6673    1      1 Q_CAP_DIFFBUS_C0201-DIFF BUS_0.22UF,6.3V,20%,X6S,SA    I20 @T6G_MB_LIB.T6G(SCH_1):PAGE393
  J112   M7     M7 CONN160_10131762101LF-CONN160_10131762-101LF,THLF,A     I7 @T6G_MB_LIB.T6G(SCH_1):PAGE329

P5E_CPU1_P1_TX_BUF_C_DP<7> @T6G_MB_LIB.T6G(SCH_1):P5E_CPU1_P1_TX_BUF_C_DP(7)
 C6675    1      1 Q_CAP_DIFFBUS_C0201-DIFF BUS_0.22UF,6.3V,20%,X6S,SA    I18 @T6G_MB_LIB.T6G(SCH_1):PAGE393
  J112   L8     L8 CONN160_10131762101LF-CONN160_10131762-101LF,THLF,A     I7 @T6G_MB_LIB.T6G(SCH_1):PAGE329

P5E_CPU1_P1_TX_BUF_C_DP<8> @T6G_MB_LIB.T6G(SCH_1):P5E_CPU1_P1_TX_BUF_C_DP(8)
 C6677    1      1 Q_CAP_DIFFBUS_C0201-DIFF BUS_0.22UF,6.3V,20%,X6S,SA   I104 @T6G_MB_LIB.T6G(SCH_1):PAGE393
  J111   M1     M1 CONN112_10137002101LF-CONN112_10137002-101LF,THLF,A    I76 @T6G_MB_LIB.T6G(SCH_1):PAGE328

P5E_CPU1_P1_TX_BUF_C_DP<9> @T6G_MB_LIB.T6G(SCH_1):P5E_CPU1_P1_TX_BUF_C_DP(9)
 C6679    1      1 Q_CAP_DIFFBUS_C0201-DIFF BUS_0.22UF,6.3V,20%,X6S,SA   I101 @T6G_MB_LIB.T6G(SCH_1):PAGE393
  J111   L2     L2 CONN112_10137002101LF-CONN112_10137002-101LF,THLF,A    I76 @T6G_MB_LIB.T6G(SCH_1):PAGE328

P5E_CPU1_P1_TX_BUF_DN<0> @T6G_MB_LIB.T6G(SCH_1):P5E_CPU1_P1_TX_BUF_DN(0)
 C6662    2      2 Q_CAP_DIFFBUS_C0201-DIFF BUS_0.22UF,6.3V,20%,X6S,SA    I33 @T6G_MB_LIB.T6G(SCH_1):PAGE393
 U6015 EW10 B_PETN15 PT5161LRS-PT5161LRS,SMLF,IC,AJ051610U03   I142 @T6G_MB_LIB.T6G(SCH_1):PAGE393

P5E_CPU1_P1_TX_BUF_DN<10> @T6G_MB_LIB.T6G(SCH_1):P5E_CPU1_P1_TX_BUF_DN(10)
 U6015 BJ10 B_PETN5 PT5161LRS-PT5161LRS,SMLF,IC,AJ051610U03    I41 @T6G_MB_LIB.T6G(SCH_1):PAGE393
 C6682    2      2 Q_CAP_DIFFBUS_C0201-DIFF BUS_0.22UF,6.3V,20%,X6S,SA   I100 @T6G_MB_LIB.T6G(SCH_1):PAGE393

P5E_CPU1_P1_TX_BUF_DN<11> @T6G_MB_LIB.T6G(SCH_1):P5E_CPU1_P1_TX_BUF_DN(11)
 U6015 BB10 B_PETN4 PT5161LRS-PT5161LRS,SMLF,IC,AJ051610U03    I41 @T6G_MB_LIB.T6G(SCH_1):PAGE393
 C6684    2      2 Q_CAP_DIFFBUS_C0201-DIFF BUS_0.22UF,6.3V,20%,X6S,SA    I97 @T6G_MB_LIB.T6G(SCH_1):PAGE393

P5E_CPU1_P1_TX_BUF_DN<12> @T6G_MB_LIB.T6G(SCH_1):P5E_CPU1_P1_TX_BUF_DN(12)
 U6015 AR10 B_PETN3 PT5161LRS-PT5161LRS,SMLF,IC,AJ051610U03    I41 @T6G_MB_LIB.T6G(SCH_1):PAGE393
 C6686    2      2 Q_CAP_DIFFBUS_C0201-DIFF BUS_0.22UF,6.3V,20%,X6S,SA    I95 @T6G_MB_LIB.T6G(SCH_1):PAGE393

P5E_CPU1_P1_TX_BUF_DN<13> @T6G_MB_LIB.T6G(SCH_1):P5E_CPU1_P1_TX_BUF_DN(13)
 U6015 AH10 B_PETN2 PT5161LRS-PT5161LRS,SMLF,IC,AJ051610U03    I41 @T6G_MB_LIB.T6G(SCH_1):PAGE393
 C6688    2      2 Q_CAP_DIFFBUS_C0201-DIFF BUS_0.22UF,6.3V,20%,X6S,SA    I88 @T6G_MB_LIB.T6G(SCH_1):PAGE393

P5E_CPU1_P1_TX_BUF_DN<14> @T6G_MB_LIB.T6G(SCH_1):P5E_CPU1_P1_TX_BUF_DN(14)
 U6015 AA10 B_PETN1 PT5161LRS-PT5161LRS,SMLF,IC,AJ051610U03    I41 @T6G_MB_LIB.T6G(SCH_1):PAGE393
 C6690    2      2 Q_CAP_DIFFBUS_C0201-DIFF BUS_0.22UF,6.3V,20%,X6S,SA    I86 @T6G_MB_LIB.T6G(SCH_1):PAGE393

P5E_CPU1_P1_TX_BUF_DN<15> @T6G_MB_LIB.T6G(SCH_1):P5E_CPU1_P1_TX_BUF_DN(15)
 U6015  P10 B_PETN0 PT5161LRS-PT5161LRS,SMLF,IC,AJ051610U03    I41 @T6G_MB_LIB.T6G(SCH_1):PAGE393
 C6692    2      2 Q_CAP_DIFFBUS_C0201-DIFF BUS_0.22UF,6.3V,20%,X6S,SA    I84 @T6G_MB_LIB.T6G(SCH_1):PAGE393

P5E_CPU1_P1_TX_BUF_DN<1> @T6G_MB_LIB.T6G(SCH_1):P5E_CPU1_P1_TX_BUF_DN(1)
 C6664    2      2 Q_CAP_DIFFBUS_C0201-DIFF BUS_0.22UF,6.3V,20%,X6S,SA    I32 @T6G_MB_LIB.T6G(SCH_1):PAGE393
 U6015 EM10 B_PETN14 PT5161LRS-PT5161LRS,SMLF,IC,AJ051610U03   I142 @T6G_MB_LIB.T6G(SCH_1):PAGE393

P5E_CPU1_P1_TX_BUF_DN<2> @T6G_MB_LIB.T6G(SCH_1):P5E_CPU1_P1_TX_BUF_DN(2)
 C6666    2      2 Q_CAP_DIFFBUS_C0201-DIFF BUS_0.22UF,6.3V,20%,X6S,SA    I29 @T6G_MB_LIB.T6G(SCH_1):PAGE393
 U6015 EE10 B_PETN13 PT5161LRS-PT5161LRS,SMLF,IC,AJ051610U03   I142 @T6G_MB_LIB.T6G(SCH_1):PAGE393

P5E_CPU1_P1_TX_BUF_DN<3> @T6G_MB_LIB.T6G(SCH_1):P5E_CPU1_P1_TX_BUF_DN(3)
 C6668    2      2 Q_CAP_DIFFBUS_C0201-DIFF BUS_0.22UF,6.3V,20%,X6S,SA    I28 @T6G_MB_LIB.T6G(SCH_1):PAGE393
 U6015 DV10 B_PETN12 PT5161LRS-PT5161LRS,SMLF,IC,AJ051610U03   I142 @T6G_MB_LIB.T6G(SCH_1):PAGE393

P5E_CPU1_P1_TX_BUF_DN<4> @T6G_MB_LIB.T6G(SCH_1):P5E_CPU1_P1_TX_BUF_DN(4)
 C6670    2      2 Q_CAP_DIFFBUS_C0201-DIFF BUS_0.22UF,6.3V,20%,X6S,SA    I25 @T6G_MB_LIB.T6G(SCH_1):PAGE393
 U6015 DL10 B_PETN11 PT5161LRS-PT5161LRS,SMLF,IC,AJ051610U03   I142 @T6G_MB_LIB.T6G(SCH_1):PAGE393

P5E_CPU1_P1_TX_BUF_DN<5> @T6G_MB_LIB.T6G(SCH_1):P5E_CPU1_P1_TX_BUF_DN(5)
 C6672    2      2 Q_CAP_DIFFBUS_C0201-DIFF BUS_0.22UF,6.3V,20%,X6S,SA    I23 @T6G_MB_LIB.T6G(SCH_1):PAGE393
 U6015 DD10 B_PETN10 PT5161LRS-PT5161LRS,SMLF,IC,AJ051610U03   I142 @T6G_MB_LIB.T6G(SCH_1):PAGE393

P5E_CPU1_P1_TX_BUF_DN<6> @T6G_MB_LIB.T6G(SCH_1):P5E_CPU1_P1_TX_BUF_DN(6)
 C6674    2      2 Q_CAP_DIFFBUS_C0201-DIFF BUS_0.22UF,6.3V,20%,X6S,SA    I19 @T6G_MB_LIB.T6G(SCH_1):PAGE393
 U6015 CU10 B_PETN9 PT5161LRS-PT5161LRS,SMLF,IC,AJ051610U03   I142 @T6G_MB_LIB.T6G(SCH_1):PAGE393

P5E_CPU1_P1_TX_BUF_DN<7> @T6G_MB_LIB.T6G(SCH_1):P5E_CPU1_P1_TX_BUF_DN(7)
 C6676    2      2 Q_CAP_DIFFBUS_C0201-DIFF BUS_0.22UF,6.3V,20%,X6S,SA    I17 @T6G_MB_LIB.T6G(SCH_1):PAGE393
 U6015 CK10 B_PETN8 PT5161LRS-PT5161LRS,SMLF,IC,AJ051610U03   I142 @T6G_MB_LIB.T6G(SCH_1):PAGE393

P5E_CPU1_P1_TX_BUF_DN<8> @T6G_MB_LIB.T6G(SCH_1):P5E_CPU1_P1_TX_BUF_DN(8)
 U6015 CC10 B_PETN7 PT5161LRS-PT5161LRS,SMLF,IC,AJ051610U03    I41 @T6G_MB_LIB.T6G(SCH_1):PAGE393
 C6678    2      2 Q_CAP_DIFFBUS_C0201-DIFF BUS_0.22UF,6.3V,20%,X6S,SA   I103 @T6G_MB_LIB.T6G(SCH_1):PAGE393

P5E_CPU1_P1_TX_BUF_DN<9> @T6G_MB_LIB.T6G(SCH_1):P5E_CPU1_P1_TX_BUF_DN(9)
 U6015 BT10 B_PETN6 PT5161LRS-PT5161LRS,SMLF,IC,AJ051610U03    I41 @T6G_MB_LIB.T6G(SCH_1):PAGE393
 C6680    2      2 Q_CAP_DIFFBUS_C0201-DIFF BUS_0.22UF,6.3V,20%,X6S,SA   I102 @T6G_MB_LIB.T6G(SCH_1):PAGE393

P5E_CPU1_P1_TX_BUF_DP<0> @T6G_MB_LIB.T6G(SCH_1):P5E_CPU1_P1_TX_BUF_DP(0)
 C6661    2      2 Q_CAP_DIFFBUS_C0201-DIFF BUS_0.22UF,6.3V,20%,X6S,SA    I42 @T6G_MB_LIB.T6G(SCH_1):PAGE393
 U6015  EU7 B_PETP15 PT5161LRS-PT5161LRS,SMLF,IC,AJ051610U03   I142 @T6G_MB_LIB.T6G(SCH_1):PAGE393

P5E_CPU1_P1_TX_BUF_DP<10> @T6G_MB_LIB.T6G(SCH_1):P5E_CPU1_P1_TX_BUF_DP(10)
 U6015  BG7 B_PETP5 PT5161LRS-PT5161LRS,SMLF,IC,AJ051610U03    I41 @T6G_MB_LIB.T6G(SCH_1):PAGE393
 C6681    2      2 Q_CAP_DIFFBUS_C0201-DIFF BUS_0.22UF,6.3V,20%,X6S,SA    I99 @T6G_MB_LIB.T6G(SCH_1):PAGE393

P5E_CPU1_P1_TX_BUF_DP<11> @T6G_MB_LIB.T6G(SCH_1):P5E_CPU1_P1_TX_BUF_DP(11)
 U6015  AY7 B_PETP4 PT5161LRS-PT5161LRS,SMLF,IC,AJ051610U03    I41 @T6G_MB_LIB.T6G(SCH_1):PAGE393
 C6683    2      2 Q_CAP_DIFFBUS_C0201-DIFF BUS_0.22UF,6.3V,20%,X6S,SA    I98 @T6G_MB_LIB.T6G(SCH_1):PAGE393

P5E_CPU1_P1_TX_BUF_DP<12> @T6G_MB_LIB.T6G(SCH_1):P5E_CPU1_P1_TX_BUF_DP(12)
 U6015  AN7 B_PETP3 PT5161LRS-PT5161LRS,SMLF,IC,AJ051610U03    I41 @T6G_MB_LIB.T6G(SCH_1):PAGE393
 C6685    2      2 Q_CAP_DIFFBUS_C0201-DIFF BUS_0.22UF,6.3V,20%,X6S,SA    I96 @T6G_MB_LIB.T6G(SCH_1):PAGE393

P5E_CPU1_P1_TX_BUF_DP<13> @T6G_MB_LIB.T6G(SCH_1):P5E_CPU1_P1_TX_BUF_DP(13)
 U6015  AF7 B_PETP2 PT5161LRS-PT5161LRS,SMLF,IC,AJ051610U03    I41 @T6G_MB_LIB.T6G(SCH_1):PAGE393
 C6687    2      2 Q_CAP_DIFFBUS_C0201-DIFF BUS_0.22UF,6.3V,20%,X6S,SA    I89 @T6G_MB_LIB.T6G(SCH_1):PAGE393

P5E_CPU1_P1_TX_BUF_DP<14> @T6G_MB_LIB.T6G(SCH_1):P5E_CPU1_P1_TX_BUF_DP(14)
 U6015   W7 B_PETP1 PT5161LRS-PT5161LRS,SMLF,IC,AJ051610U03    I41 @T6G_MB_LIB.T6G(SCH_1):PAGE393
 C6689    2      2 Q_CAP_DIFFBUS_C0201-DIFF BUS_0.22UF,6.3V,20%,X6S,SA    I87 @T6G_MB_LIB.T6G(SCH_1):PAGE393

P5E_CPU1_P1_TX_BUF_DP<15> @T6G_MB_LIB.T6G(SCH_1):P5E_CPU1_P1_TX_BUF_DP(15)
 U6015   M7 B_PETP0 PT5161LRS-PT5161LRS,SMLF,IC,AJ051610U03    I41 @T6G_MB_LIB.T6G(SCH_1):PAGE393
 C6691    2      2 Q_CAP_DIFFBUS_C0201-DIFF BUS_0.22UF,6.3V,20%,X6S,SA    I85 @T6G_MB_LIB.T6G(SCH_1):PAGE393

P5E_CPU1_P1_TX_BUF_DP<1> @T6G_MB_LIB.T6G(SCH_1):P5E_CPU1_P1_TX_BUF_DP(1)
 C6663    2      2 Q_CAP_DIFFBUS_C0201-DIFF BUS_0.22UF,6.3V,20%,X6S,SA    I31 @T6G_MB_LIB.T6G(SCH_1):PAGE393
 U6015  EK7 B_PETP14 PT5161LRS-PT5161LRS,SMLF,IC,AJ051610U03   I142 @T6G_MB_LIB.T6G(SCH_1):PAGE393

P5E_CPU1_P1_TX_BUF_DP<2> @T6G_MB_LIB.T6G(SCH_1):P5E_CPU1_P1_TX_BUF_DP(2)
 C6665    2      2 Q_CAP_DIFFBUS_C0201-DIFF BUS_0.22UF,6.3V,20%,X6S,SA    I30 @T6G_MB_LIB.T6G(SCH_1):PAGE393
 U6015  EC7 B_PETP13 PT5161LRS-PT5161LRS,SMLF,IC,AJ051610U03   I142 @T6G_MB_LIB.T6G(SCH_1):PAGE393

P5E_CPU1_P1_TX_BUF_DP<3> @T6G_MB_LIB.T6G(SCH_1):P5E_CPU1_P1_TX_BUF_DP(3)
 C6667    2      2 Q_CAP_DIFFBUS_C0201-DIFF BUS_0.22UF,6.3V,20%,X6S,SA    I27 @T6G_MB_LIB.T6G(SCH_1):PAGE393
 U6015  DT7 B_PETP12 PT5161LRS-PT5161LRS,SMLF,IC,AJ051610U03   I142 @T6G_MB_LIB.T6G(SCH_1):PAGE393

P5E_CPU1_P1_TX_BUF_DP<4> @T6G_MB_LIB.T6G(SCH_1):P5E_CPU1_P1_TX_BUF_DP(4)
 C6669    2      2 Q_CAP_DIFFBUS_C0201-DIFF BUS_0.22UF,6.3V,20%,X6S,SA    I26 @T6G_MB_LIB.T6G(SCH_1):PAGE393
 U6015  DJ7 B_PETP11 PT5161LRS-PT5161LRS,SMLF,IC,AJ051610U03   I142 @T6G_MB_LIB.T6G(SCH_1):PAGE393

P5E_CPU1_P1_TX_BUF_DP<5> @T6G_MB_LIB.T6G(SCH_1):P5E_CPU1_P1_TX_BUF_DP(5)
 C6671    2      2 Q_CAP_DIFFBUS_C0201-DIFF BUS_0.22UF,6.3V,20%,X6S,SA    I24 @T6G_MB_LIB.T6G(SCH_1):PAGE393
 U6015  DB7 B_PETP10 PT5161LRS-PT5161LRS,SMLF,IC,AJ051610U03   I142 @T6G_MB_LIB.T6G(SCH_1):PAGE393

P5E_CPU1_P1_TX_BUF_DP<6> @T6G_MB_LIB.T6G(SCH_1):P5E_CPU1_P1_TX_BUF_DP(6)
 C6673    2      2 Q_CAP_DIFFBUS_C0201-DIFF BUS_0.22UF,6.3V,20%,X6S,SA    I20 @T6G_MB_LIB.T6G(SCH_1):PAGE393
 U6015  CR7 B_PETP9 PT5161LRS-PT5161LRS,SMLF,IC,AJ051610U03   I142 @T6G_MB_LIB.T6G(SCH_1):PAGE393

P5E_CPU1_P1_TX_BUF_DP<7> @T6G_MB_LIB.T6G(SCH_1):P5E_CPU1_P1_TX_BUF_DP(7)
 C6675    2      2 Q_CAP_DIFFBUS_C0201-DIFF BUS_0.22UF,6.3V,20%,X6S,SA    I18 @T6G_MB_LIB.T6G(SCH_1):PAGE393
 U6015  CH7 B_PETP8 PT5161LRS-PT5161LRS,SMLF,IC,AJ051610U03   I142 @T6G_MB_LIB.T6G(SCH_1):PAGE393

P5E_CPU1_P1_TX_BUF_DP<8> @T6G_MB_LIB.T6G(SCH_1):P5E_CPU1_P1_TX_BUF_DP(8)
 U6015  CA7 B_PETP7 PT5161LRS-PT5161LRS,SMLF,IC,AJ051610U03    I41 @T6G_MB_LIB.T6G(SCH_1):PAGE393
 C6677    2      2 Q_CAP_DIFFBUS_C0201-DIFF BUS_0.22UF,6.3V,20%,X6S,SA   I104 @T6G_MB_LIB.T6G(SCH_1):PAGE393

P5E_CPU1_P1_TX_BUF_DP<9> @T6G_MB_LIB.T6G(SCH_1):P5E_CPU1_P1_TX_BUF_DP(9)
 U6015  BP7 B_PETP6 PT5161LRS-PT5161LRS,SMLF,IC,AJ051610U03    I41 @T6G_MB_LIB.T6G(SCH_1):PAGE393
 C6679    2      2 Q_CAP_DIFFBUS_C0201-DIFF BUS_0.22UF,6.3V,20%,X6S,SA   I101 @T6G_MB_LIB.T6G(SCH_1):PAGE393

P5E_CPU1_P1_TX_C_DN<0> @T6G_MB_LIB.T6G(SCH_1):P5E_CPU1_P1_TX_C_DN(0)
  C740    1      1 Q_CAP_DIFFBUS_C0201-DIFF BUS_0.22UF,6.3V,20%,X6S,SA   I229 @T6G_MB_LIB.T6G(SCH_1):PAGE354
 U6015 EV34 B_PERP15 PT5161LRS-PT5161LRS,SMLF,IC,AJ051610U03    I38 @T6G_MB_LIB.T6G(SCH_1):PAGE396

P5E_CPU1_P1_TX_C_DN<10> @T6G_MB_LIB.T6G(SCH_1):P5E_CPU1_P1_TX_C_DN(10)
  C720    1      1 Q_CAP_DIFFBUS_C0201-DIFF BUS_0.22UF,6.3V,20%,X6S,SA   I279 @T6G_MB_LIB.T6G(SCH_1):PAGE354
 U6015 BH34 B_PERP5 PT5161LRS-PT5161LRS,SMLF,IC,AJ051610U03     I1 @T6G_MB_LIB.T6G(SCH_1):PAGE396

P5E_CPU1_P1_TX_C_DN<11> @T6G_MB_LIB.T6G(SCH_1):P5E_CPU1_P1_TX_C_DN(11)
  C718    1      1 Q_CAP_DIFFBUS_C0201-DIFF BUS_0.22UF,6.3V,20%,X6S,SA   I281 @T6G_MB_LIB.T6G(SCH_1):PAGE354
 U6015 BA34 B_PERP4 PT5161LRS-PT5161LRS,SMLF,IC,AJ051610U03     I1 @T6G_MB_LIB.T6G(SCH_1):PAGE396

P5E_CPU1_P1_TX_C_DN<12> @T6G_MB_LIB.T6G(SCH_1):P5E_CPU1_P1_TX_C_DN(12)
  C716    1      1 Q_CAP_DIFFBUS_C0201-DIFF BUS_0.22UF,6.3V,20%,X6S,SA   I283 @T6G_MB_LIB.T6G(SCH_1):PAGE354
 U6015 AP34 B_PERP3 PT5161LRS-PT5161LRS,SMLF,IC,AJ051610U03     I1 @T6G_MB_LIB.T6G(SCH_1):PAGE396

P5E_CPU1_P1_TX_C_DN<13> @T6G_MB_LIB.T6G(SCH_1):P5E_CPU1_P1_TX_C_DN(13)
  C714    1      1 Q_CAP_DIFFBUS_C0201-DIFF BUS_0.22UF,6.3V,20%,X6S,SA   I295 @T6G_MB_LIB.T6G(SCH_1):PAGE354
 U6015 AG34 B_PERP2 PT5161LRS-PT5161LRS,SMLF,IC,AJ051610U03     I1 @T6G_MB_LIB.T6G(SCH_1):PAGE396

P5E_CPU1_P1_TX_C_DN<14> @T6G_MB_LIB.T6G(SCH_1):P5E_CPU1_P1_TX_C_DN(14)
  C712    1      1 Q_CAP_DIFFBUS_C0201-DIFF BUS_0.22UF,6.3V,20%,X6S,SA   I296 @T6G_MB_LIB.T6G(SCH_1):PAGE354
 U6015 AB35 B_PERN1 PT5161LRS-PT5161LRS,SMLF,IC,AJ051610U03     I1 @T6G_MB_LIB.T6G(SCH_1):PAGE396

P5E_CPU1_P1_TX_C_DN<15> @T6G_MB_LIB.T6G(SCH_1):P5E_CPU1_P1_TX_C_DN(15)
  C710    1      1 Q_CAP_DIFFBUS_C0201-DIFF BUS_0.22UF,6.3V,20%,X6S,SA   I299 @T6G_MB_LIB.T6G(SCH_1):PAGE354
 U6015  N34 B_PERP0 PT5161LRS-PT5161LRS,SMLF,IC,AJ051610U03     I1 @T6G_MB_LIB.T6G(SCH_1):PAGE396

P5E_CPU1_P1_TX_C_DN<1> @T6G_MB_LIB.T6G(SCH_1):P5E_CPU1_P1_TX_C_DN(1)
  C738    1      1 Q_CAP_DIFFBUS_C0201-DIFF BUS_0.22UF,6.3V,20%,X6S,SA   I232 @T6G_MB_LIB.T6G(SCH_1):PAGE354
 U6015 EN35 B_PERN14 PT5161LRS-PT5161LRS,SMLF,IC,AJ051610U03    I38 @T6G_MB_LIB.T6G(SCH_1):PAGE396

P5E_CPU1_P1_TX_C_DN<2> @T6G_MB_LIB.T6G(SCH_1):P5E_CPU1_P1_TX_C_DN(2)
  C736    1      1 Q_CAP_DIFFBUS_C0201-DIFF BUS_0.22UF,6.3V,20%,X6S,SA   I234 @T6G_MB_LIB.T6G(SCH_1):PAGE354
 U6015 ED34 B_PERP13 PT5161LRS-PT5161LRS,SMLF,IC,AJ051610U03    I38 @T6G_MB_LIB.T6G(SCH_1):PAGE396

P5E_CPU1_P1_TX_C_DN<3> @T6G_MB_LIB.T6G(SCH_1):P5E_CPU1_P1_TX_C_DN(3)
  C734    1      1 Q_CAP_DIFFBUS_C0201-DIFF BUS_0.22UF,6.3V,20%,X6S,SA   I235 @T6G_MB_LIB.T6G(SCH_1):PAGE354
 U6015 DU34 B_PERP12 PT5161LRS-PT5161LRS,SMLF,IC,AJ051610U03    I38 @T6G_MB_LIB.T6G(SCH_1):PAGE396

P5E_CPU1_P1_TX_C_DN<4> @T6G_MB_LIB.T6G(SCH_1):P5E_CPU1_P1_TX_C_DN(4)
  C732    1      1 Q_CAP_DIFFBUS_C0201-DIFF BUS_0.22UF,6.3V,20%,X6S,SA   I246 @T6G_MB_LIB.T6G(SCH_1):PAGE354
 U6015 DK34 B_PERP11 PT5161LRS-PT5161LRS,SMLF,IC,AJ051610U03    I38 @T6G_MB_LIB.T6G(SCH_1):PAGE396

P5E_CPU1_P1_TX_C_DN<5> @T6G_MB_LIB.T6G(SCH_1):P5E_CPU1_P1_TX_C_DN(5)
  C730    1      1 Q_CAP_DIFFBUS_C0201-DIFF BUS_0.22UF,6.3V,20%,X6S,SA   I248 @T6G_MB_LIB.T6G(SCH_1):PAGE354
 U6015 DC34 B_PERP10 PT5161LRS-PT5161LRS,SMLF,IC,AJ051610U03    I38 @T6G_MB_LIB.T6G(SCH_1):PAGE396

P5E_CPU1_P1_TX_C_DN<6> @T6G_MB_LIB.T6G(SCH_1):P5E_CPU1_P1_TX_C_DN(6)
  C728    1      1 Q_CAP_DIFFBUS_C0201-DIFF BUS_0.22UF,6.3V,20%,X6S,SA   I250 @T6G_MB_LIB.T6G(SCH_1):PAGE354
 U6015 CT34 B_PERP9 PT5161LRS-PT5161LRS,SMLF,IC,AJ051610U03    I38 @T6G_MB_LIB.T6G(SCH_1):PAGE396

P5E_CPU1_P1_TX_C_DN<7> @T6G_MB_LIB.T6G(SCH_1):P5E_CPU1_P1_TX_C_DN(7)
  C726    1      1 Q_CAP_DIFFBUS_C0201-DIFF BUS_0.22UF,6.3V,20%,X6S,SA   I312 @T6G_MB_LIB.T6G(SCH_1):PAGE354
 U6015 CJ34 B_PERP8 PT5161LRS-PT5161LRS,SMLF,IC,AJ051610U03    I38 @T6G_MB_LIB.T6G(SCH_1):PAGE396

P5E_CPU1_P1_TX_C_DN<8> @T6G_MB_LIB.T6G(SCH_1):P5E_CPU1_P1_TX_C_DN(8)
  C724    1      1 Q_CAP_DIFFBUS_C0201-DIFF BUS_0.22UF,6.3V,20%,X6S,SA   I275 @T6G_MB_LIB.T6G(SCH_1):PAGE354
 U6015 CB34 B_PERP7 PT5161LRS-PT5161LRS,SMLF,IC,AJ051610U03     I1 @T6G_MB_LIB.T6G(SCH_1):PAGE396

P5E_CPU1_P1_TX_C_DN<9> @T6G_MB_LIB.T6G(SCH_1):P5E_CPU1_P1_TX_C_DN(9)
  C722    1      1 Q_CAP_DIFFBUS_C0201-DIFF BUS_0.22UF,6.3V,20%,X6S,SA   I276 @T6G_MB_LIB.T6G(SCH_1):PAGE354
 U6015 BR34 B_PERP6 PT5161LRS-PT5161LRS,SMLF,IC,AJ051610U03     I1 @T6G_MB_LIB.T6G(SCH_1):PAGE396

P5E_CPU1_P1_TX_C_DP<0> @T6G_MB_LIB.T6G(SCH_1):P5E_CPU1_P1_TX_C_DP(0)
  C741    1      1 Q_CAP_DIFFBUS_C0201-DIFF BUS_0.22UF,6.3V,20%,X6S,SA   I230 @T6G_MB_LIB.T6G(SCH_1):PAGE354
 U6015 EY35 B_PERN15 PT5161LRS-PT5161LRS,SMLF,IC,AJ051610U03    I38 @T6G_MB_LIB.T6G(SCH_1):PAGE396

P5E_CPU1_P1_TX_C_DP<10> @T6G_MB_LIB.T6G(SCH_1):P5E_CPU1_P1_TX_C_DP(10)
  C721    1      1 Q_CAP_DIFFBUS_C0201-DIFF BUS_0.22UF,6.3V,20%,X6S,SA   I278 @T6G_MB_LIB.T6G(SCH_1):PAGE354
 U6015 BK35 B_PERN5 PT5161LRS-PT5161LRS,SMLF,IC,AJ051610U03     I1 @T6G_MB_LIB.T6G(SCH_1):PAGE396

P5E_CPU1_P1_TX_C_DP<11> @T6G_MB_LIB.T6G(SCH_1):P5E_CPU1_P1_TX_C_DP(11)
  C719    1      1 Q_CAP_DIFFBUS_C0201-DIFF BUS_0.22UF,6.3V,20%,X6S,SA   I280 @T6G_MB_LIB.T6G(SCH_1):PAGE354
 U6015 BC35 B_PERN4 PT5161LRS-PT5161LRS,SMLF,IC,AJ051610U03     I1 @T6G_MB_LIB.T6G(SCH_1):PAGE396

P5E_CPU1_P1_TX_C_DP<12> @T6G_MB_LIB.T6G(SCH_1):P5E_CPU1_P1_TX_C_DP(12)
  C717    1      1 Q_CAP_DIFFBUS_C0201-DIFF BUS_0.22UF,6.3V,20%,X6S,SA   I282 @T6G_MB_LIB.T6G(SCH_1):PAGE354
 U6015 AT35 B_PERN3 PT5161LRS-PT5161LRS,SMLF,IC,AJ051610U03     I1 @T6G_MB_LIB.T6G(SCH_1):PAGE396

P5E_CPU1_P1_TX_C_DP<13> @T6G_MB_LIB.T6G(SCH_1):P5E_CPU1_P1_TX_C_DP(13)
  C715    1      1 Q_CAP_DIFFBUS_C0201-DIFF BUS_0.22UF,6.3V,20%,X6S,SA   I294 @T6G_MB_LIB.T6G(SCH_1):PAGE354
 U6015 AJ35 B_PERN2 PT5161LRS-PT5161LRS,SMLF,IC,AJ051610U03     I1 @T6G_MB_LIB.T6G(SCH_1):PAGE396

P5E_CPU1_P1_TX_C_DP<14> @T6G_MB_LIB.T6G(SCH_1):P5E_CPU1_P1_TX_C_DP(14)
  C713    1      1 Q_CAP_DIFFBUS_C0201-DIFF BUS_0.22UF,6.3V,20%,X6S,SA   I297 @T6G_MB_LIB.T6G(SCH_1):PAGE354
 U6015  Y34 B_PERP1 PT5161LRS-PT5161LRS,SMLF,IC,AJ051610U03     I1 @T6G_MB_LIB.T6G(SCH_1):PAGE396

P5E_CPU1_P1_TX_C_DP<15> @T6G_MB_LIB.T6G(SCH_1):P5E_CPU1_P1_TX_C_DP(15)
  C711    1      1 Q_CAP_DIFFBUS_C0201-DIFF BUS_0.22UF,6.3V,20%,X6S,SA   I298 @T6G_MB_LIB.T6G(SCH_1):PAGE354
 U6015  R35 B_PERN0 PT5161LRS-PT5161LRS,SMLF,IC,AJ051610U03     I1 @T6G_MB_LIB.T6G(SCH_1):PAGE396

P5E_CPU1_P1_TX_C_DP<1> @T6G_MB_LIB.T6G(SCH_1):P5E_CPU1_P1_TX_C_DP(1)
  C739    1      1 Q_CAP_DIFFBUS_C0201-DIFF BUS_0.22UF,6.3V,20%,X6S,SA   I231 @T6G_MB_LIB.T6G(SCH_1):PAGE354
 U6015 EL34 B_PERP14 PT5161LRS-PT5161LRS,SMLF,IC,AJ051610U03    I38 @T6G_MB_LIB.T6G(SCH_1):PAGE396

P5E_CPU1_P1_TX_C_DP<2> @T6G_MB_LIB.T6G(SCH_1):P5E_CPU1_P1_TX_C_DP(2)
  C737    1      1 Q_CAP_DIFFBUS_C0201-DIFF BUS_0.22UF,6.3V,20%,X6S,SA   I233 @T6G_MB_LIB.T6G(SCH_1):PAGE354
 U6015 EF35 B_PERN13 PT5161LRS-PT5161LRS,SMLF,IC,AJ051610U03    I38 @T6G_MB_LIB.T6G(SCH_1):PAGE396

P5E_CPU1_P1_TX_C_DP<3> @T6G_MB_LIB.T6G(SCH_1):P5E_CPU1_P1_TX_C_DP(3)
  C735    1      1 Q_CAP_DIFFBUS_C0201-DIFF BUS_0.22UF,6.3V,20%,X6S,SA   I236 @T6G_MB_LIB.T6G(SCH_1):PAGE354
 U6015 DW35 B_PERN12 PT5161LRS-PT5161LRS,SMLF,IC,AJ051610U03    I38 @T6G_MB_LIB.T6G(SCH_1):PAGE396

P5E_CPU1_P1_TX_C_DP<4> @T6G_MB_LIB.T6G(SCH_1):P5E_CPU1_P1_TX_C_DP(4)
  C733    1      1 Q_CAP_DIFFBUS_C0201-DIFF BUS_0.22UF,6.3V,20%,X6S,SA   I237 @T6G_MB_LIB.T6G(SCH_1):PAGE354
 U6015 DM35 B_PERN11 PT5161LRS-PT5161LRS,SMLF,IC,AJ051610U03    I38 @T6G_MB_LIB.T6G(SCH_1):PAGE396

P5E_CPU1_P1_TX_C_DP<5> @T6G_MB_LIB.T6G(SCH_1):P5E_CPU1_P1_TX_C_DP(5)
  C731    1      1 Q_CAP_DIFFBUS_C0201-DIFF BUS_0.22UF,6.3V,20%,X6S,SA   I247 @T6G_MB_LIB.T6G(SCH_1):PAGE354
 U6015 DE35 B_PERN10 PT5161LRS-PT5161LRS,SMLF,IC,AJ051610U03    I38 @T6G_MB_LIB.T6G(SCH_1):PAGE396

P5E_CPU1_P1_TX_C_DP<6> @T6G_MB_LIB.T6G(SCH_1):P5E_CPU1_P1_TX_C_DP(6)
  C729    1      1 Q_CAP_DIFFBUS_C0201-DIFF BUS_0.22UF,6.3V,20%,X6S,SA   I249 @T6G_MB_LIB.T6G(SCH_1):PAGE354
 U6015 CV35 B_PERN9 PT5161LRS-PT5161LRS,SMLF,IC,AJ051610U03    I38 @T6G_MB_LIB.T6G(SCH_1):PAGE396

P5E_CPU1_P1_TX_C_DP<7> @T6G_MB_LIB.T6G(SCH_1):P5E_CPU1_P1_TX_C_DP(7)
  C727    1      1 Q_CAP_DIFFBUS_C0201-DIFF BUS_0.22UF,6.3V,20%,X6S,SA   I251 @T6G_MB_LIB.T6G(SCH_1):PAGE354
 U6015 CL35 B_PERN8 PT5161LRS-PT5161LRS,SMLF,IC,AJ051610U03    I38 @T6G_MB_LIB.T6G(SCH_1):PAGE396

P5E_CPU1_P1_TX_C_DP<8> @T6G_MB_LIB.T6G(SCH_1):P5E_CPU1_P1_TX_C_DP(8)
  C725    1      1 Q_CAP_DIFFBUS_C0201-DIFF BUS_0.22UF,6.3V,20%,X6S,SA   I274 @T6G_MB_LIB.T6G(SCH_1):PAGE354
 U6015 CD35 B_PERN7 PT5161LRS-PT5161LRS,SMLF,IC,AJ051610U03     I1 @T6G_MB_LIB.T6G(SCH_1):PAGE396

P5E_CPU1_P1_TX_C_DP<9> @T6G_MB_LIB.T6G(SCH_1):P5E_CPU1_P1_TX_C_DP(9)
  C723    1      1 Q_CAP_DIFFBUS_C0201-DIFF BUS_0.22UF,6.3V,20%,X6S,SA   I277 @T6G_MB_LIB.T6G(SCH_1):PAGE354
 U6015 BU35 B_PERN6 PT5161LRS-PT5161LRS,SMLF,IC,AJ051610U03     I1 @T6G_MB_LIB.T6G(SCH_1):PAGE396

P5E_CPU1_P1_TX_DN<0> @T6G_MB_LIB.T6G(SCH_1):P5E_CPU1_P1_TX_DN(0)
   U26 CU52 P1_TXN0 GENOA_SP5-SOCKET6096_13568-001,SMLF,IO,DGA^6000030   I148 @T6G_MB_LIB.T6G(SCH_1):PAGE51
  C740    2      2 Q_CAP_DIFFBUS_C0201-DIFF BUS_0.22UF,6.3V,20%,X6S,SA   I229 @T6G_MB_LIB.T6G(SCH_1):PAGE354

P5E_CPU1_P1_TX_DN<10> @T6G_MB_LIB.T6G(SCH_1):P5E_CPU1_P1_TX_DN(10)
   U26 DA43 P1_TXN10 GENOA_SP5-SOCKET6096_13568-001,SMLF,IO,DGA^6000030   I148 @T6G_MB_LIB.T6G(SCH_1):PAGE51
  C720    2      2 Q_CAP_DIFFBUS_C0201-DIFF BUS_0.22UF,6.3V,20%,X6S,SA   I279 @T6G_MB_LIB.T6G(SCH_1):PAGE354

P5E_CPU1_P1_TX_DN<11> @T6G_MB_LIB.T6G(SCH_1):P5E_CPU1_P1_TX_DN(11)
   U26 DC43 P1_TXN11 GENOA_SP5-SOCKET6096_13568-001,SMLF,IO,DGA^6000030   I148 @T6G_MB_LIB.T6G(SCH_1):PAGE51
  C718    2      2 Q_CAP_DIFFBUS_C0201-DIFF BUS_0.22UF,6.3V,20%,X6S,SA   I281 @T6G_MB_LIB.T6G(SCH_1):PAGE354

P5E_CPU1_P1_TX_DN<12> @T6G_MB_LIB.T6G(SCH_1):P5E_CPU1_P1_TX_DN(12)
   U26 CW43 P1_TXN12 GENOA_SP5-SOCKET6096_13568-001,SMLF,IO,DGA^6000030   I148 @T6G_MB_LIB.T6G(SCH_1):PAGE51
  C716    2      2 Q_CAP_DIFFBUS_C0201-DIFF BUS_0.22UF,6.3V,20%,X6S,SA   I283 @T6G_MB_LIB.T6G(SCH_1):PAGE354

P5E_CPU1_P1_TX_DN<13> @T6G_MB_LIB.T6G(SCH_1):P5E_CPU1_P1_TX_DN(13)
   U26 DB40 P1_TXN13 GENOA_SP5-SOCKET6096_13568-001,SMLF,IO,DGA^6000030   I148 @T6G_MB_LIB.T6G(SCH_1):PAGE51
  C714    2      2 Q_CAP_DIFFBUS_C0201-DIFF BUS_0.22UF,6.3V,20%,X6S,SA   I295 @T6G_MB_LIB.T6G(SCH_1):PAGE354

P5E_CPU1_P1_TX_DN<14> @T6G_MB_LIB.T6G(SCH_1):P5E_CPU1_P1_TX_DN(14)
   U26 CY40 P1_TXN14 GENOA_SP5-SOCKET6096_13568-001,SMLF,IO,DGA^6000030   I148 @T6G_MB_LIB.T6G(SCH_1):PAGE51
  C712    2      2 Q_CAP_DIFFBUS_C0201-DIFF BUS_0.22UF,6.3V,20%,X6S,SA   I296 @T6G_MB_LIB.T6G(SCH_1):PAGE354

P5E_CPU1_P1_TX_DN<15> @T6G_MB_LIB.T6G(SCH_1):P5E_CPU1_P1_TX_DN(15)
   U26 CV40 P1_TXN15 GENOA_SP5-SOCKET6096_13568-001,SMLF,IO,DGA^6000030   I148 @T6G_MB_LIB.T6G(SCH_1):PAGE51
  C710    2      2 Q_CAP_DIFFBUS_C0201-DIFF BUS_0.22UF,6.3V,20%,X6S,SA   I299 @T6G_MB_LIB.T6G(SCH_1):PAGE354

P5E_CPU1_P1_TX_DN<1> @T6G_MB_LIB.T6G(SCH_1):P5E_CPU1_P1_TX_DN(1)
   U26 DA52 P1_TXN1 GENOA_SP5-SOCKET6096_13568-001,SMLF,IO,DGA^6000030   I148 @T6G_MB_LIB.T6G(SCH_1):PAGE51
  C738    2      2 Q_CAP_DIFFBUS_C0201-DIFF BUS_0.22UF,6.3V,20%,X6S,SA   I232 @T6G_MB_LIB.T6G(SCH_1):PAGE354

P5E_CPU1_P1_TX_DN<2> @T6G_MB_LIB.T6G(SCH_1):P5E_CPU1_P1_TX_DN(2)
   U26 DC52 P1_TXN2 GENOA_SP5-SOCKET6096_13568-001,SMLF,IO,DGA^6000030   I148 @T6G_MB_LIB.T6G(SCH_1):PAGE51
  C736    2      2 Q_CAP_DIFFBUS_C0201-DIFF BUS_0.22UF,6.3V,20%,X6S,SA   I234 @T6G_MB_LIB.T6G(SCH_1):PAGE354

P5E_CPU1_P1_TX_DN<3> @T6G_MB_LIB.T6G(SCH_1):P5E_CPU1_P1_TX_DN(3)
   U26 CW52 P1_TXN3 GENOA_SP5-SOCKET6096_13568-001,SMLF,IO,DGA^6000030   I148 @T6G_MB_LIB.T6G(SCH_1):PAGE51
  C734    2      2 Q_CAP_DIFFBUS_C0201-DIFF BUS_0.22UF,6.3V,20%,X6S,SA   I235 @T6G_MB_LIB.T6G(SCH_1):PAGE354

P5E_CPU1_P1_TX_DN<4> @T6G_MB_LIB.T6G(SCH_1):P5E_CPU1_P1_TX_DN(4)
   U26 DA49 P1_TXN4 GENOA_SP5-SOCKET6096_13568-001,SMLF,IO,DGA^6000030   I148 @T6G_MB_LIB.T6G(SCH_1):PAGE51
  C732    2      2 Q_CAP_DIFFBUS_C0201-DIFF BUS_0.22UF,6.3V,20%,X6S,SA   I246 @T6G_MB_LIB.T6G(SCH_1):PAGE354

P5E_CPU1_P1_TX_DN<5> @T6G_MB_LIB.T6G(SCH_1):P5E_CPU1_P1_TX_DN(5)
   U26 DC49 P1_TXN5 GENOA_SP5-SOCKET6096_13568-001,SMLF,IO,DGA^6000030   I148 @T6G_MB_LIB.T6G(SCH_1):PAGE51
  C730    2      2 Q_CAP_DIFFBUS_C0201-DIFF BUS_0.22UF,6.3V,20%,X6S,SA   I248 @T6G_MB_LIB.T6G(SCH_1):PAGE354

P5E_CPU1_P1_TX_DN<6> @T6G_MB_LIB.T6G(SCH_1):P5E_CPU1_P1_TX_DN(6)
   U26 CW49 P1_TXN6 GENOA_SP5-SOCKET6096_13568-001,SMLF,IO,DGA^6000030   I148 @T6G_MB_LIB.T6G(SCH_1):PAGE51
  C728    2      2 Q_CAP_DIFFBUS_C0201-DIFF BUS_0.22UF,6.3V,20%,X6S,SA   I250 @T6G_MB_LIB.T6G(SCH_1):PAGE354

P5E_CPU1_P1_TX_DN<7> @T6G_MB_LIB.T6G(SCH_1):P5E_CPU1_P1_TX_DN(7)
   U26 DA46 P1_TXN7 GENOA_SP5-SOCKET6096_13568-001,SMLF,IO,DGA^6000030   I148 @T6G_MB_LIB.T6G(SCH_1):PAGE51
  C726    2      2 Q_CAP_DIFFBUS_C0201-DIFF BUS_0.22UF,6.3V,20%,X6S,SA   I312 @T6G_MB_LIB.T6G(SCH_1):PAGE354

P5E_CPU1_P1_TX_DN<8> @T6G_MB_LIB.T6G(SCH_1):P5E_CPU1_P1_TX_DN(8)
   U26 DC46 P1_TXN8 GENOA_SP5-SOCKET6096_13568-001,SMLF,IO,DGA^6000030   I148 @T6G_MB_LIB.T6G(SCH_1):PAGE51
  C724    2      2 Q_CAP_DIFFBUS_C0201-DIFF BUS_0.22UF,6.3V,20%,X6S,SA   I275 @T6G_MB_LIB.T6G(SCH_1):PAGE354

P5E_CPU1_P1_TX_DN<9> @T6G_MB_LIB.T6G(SCH_1):P5E_CPU1_P1_TX_DN(9)
   U26 CW46 P1_TXN9 GENOA_SP5-SOCKET6096_13568-001,SMLF,IO,DGA^6000030   I148 @T6G_MB_LIB.T6G(SCH_1):PAGE51
  C722    2      2 Q_CAP_DIFFBUS_C0201-DIFF BUS_0.22UF,6.3V,20%,X6S,SA   I276 @T6G_MB_LIB.T6G(SCH_1):PAGE354

P5E_CPU1_P1_TX_DP<0> @T6G_MB_LIB.T6G(SCH_1):P5E_CPU1_P1_TX_DP(0)
   U26 CU53 P1_TXP0 GENOA_SP5-SOCKET6096_13568-001,SMLF,IO,DGA^6000030   I148 @T6G_MB_LIB.T6G(SCH_1):PAGE51
  C741    2      2 Q_CAP_DIFFBUS_C0201-DIFF BUS_0.22UF,6.3V,20%,X6S,SA   I230 @T6G_MB_LIB.T6G(SCH_1):PAGE354

P5E_CPU1_P1_TX_DP<10> @T6G_MB_LIB.T6G(SCH_1):P5E_CPU1_P1_TX_DP(10)
   U26 DA44 P1_TXP10 GENOA_SP5-SOCKET6096_13568-001,SMLF,IO,DGA^6000030   I148 @T6G_MB_LIB.T6G(SCH_1):PAGE51
  C721    2      2 Q_CAP_DIFFBUS_C0201-DIFF BUS_0.22UF,6.3V,20%,X6S,SA   I278 @T6G_MB_LIB.T6G(SCH_1):PAGE354

P5E_CPU1_P1_TX_DP<11> @T6G_MB_LIB.T6G(SCH_1):P5E_CPU1_P1_TX_DP(11)
   U26 DC44 P1_TXP11 GENOA_SP5-SOCKET6096_13568-001,SMLF,IO,DGA^6000030   I148 @T6G_MB_LIB.T6G(SCH_1):PAGE51
  C719    2      2 Q_CAP_DIFFBUS_C0201-DIFF BUS_0.22UF,6.3V,20%,X6S,SA   I280 @T6G_MB_LIB.T6G(SCH_1):PAGE354

P5E_CPU1_P1_TX_DP<12> @T6G_MB_LIB.T6G(SCH_1):P5E_CPU1_P1_TX_DP(12)
   U26 CW44 P1_TXP12 GENOA_SP5-SOCKET6096_13568-001,SMLF,IO,DGA^6000030   I148 @T6G_MB_LIB.T6G(SCH_1):PAGE51
  C717    2      2 Q_CAP_DIFFBUS_C0201-DIFF BUS_0.22UF,6.3V,20%,X6S,SA   I282 @T6G_MB_LIB.T6G(SCH_1):PAGE354

P5E_CPU1_P1_TX_DP<13> @T6G_MB_LIB.T6G(SCH_1):P5E_CPU1_P1_TX_DP(13)
   U26 DB41 P1_TXP13 GENOA_SP5-SOCKET6096_13568-001,SMLF,IO,DGA^6000030   I148 @T6G_MB_LIB.T6G(SCH_1):PAGE51
  C715    2      2 Q_CAP_DIFFBUS_C0201-DIFF BUS_0.22UF,6.3V,20%,X6S,SA   I294 @T6G_MB_LIB.T6G(SCH_1):PAGE354

P5E_CPU1_P1_TX_DP<14> @T6G_MB_LIB.T6G(SCH_1):P5E_CPU1_P1_TX_DP(14)
   U26 CY41 P1_TXP14 GENOA_SP5-SOCKET6096_13568-001,SMLF,IO,DGA^6000030   I148 @T6G_MB_LIB.T6G(SCH_1):PAGE51
  C713    2      2 Q_CAP_DIFFBUS_C0201-DIFF BUS_0.22UF,6.3V,20%,X6S,SA   I297 @T6G_MB_LIB.T6G(SCH_1):PAGE354

P5E_CPU1_P1_TX_DP<15> @T6G_MB_LIB.T6G(SCH_1):P5E_CPU1_P1_TX_DP(15)
   U26 CV41 P1_TXP15 GENOA_SP5-SOCKET6096_13568-001,SMLF,IO,DGA^6000030   I148 @T6G_MB_LIB.T6G(SCH_1):PAGE51
  C711    2      2 Q_CAP_DIFFBUS_C0201-DIFF BUS_0.22UF,6.3V,20%,X6S,SA   I298 @T6G_MB_LIB.T6G(SCH_1):PAGE354

P5E_CPU1_P1_TX_DP<1> @T6G_MB_LIB.T6G(SCH_1):P5E_CPU1_P1_TX_DP(1)
   U26 DA53 P1_TXP1 GENOA_SP5-SOCKET6096_13568-001,SMLF,IO,DGA^6000030   I148 @T6G_MB_LIB.T6G(SCH_1):PAGE51
  C739    2      2 Q_CAP_DIFFBUS_C0201-DIFF BUS_0.22UF,6.3V,20%,X6S,SA   I231 @T6G_MB_LIB.T6G(SCH_1):PAGE354

P5E_CPU1_P1_TX_DP<2> @T6G_MB_LIB.T6G(SCH_1):P5E_CPU1_P1_TX_DP(2)
   U26 DC53 P1_TXP2 GENOA_SP5-SOCKET6096_13568-001,SMLF,IO,DGA^6000030   I148 @T6G_MB_LIB.T6G(SCH_1):PAGE51
  C737    2      2 Q_CAP_DIFFBUS_C0201-DIFF BUS_0.22UF,6.3V,20%,X6S,SA   I233 @T6G_MB_LIB.T6G(SCH_1):PAGE354

P5E_CPU1_P1_TX_DP<3> @T6G_MB_LIB.T6G(SCH_1):P5E_CPU1_P1_TX_DP(3)
   U26 CW53 P1_TXP3 GENOA_SP5-SOCKET6096_13568-001,SMLF,IO,DGA^6000030   I148 @T6G_MB_LIB.T6G(SCH_1):PAGE51
  C735    2      2 Q_CAP_DIFFBUS_C0201-DIFF BUS_0.22UF,6.3V,20%,X6S,SA   I236 @T6G_MB_LIB.T6G(SCH_1):PAGE354

P5E_CPU1_P1_TX_DP<4> @T6G_MB_LIB.T6G(SCH_1):P5E_CPU1_P1_TX_DP(4)
   U26 DA50 P1_TXP4 GENOA_SP5-SOCKET6096_13568-001,SMLF,IO,DGA^6000030   I148 @T6G_MB_LIB.T6G(SCH_1):PAGE51
  C733    2      2 Q_CAP_DIFFBUS_C0201-DIFF BUS_0.22UF,6.3V,20%,X6S,SA   I237 @T6G_MB_LIB.T6G(SCH_1):PAGE354

P5E_CPU1_P1_TX_DP<5> @T6G_MB_LIB.T6G(SCH_1):P5E_CPU1_P1_TX_DP(5)
   U26 DC50 P1_TXP5 GENOA_SP5-SOCKET6096_13568-001,SMLF,IO,DGA^6000030   I148 @T6G_MB_LIB.T6G(SCH_1):PAGE51
  C731    2      2 Q_CAP_DIFFBUS_C0201-DIFF BUS_0.22UF,6.3V,20%,X6S,SA   I247 @T6G_MB_LIB.T6G(SCH_1):PAGE354

P5E_CPU1_P1_TX_DP<6> @T6G_MB_LIB.T6G(SCH_1):P5E_CPU1_P1_TX_DP(6)
   U26 CW50 P1_TXP6 GENOA_SP5-SOCKET6096_13568-001,SMLF,IO,DGA^6000030   I148 @T6G_MB_LIB.T6G(SCH_1):PAGE51
  C729    2      2 Q_CAP_DIFFBUS_C0201-DIFF BUS_0.22UF,6.3V,20%,X6S,SA   I249 @T6G_MB_LIB.T6G(SCH_1):PAGE354

P5E_CPU1_P1_TX_DP<7> @T6G_MB_LIB.T6G(SCH_1):P5E_CPU1_P1_TX_DP(7)
   U26 DA47 P1_TXP7 GENOA_SP5-SOCKET6096_13568-001,SMLF,IO,DGA^6000030   I148 @T6G_MB_LIB.T6G(SCH_1):PAGE51
  C727    2      2 Q_CAP_DIFFBUS_C0201-DIFF BUS_0.22UF,6.3V,20%,X6S,SA   I251 @T6G_MB_LIB.T6G(SCH_1):PAGE354

P5E_CPU1_P1_TX_DP<8> @T6G_MB_LIB.T6G(SCH_1):P5E_CPU1_P1_TX_DP(8)
   U26 DC47 P1_TXP8 GENOA_SP5-SOCKET6096_13568-001,SMLF,IO,DGA^6000030   I148 @T6G_MB_LIB.T6G(SCH_1):PAGE51
  C725    2      2 Q_CAP_DIFFBUS_C0201-DIFF BUS_0.22UF,6.3V,20%,X6S,SA   I274 @T6G_MB_LIB.T6G(SCH_1):PAGE354

P5E_CPU1_P1_TX_DP<9> @T6G_MB_LIB.T6G(SCH_1):P5E_CPU1_P1_TX_DP(9)
   U26 CW47 P1_TXP9 GENOA_SP5-SOCKET6096_13568-001,SMLF,IO,DGA^6000030   I148 @T6G_MB_LIB.T6G(SCH_1):PAGE51
  C723    2      2 Q_CAP_DIFFBUS_C0201-DIFF BUS_0.22UF,6.3V,20%,X6S,SA   I277 @T6G_MB_LIB.T6G(SCH_1):PAGE354

P5E_CPU1_P2_RX_BUF_DN<0> @T6G_MB_LIB.T6G(SCH_1):P5E_CPU1_P2_RX_BUF_DN(0)
 U6016  EV2 A_PERN15 PT5161LRS-PT5161LRS,SMLF,IC,AJ051610U03    I38 @T6G_MB_LIB.T6G(SCH_1):PAGE449
  J110   C1     C1 CONN112_10137002101LF-CONN112_10137002-101LF,THLF,A    I76 @T6G_MB_LIB.T6G(SCH_1):PAGE318

P5E_CPU1_P2_RX_BUF_DN<10> @T6G_MB_LIB.T6G(SCH_1):P5E_CPU1_P2_RX_BUF_DN(10)
 U6016  BH2 A_PERN5 PT5161LRS-PT5161LRS,SMLF,IC,AJ051610U03     I1 @T6G_MB_LIB.T6G(SCH_1):PAGE449
  J109   C3     C3 CONN112_10137002101LF-CONN112_10137002-101LF,THLF,A    I76 @T6G_MB_LIB.T6G(SCH_1):PAGE319

P5E_CPU1_P2_RX_BUF_DN<11> @T6G_MB_LIB.T6G(SCH_1):P5E_CPU1_P2_RX_BUF_DN(11)
 U6016  BA2 A_PERN4 PT5161LRS-PT5161LRS,SMLF,IC,AJ051610U03     I1 @T6G_MB_LIB.T6G(SCH_1):PAGE449
  J109   B4     B4 CONN112_10137002101LF-CONN112_10137002-101LF,THLF,A    I76 @T6G_MB_LIB.T6G(SCH_1):PAGE319

P5E_CPU1_P2_RX_BUF_DN<12> @T6G_MB_LIB.T6G(SCH_1):P5E_CPU1_P2_RX_BUF_DN(12)
 U6016  AP2 A_PERN3 PT5161LRS-PT5161LRS,SMLF,IC,AJ051610U03     I1 @T6G_MB_LIB.T6G(SCH_1):PAGE449
  J109   C5     C5 CONN112_10137002101LF-CONN112_10137002-101LF,THLF,A    I16 @T6G_MB_LIB.T6G(SCH_1):PAGE319

P5E_CPU1_P2_RX_BUF_DN<13> @T6G_MB_LIB.T6G(SCH_1):P5E_CPU1_P2_RX_BUF_DN(13)
 U6016  AG2 A_PERN2 PT5161LRS-PT5161LRS,SMLF,IC,AJ051610U03     I1 @T6G_MB_LIB.T6G(SCH_1):PAGE449
  J109   B6     B6 CONN112_10137002101LF-CONN112_10137002-101LF,THLF,A    I16 @T6G_MB_LIB.T6G(SCH_1):PAGE319

P5E_CPU1_P2_RX_BUF_DN<14> @T6G_MB_LIB.T6G(SCH_1):P5E_CPU1_P2_RX_BUF_DN(14)
 U6016   Y2 A_PERN1 PT5161LRS-PT5161LRS,SMLF,IC,AJ051610U03     I1 @T6G_MB_LIB.T6G(SCH_1):PAGE449
  J109   C7     C7 CONN112_10137002101LF-CONN112_10137002-101LF,THLF,A    I16 @T6G_MB_LIB.T6G(SCH_1):PAGE319

P5E_CPU1_P2_RX_BUF_DN<15> @T6G_MB_LIB.T6G(SCH_1):P5E_CPU1_P2_RX_BUF_DN(15)
 U6016   N2 A_PERN0 PT5161LRS-PT5161LRS,SMLF,IC,AJ051610U03     I1 @T6G_MB_LIB.T6G(SCH_1):PAGE449
  J109   B8     B8 CONN112_10137002101LF-CONN112_10137002-101LF,THLF,A    I16 @T6G_MB_LIB.T6G(SCH_1):PAGE319

P5E_CPU1_P2_RX_BUF_DN<1> @T6G_MB_LIB.T6G(SCH_1):P5E_CPU1_P2_RX_BUF_DN(1)
 U6016  EL2 A_PERN14 PT5161LRS-PT5161LRS,SMLF,IC,AJ051610U03    I38 @T6G_MB_LIB.T6G(SCH_1):PAGE449
  J110   B2     B2 CONN112_10137002101LF-CONN112_10137002-101LF,THLF,A    I76 @T6G_MB_LIB.T6G(SCH_1):PAGE318

P5E_CPU1_P2_RX_BUF_DN<2> @T6G_MB_LIB.T6G(SCH_1):P5E_CPU1_P2_RX_BUF_DN(2)
 U6016  ED2 A_PERN13 PT5161LRS-PT5161LRS,SMLF,IC,AJ051610U03    I38 @T6G_MB_LIB.T6G(SCH_1):PAGE449
  J110   C3     C3 CONN112_10137002101LF-CONN112_10137002-101LF,THLF,A    I76 @T6G_MB_LIB.T6G(SCH_1):PAGE318

P5E_CPU1_P2_RX_BUF_DN<3> @T6G_MB_LIB.T6G(SCH_1):P5E_CPU1_P2_RX_BUF_DN(3)
 U6016  DU2 A_PERN12 PT5161LRS-PT5161LRS,SMLF,IC,AJ051610U03    I38 @T6G_MB_LIB.T6G(SCH_1):PAGE449
  J110   B4     B4 CONN112_10137002101LF-CONN112_10137002-101LF,THLF,A    I76 @T6G_MB_LIB.T6G(SCH_1):PAGE318

P5E_CPU1_P2_RX_BUF_DN<4> @T6G_MB_LIB.T6G(SCH_1):P5E_CPU1_P2_RX_BUF_DN(4)
 U6016  DK2 A_PERN11 PT5161LRS-PT5161LRS,SMLF,IC,AJ051610U03    I38 @T6G_MB_LIB.T6G(SCH_1):PAGE449
  J110   C5     C5 CONN112_10137002101LF-CONN112_10137002-101LF,THLF,A    I16 @T6G_MB_LIB.T6G(SCH_1):PAGE318

P5E_CPU1_P2_RX_BUF_DN<5> @T6G_MB_LIB.T6G(SCH_1):P5E_CPU1_P2_RX_BUF_DN(5)
 U6016  DC2 A_PERN10 PT5161LRS-PT5161LRS,SMLF,IC,AJ051610U03    I38 @T6G_MB_LIB.T6G(SCH_1):PAGE449
  J110   B6     B6 CONN112_10137002101LF-CONN112_10137002-101LF,THLF,A    I16 @T6G_MB_LIB.T6G(SCH_1):PAGE318

P5E_CPU1_P2_RX_BUF_DN<6> @T6G_MB_LIB.T6G(SCH_1):P5E_CPU1_P2_RX_BUF_DN(6)
 U6016  CT2 A_PERN9 PT5161LRS-PT5161LRS,SMLF,IC,AJ051610U03    I38 @T6G_MB_LIB.T6G(SCH_1):PAGE449
  J110   C7     C7 CONN112_10137002101LF-CONN112_10137002-101LF,THLF,A    I16 @T6G_MB_LIB.T6G(SCH_1):PAGE318

P5E_CPU1_P2_RX_BUF_DN<7> @T6G_MB_LIB.T6G(SCH_1):P5E_CPU1_P2_RX_BUF_DN(7)
 U6016  CJ2 A_PERN8 PT5161LRS-PT5161LRS,SMLF,IC,AJ051610U03    I38 @T6G_MB_LIB.T6G(SCH_1):PAGE449
  J110   B8     B8 CONN112_10137002101LF-CONN112_10137002-101LF,THLF,A    I16 @T6G_MB_LIB.T6G(SCH_1):PAGE318

P5E_CPU1_P2_RX_BUF_DN<8> @T6G_MB_LIB.T6G(SCH_1):P5E_CPU1_P2_RX_BUF_DN(8)
 U6016  CB2 A_PERN7 PT5161LRS-PT5161LRS,SMLF,IC,AJ051610U03     I1 @T6G_MB_LIB.T6G(SCH_1):PAGE449
  J109   C1     C1 CONN112_10137002101LF-CONN112_10137002-101LF,THLF,A    I76 @T6G_MB_LIB.T6G(SCH_1):PAGE319

P5E_CPU1_P2_RX_BUF_DN<9> @T6G_MB_LIB.T6G(SCH_1):P5E_CPU1_P2_RX_BUF_DN(9)
 U6016  BR2 A_PERN6 PT5161LRS-PT5161LRS,SMLF,IC,AJ051610U03     I1 @T6G_MB_LIB.T6G(SCH_1):PAGE449
  J109   B2     B2 CONN112_10137002101LF-CONN112_10137002-101LF,THLF,A    I76 @T6G_MB_LIB.T6G(SCH_1):PAGE319

P5E_CPU1_P2_RX_BUF_DP<0> @T6G_MB_LIB.T6G(SCH_1):P5E_CPU1_P2_RX_BUF_DP(0)
 U6016  EY1 A_PERP15 PT5161LRS-PT5161LRS,SMLF,IC,AJ051610U03    I38 @T6G_MB_LIB.T6G(SCH_1):PAGE449
  J110   D1     D1 CONN112_10137002101LF-CONN112_10137002-101LF,THLF,A    I76 @T6G_MB_LIB.T6G(SCH_1):PAGE318

P5E_CPU1_P2_RX_BUF_DP<10> @T6G_MB_LIB.T6G(SCH_1):P5E_CPU1_P2_RX_BUF_DP(10)
 U6016  BK1 A_PERP5 PT5161LRS-PT5161LRS,SMLF,IC,AJ051610U03     I1 @T6G_MB_LIB.T6G(SCH_1):PAGE449
  J109   D3     D3 CONN112_10137002101LF-CONN112_10137002-101LF,THLF,A    I76 @T6G_MB_LIB.T6G(SCH_1):PAGE319

P5E_CPU1_P2_RX_BUF_DP<11> @T6G_MB_LIB.T6G(SCH_1):P5E_CPU1_P2_RX_BUF_DP(11)
 U6016  BC1 A_PERP4 PT5161LRS-PT5161LRS,SMLF,IC,AJ051610U03     I1 @T6G_MB_LIB.T6G(SCH_1):PAGE449
  J109   C4     C4 CONN112_10137002101LF-CONN112_10137002-101LF,THLF,A    I76 @T6G_MB_LIB.T6G(SCH_1):PAGE319

P5E_CPU1_P2_RX_BUF_DP<12> @T6G_MB_LIB.T6G(SCH_1):P5E_CPU1_P2_RX_BUF_DP(12)
 U6016  AT1 A_PERP3 PT5161LRS-PT5161LRS,SMLF,IC,AJ051610U03     I1 @T6G_MB_LIB.T6G(SCH_1):PAGE449
  J109   D5     D5 CONN112_10137002101LF-CONN112_10137002-101LF,THLF,A    I16 @T6G_MB_LIB.T6G(SCH_1):PAGE319

P5E_CPU1_P2_RX_BUF_DP<13> @T6G_MB_LIB.T6G(SCH_1):P5E_CPU1_P2_RX_BUF_DP(13)
 U6016  AJ1 A_PERP2 PT5161LRS-PT5161LRS,SMLF,IC,AJ051610U03     I1 @T6G_MB_LIB.T6G(SCH_1):PAGE449
  J109   C6     C6 CONN112_10137002101LF-CONN112_10137002-101LF,THLF,A    I16 @T6G_MB_LIB.T6G(SCH_1):PAGE319

P5E_CPU1_P2_RX_BUF_DP<14> @T6G_MB_LIB.T6G(SCH_1):P5E_CPU1_P2_RX_BUF_DP(14)
 U6016  AB1 A_PERP1 PT5161LRS-PT5161LRS,SMLF,IC,AJ051610U03     I1 @T6G_MB_LIB.T6G(SCH_1):PAGE449
  J109   D7     D7 CONN112_10137002101LF-CONN112_10137002-101LF,THLF,A    I16 @T6G_MB_LIB.T6G(SCH_1):PAGE319

P5E_CPU1_P2_RX_BUF_DP<15> @T6G_MB_LIB.T6G(SCH_1):P5E_CPU1_P2_RX_BUF_DP(15)
 U6016   R1 A_PERP0 PT5161LRS-PT5161LRS,SMLF,IC,AJ051610U03     I1 @T6G_MB_LIB.T6G(SCH_1):PAGE449
  J109   C8     C8 CONN112_10137002101LF-CONN112_10137002-101LF,THLF,A    I16 @T6G_MB_LIB.T6G(SCH_1):PAGE319

P5E_CPU1_P2_RX_BUF_DP<1> @T6G_MB_LIB.T6G(SCH_1):P5E_CPU1_P2_RX_BUF_DP(1)
 U6016  EN1 A_PERP14 PT5161LRS-PT5161LRS,SMLF,IC,AJ051610U03    I38 @T6G_MB_LIB.T6G(SCH_1):PAGE449
  J110   C2     C2 CONN112_10137002101LF-CONN112_10137002-101LF,THLF,A    I76 @T6G_MB_LIB.T6G(SCH_1):PAGE318

P5E_CPU1_P2_RX_BUF_DP<2> @T6G_MB_LIB.T6G(SCH_1):P5E_CPU1_P2_RX_BUF_DP(2)
 U6016  EF1 A_PERP13 PT5161LRS-PT5161LRS,SMLF,IC,AJ051610U03    I38 @T6G_MB_LIB.T6G(SCH_1):PAGE449
  J110   D3     D3 CONN112_10137002101LF-CONN112_10137002-101LF,THLF,A    I76 @T6G_MB_LIB.T6G(SCH_1):PAGE318

P5E_CPU1_P2_RX_BUF_DP<3> @T6G_MB_LIB.T6G(SCH_1):P5E_CPU1_P2_RX_BUF_DP(3)
 U6016  DW1 A_PERP12 PT5161LRS-PT5161LRS,SMLF,IC,AJ051610U03    I38 @T6G_MB_LIB.T6G(SCH_1):PAGE449
  J110   C4     C4 CONN112_10137002101LF-CONN112_10137002-101LF,THLF,A    I76 @T6G_MB_LIB.T6G(SCH_1):PAGE318

P5E_CPU1_P2_RX_BUF_DP<4> @T6G_MB_LIB.T6G(SCH_1):P5E_CPU1_P2_RX_BUF_DP(4)
 U6016  DM1 A_PERP11 PT5161LRS-PT5161LRS,SMLF,IC,AJ051610U03    I38 @T6G_MB_LIB.T6G(SCH_1):PAGE449
  J110   D5     D5 CONN112_10137002101LF-CONN112_10137002-101LF,THLF,A    I16 @T6G_MB_LIB.T6G(SCH_1):PAGE318

P5E_CPU1_P2_RX_BUF_DP<5> @T6G_MB_LIB.T6G(SCH_1):P5E_CPU1_P2_RX_BUF_DP(5)
 U6016  DE1 A_PERP10 PT5161LRS-PT5161LRS,SMLF,IC,AJ051610U03    I38 @T6G_MB_LIB.T6G(SCH_1):PAGE449
  J110   C6     C6 CONN112_10137002101LF-CONN112_10137002-101LF,THLF,A    I16 @T6G_MB_LIB.T6G(SCH_1):PAGE318

P5E_CPU1_P2_RX_BUF_DP<6> @T6G_MB_LIB.T6G(SCH_1):P5E_CPU1_P2_RX_BUF_DP(6)
 U6016  CV1 A_PERP9 PT5161LRS-PT5161LRS,SMLF,IC,AJ051610U03    I38 @T6G_MB_LIB.T6G(SCH_1):PAGE449
  J110   D7     D7 CONN112_10137002101LF-CONN112_10137002-101LF,THLF,A    I16 @T6G_MB_LIB.T6G(SCH_1):PAGE318

P5E_CPU1_P2_RX_BUF_DP<7> @T6G_MB_LIB.T6G(SCH_1):P5E_CPU1_P2_RX_BUF_DP(7)
 U6016  CL1 A_PERP8 PT5161LRS-PT5161LRS,SMLF,IC,AJ051610U03    I38 @T6G_MB_LIB.T6G(SCH_1):PAGE449
  J110   C8     C8 CONN112_10137002101LF-CONN112_10137002-101LF,THLF,A    I16 @T6G_MB_LIB.T6G(SCH_1):PAGE318

P5E_CPU1_P2_RX_BUF_DP<8> @T6G_MB_LIB.T6G(SCH_1):P5E_CPU1_P2_RX_BUF_DP(8)
 U6016  CD1 A_PERP7 PT5161LRS-PT5161LRS,SMLF,IC,AJ051610U03     I1 @T6G_MB_LIB.T6G(SCH_1):PAGE449
  J109   D1     D1 CONN112_10137002101LF-CONN112_10137002-101LF,THLF,A    I76 @T6G_MB_LIB.T6G(SCH_1):PAGE319

P5E_CPU1_P2_RX_BUF_DP<9> @T6G_MB_LIB.T6G(SCH_1):P5E_CPU1_P2_RX_BUF_DP(9)
 U6016  BU1 A_PERP6 PT5161LRS-PT5161LRS,SMLF,IC,AJ051610U03     I1 @T6G_MB_LIB.T6G(SCH_1):PAGE449
  J109   C2     C2 CONN112_10137002101LF-CONN112_10137002-101LF,THLF,A    I76 @T6G_MB_LIB.T6G(SCH_1):PAGE319

P5E_CPU1_P2_RX_DN<0> @T6G_MB_LIB.T6G(SCH_1):P5E_CPU1_P2_RX_DN(0)
   U26 CM36 P2_RXN0 GENOA_SP5-SOCKET6096_13568-001,SMLF,IO,DGA^6000030   I148 @T6G_MB_LIB.T6G(SCH_1):PAGE52
 U6016 EW29 A_PETN15 PT5161LRS-PT5161LRS,SMLF,IC,AJ051610U03    I38 @T6G_MB_LIB.T6G(SCH_1):PAGE448

P5E_CPU1_P2_RX_DN<10> @T6G_MB_LIB.T6G(SCH_1):P5E_CPU1_P2_RX_DN(10)
   U26 CU27 P2_RXN10 GENOA_SP5-SOCKET6096_13568-001,SMLF,IO,DGA^6000030   I148 @T6G_MB_LIB.T6G(SCH_1):PAGE52
 U6016 BJ29 A_PETN5 PT5161LRS-PT5161LRS,SMLF,IC,AJ051610U03     I1 @T6G_MB_LIB.T6G(SCH_1):PAGE448

P5E_CPU1_P2_RX_DN<11> @T6G_MB_LIB.T6G(SCH_1):P5E_CPU1_P2_RX_DN(11)
   U26 CR27 P2_RXN11 GENOA_SP5-SOCKET6096_13568-001,SMLF,IO,DGA^6000030   I148 @T6G_MB_LIB.T6G(SCH_1):PAGE52
 U6016 BB29 A_PETN4 PT5161LRS-PT5161LRS,SMLF,IC,AJ051610U03     I1 @T6G_MB_LIB.T6G(SCH_1):PAGE448

P5E_CPU1_P2_RX_DN<12> @T6G_MB_LIB.T6G(SCH_1):P5E_CPU1_P2_RX_DN(12)
   U26 CN27 P2_RXN12 GENOA_SP5-SOCKET6096_13568-001,SMLF,IO,DGA^6000030   I148 @T6G_MB_LIB.T6G(SCH_1):PAGE52
 U6016 AR29 A_PETN3 PT5161LRS-PT5161LRS,SMLF,IC,AJ051610U03     I1 @T6G_MB_LIB.T6G(SCH_1):PAGE448

P5E_CPU1_P2_RX_DN<13> @T6G_MB_LIB.T6G(SCH_1):P5E_CPU1_P2_RX_DN(13)
   U26 CL24 P2_RXN13 GENOA_SP5-SOCKET6096_13568-001,SMLF,IO,DGA^6000030   I148 @T6G_MB_LIB.T6G(SCH_1):PAGE52
 U6016 AH29 A_PETN2 PT5161LRS-PT5161LRS,SMLF,IC,AJ051610U03     I1 @T6G_MB_LIB.T6G(SCH_1):PAGE448

P5E_CPU1_P2_RX_DN<14> @T6G_MB_LIB.T6G(SCH_1):P5E_CPU1_P2_RX_DN(14)
   U26 CR24 P2_RXN14 GENOA_SP5-SOCKET6096_13568-001,SMLF,IO,DGA^6000030   I148 @T6G_MB_LIB.T6G(SCH_1):PAGE52
 U6016 AA29 A_PETN1 PT5161LRS-PT5161LRS,SMLF,IC,AJ051610U03     I1 @T6G_MB_LIB.T6G(SCH_1):PAGE448

P5E_CPU1_P2_RX_DN<15> @T6G_MB_LIB.T6G(SCH_1):P5E_CPU1_P2_RX_DN(15)
   U26 CN24 P2_RXN15 GENOA_SP5-SOCKET6096_13568-001,SMLF,IO,DGA^6000030   I148 @T6G_MB_LIB.T6G(SCH_1):PAGE52
 U6016  P29 A_PETN0 PT5161LRS-PT5161LRS,SMLF,IC,AJ051610U03     I1 @T6G_MB_LIB.T6G(SCH_1):PAGE448

P5E_CPU1_P2_RX_DN<1> @T6G_MB_LIB.T6G(SCH_1):P5E_CPU1_P2_RX_DN(1)
   U26 CP36 P2_RXN1 GENOA_SP5-SOCKET6096_13568-001,SMLF,IO,DGA^6000030   I148 @T6G_MB_LIB.T6G(SCH_1):PAGE52
 U6016 EM29 A_PETN14 PT5161LRS-PT5161LRS,SMLF,IC,AJ051610U03    I38 @T6G_MB_LIB.T6G(SCH_1):PAGE448

P5E_CPU1_P2_RX_DN<2> @T6G_MB_LIB.T6G(SCH_1):P5E_CPU1_P2_RX_DN(2)
   U26 CT36 P2_RXN2 GENOA_SP5-SOCKET6096_13568-001,SMLF,IO,DGA^6000030   I148 @T6G_MB_LIB.T6G(SCH_1):PAGE52
 U6016 EE29 A_PETN13 PT5161LRS-PT5161LRS,SMLF,IC,AJ051610U03    I38 @T6G_MB_LIB.T6G(SCH_1):PAGE448

P5E_CPU1_P2_RX_DN<3> @T6G_MB_LIB.T6G(SCH_1):P5E_CPU1_P2_RX_DN(3)
   U26 CN33 P2_RXN3 GENOA_SP5-SOCKET6096_13568-001,SMLF,IO,DGA^6000030   I148 @T6G_MB_LIB.T6G(SCH_1):PAGE52
 U6016 DV29 A_PETN12 PT5161LRS-PT5161LRS,SMLF,IC,AJ051610U03    I38 @T6G_MB_LIB.T6G(SCH_1):PAGE448

P5E_CPU1_P2_RX_DN<4> @T6G_MB_LIB.T6G(SCH_1):P5E_CPU1_P2_RX_DN(4)
   U26 CU33 P2_RXN4 GENOA_SP5-SOCKET6096_13568-001,SMLF,IO,DGA^6000030   I148 @T6G_MB_LIB.T6G(SCH_1):PAGE52
 U6016 DL29 A_PETN11 PT5161LRS-PT5161LRS,SMLF,IC,AJ051610U03    I38 @T6G_MB_LIB.T6G(SCH_1):PAGE448

P5E_CPU1_P2_RX_DN<5> @T6G_MB_LIB.T6G(SCH_1):P5E_CPU1_P2_RX_DN(5)
   U26 CR33 P2_RXN5 GENOA_SP5-SOCKET6096_13568-001,SMLF,IO,DGA^6000030   I148 @T6G_MB_LIB.T6G(SCH_1):PAGE52
 U6016 DD29 A_PETN10 PT5161LRS-PT5161LRS,SMLF,IC,AJ051610U03    I38 @T6G_MB_LIB.T6G(SCH_1):PAGE448

P5E_CPU1_P2_RX_DN<6> @T6G_MB_LIB.T6G(SCH_1):P5E_CPU1_P2_RX_DN(6)
   U26 CN30 P2_RXN6 GENOA_SP5-SOCKET6096_13568-001,SMLF,IO,DGA^6000030   I148 @T6G_MB_LIB.T6G(SCH_1):PAGE52
 U6016 CU29 A_PETN9 PT5161LRS-PT5161LRS,SMLF,IC,AJ051610U03    I38 @T6G_MB_LIB.T6G(SCH_1):PAGE448

P5E_CPU1_P2_RX_DN<7> @T6G_MB_LIB.T6G(SCH_1):P5E_CPU1_P2_RX_DN(7)
   U26 CU30 P2_RXN7 GENOA_SP5-SOCKET6096_13568-001,SMLF,IO,DGA^6000030   I148 @T6G_MB_LIB.T6G(SCH_1):PAGE52
 U6016 CK29 A_PETN8 PT5161LRS-PT5161LRS,SMLF,IC,AJ051610U03    I38 @T6G_MB_LIB.T6G(SCH_1):PAGE448

P5E_CPU1_P2_RX_DN<8> @T6G_MB_LIB.T6G(SCH_1):P5E_CPU1_P2_RX_DN(8)
   U26 CR30 P2_RXN8 GENOA_SP5-SOCKET6096_13568-001,SMLF,IO,DGA^6000030   I148 @T6G_MB_LIB.T6G(SCH_1):PAGE52
 U6016 CC29 A_PETN7 PT5161LRS-PT5161LRS,SMLF,IC,AJ051610U03     I1 @T6G_MB_LIB.T6G(SCH_1):PAGE448

P5E_CPU1_P2_RX_DN<9> @T6G_MB_LIB.T6G(SCH_1):P5E_CPU1_P2_RX_DN(9)
   U26 CL27 P2_RXN9 GENOA_SP5-SOCKET6096_13568-001,SMLF,IO,DGA^6000030   I148 @T6G_MB_LIB.T6G(SCH_1):PAGE52
 U6016 BT29 A_PETN6 PT5161LRS-PT5161LRS,SMLF,IC,AJ051610U03     I1 @T6G_MB_LIB.T6G(SCH_1):PAGE448

P5E_CPU1_P2_RX_DP<0> @T6G_MB_LIB.T6G(SCH_1):P5E_CPU1_P2_RX_DP(0)
   U26 CM35 P2_RXP0 GENOA_SP5-SOCKET6096_13568-001,SMLF,IO,DGA^6000030   I148 @T6G_MB_LIB.T6G(SCH_1):PAGE52
 U6016 EU26 A_PETP15 PT5161LRS-PT5161LRS,SMLF,IC,AJ051610U03    I38 @T6G_MB_LIB.T6G(SCH_1):PAGE448

P5E_CPU1_P2_RX_DP<10> @T6G_MB_LIB.T6G(SCH_1):P5E_CPU1_P2_RX_DP(10)
   U26 CU26 P2_RXP10 GENOA_SP5-SOCKET6096_13568-001,SMLF,IO,DGA^6000030   I148 @T6G_MB_LIB.T6G(SCH_1):PAGE52
 U6016 BG26 A_PETP5 PT5161LRS-PT5161LRS,SMLF,IC,AJ051610U03     I1 @T6G_MB_LIB.T6G(SCH_1):PAGE448

P5E_CPU1_P2_RX_DP<11> @T6G_MB_LIB.T6G(SCH_1):P5E_CPU1_P2_RX_DP(11)
   U26 CR26 P2_RXP11 GENOA_SP5-SOCKET6096_13568-001,SMLF,IO,DGA^6000030   I148 @T6G_MB_LIB.T6G(SCH_1):PAGE52
 U6016 AY26 A_PETP4 PT5161LRS-PT5161LRS,SMLF,IC,AJ051610U03     I1 @T6G_MB_LIB.T6G(SCH_1):PAGE448

P5E_CPU1_P2_RX_DP<12> @T6G_MB_LIB.T6G(SCH_1):P5E_CPU1_P2_RX_DP(12)
   U26 CN26 P2_RXP12 GENOA_SP5-SOCKET6096_13568-001,SMLF,IO,DGA^6000030   I148 @T6G_MB_LIB.T6G(SCH_1):PAGE52
 U6016 AN26 A_PETP3 PT5161LRS-PT5161LRS,SMLF,IC,AJ051610U03     I1 @T6G_MB_LIB.T6G(SCH_1):PAGE448

P5E_CPU1_P2_RX_DP<13> @T6G_MB_LIB.T6G(SCH_1):P5E_CPU1_P2_RX_DP(13)
   U26 CL23 P2_RXP13 GENOA_SP5-SOCKET6096_13568-001,SMLF,IO,DGA^6000030   I148 @T6G_MB_LIB.T6G(SCH_1):PAGE52
 U6016 AF26 A_PETP2 PT5161LRS-PT5161LRS,SMLF,IC,AJ051610U03     I1 @T6G_MB_LIB.T6G(SCH_1):PAGE448

P5E_CPU1_P2_RX_DP<14> @T6G_MB_LIB.T6G(SCH_1):P5E_CPU1_P2_RX_DP(14)
   U26 CR23 P2_RXP14 GENOA_SP5-SOCKET6096_13568-001,SMLF,IO,DGA^6000030   I148 @T6G_MB_LIB.T6G(SCH_1):PAGE52
 U6016  W26 A_PETP1 PT5161LRS-PT5161LRS,SMLF,IC,AJ051610U03     I1 @T6G_MB_LIB.T6G(SCH_1):PAGE448

P5E_CPU1_P2_RX_DP<15> @T6G_MB_LIB.T6G(SCH_1):P5E_CPU1_P2_RX_DP(15)
   U26 CN23 P2_RXP15 GENOA_SP5-SOCKET6096_13568-001,SMLF,IO,DGA^6000030   I148 @T6G_MB_LIB.T6G(SCH_1):PAGE52
 U6016  M26 A_PETP0 PT5161LRS-PT5161LRS,SMLF,IC,AJ051610U03     I1 @T6G_MB_LIB.T6G(SCH_1):PAGE448

P5E_CPU1_P2_RX_DP<1> @T6G_MB_LIB.T6G(SCH_1):P5E_CPU1_P2_RX_DP(1)
   U26 CP35 P2_RXP1 GENOA_SP5-SOCKET6096_13568-001,SMLF,IO,DGA^6000030   I148 @T6G_MB_LIB.T6G(SCH_1):PAGE52
 U6016 EK26 A_PETP14 PT5161LRS-PT5161LRS,SMLF,IC,AJ051610U03    I38 @T6G_MB_LIB.T6G(SCH_1):PAGE448

P5E_CPU1_P2_RX_DP<2> @T6G_MB_LIB.T6G(SCH_1):P5E_CPU1_P2_RX_DP(2)
   U26 CT35 P2_RXP2 GENOA_SP5-SOCKET6096_13568-001,SMLF,IO,DGA^6000030   I148 @T6G_MB_LIB.T6G(SCH_1):PAGE52
 U6016 EC26 A_PETP13 PT5161LRS-PT5161LRS,SMLF,IC,AJ051610U03    I38 @T6G_MB_LIB.T6G(SCH_1):PAGE448

P5E_CPU1_P2_RX_DP<3> @T6G_MB_LIB.T6G(SCH_1):P5E_CPU1_P2_RX_DP(3)
   U26 CN32 P2_RXP3 GENOA_SP5-SOCKET6096_13568-001,SMLF,IO,DGA^6000030   I148 @T6G_MB_LIB.T6G(SCH_1):PAGE52
 U6016 DT26 A_PETP12 PT5161LRS-PT5161LRS,SMLF,IC,AJ051610U03    I38 @T6G_MB_LIB.T6G(SCH_1):PAGE448

P5E_CPU1_P2_RX_DP<4> @T6G_MB_LIB.T6G(SCH_1):P5E_CPU1_P2_RX_DP(4)
   U26 CU32 P2_RXP4 GENOA_SP5-SOCKET6096_13568-001,SMLF,IO,DGA^6000030   I148 @T6G_MB_LIB.T6G(SCH_1):PAGE52
 U6016 DJ26 A_PETP11 PT5161LRS-PT5161LRS,SMLF,IC,AJ051610U03    I38 @T6G_MB_LIB.T6G(SCH_1):PAGE448

P5E_CPU1_P2_RX_DP<5> @T6G_MB_LIB.T6G(SCH_1):P5E_CPU1_P2_RX_DP(5)
   U26 CR32 P2_RXP5 GENOA_SP5-SOCKET6096_13568-001,SMLF,IO,DGA^6000030   I148 @T6G_MB_LIB.T6G(SCH_1):PAGE52
 U6016 DB26 A_PETP10 PT5161LRS-PT5161LRS,SMLF,IC,AJ051610U03    I38 @T6G_MB_LIB.T6G(SCH_1):PAGE448

P5E_CPU1_P2_RX_DP<6> @T6G_MB_LIB.T6G(SCH_1):P5E_CPU1_P2_RX_DP(6)
   U26 CN29 P2_RXP6 GENOA_SP5-SOCKET6096_13568-001,SMLF,IO,DGA^6000030   I148 @T6G_MB_LIB.T6G(SCH_1):PAGE52
 U6016 CR26 A_PETP9 PT5161LRS-PT5161LRS,SMLF,IC,AJ051610U03    I38 @T6G_MB_LIB.T6G(SCH_1):PAGE448

P5E_CPU1_P2_RX_DP<7> @T6G_MB_LIB.T6G(SCH_1):P5E_CPU1_P2_RX_DP(7)
   U26 CU29 P2_RXP7 GENOA_SP5-SOCKET6096_13568-001,SMLF,IO,DGA^6000030   I148 @T6G_MB_LIB.T6G(SCH_1):PAGE52
 U6016 CH26 A_PETP8 PT5161LRS-PT5161LRS,SMLF,IC,AJ051610U03    I38 @T6G_MB_LIB.T6G(SCH_1):PAGE448

P5E_CPU1_P2_RX_DP<8> @T6G_MB_LIB.T6G(SCH_1):P5E_CPU1_P2_RX_DP(8)
   U26 CR29 P2_RXP8 GENOA_SP5-SOCKET6096_13568-001,SMLF,IO,DGA^6000030   I148 @T6G_MB_LIB.T6G(SCH_1):PAGE52
 U6016 CA26 A_PETP7 PT5161LRS-PT5161LRS,SMLF,IC,AJ051610U03     I1 @T6G_MB_LIB.T6G(SCH_1):PAGE448

P5E_CPU1_P2_RX_DP<9> @T6G_MB_LIB.T6G(SCH_1):P5E_CPU1_P2_RX_DP(9)
   U26 CL26 P2_RXP9 GENOA_SP5-SOCKET6096_13568-001,SMLF,IO,DGA^6000030   I148 @T6G_MB_LIB.T6G(SCH_1):PAGE52
 U6016 BP26 A_PETP6 PT5161LRS-PT5161LRS,SMLF,IC,AJ051610U03     I1 @T6G_MB_LIB.T6G(SCH_1):PAGE448

P5E_CPU1_P2_TX_BUF_C_DN<0> @T6G_MB_LIB.T6G(SCH_1):P5E_CPU1_P2_TX_BUF_C_DN(0)
 C6694    1      1 Q_CAP_DIFFBUS_C0201-DIFF BUS_0.22UF,6.3V,20%,X6S,SA    I35 @T6G_MB_LIB.T6G(SCH_1):PAGE450
  J110   I1     I1 CONN112_10137002101LF-CONN112_10137002-101LF,THLF,A    I76 @T6G_MB_LIB.T6G(SCH_1):PAGE318

P5E_CPU1_P2_TX_BUF_C_DN<10> @T6G_MB_LIB.T6G(SCH_1):P5E_CPU1_P2_TX_BUF_C_DN(10)
 C6714    1      1 Q_CAP_DIFFBUS_C0201-DIFF BUS_0.22UF,6.3V,20%,X6S,SA    I96 @T6G_MB_LIB.T6G(SCH_1):PAGE450
  J109   I3     I3 CONN112_10137002101LF-CONN112_10137002-101LF,THLF,A    I76 @T6G_MB_LIB.T6G(SCH_1):PAGE319

P5E_CPU1_P2_TX_BUF_C_DN<11> @T6G_MB_LIB.T6G(SCH_1):P5E_CPU1_P2_TX_BUF_C_DN(11)
 C6716    1      1 Q_CAP_DIFFBUS_C0201-DIFF BUS_0.22UF,6.3V,20%,X6S,SA    I94 @T6G_MB_LIB.T6G(SCH_1):PAGE450
  J109   H4     H4 CONN112_10137002101LF-CONN112_10137002-101LF,THLF,A    I76 @T6G_MB_LIB.T6G(SCH_1):PAGE319

P5E_CPU1_P2_TX_BUF_C_DN<12> @T6G_MB_LIB.T6G(SCH_1):P5E_CPU1_P2_TX_BUF_C_DN(12)
 C6718    1      1 Q_CAP_DIFFBUS_C0201-DIFF BUS_0.22UF,6.3V,20%,X6S,SA    I92 @T6G_MB_LIB.T6G(SCH_1):PAGE450
  J109   I5     I5 CONN112_10137002101LF-CONN112_10137002-101LF,THLF,A    I16 @T6G_MB_LIB.T6G(SCH_1):PAGE319

P5E_CPU1_P2_TX_BUF_C_DN<13> @T6G_MB_LIB.T6G(SCH_1):P5E_CPU1_P2_TX_BUF_C_DN(13)
 C6720    1      1 Q_CAP_DIFFBUS_C0201-DIFF BUS_0.22UF,6.3V,20%,X6S,SA    I90 @T6G_MB_LIB.T6G(SCH_1):PAGE450
  J109   H6     H6 CONN112_10137002101LF-CONN112_10137002-101LF,THLF,A    I16 @T6G_MB_LIB.T6G(SCH_1):PAGE319

P5E_CPU1_P2_TX_BUF_C_DN<14> @T6G_MB_LIB.T6G(SCH_1):P5E_CPU1_P2_TX_BUF_C_DN(14)
 C6722    1      1 Q_CAP_DIFFBUS_C0201-DIFF BUS_0.22UF,6.3V,20%,X6S,SA    I83 @T6G_MB_LIB.T6G(SCH_1):PAGE450
  J109   I7     I7 CONN112_10137002101LF-CONN112_10137002-101LF,THLF,A    I16 @T6G_MB_LIB.T6G(SCH_1):PAGE319

P5E_CPU1_P2_TX_BUF_C_DN<15> @T6G_MB_LIB.T6G(SCH_1):P5E_CPU1_P2_TX_BUF_C_DN(15)
 C6724    1      1 Q_CAP_DIFFBUS_C0201-DIFF BUS_0.22UF,6.3V,20%,X6S,SA    I81 @T6G_MB_LIB.T6G(SCH_1):PAGE450
  J109   H8     H8 CONN112_10137002101LF-CONN112_10137002-101LF,THLF,A    I16 @T6G_MB_LIB.T6G(SCH_1):PAGE319

P5E_CPU1_P2_TX_BUF_C_DN<1> @T6G_MB_LIB.T6G(SCH_1):P5E_CPU1_P2_TX_BUF_C_DN(1)
 C6696    1      1 Q_CAP_DIFFBUS_C0201-DIFF BUS_0.22UF,6.3V,20%,X6S,SA    I28 @T6G_MB_LIB.T6G(SCH_1):PAGE450
  J110   H2     H2 CONN112_10137002101LF-CONN112_10137002-101LF,THLF,A    I76 @T6G_MB_LIB.T6G(SCH_1):PAGE318

P5E_CPU1_P2_TX_BUF_C_DN<2> @T6G_MB_LIB.T6G(SCH_1):P5E_CPU1_P2_TX_BUF_C_DN(2)
 C6698    1      1 Q_CAP_DIFFBUS_C0201-DIFF BUS_0.22UF,6.3V,20%,X6S,SA    I27 @T6G_MB_LIB.T6G(SCH_1):PAGE450
  J110   I3     I3 CONN112_10137002101LF-CONN112_10137002-101LF,THLF,A    I76 @T6G_MB_LIB.T6G(SCH_1):PAGE318

P5E_CPU1_P2_TX_BUF_C_DN<3> @T6G_MB_LIB.T6G(SCH_1):P5E_CPU1_P2_TX_BUF_C_DN(3)
 C6700    1      1 Q_CAP_DIFFBUS_C0201-DIFF BUS_0.22UF,6.3V,20%,X6S,SA    I26 @T6G_MB_LIB.T6G(SCH_1):PAGE450
  J110   H4     H4 CONN112_10137002101LF-CONN112_10137002-101LF,THLF,A    I76 @T6G_MB_LIB.T6G(SCH_1):PAGE318

P5E_CPU1_P2_TX_BUF_C_DN<4> @T6G_MB_LIB.T6G(SCH_1):P5E_CPU1_P2_TX_BUF_C_DN(4)
 C6702    1      1 Q_CAP_DIFFBUS_C0201-DIFF BUS_0.22UF,6.3V,20%,X6S,SA    I23 @T6G_MB_LIB.T6G(SCH_1):PAGE450
  J110   I5     I5 CONN112_10137002101LF-CONN112_10137002-101LF,THLF,A    I16 @T6G_MB_LIB.T6G(SCH_1):PAGE318

P5E_CPU1_P2_TX_BUF_C_DN<5> @T6G_MB_LIB.T6G(SCH_1):P5E_CPU1_P2_TX_BUF_C_DN(5)
 C6704    1      1 Q_CAP_DIFFBUS_C0201-DIFF BUS_0.22UF,6.3V,20%,X6S,SA    I21 @T6G_MB_LIB.T6G(SCH_1):PAGE450
  J110   H6     H6 CONN112_10137002101LF-CONN112_10137002-101LF,THLF,A    I16 @T6G_MB_LIB.T6G(SCH_1):PAGE318

P5E_CPU1_P2_TX_BUF_C_DN<6> @T6G_MB_LIB.T6G(SCH_1):P5E_CPU1_P2_TX_BUF_C_DN(6)
 C6706    1      1 Q_CAP_DIFFBUS_C0201-DIFF BUS_0.22UF,6.3V,20%,X6S,SA    I19 @T6G_MB_LIB.T6G(SCH_1):PAGE450
  J110   I7     I7 CONN112_10137002101LF-CONN112_10137002-101LF,THLF,A    I16 @T6G_MB_LIB.T6G(SCH_1):PAGE318

P5E_CPU1_P2_TX_BUF_C_DN<7> @T6G_MB_LIB.T6G(SCH_1):P5E_CPU1_P2_TX_BUF_C_DN(7)
 C6708    1      1 Q_CAP_DIFFBUS_C0201-DIFF BUS_0.22UF,6.3V,20%,X6S,SA    I17 @T6G_MB_LIB.T6G(SCH_1):PAGE450
  J110   H8     H8 CONN112_10137002101LF-CONN112_10137002-101LF,THLF,A    I16 @T6G_MB_LIB.T6G(SCH_1):PAGE318

P5E_CPU1_P2_TX_BUF_C_DN<8> @T6G_MB_LIB.T6G(SCH_1):P5E_CPU1_P2_TX_BUF_C_DN(8)
 C6710    1      1 Q_CAP_DIFFBUS_C0201-DIFF BUS_0.22UF,6.3V,20%,X6S,SA   I103 @T6G_MB_LIB.T6G(SCH_1):PAGE450
  J109   I1     I1 CONN112_10137002101LF-CONN112_10137002-101LF,THLF,A    I76 @T6G_MB_LIB.T6G(SCH_1):PAGE319

P5E_CPU1_P2_TX_BUF_C_DN<9> @T6G_MB_LIB.T6G(SCH_1):P5E_CPU1_P2_TX_BUF_C_DN(9)
 C6712    1      1 Q_CAP_DIFFBUS_C0201-DIFF BUS_0.22UF,6.3V,20%,X6S,SA    I98 @T6G_MB_LIB.T6G(SCH_1):PAGE450
  J109   H2     H2 CONN112_10137002101LF-CONN112_10137002-101LF,THLF,A    I76 @T6G_MB_LIB.T6G(SCH_1):PAGE319

P5E_CPU1_P2_TX_BUF_C_DP<0> @T6G_MB_LIB.T6G(SCH_1):P5E_CPU1_P2_TX_BUF_C_DP(0)
 C6693    1      1 Q_CAP_DIFFBUS_C0201-DIFF BUS_0.22UF,6.3V,20%,X6S,SA    I34 @T6G_MB_LIB.T6G(SCH_1):PAGE450
  J110   J1     J1 CONN112_10137002101LF-CONN112_10137002-101LF,THLF,A    I76 @T6G_MB_LIB.T6G(SCH_1):PAGE318

P5E_CPU1_P2_TX_BUF_C_DP<10> @T6G_MB_LIB.T6G(SCH_1):P5E_CPU1_P2_TX_BUF_C_DP(10)
 C6713    1      1 Q_CAP_DIFFBUS_C0201-DIFF BUS_0.22UF,6.3V,20%,X6S,SA    I97 @T6G_MB_LIB.T6G(SCH_1):PAGE450
  J109   J3     J3 CONN112_10137002101LF-CONN112_10137002-101LF,THLF,A    I76 @T6G_MB_LIB.T6G(SCH_1):PAGE319

P5E_CPU1_P2_TX_BUF_C_DP<11> @T6G_MB_LIB.T6G(SCH_1):P5E_CPU1_P2_TX_BUF_C_DP(11)
 C6715    1      1 Q_CAP_DIFFBUS_C0201-DIFF BUS_0.22UF,6.3V,20%,X6S,SA    I95 @T6G_MB_LIB.T6G(SCH_1):PAGE450
  J109   I4     I4 CONN112_10137002101LF-CONN112_10137002-101LF,THLF,A    I76 @T6G_MB_LIB.T6G(SCH_1):PAGE319

P5E_CPU1_P2_TX_BUF_C_DP<12> @T6G_MB_LIB.T6G(SCH_1):P5E_CPU1_P2_TX_BUF_C_DP(12)
 C6717    1      1 Q_CAP_DIFFBUS_C0201-DIFF BUS_0.22UF,6.3V,20%,X6S,SA    I93 @T6G_MB_LIB.T6G(SCH_1):PAGE450
  J109   J5     J5 CONN112_10137002101LF-CONN112_10137002-101LF,THLF,A    I16 @T6G_MB_LIB.T6G(SCH_1):PAGE319

P5E_CPU1_P2_TX_BUF_C_DP<13> @T6G_MB_LIB.T6G(SCH_1):P5E_CPU1_P2_TX_BUF_C_DP(13)
 C6719    1      1 Q_CAP_DIFFBUS_C0201-DIFF BUS_0.22UF,6.3V,20%,X6S,SA    I91 @T6G_MB_LIB.T6G(SCH_1):PAGE450
  J109   I6     I6 CONN112_10137002101LF-CONN112_10137002-101LF,THLF,A    I16 @T6G_MB_LIB.T6G(SCH_1):PAGE319

P5E_CPU1_P2_TX_BUF_C_DP<14> @T6G_MB_LIB.T6G(SCH_1):P5E_CPU1_P2_TX_BUF_C_DP(14)
 C6721    1      1 Q_CAP_DIFFBUS_C0201-DIFF BUS_0.22UF,6.3V,20%,X6S,SA    I84 @T6G_MB_LIB.T6G(SCH_1):PAGE450
  J109   J7     J7 CONN112_10137002101LF-CONN112_10137002-101LF,THLF,A    I16 @T6G_MB_LIB.T6G(SCH_1):PAGE319

P5E_CPU1_P2_TX_BUF_C_DP<15> @T6G_MB_LIB.T6G(SCH_1):P5E_CPU1_P2_TX_BUF_C_DP(15)
 C6723    1      1 Q_CAP_DIFFBUS_C0201-DIFF BUS_0.22UF,6.3V,20%,X6S,SA    I82 @T6G_MB_LIB.T6G(SCH_1):PAGE450
  J109   I8     I8 CONN112_10137002101LF-CONN112_10137002-101LF,THLF,A    I16 @T6G_MB_LIB.T6G(SCH_1):PAGE319

P5E_CPU1_P2_TX_BUF_C_DP<1> @T6G_MB_LIB.T6G(SCH_1):P5E_CPU1_P2_TX_BUF_C_DP(1)
 C6695    1      1 Q_CAP_DIFFBUS_C0201-DIFF BUS_0.22UF,6.3V,20%,X6S,SA    I29 @T6G_MB_LIB.T6G(SCH_1):PAGE450
  J110   I2     I2 CONN112_10137002101LF-CONN112_10137002-101LF,THLF,A    I76 @T6G_MB_LIB.T6G(SCH_1):PAGE318

P5E_CPU1_P2_TX_BUF_C_DP<2> @T6G_MB_LIB.T6G(SCH_1):P5E_CPU1_P2_TX_BUF_C_DP(2)
 C6697    1      1 Q_CAP_DIFFBUS_C0201-DIFF BUS_0.22UF,6.3V,20%,X6S,SA    I30 @T6G_MB_LIB.T6G(SCH_1):PAGE450
  J110   J3     J3 CONN112_10137002101LF-CONN112_10137002-101LF,THLF,A    I76 @T6G_MB_LIB.T6G(SCH_1):PAGE318

P5E_CPU1_P2_TX_BUF_C_DP<3> @T6G_MB_LIB.T6G(SCH_1):P5E_CPU1_P2_TX_BUF_C_DP(3)
 C6699    1      1 Q_CAP_DIFFBUS_C0201-DIFF BUS_0.22UF,6.3V,20%,X6S,SA    I25 @T6G_MB_LIB.T6G(SCH_1):PAGE450
  J110   I4     I4 CONN112_10137002101LF-CONN112_10137002-101LF,THLF,A    I76 @T6G_MB_LIB.T6G(SCH_1):PAGE318

P5E_CPU1_P2_TX_BUF_C_DP<4> @T6G_MB_LIB.T6G(SCH_1):P5E_CPU1_P2_TX_BUF_C_DP(4)
 C6701    1      1 Q_CAP_DIFFBUS_C0201-DIFF BUS_0.22UF,6.3V,20%,X6S,SA    I24 @T6G_MB_LIB.T6G(SCH_1):PAGE450
  J110   J5     J5 CONN112_10137002101LF-CONN112_10137002-101LF,THLF,A    I16 @T6G_MB_LIB.T6G(SCH_1):PAGE318

P5E_CPU1_P2_TX_BUF_C_DP<5> @T6G_MB_LIB.T6G(SCH_1):P5E_CPU1_P2_TX_BUF_C_DP(5)
 C6703    1      1 Q_CAP_DIFFBUS_C0201-DIFF BUS_0.22UF,6.3V,20%,X6S,SA    I22 @T6G_MB_LIB.T6G(SCH_1):PAGE450
  J110   I6     I6 CONN112_10137002101LF-CONN112_10137002-101LF,THLF,A    I16 @T6G_MB_LIB.T6G(SCH_1):PAGE318

P5E_CPU1_P2_TX_BUF_C_DP<6> @T6G_MB_LIB.T6G(SCH_1):P5E_CPU1_P2_TX_BUF_C_DP(6)
 C6705    1      1 Q_CAP_DIFFBUS_C0201-DIFF BUS_0.22UF,6.3V,20%,X6S,SA    I20 @T6G_MB_LIB.T6G(SCH_1):PAGE450
  J110   J7     J7 CONN112_10137002101LF-CONN112_10137002-101LF,THLF,A    I16 @T6G_MB_LIB.T6G(SCH_1):PAGE318

P5E_CPU1_P2_TX_BUF_C_DP<7> @T6G_MB_LIB.T6G(SCH_1):P5E_CPU1_P2_TX_BUF_C_DP(7)
 C6707    1      1 Q_CAP_DIFFBUS_C0201-DIFF BUS_0.22UF,6.3V,20%,X6S,SA    I18 @T6G_MB_LIB.T6G(SCH_1):PAGE450
  J110   I8     I8 CONN112_10137002101LF-CONN112_10137002-101LF,THLF,A    I16 @T6G_MB_LIB.T6G(SCH_1):PAGE318

P5E_CPU1_P2_TX_BUF_C_DP<8> @T6G_MB_LIB.T6G(SCH_1):P5E_CPU1_P2_TX_BUF_C_DP(8)
 C6709    1      1 Q_CAP_DIFFBUS_C0201-DIFF BUS_0.22UF,6.3V,20%,X6S,SA   I102 @T6G_MB_LIB.T6G(SCH_1):PAGE450
  J109   J1     J1 CONN112_10137002101LF-CONN112_10137002-101LF,THLF,A    I76 @T6G_MB_LIB.T6G(SCH_1):PAGE319

P5E_CPU1_P2_TX_BUF_C_DP<9> @T6G_MB_LIB.T6G(SCH_1):P5E_CPU1_P2_TX_BUF_C_DP(9)
 C6711    1      1 Q_CAP_DIFFBUS_C0201-DIFF BUS_0.22UF,6.3V,20%,X6S,SA    I99 @T6G_MB_LIB.T6G(SCH_1):PAGE450
  J109   I2     I2 CONN112_10137002101LF-CONN112_10137002-101LF,THLF,A    I76 @T6G_MB_LIB.T6G(SCH_1):PAGE319

P5E_CPU1_P2_TX_BUF_DN<0> @T6G_MB_LIB.T6G(SCH_1):P5E_CPU1_P2_TX_BUF_DN(0)
 C6694    2      2 Q_CAP_DIFFBUS_C0201-DIFF BUS_0.22UF,6.3V,20%,X6S,SA    I35 @T6G_MB_LIB.T6G(SCH_1):PAGE450
 U6016 EW10 B_PETN15 PT5161LRS-PT5161LRS,SMLF,IC,AJ051610U03   I142 @T6G_MB_LIB.T6G(SCH_1):PAGE450

P5E_CPU1_P2_TX_BUF_DN<10> @T6G_MB_LIB.T6G(SCH_1):P5E_CPU1_P2_TX_BUF_DN(10)
 U6016 BJ10 B_PETN5 PT5161LRS-PT5161LRS,SMLF,IC,AJ051610U03    I33 @T6G_MB_LIB.T6G(SCH_1):PAGE450
 C6714    2      2 Q_CAP_DIFFBUS_C0201-DIFF BUS_0.22UF,6.3V,20%,X6S,SA    I96 @T6G_MB_LIB.T6G(SCH_1):PAGE450

P5E_CPU1_P2_TX_BUF_DN<11> @T6G_MB_LIB.T6G(SCH_1):P5E_CPU1_P2_TX_BUF_DN(11)
 U6016 BB10 B_PETN4 PT5161LRS-PT5161LRS,SMLF,IC,AJ051610U03    I33 @T6G_MB_LIB.T6G(SCH_1):PAGE450
 C6716    2      2 Q_CAP_DIFFBUS_C0201-DIFF BUS_0.22UF,6.3V,20%,X6S,SA    I94 @T6G_MB_LIB.T6G(SCH_1):PAGE450

P5E_CPU1_P2_TX_BUF_DN<12> @T6G_MB_LIB.T6G(SCH_1):P5E_CPU1_P2_TX_BUF_DN(12)
 U6016 AR10 B_PETN3 PT5161LRS-PT5161LRS,SMLF,IC,AJ051610U03    I33 @T6G_MB_LIB.T6G(SCH_1):PAGE450
 C6718    2      2 Q_CAP_DIFFBUS_C0201-DIFF BUS_0.22UF,6.3V,20%,X6S,SA    I92 @T6G_MB_LIB.T6G(SCH_1):PAGE450

P5E_CPU1_P2_TX_BUF_DN<13> @T6G_MB_LIB.T6G(SCH_1):P5E_CPU1_P2_TX_BUF_DN(13)
 U6016 AH10 B_PETN2 PT5161LRS-PT5161LRS,SMLF,IC,AJ051610U03    I33 @T6G_MB_LIB.T6G(SCH_1):PAGE450
 C6720    2      2 Q_CAP_DIFFBUS_C0201-DIFF BUS_0.22UF,6.3V,20%,X6S,SA    I90 @T6G_MB_LIB.T6G(SCH_1):PAGE450

P5E_CPU1_P2_TX_BUF_DN<14> @T6G_MB_LIB.T6G(SCH_1):P5E_CPU1_P2_TX_BUF_DN(14)
 U6016 AA10 B_PETN1 PT5161LRS-PT5161LRS,SMLF,IC,AJ051610U03    I33 @T6G_MB_LIB.T6G(SCH_1):PAGE450
 C6722    2      2 Q_CAP_DIFFBUS_C0201-DIFF BUS_0.22UF,6.3V,20%,X6S,SA    I83 @T6G_MB_LIB.T6G(SCH_1):PAGE450

P5E_CPU1_P2_TX_BUF_DN<15> @T6G_MB_LIB.T6G(SCH_1):P5E_CPU1_P2_TX_BUF_DN(15)
 U6016  P10 B_PETN0 PT5161LRS-PT5161LRS,SMLF,IC,AJ051610U03    I33 @T6G_MB_LIB.T6G(SCH_1):PAGE450
 C6724    2      2 Q_CAP_DIFFBUS_C0201-DIFF BUS_0.22UF,6.3V,20%,X6S,SA    I81 @T6G_MB_LIB.T6G(SCH_1):PAGE450

P5E_CPU1_P2_TX_BUF_DN<1> @T6G_MB_LIB.T6G(SCH_1):P5E_CPU1_P2_TX_BUF_DN(1)
 C6696    2      2 Q_CAP_DIFFBUS_C0201-DIFF BUS_0.22UF,6.3V,20%,X6S,SA    I28 @T6G_MB_LIB.T6G(SCH_1):PAGE450
 U6016 EM10 B_PETN14 PT5161LRS-PT5161LRS,SMLF,IC,AJ051610U03   I142 @T6G_MB_LIB.T6G(SCH_1):PAGE450

P5E_CPU1_P2_TX_BUF_DN<2> @T6G_MB_LIB.T6G(SCH_1):P5E_CPU1_P2_TX_BUF_DN(2)
 C6698    2      2 Q_CAP_DIFFBUS_C0201-DIFF BUS_0.22UF,6.3V,20%,X6S,SA    I27 @T6G_MB_LIB.T6G(SCH_1):PAGE450
 U6016 EE10 B_PETN13 PT5161LRS-PT5161LRS,SMLF,IC,AJ051610U03   I142 @T6G_MB_LIB.T6G(SCH_1):PAGE450

P5E_CPU1_P2_TX_BUF_DN<3> @T6G_MB_LIB.T6G(SCH_1):P5E_CPU1_P2_TX_BUF_DN(3)
 C6700    2      2 Q_CAP_DIFFBUS_C0201-DIFF BUS_0.22UF,6.3V,20%,X6S,SA    I26 @T6G_MB_LIB.T6G(SCH_1):PAGE450
 U6016 DV10 B_PETN12 PT5161LRS-PT5161LRS,SMLF,IC,AJ051610U03   I142 @T6G_MB_LIB.T6G(SCH_1):PAGE450

P5E_CPU1_P2_TX_BUF_DN<4> @T6G_MB_LIB.T6G(SCH_1):P5E_CPU1_P2_TX_BUF_DN(4)
 C6702    2      2 Q_CAP_DIFFBUS_C0201-DIFF BUS_0.22UF,6.3V,20%,X6S,SA    I23 @T6G_MB_LIB.T6G(SCH_1):PAGE450
 U6016 DL10 B_PETN11 PT5161LRS-PT5161LRS,SMLF,IC,AJ051610U03   I142 @T6G_MB_LIB.T6G(SCH_1):PAGE450

P5E_CPU1_P2_TX_BUF_DN<5> @T6G_MB_LIB.T6G(SCH_1):P5E_CPU1_P2_TX_BUF_DN(5)
 C6704    2      2 Q_CAP_DIFFBUS_C0201-DIFF BUS_0.22UF,6.3V,20%,X6S,SA    I21 @T6G_MB_LIB.T6G(SCH_1):PAGE450
 U6016 DD10 B_PETN10 PT5161LRS-PT5161LRS,SMLF,IC,AJ051610U03   I142 @T6G_MB_LIB.T6G(SCH_1):PAGE450

P5E_CPU1_P2_TX_BUF_DN<6> @T6G_MB_LIB.T6G(SCH_1):P5E_CPU1_P2_TX_BUF_DN(6)
 C6706    2      2 Q_CAP_DIFFBUS_C0201-DIFF BUS_0.22UF,6.3V,20%,X6S,SA    I19 @T6G_MB_LIB.T6G(SCH_1):PAGE450
 U6016 CU10 B_PETN9 PT5161LRS-PT5161LRS,SMLF,IC,AJ051610U03   I142 @T6G_MB_LIB.T6G(SCH_1):PAGE450

P5E_CPU1_P2_TX_BUF_DN<7> @T6G_MB_LIB.T6G(SCH_1):P5E_CPU1_P2_TX_BUF_DN(7)
 C6708    2      2 Q_CAP_DIFFBUS_C0201-DIFF BUS_0.22UF,6.3V,20%,X6S,SA    I17 @T6G_MB_LIB.T6G(SCH_1):PAGE450
 U6016 CK10 B_PETN8 PT5161LRS-PT5161LRS,SMLF,IC,AJ051610U03   I142 @T6G_MB_LIB.T6G(SCH_1):PAGE450

P5E_CPU1_P2_TX_BUF_DN<8> @T6G_MB_LIB.T6G(SCH_1):P5E_CPU1_P2_TX_BUF_DN(8)
 U6016 CC10 B_PETN7 PT5161LRS-PT5161LRS,SMLF,IC,AJ051610U03    I33 @T6G_MB_LIB.T6G(SCH_1):PAGE450
 C6710    2      2 Q_CAP_DIFFBUS_C0201-DIFF BUS_0.22UF,6.3V,20%,X6S,SA   I103 @T6G_MB_LIB.T6G(SCH_1):PAGE450

P5E_CPU1_P2_TX_BUF_DN<9> @T6G_MB_LIB.T6G(SCH_1):P5E_CPU1_P2_TX_BUF_DN(9)
 U6016 BT10 B_PETN6 PT5161LRS-PT5161LRS,SMLF,IC,AJ051610U03    I33 @T6G_MB_LIB.T6G(SCH_1):PAGE450
 C6712    2      2 Q_CAP_DIFFBUS_C0201-DIFF BUS_0.22UF,6.3V,20%,X6S,SA    I98 @T6G_MB_LIB.T6G(SCH_1):PAGE450

P5E_CPU1_P2_TX_BUF_DP<0> @T6G_MB_LIB.T6G(SCH_1):P5E_CPU1_P2_TX_BUF_DP(0)
 C6693    2      2 Q_CAP_DIFFBUS_C0201-DIFF BUS_0.22UF,6.3V,20%,X6S,SA    I34 @T6G_MB_LIB.T6G(SCH_1):PAGE450
 U6016  EU7 B_PETP15 PT5161LRS-PT5161LRS,SMLF,IC,AJ051610U03   I142 @T6G_MB_LIB.T6G(SCH_1):PAGE450

P5E_CPU1_P2_TX_BUF_DP<10> @T6G_MB_LIB.T6G(SCH_1):P5E_CPU1_P2_TX_BUF_DP(10)
 U6016  BG7 B_PETP5 PT5161LRS-PT5161LRS,SMLF,IC,AJ051610U03    I33 @T6G_MB_LIB.T6G(SCH_1):PAGE450
 C6713    2      2 Q_CAP_DIFFBUS_C0201-DIFF BUS_0.22UF,6.3V,20%,X6S,SA    I97 @T6G_MB_LIB.T6G(SCH_1):PAGE450

P5E_CPU1_P2_TX_BUF_DP<11> @T6G_MB_LIB.T6G(SCH_1):P5E_CPU1_P2_TX_BUF_DP(11)
 U6016  AY7 B_PETP4 PT5161LRS-PT5161LRS,SMLF,IC,AJ051610U03    I33 @T6G_MB_LIB.T6G(SCH_1):PAGE450
 C6715    2      2 Q_CAP_DIFFBUS_C0201-DIFF BUS_0.22UF,6.3V,20%,X6S,SA    I95 @T6G_MB_LIB.T6G(SCH_1):PAGE450

P5E_CPU1_P2_TX_BUF_DP<12> @T6G_MB_LIB.T6G(SCH_1):P5E_CPU1_P2_TX_BUF_DP(12)
 U6016  AN7 B_PETP3 PT5161LRS-PT5161LRS,SMLF,IC,AJ051610U03    I33 @T6G_MB_LIB.T6G(SCH_1):PAGE450
 C6717    2      2 Q_CAP_DIFFBUS_C0201-DIFF BUS_0.22UF,6.3V,20%,X6S,SA    I93 @T6G_MB_LIB.T6G(SCH_1):PAGE450

P5E_CPU1_P2_TX_BUF_DP<13> @T6G_MB_LIB.T6G(SCH_1):P5E_CPU1_P2_TX_BUF_DP(13)
 U6016  AF7 B_PETP2 PT5161LRS-PT5161LRS,SMLF,IC,AJ051610U03    I33 @T6G_MB_LIB.T6G(SCH_1):PAGE450
 C6719    2      2 Q_CAP_DIFFBUS_C0201-DIFF BUS_0.22UF,6.3V,20%,X6S,SA    I91 @T6G_MB_LIB.T6G(SCH_1):PAGE450

P5E_CPU1_P2_TX_BUF_DP<14> @T6G_MB_LIB.T6G(SCH_1):P5E_CPU1_P2_TX_BUF_DP(14)
 U6016   W7 B_PETP1 PT5161LRS-PT5161LRS,SMLF,IC,AJ051610U03    I33 @T6G_MB_LIB.T6G(SCH_1):PAGE450
 C6721    2      2 Q_CAP_DIFFBUS_C0201-DIFF BUS_0.22UF,6.3V,20%,X6S,SA    I84 @T6G_MB_LIB.T6G(SCH_1):PAGE450

P5E_CPU1_P2_TX_BUF_DP<15> @T6G_MB_LIB.T6G(SCH_1):P5E_CPU1_P2_TX_BUF_DP(15)
 U6016   M7 B_PETP0 PT5161LRS-PT5161LRS,SMLF,IC,AJ051610U03    I33 @T6G_MB_LIB.T6G(SCH_1):PAGE450
 C6723    2      2 Q_CAP_DIFFBUS_C0201-DIFF BUS_0.22UF,6.3V,20%,X6S,SA    I82 @T6G_MB_LIB.T6G(SCH_1):PAGE450

P5E_CPU1_P2_TX_BUF_DP<1> @T6G_MB_LIB.T6G(SCH_1):P5E_CPU1_P2_TX_BUF_DP(1)
 C6695    2      2 Q_CAP_DIFFBUS_C0201-DIFF BUS_0.22UF,6.3V,20%,X6S,SA    I29 @T6G_MB_LIB.T6G(SCH_1):PAGE450
 U6016  EK7 B_PETP14 PT5161LRS-PT5161LRS,SMLF,IC,AJ051610U03   I142 @T6G_MB_LIB.T6G(SCH_1):PAGE450

P5E_CPU1_P2_TX_BUF_DP<2> @T6G_MB_LIB.T6G(SCH_1):P5E_CPU1_P2_TX_BUF_DP(2)
 C6697    2      2 Q_CAP_DIFFBUS_C0201-DIFF BUS_0.22UF,6.3V,20%,X6S,SA    I30 @T6G_MB_LIB.T6G(SCH_1):PAGE450
 U6016  EC7 B_PETP13 PT5161LRS-PT5161LRS,SMLF,IC,AJ051610U03   I142 @T6G_MB_LIB.T6G(SCH_1):PAGE450

P5E_CPU1_P2_TX_BUF_DP<3> @T6G_MB_LIB.T6G(SCH_1):P5E_CPU1_P2_TX_BUF_DP(3)
 C6699    2      2 Q_CAP_DIFFBUS_C0201-DIFF BUS_0.22UF,6.3V,20%,X6S,SA    I25 @T6G_MB_LIB.T6G(SCH_1):PAGE450
 U6016  DT7 B_PETP12 PT5161LRS-PT5161LRS,SMLF,IC,AJ051610U03   I142 @T6G_MB_LIB.T6G(SCH_1):PAGE450

P5E_CPU1_P2_TX_BUF_DP<4> @T6G_MB_LIB.T6G(SCH_1):P5E_CPU1_P2_TX_BUF_DP(4)
 C6701    2      2 Q_CAP_DIFFBUS_C0201-DIFF BUS_0.22UF,6.3V,20%,X6S,SA    I24 @T6G_MB_LIB.T6G(SCH_1):PAGE450
 U6016  DJ7 B_PETP11 PT5161LRS-PT5161LRS,SMLF,IC,AJ051610U03   I142 @T6G_MB_LIB.T6G(SCH_1):PAGE450

P5E_CPU1_P2_TX_BUF_DP<5> @T6G_MB_LIB.T6G(SCH_1):P5E_CPU1_P2_TX_BUF_DP(5)
 C6703    2      2 Q_CAP_DIFFBUS_C0201-DIFF BUS_0.22UF,6.3V,20%,X6S,SA    I22 @T6G_MB_LIB.T6G(SCH_1):PAGE450
 U6016  DB7 B_PETP10 PT5161LRS-PT5161LRS,SMLF,IC,AJ051610U03   I142 @T6G_MB_LIB.T6G(SCH_1):PAGE450

P5E_CPU1_P2_TX_BUF_DP<6> @T6G_MB_LIB.T6G(SCH_1):P5E_CPU1_P2_TX_BUF_DP(6)
 C6705    2      2 Q_CAP_DIFFBUS_C0201-DIFF BUS_0.22UF,6.3V,20%,X6S,SA    I20 @T6G_MB_LIB.T6G(SCH_1):PAGE450
 U6016  CR7 B_PETP9 PT5161LRS-PT5161LRS,SMLF,IC,AJ051610U03   I142 @T6G_MB_LIB.T6G(SCH_1):PAGE450

P5E_CPU1_P2_TX_BUF_DP<7> @T6G_MB_LIB.T6G(SCH_1):P5E_CPU1_P2_TX_BUF_DP(7)
 C6707    2      2 Q_CAP_DIFFBUS_C0201-DIFF BUS_0.22UF,6.3V,20%,X6S,SA    I18 @T6G_MB_LIB.T6G(SCH_1):PAGE450
 U6016  CH7 B_PETP8 PT5161LRS-PT5161LRS,SMLF,IC,AJ051610U03   I142 @T6G_MB_LIB.T6G(SCH_1):PAGE450

P5E_CPU1_P2_TX_BUF_DP<8> @T6G_MB_LIB.T6G(SCH_1):P5E_CPU1_P2_TX_BUF_DP(8)
 U6016  CA7 B_PETP7 PT5161LRS-PT5161LRS,SMLF,IC,AJ051610U03    I33 @T6G_MB_LIB.T6G(SCH_1):PAGE450
 C6709    2      2 Q_CAP_DIFFBUS_C0201-DIFF BUS_0.22UF,6.3V,20%,X6S,SA   I102 @T6G_MB_LIB.T6G(SCH_1):PAGE450

P5E_CPU1_P2_TX_BUF_DP<9> @T6G_MB_LIB.T6G(SCH_1):P5E_CPU1_P2_TX_BUF_DP(9)
 U6016  BP7 B_PETP6 PT5161LRS-PT5161LRS,SMLF,IC,AJ051610U03    I33 @T6G_MB_LIB.T6G(SCH_1):PAGE450
 C6711    2      2 Q_CAP_DIFFBUS_C0201-DIFF BUS_0.22UF,6.3V,20%,X6S,SA    I99 @T6G_MB_LIB.T6G(SCH_1):PAGE450

P5E_CPU1_P2_TX_C_DN<0> @T6G_MB_LIB.T6G(SCH_1):P5E_CPU1_P2_TX_C_DN(0)
  C772    1      1 Q_CAP_DIFFBUS_C0201-DIFF BUS_0.22UF,6.3V,20%,X6S,SA   I123 @T6G_MB_LIB.T6G(SCH_1):PAGE354
 U6016 EV34 B_PERP15 PT5161LRS-PT5161LRS,SMLF,IC,AJ051610U03    I38 @T6G_MB_LIB.T6G(SCH_1):PAGE447

P5E_CPU1_P2_TX_C_DN<10> @T6G_MB_LIB.T6G(SCH_1):P5E_CPU1_P2_TX_C_DN(10)
  C752    1      1 Q_CAP_DIFFBUS_C0201-DIFF BUS_0.22UF,6.3V,20%,X6S,SA   I159 @T6G_MB_LIB.T6G(SCH_1):PAGE354
 U6016 BH34 B_PERP5 PT5161LRS-PT5161LRS,SMLF,IC,AJ051610U03     I1 @T6G_MB_LIB.T6G(SCH_1):PAGE447

P5E_CPU1_P2_TX_C_DN<11> @T6G_MB_LIB.T6G(SCH_1):P5E_CPU1_P2_TX_C_DN(11)
  C750    1      1 Q_CAP_DIFFBUS_C0201-DIFF BUS_0.22UF,6.3V,20%,X6S,SA   I160 @T6G_MB_LIB.T6G(SCH_1):PAGE354
 U6016 BA34 B_PERP4 PT5161LRS-PT5161LRS,SMLF,IC,AJ051610U03     I1 @T6G_MB_LIB.T6G(SCH_1):PAGE447

P5E_CPU1_P2_TX_C_DN<12> @T6G_MB_LIB.T6G(SCH_1):P5E_CPU1_P2_TX_C_DN(12)
  C748    1      1 Q_CAP_DIFFBUS_C0201-DIFF BUS_0.22UF,6.3V,20%,X6S,SA   I163 @T6G_MB_LIB.T6G(SCH_1):PAGE354
 U6016 AP34 B_PERP3 PT5161LRS-PT5161LRS,SMLF,IC,AJ051610U03     I1 @T6G_MB_LIB.T6G(SCH_1):PAGE447

P5E_CPU1_P2_TX_C_DN<13> @T6G_MB_LIB.T6G(SCH_1):P5E_CPU1_P2_TX_C_DN(13)
  C746    1      1 Q_CAP_DIFFBUS_C0201-DIFF BUS_0.22UF,6.3V,20%,X6S,SA   I168 @T6G_MB_LIB.T6G(SCH_1):PAGE354
 U6016 AG34 B_PERP2 PT5161LRS-PT5161LRS,SMLF,IC,AJ051610U03     I1 @T6G_MB_LIB.T6G(SCH_1):PAGE447

P5E_CPU1_P2_TX_C_DN<14> @T6G_MB_LIB.T6G(SCH_1):P5E_CPU1_P2_TX_C_DN(14)
  C744    1      1 Q_CAP_DIFFBUS_C0201-DIFF BUS_0.22UF,6.3V,20%,X6S,SA   I170 @T6G_MB_LIB.T6G(SCH_1):PAGE354
 U6016  Y34 B_PERP1 PT5161LRS-PT5161LRS,SMLF,IC,AJ051610U03     I1 @T6G_MB_LIB.T6G(SCH_1):PAGE447

P5E_CPU1_P2_TX_C_DN<15> @T6G_MB_LIB.T6G(SCH_1):P5E_CPU1_P2_TX_C_DN(15)
  C742    1      1 Q_CAP_DIFFBUS_C0201-DIFF BUS_0.22UF,6.3V,20%,X6S,SA   I172 @T6G_MB_LIB.T6G(SCH_1):PAGE354
 U6016  N34 B_PERP0 PT5161LRS-PT5161LRS,SMLF,IC,AJ051610U03     I1 @T6G_MB_LIB.T6G(SCH_1):PAGE447

P5E_CPU1_P2_TX_C_DN<1> @T6G_MB_LIB.T6G(SCH_1):P5E_CPU1_P2_TX_C_DN(1)
  C770    1      1 Q_CAP_DIFFBUS_C0201-DIFF BUS_0.22UF,6.3V,20%,X6S,SA   I125 @T6G_MB_LIB.T6G(SCH_1):PAGE354
 U6016 EN35 B_PERN14 PT5161LRS-PT5161LRS,SMLF,IC,AJ051610U03    I38 @T6G_MB_LIB.T6G(SCH_1):PAGE447

P5E_CPU1_P2_TX_C_DN<2> @T6G_MB_LIB.T6G(SCH_1):P5E_CPU1_P2_TX_C_DN(2)
  C768    1      1 Q_CAP_DIFFBUS_C0201-DIFF BUS_0.22UF,6.3V,20%,X6S,SA   I127 @T6G_MB_LIB.T6G(SCH_1):PAGE354
 U6016 ED34 B_PERP13 PT5161LRS-PT5161LRS,SMLF,IC,AJ051610U03    I38 @T6G_MB_LIB.T6G(SCH_1):PAGE447

P5E_CPU1_P2_TX_C_DN<3> @T6G_MB_LIB.T6G(SCH_1):P5E_CPU1_P2_TX_C_DN(3)
  C766    1      1 Q_CAP_DIFFBUS_C0201-DIFF BUS_0.22UF,6.3V,20%,X6S,SA   I129 @T6G_MB_LIB.T6G(SCH_1):PAGE354
 U6016 DU34 B_PERP12 PT5161LRS-PT5161LRS,SMLF,IC,AJ051610U03    I38 @T6G_MB_LIB.T6G(SCH_1):PAGE447

P5E_CPU1_P2_TX_C_DN<4> @T6G_MB_LIB.T6G(SCH_1):P5E_CPU1_P2_TX_C_DN(4)
  C764    1      1 Q_CAP_DIFFBUS_C0201-DIFF BUS_0.22UF,6.3V,20%,X6S,SA   I130 @T6G_MB_LIB.T6G(SCH_1):PAGE354
 U6016 DK34 B_PERP11 PT5161LRS-PT5161LRS,SMLF,IC,AJ051610U03    I38 @T6G_MB_LIB.T6G(SCH_1):PAGE447

P5E_CPU1_P2_TX_C_DN<5> @T6G_MB_LIB.T6G(SCH_1):P5E_CPU1_P2_TX_C_DN(5)
  C762    1      1 Q_CAP_DIFFBUS_C0201-DIFF BUS_0.22UF,6.3V,20%,X6S,SA   I136 @T6G_MB_LIB.T6G(SCH_1):PAGE354
 U6016 DC34 B_PERP10 PT5161LRS-PT5161LRS,SMLF,IC,AJ051610U03    I38 @T6G_MB_LIB.T6G(SCH_1):PAGE447

P5E_CPU1_P2_TX_C_DN<6> @T6G_MB_LIB.T6G(SCH_1):P5E_CPU1_P2_TX_C_DN(6)
  C760    1      1 Q_CAP_DIFFBUS_C0201-DIFF BUS_0.22UF,6.3V,20%,X6S,SA   I138 @T6G_MB_LIB.T6G(SCH_1):PAGE354
 U6016 CT34 B_PERP9 PT5161LRS-PT5161LRS,SMLF,IC,AJ051610U03    I38 @T6G_MB_LIB.T6G(SCH_1):PAGE447

P5E_CPU1_P2_TX_C_DN<7> @T6G_MB_LIB.T6G(SCH_1):P5E_CPU1_P2_TX_C_DN(7)
  C758    1      1 Q_CAP_DIFFBUS_C0201-DIFF BUS_0.22UF,6.3V,20%,X6S,SA   I140 @T6G_MB_LIB.T6G(SCH_1):PAGE354
 U6016 CJ34 B_PERP8 PT5161LRS-PT5161LRS,SMLF,IC,AJ051610U03    I38 @T6G_MB_LIB.T6G(SCH_1):PAGE447

P5E_CPU1_P2_TX_C_DN<8> @T6G_MB_LIB.T6G(SCH_1):P5E_CPU1_P2_TX_C_DN(8)
  C756    1      1 Q_CAP_DIFFBUS_C0201-DIFF BUS_0.22UF,6.3V,20%,X6S,SA   I154 @T6G_MB_LIB.T6G(SCH_1):PAGE354
 U6016 CB34 B_PERP7 PT5161LRS-PT5161LRS,SMLF,IC,AJ051610U03     I1 @T6G_MB_LIB.T6G(SCH_1):PAGE447

P5E_CPU1_P2_TX_C_DN<9> @T6G_MB_LIB.T6G(SCH_1):P5E_CPU1_P2_TX_C_DN(9)
  C754    1      1 Q_CAP_DIFFBUS_C0201-DIFF BUS_0.22UF,6.3V,20%,X6S,SA   I157 @T6G_MB_LIB.T6G(SCH_1):PAGE354
 U6016 BR34 B_PERP6 PT5161LRS-PT5161LRS,SMLF,IC,AJ051610U03     I1 @T6G_MB_LIB.T6G(SCH_1):PAGE447

P5E_CPU1_P2_TX_C_DP<0> @T6G_MB_LIB.T6G(SCH_1):P5E_CPU1_P2_TX_C_DP(0)
  C773    1      1 Q_CAP_DIFFBUS_C0201-DIFF BUS_0.22UF,6.3V,20%,X6S,SA   I122 @T6G_MB_LIB.T6G(SCH_1):PAGE354
 U6016 EY35 B_PERN15 PT5161LRS-PT5161LRS,SMLF,IC,AJ051610U03    I38 @T6G_MB_LIB.T6G(SCH_1):PAGE447

P5E_CPU1_P2_TX_C_DP<10> @T6G_MB_LIB.T6G(SCH_1):P5E_CPU1_P2_TX_C_DP(10)
  C753    1      1 Q_CAP_DIFFBUS_C0201-DIFF BUS_0.22UF,6.3V,20%,X6S,SA   I158 @T6G_MB_LIB.T6G(SCH_1):PAGE354
 U6016 BK35 B_PERN5 PT5161LRS-PT5161LRS,SMLF,IC,AJ051610U03     I1 @T6G_MB_LIB.T6G(SCH_1):PAGE447

P5E_CPU1_P2_TX_C_DP<11> @T6G_MB_LIB.T6G(SCH_1):P5E_CPU1_P2_TX_C_DP(11)
  C751    1      1 Q_CAP_DIFFBUS_C0201-DIFF BUS_0.22UF,6.3V,20%,X6S,SA   I161 @T6G_MB_LIB.T6G(SCH_1):PAGE354
 U6016 BC35 B_PERN4 PT5161LRS-PT5161LRS,SMLF,IC,AJ051610U03     I1 @T6G_MB_LIB.T6G(SCH_1):PAGE447

P5E_CPU1_P2_TX_C_DP<12> @T6G_MB_LIB.T6G(SCH_1):P5E_CPU1_P2_TX_C_DP(12)
  C749    1      1 Q_CAP_DIFFBUS_C0201-DIFF BUS_0.22UF,6.3V,20%,X6S,SA   I162 @T6G_MB_LIB.T6G(SCH_1):PAGE354
 U6016 AT35 B_PERN3 PT5161LRS-PT5161LRS,SMLF,IC,AJ051610U03     I1 @T6G_MB_LIB.T6G(SCH_1):PAGE447

P5E_CPU1_P2_TX_C_DP<13> @T6G_MB_LIB.T6G(SCH_1):P5E_CPU1_P2_TX_C_DP(13)
  C747    1      1 Q_CAP_DIFFBUS_C0201-DIFF BUS_0.22UF,6.3V,20%,X6S,SA   I167 @T6G_MB_LIB.T6G(SCH_1):PAGE354
 U6016 AJ35 B_PERN2 PT5161LRS-PT5161LRS,SMLF,IC,AJ051610U03     I1 @T6G_MB_LIB.T6G(SCH_1):PAGE447

P5E_CPU1_P2_TX_C_DP<14> @T6G_MB_LIB.T6G(SCH_1):P5E_CPU1_P2_TX_C_DP(14)
  C745    1      1 Q_CAP_DIFFBUS_C0201-DIFF BUS_0.22UF,6.3V,20%,X6S,SA   I169 @T6G_MB_LIB.T6G(SCH_1):PAGE354
 U6016 AB35 B_PERN1 PT5161LRS-PT5161LRS,SMLF,IC,AJ051610U03     I1 @T6G_MB_LIB.T6G(SCH_1):PAGE447

P5E_CPU1_P2_TX_C_DP<15> @T6G_MB_LIB.T6G(SCH_1):P5E_CPU1_P2_TX_C_DP(15)
  C743    1      1 Q_CAP_DIFFBUS_C0201-DIFF BUS_0.22UF,6.3V,20%,X6S,SA   I171 @T6G_MB_LIB.T6G(SCH_1):PAGE354
 U6016  R35 B_PERN0 PT5161LRS-PT5161LRS,SMLF,IC,AJ051610U03     I1 @T6G_MB_LIB.T6G(SCH_1):PAGE447

P5E_CPU1_P2_TX_C_DP<1> @T6G_MB_LIB.T6G(SCH_1):P5E_CPU1_P2_TX_C_DP(1)
  C771    1      1 Q_CAP_DIFFBUS_C0201-DIFF BUS_0.22UF,6.3V,20%,X6S,SA   I124 @T6G_MB_LIB.T6G(SCH_1):PAGE354
 U6016 EL34 B_PERP14 PT5161LRS-PT5161LRS,SMLF,IC,AJ051610U03    I38 @T6G_MB_LIB.T6G(SCH_1):PAGE447

P5E_CPU1_P2_TX_C_DP<2> @T6G_MB_LIB.T6G(SCH_1):P5E_CPU1_P2_TX_C_DP(2)
  C769    1      1 Q_CAP_DIFFBUS_C0201-DIFF BUS_0.22UF,6.3V,20%,X6S,SA   I126 @T6G_MB_LIB.T6G(SCH_1):PAGE354
 U6016 EF35 B_PERN13 PT5161LRS-PT5161LRS,SMLF,IC,AJ051610U03    I38 @T6G_MB_LIB.T6G(SCH_1):PAGE447

P5E_CPU1_P2_TX_C_DP<3> @T6G_MB_LIB.T6G(SCH_1):P5E_CPU1_P2_TX_C_DP(3)
  C767    1      1 Q_CAP_DIFFBUS_C0201-DIFF BUS_0.22UF,6.3V,20%,X6S,SA   I128 @T6G_MB_LIB.T6G(SCH_1):PAGE354
 U6016 DW35 B_PERN12 PT5161LRS-PT5161LRS,SMLF,IC,AJ051610U03    I38 @T6G_MB_LIB.T6G(SCH_1):PAGE447

P5E_CPU1_P2_TX_C_DP<4> @T6G_MB_LIB.T6G(SCH_1):P5E_CPU1_P2_TX_C_DP(4)
  C765    1      1 Q_CAP_DIFFBUS_C0201-DIFF BUS_0.22UF,6.3V,20%,X6S,SA   I131 @T6G_MB_LIB.T6G(SCH_1):PAGE354
 U6016 DM35 B_PERN11 PT5161LRS-PT5161LRS,SMLF,IC,AJ051610U03    I38 @T6G_MB_LIB.T6G(SCH_1):PAGE447

P5E_CPU1_P2_TX_C_DP<5> @T6G_MB_LIB.T6G(SCH_1):P5E_CPU1_P2_TX_C_DP(5)
  C763    1      1 Q_CAP_DIFFBUS_C0201-DIFF BUS_0.22UF,6.3V,20%,X6S,SA   I135 @T6G_MB_LIB.T6G(SCH_1):PAGE354
 U6016 DE35 B_PERN10 PT5161LRS-PT5161LRS,SMLF,IC,AJ051610U03    I38 @T6G_MB_LIB.T6G(SCH_1):PAGE447

P5E_CPU1_P2_TX_C_DP<6> @T6G_MB_LIB.T6G(SCH_1):P5E_CPU1_P2_TX_C_DP(6)
  C761    1      1 Q_CAP_DIFFBUS_C0201-DIFF BUS_0.22UF,6.3V,20%,X6S,SA   I137 @T6G_MB_LIB.T6G(SCH_1):PAGE354
 U6016 CV35 B_PERN9 PT5161LRS-PT5161LRS,SMLF,IC,AJ051610U03    I38 @T6G_MB_LIB.T6G(SCH_1):PAGE447

P5E_CPU1_P2_TX_C_DP<7> @T6G_MB_LIB.T6G(SCH_1):P5E_CPU1_P2_TX_C_DP(7)
  C759    1      1 Q_CAP_DIFFBUS_C0201-DIFF BUS_0.22UF,6.3V,20%,X6S,SA   I139 @T6G_MB_LIB.T6G(SCH_1):PAGE354
 U6016 CL35 B_PERN8 PT5161LRS-PT5161LRS,SMLF,IC,AJ051610U03    I38 @T6G_MB_LIB.T6G(SCH_1):PAGE447

P5E_CPU1_P2_TX_C_DP<8> @T6G_MB_LIB.T6G(SCH_1):P5E_CPU1_P2_TX_C_DP(8)
  C757    1      1 Q_CAP_DIFFBUS_C0201-DIFF BUS_0.22UF,6.3V,20%,X6S,SA   I155 @T6G_MB_LIB.T6G(SCH_1):PAGE354
 U6016 CD35 B_PERN7 PT5161LRS-PT5161LRS,SMLF,IC,AJ051610U03     I1 @T6G_MB_LIB.T6G(SCH_1):PAGE447

P5E_CPU1_P2_TX_C_DP<9> @T6G_MB_LIB.T6G(SCH_1):P5E_CPU1_P2_TX_C_DP(9)
  C755    1      1 Q_CAP_DIFFBUS_C0201-DIFF BUS_0.22UF,6.3V,20%,X6S,SA   I156 @T6G_MB_LIB.T6G(SCH_1):PAGE354
 U6016 BU35 B_PERN6 PT5161LRS-PT5161LRS,SMLF,IC,AJ051610U03     I1 @T6G_MB_LIB.T6G(SCH_1):PAGE447

P5E_CPU1_P2_TX_DN<0> @T6G_MB_LIB.T6G(SCH_1):P5E_CPU1_P2_TX_DN(0)
   U26 BT35 P2_TXN0 GENOA_SP5-SOCKET6096_13568-001,SMLF,IO,DGA^6000030   I148 @T6G_MB_LIB.T6G(SCH_1):PAGE52
  C772    2      2 Q_CAP_DIFFBUS_C0201-DIFF BUS_0.22UF,6.3V,20%,X6S,SA   I123 @T6G_MB_LIB.T6G(SCH_1):PAGE354

P5E_CPU1_P2_TX_DN<10> @T6G_MB_LIB.T6G(SCH_1):P5E_CPU1_P2_TX_DN(10)
   U26 BU26 P2_TXN10 GENOA_SP5-SOCKET6096_13568-001,SMLF,IO,DGA^6000030   I148 @T6G_MB_LIB.T6G(SCH_1):PAGE52
  C752    2      2 Q_CAP_DIFFBUS_C0201-DIFF BUS_0.22UF,6.3V,20%,X6S,SA   I159 @T6G_MB_LIB.T6G(SCH_1):PAGE354

P5E_CPU1_P2_TX_DN<11> @T6G_MB_LIB.T6G(SCH_1):P5E_CPU1_P2_TX_DN(11)
   U26 CA26 P2_TXN11 GENOA_SP5-SOCKET6096_13568-001,SMLF,IO,DGA^6000030   I148 @T6G_MB_LIB.T6G(SCH_1):PAGE52
  C750    2      2 Q_CAP_DIFFBUS_C0201-DIFF BUS_0.22UF,6.3V,20%,X6S,SA   I160 @T6G_MB_LIB.T6G(SCH_1):PAGE354

P5E_CPU1_P2_TX_DN<12> @T6G_MB_LIB.T6G(SCH_1):P5E_CPU1_P2_TX_DN(12)
   U26 BW26 P2_TXN12 GENOA_SP5-SOCKET6096_13568-001,SMLF,IO,DGA^6000030   I148 @T6G_MB_LIB.T6G(SCH_1):PAGE52
  C748    2      2 Q_CAP_DIFFBUS_C0201-DIFF BUS_0.22UF,6.3V,20%,X6S,SA   I163 @T6G_MB_LIB.T6G(SCH_1):PAGE354

P5E_CPU1_P2_TX_DN<13> @T6G_MB_LIB.T6G(SCH_1):P5E_CPU1_P2_TX_DN(13)
   U26 BU23 P2_TXN13 GENOA_SP5-SOCKET6096_13568-001,SMLF,IO,DGA^6000030   I148 @T6G_MB_LIB.T6G(SCH_1):PAGE52
  C746    2      2 Q_CAP_DIFFBUS_C0201-DIFF BUS_0.22UF,6.3V,20%,X6S,SA   I168 @T6G_MB_LIB.T6G(SCH_1):PAGE354

P5E_CPU1_P2_TX_DN<14> @T6G_MB_LIB.T6G(SCH_1):P5E_CPU1_P2_TX_DN(14)
   U26 CA23 P2_TXN14 GENOA_SP5-SOCKET6096_13568-001,SMLF,IO,DGA^6000030   I148 @T6G_MB_LIB.T6G(SCH_1):PAGE52
  C744    2      2 Q_CAP_DIFFBUS_C0201-DIFF BUS_0.22UF,6.3V,20%,X6S,SA   I170 @T6G_MB_LIB.T6G(SCH_1):PAGE354

P5E_CPU1_P2_TX_DN<15> @T6G_MB_LIB.T6G(SCH_1):P5E_CPU1_P2_TX_DN(15)
   U26 BW23 P2_TXN15 GENOA_SP5-SOCKET6096_13568-001,SMLF,IO,DGA^6000030   I148 @T6G_MB_LIB.T6G(SCH_1):PAGE52
  C742    2      2 Q_CAP_DIFFBUS_C0201-DIFF BUS_0.22UF,6.3V,20%,X6S,SA   I172 @T6G_MB_LIB.T6G(SCH_1):PAGE354

P5E_CPU1_P2_TX_DN<1> @T6G_MB_LIB.T6G(SCH_1):P5E_CPU1_P2_TX_DN(1)
   U26 BV35 P2_TXN1 GENOA_SP5-SOCKET6096_13568-001,SMLF,IO,DGA^6000030   I148 @T6G_MB_LIB.T6G(SCH_1):PAGE52
  C770    2      2 Q_CAP_DIFFBUS_C0201-DIFF BUS_0.22UF,6.3V,20%,X6S,SA   I125 @T6G_MB_LIB.T6G(SCH_1):PAGE354

P5E_CPU1_P2_TX_DN<2> @T6G_MB_LIB.T6G(SCH_1):P5E_CPU1_P2_TX_DN(2)
   U26 CB35 P2_TXN2 GENOA_SP5-SOCKET6096_13568-001,SMLF,IO,DGA^6000030   I148 @T6G_MB_LIB.T6G(SCH_1):PAGE52
  C768    2      2 Q_CAP_DIFFBUS_C0201-DIFF BUS_0.22UF,6.3V,20%,X6S,SA   I127 @T6G_MB_LIB.T6G(SCH_1):PAGE354

P5E_CPU1_P2_TX_DN<3> @T6G_MB_LIB.T6G(SCH_1):P5E_CPU1_P2_TX_DN(3)
   U26 BY35 P2_TXN3 GENOA_SP5-SOCKET6096_13568-001,SMLF,IO,DGA^6000030   I148 @T6G_MB_LIB.T6G(SCH_1):PAGE52
  C766    2      2 Q_CAP_DIFFBUS_C0201-DIFF BUS_0.22UF,6.3V,20%,X6S,SA   I129 @T6G_MB_LIB.T6G(SCH_1):PAGE354

P5E_CPU1_P2_TX_DN<4> @T6G_MB_LIB.T6G(SCH_1):P5E_CPU1_P2_TX_DN(4)
   U26 BU32 P2_TXN4 GENOA_SP5-SOCKET6096_13568-001,SMLF,IO,DGA^6000030   I148 @T6G_MB_LIB.T6G(SCH_1):PAGE52
  C764    2      2 Q_CAP_DIFFBUS_C0201-DIFF BUS_0.22UF,6.3V,20%,X6S,SA   I130 @T6G_MB_LIB.T6G(SCH_1):PAGE354

P5E_CPU1_P2_TX_DN<5> @T6G_MB_LIB.T6G(SCH_1):P5E_CPU1_P2_TX_DN(5)
   U26 CA32 P2_TXN5 GENOA_SP5-SOCKET6096_13568-001,SMLF,IO,DGA^6000030   I148 @T6G_MB_LIB.T6G(SCH_1):PAGE52
  C762    2      2 Q_CAP_DIFFBUS_C0201-DIFF BUS_0.22UF,6.3V,20%,X6S,SA   I136 @T6G_MB_LIB.T6G(SCH_1):PAGE354

P5E_CPU1_P2_TX_DN<6> @T6G_MB_LIB.T6G(SCH_1):P5E_CPU1_P2_TX_DN(6)
   U26 BW32 P2_TXN6 GENOA_SP5-SOCKET6096_13568-001,SMLF,IO,DGA^6000030   I148 @T6G_MB_LIB.T6G(SCH_1):PAGE52
  C760    2      2 Q_CAP_DIFFBUS_C0201-DIFF BUS_0.22UF,6.3V,20%,X6S,SA   I138 @T6G_MB_LIB.T6G(SCH_1):PAGE354

P5E_CPU1_P2_TX_DN<7> @T6G_MB_LIB.T6G(SCH_1):P5E_CPU1_P2_TX_DN(7)
   U26 BU29 P2_TXN7 GENOA_SP5-SOCKET6096_13568-001,SMLF,IO,DGA^6000030   I148 @T6G_MB_LIB.T6G(SCH_1):PAGE52
  C758    2      2 Q_CAP_DIFFBUS_C0201-DIFF BUS_0.22UF,6.3V,20%,X6S,SA   I140 @T6G_MB_LIB.T6G(SCH_1):PAGE354

P5E_CPU1_P2_TX_DN<8> @T6G_MB_LIB.T6G(SCH_1):P5E_CPU1_P2_TX_DN(8)
   U26 CA29 P2_TXN8 GENOA_SP5-SOCKET6096_13568-001,SMLF,IO,DGA^6000030   I148 @T6G_MB_LIB.T6G(SCH_1):PAGE52
  C756    2      2 Q_CAP_DIFFBUS_C0201-DIFF BUS_0.22UF,6.3V,20%,X6S,SA   I154 @T6G_MB_LIB.T6G(SCH_1):PAGE354

P5E_CPU1_P2_TX_DN<9> @T6G_MB_LIB.T6G(SCH_1):P5E_CPU1_P2_TX_DN(9)
   U26 BW29 P2_TXN9 GENOA_SP5-SOCKET6096_13568-001,SMLF,IO,DGA^6000030   I148 @T6G_MB_LIB.T6G(SCH_1):PAGE52
  C754    2      2 Q_CAP_DIFFBUS_C0201-DIFF BUS_0.22UF,6.3V,20%,X6S,SA   I157 @T6G_MB_LIB.T6G(SCH_1):PAGE354

P5E_CPU1_P2_TX_DP<0> @T6G_MB_LIB.T6G(SCH_1):P5E_CPU1_P2_TX_DP(0)
   U26 BT36 P2_TXP0 GENOA_SP5-SOCKET6096_13568-001,SMLF,IO,DGA^6000030   I148 @T6G_MB_LIB.T6G(SCH_1):PAGE52
  C773    2      2 Q_CAP_DIFFBUS_C0201-DIFF BUS_0.22UF,6.3V,20%,X6S,SA   I122 @T6G_MB_LIB.T6G(SCH_1):PAGE354

P5E_CPU1_P2_TX_DP<10> @T6G_MB_LIB.T6G(SCH_1):P5E_CPU1_P2_TX_DP(10)
   U26 BU27 P2_TXP10 GENOA_SP5-SOCKET6096_13568-001,SMLF,IO,DGA^6000030   I148 @T6G_MB_LIB.T6G(SCH_1):PAGE52
  C753    2      2 Q_CAP_DIFFBUS_C0201-DIFF BUS_0.22UF,6.3V,20%,X6S,SA   I158 @T6G_MB_LIB.T6G(SCH_1):PAGE354

P5E_CPU1_P2_TX_DP<11> @T6G_MB_LIB.T6G(SCH_1):P5E_CPU1_P2_TX_DP(11)
   U26 CA27 P2_TXP11 GENOA_SP5-SOCKET6096_13568-001,SMLF,IO,DGA^6000030   I148 @T6G_MB_LIB.T6G(SCH_1):PAGE52
  C751    2      2 Q_CAP_DIFFBUS_C0201-DIFF BUS_0.22UF,6.3V,20%,X6S,SA   I161 @T6G_MB_LIB.T6G(SCH_1):PAGE354

P5E_CPU1_P2_TX_DP<12> @T6G_MB_LIB.T6G(SCH_1):P5E_CPU1_P2_TX_DP(12)
   U26 BW27 P2_TXP12 GENOA_SP5-SOCKET6096_13568-001,SMLF,IO,DGA^6000030   I148 @T6G_MB_LIB.T6G(SCH_1):PAGE52
  C749    2      2 Q_CAP_DIFFBUS_C0201-DIFF BUS_0.22UF,6.3V,20%,X6S,SA   I162 @T6G_MB_LIB.T6G(SCH_1):PAGE354

P5E_CPU1_P2_TX_DP<13> @T6G_MB_LIB.T6G(SCH_1):P5E_CPU1_P2_TX_DP(13)
   U26 BU24 P2_TXP13 GENOA_SP5-SOCKET6096_13568-001,SMLF,IO,DGA^6000030   I148 @T6G_MB_LIB.T6G(SCH_1):PAGE52
  C747    2      2 Q_CAP_DIFFBUS_C0201-DIFF BUS_0.22UF,6.3V,20%,X6S,SA   I167 @T6G_MB_LIB.T6G(SCH_1):PAGE354

P5E_CPU1_P2_TX_DP<14> @T6G_MB_LIB.T6G(SCH_1):P5E_CPU1_P2_TX_DP(14)
   U26 CA24 P2_TXP14 GENOA_SP5-SOCKET6096_13568-001,SMLF,IO,DGA^6000030   I148 @T6G_MB_LIB.T6G(SCH_1):PAGE52
  C745    2      2 Q_CAP_DIFFBUS_C0201-DIFF BUS_0.22UF,6.3V,20%,X6S,SA   I169 @T6G_MB_LIB.T6G(SCH_1):PAGE354

P5E_CPU1_P2_TX_DP<15> @T6G_MB_LIB.T6G(SCH_1):P5E_CPU1_P2_TX_DP(15)
   U26 BW24 P2_TXP15 GENOA_SP5-SOCKET6096_13568-001,SMLF,IO,DGA^6000030   I148 @T6G_MB_LIB.T6G(SCH_1):PAGE52
  C743    2      2 Q_CAP_DIFFBUS_C0201-DIFF BUS_0.22UF,6.3V,20%,X6S,SA   I171 @T6G_MB_LIB.T6G(SCH_1):PAGE354

P5E_CPU1_P2_TX_DP<1> @T6G_MB_LIB.T6G(SCH_1):P5E_CPU1_P2_TX_DP(1)
   U26 BV36 P2_TXP1 GENOA_SP5-SOCKET6096_13568-001,SMLF,IO,DGA^6000030   I148 @T6G_MB_LIB.T6G(SCH_1):PAGE52
  C771    2      2 Q_CAP_DIFFBUS_C0201-DIFF BUS_0.22UF,6.3V,20%,X6S,SA   I124 @T6G_MB_LIB.T6G(SCH_1):PAGE354

P5E_CPU1_P2_TX_DP<2> @T6G_MB_LIB.T6G(SCH_1):P5E_CPU1_P2_TX_DP(2)
   U26 CB36 P2_TXP2 GENOA_SP5-SOCKET6096_13568-001,SMLF,IO,DGA^6000030   I148 @T6G_MB_LIB.T6G(SCH_1):PAGE52
  C769    2      2 Q_CAP_DIFFBUS_C0201-DIFF BUS_0.22UF,6.3V,20%,X6S,SA   I126 @T6G_MB_LIB.T6G(SCH_1):PAGE354

P5E_CPU1_P2_TX_DP<3> @T6G_MB_LIB.T6G(SCH_1):P5E_CPU1_P2_TX_DP(3)
   U26 BY36 P2_TXP3 GENOA_SP5-SOCKET6096_13568-001,SMLF,IO,DGA^6000030   I148 @T6G_MB_LIB.T6G(SCH_1):PAGE52
  C767    2      2 Q_CAP_DIFFBUS_C0201-DIFF BUS_0.22UF,6.3V,20%,X6S,SA   I128 @T6G_MB_LIB.T6G(SCH_1):PAGE354

P5E_CPU1_P2_TX_DP<4> @T6G_MB_LIB.T6G(SCH_1):P5E_CPU1_P2_TX_DP(4)
   U26 BU33 P2_TXP4 GENOA_SP5-SOCKET6096_13568-001,SMLF,IO,DGA^6000030   I148 @T6G_MB_LIB.T6G(SCH_1):PAGE52
  C765    2      2 Q_CAP_DIFFBUS_C0201-DIFF BUS_0.22UF,6.3V,20%,X6S,SA   I131 @T6G_MB_LIB.T6G(SCH_1):PAGE354

P5E_CPU1_P2_TX_DP<5> @T6G_MB_LIB.T6G(SCH_1):P5E_CPU1_P2_TX_DP(5)
   U26 CA33 P2_TXP5 GENOA_SP5-SOCKET6096_13568-001,SMLF,IO,DGA^6000030   I148 @T6G_MB_LIB.T6G(SCH_1):PAGE52
  C763    2      2 Q_CAP_DIFFBUS_C0201-DIFF BUS_0.22UF,6.3V,20%,X6S,SA   I135 @T6G_MB_LIB.T6G(SCH_1):PAGE354

P5E_CPU1_P2_TX_DP<6> @T6G_MB_LIB.T6G(SCH_1):P5E_CPU1_P2_TX_DP(6)
   U26 BW33 P2_TXP6 GENOA_SP5-SOCKET6096_13568-001,SMLF,IO,DGA^6000030   I148 @T6G_MB_LIB.T6G(SCH_1):PAGE52
  C761    2      2 Q_CAP_DIFFBUS_C0201-DIFF BUS_0.22UF,6.3V,20%,X6S,SA   I137 @T6G_MB_LIB.T6G(SCH_1):PAGE354

P5E_CPU1_P2_TX_DP<7> @T6G_MB_LIB.T6G(SCH_1):P5E_CPU1_P2_TX_DP(7)
   U26 BU30 P2_TXP7 GENOA_SP5-SOCKET6096_13568-001,SMLF,IO,DGA^6000030   I148 @T6G_MB_LIB.T6G(SCH_1):PAGE52
  C759    2      2 Q_CAP_DIFFBUS_C0201-DIFF BUS_0.22UF,6.3V,20%,X6S,SA   I139 @T6G_MB_LIB.T6G(SCH_1):PAGE354

P5E_CPU1_P2_TX_DP<8> @T6G_MB_LIB.T6G(SCH_1):P5E_CPU1_P2_TX_DP(8)
   U26 CA30 P2_TXP8 GENOA_SP5-SOCKET6096_13568-001,SMLF,IO,DGA^6000030   I148 @T6G_MB_LIB.T6G(SCH_1):PAGE52
  C757    2      2 Q_CAP_DIFFBUS_C0201-DIFF BUS_0.22UF,6.3V,20%,X6S,SA   I155 @T6G_MB_LIB.T6G(SCH_1):PAGE354

P5E_CPU1_P2_TX_DP<9> @T6G_MB_LIB.T6G(SCH_1):P5E_CPU1_P2_TX_DP(9)
   U26 BW30 P2_TXP9 GENOA_SP5-SOCKET6096_13568-001,SMLF,IO,DGA^6000030   I148 @T6G_MB_LIB.T6G(SCH_1):PAGE52
  C755    2      2 Q_CAP_DIFFBUS_C0201-DIFF BUS_0.22UF,6.3V,20%,X6S,SA   I156 @T6G_MB_LIB.T6G(SCH_1):PAGE354

P5E_CPU1_P3_RX_BUF_DN<0> @T6G_MB_LIB.T6G(SCH_1):P5E_CPU1_P3_RX_BUF_DN(0)
 U6017  EV2 A_PERN15 PT5161LRS-PT5161LRS,SMLF,IC,AJ051610U03    I38 @T6G_MB_LIB.T6G(SCH_1):PAGE460
  J110   F1     F1 CONN112_10137002101LF-CONN112_10137002-101LF,THLF,A    I76 @T6G_MB_LIB.T6G(SCH_1):PAGE318

P5E_CPU1_P3_RX_BUF_DN<10> @T6G_MB_LIB.T6G(SCH_1):P5E_CPU1_P3_RX_BUF_DN(10)
 U6017  BH2 A_PERN5 PT5161LRS-PT5161LRS,SMLF,IC,AJ051610U03     I1 @T6G_MB_LIB.T6G(SCH_1):PAGE460
  J109   F3     F3 CONN112_10137002101LF-CONN112_10137002-101LF,THLF,A    I76 @T6G_MB_LIB.T6G(SCH_1):PAGE319

P5E_CPU1_P3_RX_BUF_DN<11> @T6G_MB_LIB.T6G(SCH_1):P5E_CPU1_P3_RX_BUF_DN(11)
 U6017  BA2 A_PERN4 PT5161LRS-PT5161LRS,SMLF,IC,AJ051610U03     I1 @T6G_MB_LIB.T6G(SCH_1):PAGE460
  J109   E4     E4 CONN112_10137002101LF-CONN112_10137002-101LF,THLF,A    I76 @T6G_MB_LIB.T6G(SCH_1):PAGE319

P5E_CPU1_P3_RX_BUF_DN<12> @T6G_MB_LIB.T6G(SCH_1):P5E_CPU1_P3_RX_BUF_DN(12)
 U6017  AP2 A_PERN3 PT5161LRS-PT5161LRS,SMLF,IC,AJ051610U03     I1 @T6G_MB_LIB.T6G(SCH_1):PAGE460
  J109   F5     F5 CONN112_10137002101LF-CONN112_10137002-101LF,THLF,A    I16 @T6G_MB_LIB.T6G(SCH_1):PAGE319

P5E_CPU1_P3_RX_BUF_DN<13> @T6G_MB_LIB.T6G(SCH_1):P5E_CPU1_P3_RX_BUF_DN(13)
 U6017  AG2 A_PERN2 PT5161LRS-PT5161LRS,SMLF,IC,AJ051610U03     I1 @T6G_MB_LIB.T6G(SCH_1):PAGE460
  J109   E6     E6 CONN112_10137002101LF-CONN112_10137002-101LF,THLF,A    I16 @T6G_MB_LIB.T6G(SCH_1):PAGE319

P5E_CPU1_P3_RX_BUF_DN<14> @T6G_MB_LIB.T6G(SCH_1):P5E_CPU1_P3_RX_BUF_DN(14)
 U6017   Y2 A_PERN1 PT5161LRS-PT5161LRS,SMLF,IC,AJ051610U03     I1 @T6G_MB_LIB.T6G(SCH_1):PAGE460
  J109   F7     F7 CONN112_10137002101LF-CONN112_10137002-101LF,THLF,A    I16 @T6G_MB_LIB.T6G(SCH_1):PAGE319

P5E_CPU1_P3_RX_BUF_DN<15> @T6G_MB_LIB.T6G(SCH_1):P5E_CPU1_P3_RX_BUF_DN(15)
 U6017   N2 A_PERN0 PT5161LRS-PT5161LRS,SMLF,IC,AJ051610U03     I1 @T6G_MB_LIB.T6G(SCH_1):PAGE460
  J109   E8     E8 CONN112_10137002101LF-CONN112_10137002-101LF,THLF,A    I16 @T6G_MB_LIB.T6G(SCH_1):PAGE319

P5E_CPU1_P3_RX_BUF_DN<1> @T6G_MB_LIB.T6G(SCH_1):P5E_CPU1_P3_RX_BUF_DN(1)
 U6017  EL2 A_PERN14 PT5161LRS-PT5161LRS,SMLF,IC,AJ051610U03    I38 @T6G_MB_LIB.T6G(SCH_1):PAGE460
  J110   E2     E2 CONN112_10137002101LF-CONN112_10137002-101LF,THLF,A    I76 @T6G_MB_LIB.T6G(SCH_1):PAGE318

P5E_CPU1_P3_RX_BUF_DN<2> @T6G_MB_LIB.T6G(SCH_1):P5E_CPU1_P3_RX_BUF_DN(2)
 U6017  ED2 A_PERN13 PT5161LRS-PT5161LRS,SMLF,IC,AJ051610U03    I38 @T6G_MB_LIB.T6G(SCH_1):PAGE460
  J110   F3     F3 CONN112_10137002101LF-CONN112_10137002-101LF,THLF,A    I76 @T6G_MB_LIB.T6G(SCH_1):PAGE318

P5E_CPU1_P3_RX_BUF_DN<3> @T6G_MB_LIB.T6G(SCH_1):P5E_CPU1_P3_RX_BUF_DN(3)
 U6017  DU2 A_PERN12 PT5161LRS-PT5161LRS,SMLF,IC,AJ051610U03    I38 @T6G_MB_LIB.T6G(SCH_1):PAGE460
  J110   E4     E4 CONN112_10137002101LF-CONN112_10137002-101LF,THLF,A    I76 @T6G_MB_LIB.T6G(SCH_1):PAGE318

P5E_CPU1_P3_RX_BUF_DN<4> @T6G_MB_LIB.T6G(SCH_1):P5E_CPU1_P3_RX_BUF_DN(4)
 U6017  DK2 A_PERN11 PT5161LRS-PT5161LRS,SMLF,IC,AJ051610U03    I38 @T6G_MB_LIB.T6G(SCH_1):PAGE460
  J110   F5     F5 CONN112_10137002101LF-CONN112_10137002-101LF,THLF,A    I16 @T6G_MB_LIB.T6G(SCH_1):PAGE318

P5E_CPU1_P3_RX_BUF_DN<5> @T6G_MB_LIB.T6G(SCH_1):P5E_CPU1_P3_RX_BUF_DN(5)
 U6017  DC2 A_PERN10 PT5161LRS-PT5161LRS,SMLF,IC,AJ051610U03    I38 @T6G_MB_LIB.T6G(SCH_1):PAGE460
  J110   E6     E6 CONN112_10137002101LF-CONN112_10137002-101LF,THLF,A    I16 @T6G_MB_LIB.T6G(SCH_1):PAGE318

P5E_CPU1_P3_RX_BUF_DN<6> @T6G_MB_LIB.T6G(SCH_1):P5E_CPU1_P3_RX_BUF_DN(6)
 U6017  CT2 A_PERN9 PT5161LRS-PT5161LRS,SMLF,IC,AJ051610U03    I38 @T6G_MB_LIB.T6G(SCH_1):PAGE460
  J110   F7     F7 CONN112_10137002101LF-CONN112_10137002-101LF,THLF,A    I16 @T6G_MB_LIB.T6G(SCH_1):PAGE318

P5E_CPU1_P3_RX_BUF_DN<7> @T6G_MB_LIB.T6G(SCH_1):P5E_CPU1_P3_RX_BUF_DN(7)
 U6017  CJ2 A_PERN8 PT5161LRS-PT5161LRS,SMLF,IC,AJ051610U03    I38 @T6G_MB_LIB.T6G(SCH_1):PAGE460
  J110   E8     E8 CONN112_10137002101LF-CONN112_10137002-101LF,THLF,A    I16 @T6G_MB_LIB.T6G(SCH_1):PAGE318

P5E_CPU1_P3_RX_BUF_DN<8> @T6G_MB_LIB.T6G(SCH_1):P5E_CPU1_P3_RX_BUF_DN(8)
 U6017  CB2 A_PERN7 PT5161LRS-PT5161LRS,SMLF,IC,AJ051610U03     I1 @T6G_MB_LIB.T6G(SCH_1):PAGE460
  J109   F1     F1 CONN112_10137002101LF-CONN112_10137002-101LF,THLF,A    I76 @T6G_MB_LIB.T6G(SCH_1):PAGE319

P5E_CPU1_P3_RX_BUF_DN<9> @T6G_MB_LIB.T6G(SCH_1):P5E_CPU1_P3_RX_BUF_DN(9)
 U6017  BR2 A_PERN6 PT5161LRS-PT5161LRS,SMLF,IC,AJ051610U03     I1 @T6G_MB_LIB.T6G(SCH_1):PAGE460
  J109   E2     E2 CONN112_10137002101LF-CONN112_10137002-101LF,THLF,A    I76 @T6G_MB_LIB.T6G(SCH_1):PAGE319

P5E_CPU1_P3_RX_BUF_DP<0> @T6G_MB_LIB.T6G(SCH_1):P5E_CPU1_P3_RX_BUF_DP(0)
 U6017  EY1 A_PERP15 PT5161LRS-PT5161LRS,SMLF,IC,AJ051610U03    I38 @T6G_MB_LIB.T6G(SCH_1):PAGE460
  J110   G1     G1 CONN112_10137002101LF-CONN112_10137002-101LF,THLF,A    I76 @T6G_MB_LIB.T6G(SCH_1):PAGE318

P5E_CPU1_P3_RX_BUF_DP<10> @T6G_MB_LIB.T6G(SCH_1):P5E_CPU1_P3_RX_BUF_DP(10)
 U6017  BK1 A_PERP5 PT5161LRS-PT5161LRS,SMLF,IC,AJ051610U03     I1 @T6G_MB_LIB.T6G(SCH_1):PAGE460
  J109   G3     G3 CONN112_10137002101LF-CONN112_10137002-101LF,THLF,A    I76 @T6G_MB_LIB.T6G(SCH_1):PAGE319

P5E_CPU1_P3_RX_BUF_DP<11> @T6G_MB_LIB.T6G(SCH_1):P5E_CPU1_P3_RX_BUF_DP(11)
 U6017  BC1 A_PERP4 PT5161LRS-PT5161LRS,SMLF,IC,AJ051610U03     I1 @T6G_MB_LIB.T6G(SCH_1):PAGE460
  J109   F4     F4 CONN112_10137002101LF-CONN112_10137002-101LF,THLF,A    I76 @T6G_MB_LIB.T6G(SCH_1):PAGE319

P5E_CPU1_P3_RX_BUF_DP<12> @T6G_MB_LIB.T6G(SCH_1):P5E_CPU1_P3_RX_BUF_DP(12)
 U6017  AT1 A_PERP3 PT5161LRS-PT5161LRS,SMLF,IC,AJ051610U03     I1 @T6G_MB_LIB.T6G(SCH_1):PAGE460
  J109   G5     G5 CONN112_10137002101LF-CONN112_10137002-101LF,THLF,A    I16 @T6G_MB_LIB.T6G(SCH_1):PAGE319

P5E_CPU1_P3_RX_BUF_DP<13> @T6G_MB_LIB.T6G(SCH_1):P5E_CPU1_P3_RX_BUF_DP(13)
 U6017  AJ1 A_PERP2 PT5161LRS-PT5161LRS,SMLF,IC,AJ051610U03     I1 @T6G_MB_LIB.T6G(SCH_1):PAGE460
  J109   F6     F6 CONN112_10137002101LF-CONN112_10137002-101LF,THLF,A    I16 @T6G_MB_LIB.T6G(SCH_1):PAGE319

P5E_CPU1_P3_RX_BUF_DP<14> @T6G_MB_LIB.T6G(SCH_1):P5E_CPU1_P3_RX_BUF_DP(14)
 U6017  AB1 A_PERP1 PT5161LRS-PT5161LRS,SMLF,IC,AJ051610U03     I1 @T6G_MB_LIB.T6G(SCH_1):PAGE460
  J109   G7     G7 CONN112_10137002101LF-CONN112_10137002-101LF,THLF,A    I16 @T6G_MB_LIB.T6G(SCH_1):PAGE319

P5E_CPU1_P3_RX_BUF_DP<15> @T6G_MB_LIB.T6G(SCH_1):P5E_CPU1_P3_RX_BUF_DP(15)
 U6017   R1 A_PERP0 PT5161LRS-PT5161LRS,SMLF,IC,AJ051610U03     I1 @T6G_MB_LIB.T6G(SCH_1):PAGE460
  J109   F8     F8 CONN112_10137002101LF-CONN112_10137002-101LF,THLF,A    I16 @T6G_MB_LIB.T6G(SCH_1):PAGE319

P5E_CPU1_P3_RX_BUF_DP<1> @T6G_MB_LIB.T6G(SCH_1):P5E_CPU1_P3_RX_BUF_DP(1)
 U6017  EN1 A_PERP14 PT5161LRS-PT5161LRS,SMLF,IC,AJ051610U03    I38 @T6G_MB_LIB.T6G(SCH_1):PAGE460
  J110   F2     F2 CONN112_10137002101LF-CONN112_10137002-101LF,THLF,A    I76 @T6G_MB_LIB.T6G(SCH_1):PAGE318

P5E_CPU1_P3_RX_BUF_DP<2> @T6G_MB_LIB.T6G(SCH_1):P5E_CPU1_P3_RX_BUF_DP(2)
 U6017  EF1 A_PERP13 PT5161LRS-PT5161LRS,SMLF,IC,AJ051610U03    I38 @T6G_MB_LIB.T6G(SCH_1):PAGE460
  J110   G3     G3 CONN112_10137002101LF-CONN112_10137002-101LF,THLF,A    I76 @T6G_MB_LIB.T6G(SCH_1):PAGE318

P5E_CPU1_P3_RX_BUF_DP<3> @T6G_MB_LIB.T6G(SCH_1):P5E_CPU1_P3_RX_BUF_DP(3)
 U6017  DW1 A_PERP12 PT5161LRS-PT5161LRS,SMLF,IC,AJ051610U03    I38 @T6G_MB_LIB.T6G(SCH_1):PAGE460
  J110   F4     F4 CONN112_10137002101LF-CONN112_10137002-101LF,THLF,A    I76 @T6G_MB_LIB.T6G(SCH_1):PAGE318

P5E_CPU1_P3_RX_BUF_DP<4> @T6G_MB_LIB.T6G(SCH_1):P5E_CPU1_P3_RX_BUF_DP(4)
 U6017  DM1 A_PERP11 PT5161LRS-PT5161LRS,SMLF,IC,AJ051610U03    I38 @T6G_MB_LIB.T6G(SCH_1):PAGE460
  J110   G5     G5 CONN112_10137002101LF-CONN112_10137002-101LF,THLF,A    I16 @T6G_MB_LIB.T6G(SCH_1):PAGE318

P5E_CPU1_P3_RX_BUF_DP<5> @T6G_MB_LIB.T6G(SCH_1):P5E_CPU1_P3_RX_BUF_DP(5)
 U6017  DE1 A_PERP10 PT5161LRS-PT5161LRS,SMLF,IC,AJ051610U03    I38 @T6G_MB_LIB.T6G(SCH_1):PAGE460
  J110   F6     F6 CONN112_10137002101LF-CONN112_10137002-101LF,THLF,A    I16 @T6G_MB_LIB.T6G(SCH_1):PAGE318

P5E_CPU1_P3_RX_BUF_DP<6> @T6G_MB_LIB.T6G(SCH_1):P5E_CPU1_P3_RX_BUF_DP(6)
 U6017  CV1 A_PERP9 PT5161LRS-PT5161LRS,SMLF,IC,AJ051610U03    I38 @T6G_MB_LIB.T6G(SCH_1):PAGE460
  J110   G7     G7 CONN112_10137002101LF-CONN112_10137002-101LF,THLF,A    I16 @T6G_MB_LIB.T6G(SCH_1):PAGE318

P5E_CPU1_P3_RX_BUF_DP<7> @T6G_MB_LIB.T6G(SCH_1):P5E_CPU1_P3_RX_BUF_DP(7)
 U6017  CL1 A_PERP8 PT5161LRS-PT5161LRS,SMLF,IC,AJ051610U03    I38 @T6G_MB_LIB.T6G(SCH_1):PAGE460
  J110   F8     F8 CONN112_10137002101LF-CONN112_10137002-101LF,THLF,A    I16 @T6G_MB_LIB.T6G(SCH_1):PAGE318

P5E_CPU1_P3_RX_BUF_DP<8> @T6G_MB_LIB.T6G(SCH_1):P5E_CPU1_P3_RX_BUF_DP(8)
 U6017  CD1 A_PERP7 PT5161LRS-PT5161LRS,SMLF,IC,AJ051610U03     I1 @T6G_MB_LIB.T6G(SCH_1):PAGE460
  J109   G1     G1 CONN112_10137002101LF-CONN112_10137002-101LF,THLF,A    I76 @T6G_MB_LIB.T6G(SCH_1):PAGE319

P5E_CPU1_P3_RX_BUF_DP<9> @T6G_MB_LIB.T6G(SCH_1):P5E_CPU1_P3_RX_BUF_DP(9)
 U6017  BU1 A_PERP6 PT5161LRS-PT5161LRS,SMLF,IC,AJ051610U03     I1 @T6G_MB_LIB.T6G(SCH_1):PAGE460
  J109   F2     F2 CONN112_10137002101LF-CONN112_10137002-101LF,THLF,A    I76 @T6G_MB_LIB.T6G(SCH_1):PAGE319

P5E_CPU1_P3_RX_DN<0> @T6G_MB_LIB.T6G(SCH_1):P5E_CPU1_P3_RX_DN(0)
   U26 CV36 P3_RXN0 GENOA_SP5-SOCKET6096_13568-001,SMLF,IO,DGA^6000030   I147 @T6G_MB_LIB.T6G(SCH_1):PAGE52
 U6017 EW29 A_PETN15 PT5161LRS-PT5161LRS,SMLF,IC,AJ051610U03    I38 @T6G_MB_LIB.T6G(SCH_1):PAGE459

P5E_CPU1_P3_RX_DN<10> @T6G_MB_LIB.T6G(SCH_1):P5E_CPU1_P3_RX_DN(10)
   U26 DC27 P3_RXN10 GENOA_SP5-SOCKET6096_13568-001,SMLF,IO,DGA^6000030   I147 @T6G_MB_LIB.T6G(SCH_1):PAGE52
 U6017 BJ29 A_PETN5 PT5161LRS-PT5161LRS,SMLF,IC,AJ051610U03     I1 @T6G_MB_LIB.T6G(SCH_1):PAGE459

P5E_CPU1_P3_RX_DN<11> @T6G_MB_LIB.T6G(SCH_1):P5E_CPU1_P3_RX_DN(11)
   U26 DA27 P3_RXN11 GENOA_SP5-SOCKET6096_13568-001,SMLF,IO,DGA^6000030   I147 @T6G_MB_LIB.T6G(SCH_1):PAGE52
 U6017 BB29 A_PETN4 PT5161LRS-PT5161LRS,SMLF,IC,AJ051610U03     I1 @T6G_MB_LIB.T6G(SCH_1):PAGE459

P5E_CPU1_P3_RX_DN<12> @T6G_MB_LIB.T6G(SCH_1):P5E_CPU1_P3_RX_DN(12)
   U26 CW24 P3_RXN12 GENOA_SP5-SOCKET6096_13568-001,SMLF,IO,DGA^6000030   I147 @T6G_MB_LIB.T6G(SCH_1):PAGE52
 U6017 AR29 A_PETN3 PT5161LRS-PT5161LRS,SMLF,IC,AJ051610U03     I1 @T6G_MB_LIB.T6G(SCH_1):PAGE459

P5E_CPU1_P3_RX_DN<13> @T6G_MB_LIB.T6G(SCH_1):P5E_CPU1_P3_RX_DN(13)
   U26 DC24 P3_RXN13 GENOA_SP5-SOCKET6096_13568-001,SMLF,IO,DGA^6000030   I147 @T6G_MB_LIB.T6G(SCH_1):PAGE52
 U6017 AH29 A_PETN2 PT5161LRS-PT5161LRS,SMLF,IC,AJ051610U03     I1 @T6G_MB_LIB.T6G(SCH_1):PAGE459

P5E_CPU1_P3_RX_DN<14> @T6G_MB_LIB.T6G(SCH_1):P5E_CPU1_P3_RX_DN(14)
   U26 DA24 P3_RXN14 GENOA_SP5-SOCKET6096_13568-001,SMLF,IO,DGA^6000030   I147 @T6G_MB_LIB.T6G(SCH_1):PAGE52
 U6017 AA29 A_PETN1 PT5161LRS-PT5161LRS,SMLF,IC,AJ051610U03     I1 @T6G_MB_LIB.T6G(SCH_1):PAGE459

P5E_CPU1_P3_RX_DN<15> @T6G_MB_LIB.T6G(SCH_1):P5E_CPU1_P3_RX_DN(15)
   U26 CU24 P3_RXN15 GENOA_SP5-SOCKET6096_13568-001,SMLF,IO,DGA^6000030   I147 @T6G_MB_LIB.T6G(SCH_1):PAGE52
 U6017  P29 A_PETN0 PT5161LRS-PT5161LRS,SMLF,IC,AJ051610U03     I1 @T6G_MB_LIB.T6G(SCH_1):PAGE459

P5E_CPU1_P3_RX_DN<1> @T6G_MB_LIB.T6G(SCH_1):P5E_CPU1_P3_RX_DN(1)
   U26 CY36 P3_RXN1 GENOA_SP5-SOCKET6096_13568-001,SMLF,IO,DGA^6000030   I147 @T6G_MB_LIB.T6G(SCH_1):PAGE52
 U6017 EM29 A_PETN14 PT5161LRS-PT5161LRS,SMLF,IC,AJ051610U03    I38 @T6G_MB_LIB.T6G(SCH_1):PAGE459

P5E_CPU1_P3_RX_DN<2> @T6G_MB_LIB.T6G(SCH_1):P5E_CPU1_P3_RX_DN(2)
   U26 DB36 P3_RXN2 GENOA_SP5-SOCKET6096_13568-001,SMLF,IO,DGA^6000030   I147 @T6G_MB_LIB.T6G(SCH_1):PAGE52
 U6017 EE29 A_PETN13 PT5161LRS-PT5161LRS,SMLF,IC,AJ051610U03    I38 @T6G_MB_LIB.T6G(SCH_1):PAGE459

P5E_CPU1_P3_RX_DN<3> @T6G_MB_LIB.T6G(SCH_1):P5E_CPU1_P3_RX_DN(3)
   U26 CW33 P3_RXN3 GENOA_SP5-SOCKET6096_13568-001,SMLF,IO,DGA^6000030   I147 @T6G_MB_LIB.T6G(SCH_1):PAGE52
 U6017 DV29 A_PETN12 PT5161LRS-PT5161LRS,SMLF,IC,AJ051610U03    I38 @T6G_MB_LIB.T6G(SCH_1):PAGE459

P5E_CPU1_P3_RX_DN<4> @T6G_MB_LIB.T6G(SCH_1):P5E_CPU1_P3_RX_DN(4)
   U26 DC33 P3_RXN4 GENOA_SP5-SOCKET6096_13568-001,SMLF,IO,DGA^6000030   I147 @T6G_MB_LIB.T6G(SCH_1):PAGE52
 U6017 DL29 A_PETN11 PT5161LRS-PT5161LRS,SMLF,IC,AJ051610U03    I38 @T6G_MB_LIB.T6G(SCH_1):PAGE459

P5E_CPU1_P3_RX_DN<5> @T6G_MB_LIB.T6G(SCH_1):P5E_CPU1_P3_RX_DN(5)
   U26 DA33 P3_RXN5 GENOA_SP5-SOCKET6096_13568-001,SMLF,IO,DGA^6000030   I147 @T6G_MB_LIB.T6G(SCH_1):PAGE52
 U6017 DD29 A_PETN10 PT5161LRS-PT5161LRS,SMLF,IC,AJ051610U03    I38 @T6G_MB_LIB.T6G(SCH_1):PAGE459

P5E_CPU1_P3_RX_DN<6> @T6G_MB_LIB.T6G(SCH_1):P5E_CPU1_P3_RX_DN(6)
   U26 CW30 P3_RXN6 GENOA_SP5-SOCKET6096_13568-001,SMLF,IO,DGA^6000030   I147 @T6G_MB_LIB.T6G(SCH_1):PAGE52
 U6017 CU29 A_PETN9 PT5161LRS-PT5161LRS,SMLF,IC,AJ051610U03    I38 @T6G_MB_LIB.T6G(SCH_1):PAGE459

P5E_CPU1_P3_RX_DN<7> @T6G_MB_LIB.T6G(SCH_1):P5E_CPU1_P3_RX_DN(7)
   U26 DC30 P3_RXN7 GENOA_SP5-SOCKET6096_13568-001,SMLF,IO,DGA^6000030   I147 @T6G_MB_LIB.T6G(SCH_1):PAGE52
 U6017 CK29 A_PETN8 PT5161LRS-PT5161LRS,SMLF,IC,AJ051610U03    I38 @T6G_MB_LIB.T6G(SCH_1):PAGE459

P5E_CPU1_P3_RX_DN<8> @T6G_MB_LIB.T6G(SCH_1):P5E_CPU1_P3_RX_DN(8)
   U26 DA30 P3_RXN8 GENOA_SP5-SOCKET6096_13568-001,SMLF,IO,DGA^6000030   I147 @T6G_MB_LIB.T6G(SCH_1):PAGE52
 U6017 CC29 A_PETN7 PT5161LRS-PT5161LRS,SMLF,IC,AJ051610U03     I1 @T6G_MB_LIB.T6G(SCH_1):PAGE459

P5E_CPU1_P3_RX_DN<9> @T6G_MB_LIB.T6G(SCH_1):P5E_CPU1_P3_RX_DN(9)
   U26 CW27 P3_RXN9 GENOA_SP5-SOCKET6096_13568-001,SMLF,IO,DGA^6000030   I147 @T6G_MB_LIB.T6G(SCH_1):PAGE52
 U6017 BT29 A_PETN6 PT5161LRS-PT5161LRS,SMLF,IC,AJ051610U03     I1 @T6G_MB_LIB.T6G(SCH_1):PAGE459

P5E_CPU1_P3_RX_DP<0> @T6G_MB_LIB.T6G(SCH_1):P5E_CPU1_P3_RX_DP(0)
   U26 CV35 P3_RXP0 GENOA_SP5-SOCKET6096_13568-001,SMLF,IO,DGA^6000030   I147 @T6G_MB_LIB.T6G(SCH_1):PAGE52
 U6017 EU26 A_PETP15 PT5161LRS-PT5161LRS,SMLF,IC,AJ051610U03    I38 @T6G_MB_LIB.T6G(SCH_1):PAGE459

P5E_CPU1_P3_RX_DP<10> @T6G_MB_LIB.T6G(SCH_1):P5E_CPU1_P3_RX_DP(10)
   U26 DC26 P3_RXP10 GENOA_SP5-SOCKET6096_13568-001,SMLF,IO,DGA^6000030   I147 @T6G_MB_LIB.T6G(SCH_1):PAGE52
 U6017 BG26 A_PETP5 PT5161LRS-PT5161LRS,SMLF,IC,AJ051610U03     I1 @T6G_MB_LIB.T6G(SCH_1):PAGE459

P5E_CPU1_P3_RX_DP<11> @T6G_MB_LIB.T6G(SCH_1):P5E_CPU1_P3_RX_DP(11)
   U26 DA26 P3_RXP11 GENOA_SP5-SOCKET6096_13568-001,SMLF,IO,DGA^6000030   I147 @T6G_MB_LIB.T6G(SCH_1):PAGE52
 U6017 AY26 A_PETP4 PT5161LRS-PT5161LRS,SMLF,IC,AJ051610U03     I1 @T6G_MB_LIB.T6G(SCH_1):PAGE459

P5E_CPU1_P3_RX_DP<12> @T6G_MB_LIB.T6G(SCH_1):P5E_CPU1_P3_RX_DP(12)
   U26 CW23 P3_RXP12 GENOA_SP5-SOCKET6096_13568-001,SMLF,IO,DGA^6000030   I147 @T6G_MB_LIB.T6G(SCH_1):PAGE52
 U6017 AN26 A_PETP3 PT5161LRS-PT5161LRS,SMLF,IC,AJ051610U03     I1 @T6G_MB_LIB.T6G(SCH_1):PAGE459

P5E_CPU1_P3_RX_DP<13> @T6G_MB_LIB.T6G(SCH_1):P5E_CPU1_P3_RX_DP(13)
   U26 DC23 P3_RXP13 GENOA_SP5-SOCKET6096_13568-001,SMLF,IO,DGA^6000030   I147 @T6G_MB_LIB.T6G(SCH_1):PAGE52
 U6017 AF26 A_PETP2 PT5161LRS-PT5161LRS,SMLF,IC,AJ051610U03     I1 @T6G_MB_LIB.T6G(SCH_1):PAGE459

P5E_CPU1_P3_RX_DP<14> @T6G_MB_LIB.T6G(SCH_1):P5E_CPU1_P3_RX_DP(14)
   U26 DA23 P3_RXP14 GENOA_SP5-SOCKET6096_13568-001,SMLF,IO,DGA^6000030   I147 @T6G_MB_LIB.T6G(SCH_1):PAGE52
 U6017  W26 A_PETP1 PT5161LRS-PT5161LRS,SMLF,IC,AJ051610U03     I1 @T6G_MB_LIB.T6G(SCH_1):PAGE459

P5E_CPU1_P3_RX_DP<15> @T6G_MB_LIB.T6G(SCH_1):P5E_CPU1_P3_RX_DP(15)
   U26 CU23 P3_RXP15 GENOA_SP5-SOCKET6096_13568-001,SMLF,IO,DGA^6000030   I147 @T6G_MB_LIB.T6G(SCH_1):PAGE52
 U6017  M26 A_PETP0 PT5161LRS-PT5161LRS,SMLF,IC,AJ051610U03     I1 @T6G_MB_LIB.T6G(SCH_1):PAGE459

P5E_CPU1_P3_RX_DP<1> @T6G_MB_LIB.T6G(SCH_1):P5E_CPU1_P3_RX_DP(1)
   U26 CY35 P3_RXP1 GENOA_SP5-SOCKET6096_13568-001,SMLF,IO,DGA^6000030   I147 @T6G_MB_LIB.T6G(SCH_1):PAGE52
 U6017 EK26 A_PETP14 PT5161LRS-PT5161LRS,SMLF,IC,AJ051610U03    I38 @T6G_MB_LIB.T6G(SCH_1):PAGE459

P5E_CPU1_P3_RX_DP<2> @T6G_MB_LIB.T6G(SCH_1):P5E_CPU1_P3_RX_DP(2)
   U26 DB35 P3_RXP2 GENOA_SP5-SOCKET6096_13568-001,SMLF,IO,DGA^6000030   I147 @T6G_MB_LIB.T6G(SCH_1):PAGE52
 U6017 EC26 A_PETP13 PT5161LRS-PT5161LRS,SMLF,IC,AJ051610U03    I38 @T6G_MB_LIB.T6G(SCH_1):PAGE459

P5E_CPU1_P3_RX_DP<3> @T6G_MB_LIB.T6G(SCH_1):P5E_CPU1_P3_RX_DP(3)
   U26 CW32 P3_RXP3 GENOA_SP5-SOCKET6096_13568-001,SMLF,IO,DGA^6000030   I147 @T6G_MB_LIB.T6G(SCH_1):PAGE52
 U6017 DT26 A_PETP12 PT5161LRS-PT5161LRS,SMLF,IC,AJ051610U03    I38 @T6G_MB_LIB.T6G(SCH_1):PAGE459

P5E_CPU1_P3_RX_DP<4> @T6G_MB_LIB.T6G(SCH_1):P5E_CPU1_P3_RX_DP(4)
   U26 DC32 P3_RXP4 GENOA_SP5-SOCKET6096_13568-001,SMLF,IO,DGA^6000030   I147 @T6G_MB_LIB.T6G(SCH_1):PAGE52
 U6017 DJ26 A_PETP11 PT5161LRS-PT5161LRS,SMLF,IC,AJ051610U03    I38 @T6G_MB_LIB.T6G(SCH_1):PAGE459

P5E_CPU1_P3_RX_DP<5> @T6G_MB_LIB.T6G(SCH_1):P5E_CPU1_P3_RX_DP(5)
   U26 DA32 P3_RXP5 GENOA_SP5-SOCKET6096_13568-001,SMLF,IO,DGA^6000030   I147 @T6G_MB_LIB.T6G(SCH_1):PAGE52
 U6017 DB26 A_PETP10 PT5161LRS-PT5161LRS,SMLF,IC,AJ051610U03    I38 @T6G_MB_LIB.T6G(SCH_1):PAGE459

P5E_CPU1_P3_RX_DP<6> @T6G_MB_LIB.T6G(SCH_1):P5E_CPU1_P3_RX_DP(6)
   U26 CW29 P3_RXP6 GENOA_SP5-SOCKET6096_13568-001,SMLF,IO,DGA^6000030   I147 @T6G_MB_LIB.T6G(SCH_1):PAGE52
 U6017 CR26 A_PETP9 PT5161LRS-PT5161LRS,SMLF,IC,AJ051610U03    I38 @T6G_MB_LIB.T6G(SCH_1):PAGE459

P5E_CPU1_P3_RX_DP<7> @T6G_MB_LIB.T6G(SCH_1):P5E_CPU1_P3_RX_DP(7)
   U26 DC29 P3_RXP7 GENOA_SP5-SOCKET6096_13568-001,SMLF,IO,DGA^6000030   I147 @T6G_MB_LIB.T6G(SCH_1):PAGE52
 U6017 CH26 A_PETP8 PT5161LRS-PT5161LRS,SMLF,IC,AJ051610U03    I38 @T6G_MB_LIB.T6G(SCH_1):PAGE459

P5E_CPU1_P3_RX_DP<8> @T6G_MB_LIB.T6G(SCH_1):P5E_CPU1_P3_RX_DP(8)
   U26 DA29 P3_RXP8 GENOA_SP5-SOCKET6096_13568-001,SMLF,IO,DGA^6000030   I147 @T6G_MB_LIB.T6G(SCH_1):PAGE52
 U6017 CA26 A_PETP7 PT5161LRS-PT5161LRS,SMLF,IC,AJ051610U03     I1 @T6G_MB_LIB.T6G(SCH_1):PAGE459

P5E_CPU1_P3_RX_DP<9> @T6G_MB_LIB.T6G(SCH_1):P5E_CPU1_P3_RX_DP(9)
   U26 CW26 P3_RXP9 GENOA_SP5-SOCKET6096_13568-001,SMLF,IO,DGA^6000030   I147 @T6G_MB_LIB.T6G(SCH_1):PAGE52
 U6017 BP26 A_PETP6 PT5161LRS-PT5161LRS,SMLF,IC,AJ051610U03     I1 @T6G_MB_LIB.T6G(SCH_1):PAGE459

P5E_CPU1_P3_TX_BUF_C_DN<0> @T6G_MB_LIB.T6G(SCH_1):P5E_CPU1_P3_TX_BUF_C_DN(0)
 C6726    1      1 Q_CAP_DIFFBUS_C0201-DIFF BUS_0.22UF,6.3V,20%,X6S,SA    I47 @T6G_MB_LIB.T6G(SCH_1):PAGE461
  J110   L1     L1 CONN112_10137002101LF-CONN112_10137002-101LF,THLF,A    I76 @T6G_MB_LIB.T6G(SCH_1):PAGE318

P5E_CPU1_P3_TX_BUF_C_DN<10> @T6G_MB_LIB.T6G(SCH_1):P5E_CPU1_P3_TX_BUF_C_DN(10)
 C6746    1      1 Q_CAP_DIFFBUS_C0201-DIFF BUS_0.22UF,6.3V,20%,X6S,SA    I98 @T6G_MB_LIB.T6G(SCH_1):PAGE461
  J109   L3     L3 CONN112_10137002101LF-CONN112_10137002-101LF,THLF,A    I76 @T6G_MB_LIB.T6G(SCH_1):PAGE319

P5E_CPU1_P3_TX_BUF_C_DN<11> @T6G_MB_LIB.T6G(SCH_1):P5E_CPU1_P3_TX_BUF_C_DN(11)
 C6748    1      1 Q_CAP_DIFFBUS_C0201-DIFF BUS_0.22UF,6.3V,20%,X6S,SA    I96 @T6G_MB_LIB.T6G(SCH_1):PAGE461
  J109   K4     K4 CONN112_10137002101LF-CONN112_10137002-101LF,THLF,A    I76 @T6G_MB_LIB.T6G(SCH_1):PAGE319

P5E_CPU1_P3_TX_BUF_C_DN<12> @T6G_MB_LIB.T6G(SCH_1):P5E_CPU1_P3_TX_BUF_C_DN(12)
 C6750    1      1 Q_CAP_DIFFBUS_C0201-DIFF BUS_0.22UF,6.3V,20%,X6S,SA    I94 @T6G_MB_LIB.T6G(SCH_1):PAGE461
  J109   L5     L5 CONN112_10137002101LF-CONN112_10137002-101LF,THLF,A    I16 @T6G_MB_LIB.T6G(SCH_1):PAGE319

P5E_CPU1_P3_TX_BUF_C_DN<13> @T6G_MB_LIB.T6G(SCH_1):P5E_CPU1_P3_TX_BUF_C_DN(13)
 C6752    1      1 Q_CAP_DIFFBUS_C0201-DIFF BUS_0.22UF,6.3V,20%,X6S,SA    I92 @T6G_MB_LIB.T6G(SCH_1):PAGE461
  J109   K6     K6 CONN112_10137002101LF-CONN112_10137002-101LF,THLF,A    I16 @T6G_MB_LIB.T6G(SCH_1):PAGE319

P5E_CPU1_P3_TX_BUF_C_DN<14> @T6G_MB_LIB.T6G(SCH_1):P5E_CPU1_P3_TX_BUF_C_DN(14)
 C6754    1      1 Q_CAP_DIFFBUS_C0201-DIFF BUS_0.22UF,6.3V,20%,X6S,SA    I90 @T6G_MB_LIB.T6G(SCH_1):PAGE461
  J109   L7     L7 CONN112_10137002101LF-CONN112_10137002-101LF,THLF,A    I16 @T6G_MB_LIB.T6G(SCH_1):PAGE319

P5E_CPU1_P3_TX_BUF_C_DN<15> @T6G_MB_LIB.T6G(SCH_1):P5E_CPU1_P3_TX_BUF_C_DN(15)
 C6756    1      1 Q_CAP_DIFFBUS_C0201-DIFF BUS_0.22UF,6.3V,20%,X6S,SA    I88 @T6G_MB_LIB.T6G(SCH_1):PAGE461
  J109   K8     K8 CONN112_10137002101LF-CONN112_10137002-101LF,THLF,A    I16 @T6G_MB_LIB.T6G(SCH_1):PAGE319

P5E_CPU1_P3_TX_BUF_C_DN<1> @T6G_MB_LIB.T6G(SCH_1):P5E_CPU1_P3_TX_BUF_C_DN(1)
 C6728    1      1 Q_CAP_DIFFBUS_C0201-DIFF BUS_0.22UF,6.3V,20%,X6S,SA    I30 @T6G_MB_LIB.T6G(SCH_1):PAGE461
  J110   K2     K2 CONN112_10137002101LF-CONN112_10137002-101LF,THLF,A    I76 @T6G_MB_LIB.T6G(SCH_1):PAGE318

P5E_CPU1_P3_TX_BUF_C_DN<2> @T6G_MB_LIB.T6G(SCH_1):P5E_CPU1_P3_TX_BUF_C_DN(2)
 C6730    1      1 Q_CAP_DIFFBUS_C0201-DIFF BUS_0.22UF,6.3V,20%,X6S,SA    I29 @T6G_MB_LIB.T6G(SCH_1):PAGE461
  J110   L3     L3 CONN112_10137002101LF-CONN112_10137002-101LF,THLF,A    I76 @T6G_MB_LIB.T6G(SCH_1):PAGE318

P5E_CPU1_P3_TX_BUF_C_DN<3> @T6G_MB_LIB.T6G(SCH_1):P5E_CPU1_P3_TX_BUF_C_DN(3)
 C6732    1      1 Q_CAP_DIFFBUS_C0201-DIFF BUS_0.22UF,6.3V,20%,X6S,SA    I28 @T6G_MB_LIB.T6G(SCH_1):PAGE461
  J110   K4     K4 CONN112_10137002101LF-CONN112_10137002-101LF,THLF,A    I76 @T6G_MB_LIB.T6G(SCH_1):PAGE318

P5E_CPU1_P3_TX_BUF_C_DN<4> @T6G_MB_LIB.T6G(SCH_1):P5E_CPU1_P3_TX_BUF_C_DN(4)
 C6734    1      1 Q_CAP_DIFFBUS_C0201-DIFF BUS_0.22UF,6.3V,20%,X6S,SA    I25 @T6G_MB_LIB.T6G(SCH_1):PAGE461
  J110   L5     L5 CONN112_10137002101LF-CONN112_10137002-101LF,THLF,A    I16 @T6G_MB_LIB.T6G(SCH_1):PAGE318

P5E_CPU1_P3_TX_BUF_C_DN<5> @T6G_MB_LIB.T6G(SCH_1):P5E_CPU1_P3_TX_BUF_C_DN(5)
 C6736    1      1 Q_CAP_DIFFBUS_C0201-DIFF BUS_0.22UF,6.3V,20%,X6S,SA    I23 @T6G_MB_LIB.T6G(SCH_1):PAGE461
  J110   K6     K6 CONN112_10137002101LF-CONN112_10137002-101LF,THLF,A    I16 @T6G_MB_LIB.T6G(SCH_1):PAGE318

P5E_CPU1_P3_TX_BUF_C_DN<6> @T6G_MB_LIB.T6G(SCH_1):P5E_CPU1_P3_TX_BUF_C_DN(6)
 C6738    1      1 Q_CAP_DIFFBUS_C0201-DIFF BUS_0.22UF,6.3V,20%,X6S,SA    I16 @T6G_MB_LIB.T6G(SCH_1):PAGE461
  J110   L7     L7 CONN112_10137002101LF-CONN112_10137002-101LF,THLF,A    I16 @T6G_MB_LIB.T6G(SCH_1):PAGE318

P5E_CPU1_P3_TX_BUF_C_DN<7> @T6G_MB_LIB.T6G(SCH_1):P5E_CPU1_P3_TX_BUF_C_DN(7)
 C6740    1      1 Q_CAP_DIFFBUS_C0201-DIFF BUS_0.22UF,6.3V,20%,X6S,SA    I18 @T6G_MB_LIB.T6G(SCH_1):PAGE461
  J110   K8     K8 CONN112_10137002101LF-CONN112_10137002-101LF,THLF,A    I16 @T6G_MB_LIB.T6G(SCH_1):PAGE318

P5E_CPU1_P3_TX_BUF_C_DN<8> @T6G_MB_LIB.T6G(SCH_1):P5E_CPU1_P3_TX_BUF_C_DN(8)
 C6742    1      1 Q_CAP_DIFFBUS_C0201-DIFF BUS_0.22UF,6.3V,20%,X6S,SA   I104 @T6G_MB_LIB.T6G(SCH_1):PAGE461
  J109   L1     L1 CONN112_10137002101LF-CONN112_10137002-101LF,THLF,A    I76 @T6G_MB_LIB.T6G(SCH_1):PAGE319

P5E_CPU1_P3_TX_BUF_C_DN<9> @T6G_MB_LIB.T6G(SCH_1):P5E_CPU1_P3_TX_BUF_C_DN(9)
 C6744    1      1 Q_CAP_DIFFBUS_C0201-DIFF BUS_0.22UF,6.3V,20%,X6S,SA   I100 @T6G_MB_LIB.T6G(SCH_1):PAGE461
  J109   K2     K2 CONN112_10137002101LF-CONN112_10137002-101LF,THLF,A    I76 @T6G_MB_LIB.T6G(SCH_1):PAGE319

P5E_CPU1_P3_TX_BUF_C_DP<0> @T6G_MB_LIB.T6G(SCH_1):P5E_CPU1_P3_TX_BUF_C_DP(0)
 C6725    1      1 Q_CAP_DIFFBUS_C0201-DIFF BUS_0.22UF,6.3V,20%,X6S,SA    I48 @T6G_MB_LIB.T6G(SCH_1):PAGE461
  J110   M1     M1 CONN112_10137002101LF-CONN112_10137002-101LF,THLF,A    I76 @T6G_MB_LIB.T6G(SCH_1):PAGE318

P5E_CPU1_P3_TX_BUF_C_DP<10> @T6G_MB_LIB.T6G(SCH_1):P5E_CPU1_P3_TX_BUF_C_DP(10)
 C6745    1      1 Q_CAP_DIFFBUS_C0201-DIFF BUS_0.22UF,6.3V,20%,X6S,SA    I99 @T6G_MB_LIB.T6G(SCH_1):PAGE461
  J109   M3     M3 CONN112_10137002101LF-CONN112_10137002-101LF,THLF,A    I76 @T6G_MB_LIB.T6G(SCH_1):PAGE319

P5E_CPU1_P3_TX_BUF_C_DP<11> @T6G_MB_LIB.T6G(SCH_1):P5E_CPU1_P3_TX_BUF_C_DP(11)
 C6747    1      1 Q_CAP_DIFFBUS_C0201-DIFF BUS_0.22UF,6.3V,20%,X6S,SA    I97 @T6G_MB_LIB.T6G(SCH_1):PAGE461
  J109   L4     L4 CONN112_10137002101LF-CONN112_10137002-101LF,THLF,A    I76 @T6G_MB_LIB.T6G(SCH_1):PAGE319

P5E_CPU1_P3_TX_BUF_C_DP<12> @T6G_MB_LIB.T6G(SCH_1):P5E_CPU1_P3_TX_BUF_C_DP(12)
 C6749    1      1 Q_CAP_DIFFBUS_C0201-DIFF BUS_0.22UF,6.3V,20%,X6S,SA    I95 @T6G_MB_LIB.T6G(SCH_1):PAGE461
  J109   M5     M5 CONN112_10137002101LF-CONN112_10137002-101LF,THLF,A    I16 @T6G_MB_LIB.T6G(SCH_1):PAGE319

P5E_CPU1_P3_TX_BUF_C_DP<13> @T6G_MB_LIB.T6G(SCH_1):P5E_CPU1_P3_TX_BUF_C_DP(13)
 C6751    1      1 Q_CAP_DIFFBUS_C0201-DIFF BUS_0.22UF,6.3V,20%,X6S,SA    I93 @T6G_MB_LIB.T6G(SCH_1):PAGE461
  J109   L6     L6 CONN112_10137002101LF-CONN112_10137002-101LF,THLF,A    I16 @T6G_MB_LIB.T6G(SCH_1):PAGE319

P5E_CPU1_P3_TX_BUF_C_DP<14> @T6G_MB_LIB.T6G(SCH_1):P5E_CPU1_P3_TX_BUF_C_DP(14)
 C6753    1      1 Q_CAP_DIFFBUS_C0201-DIFF BUS_0.22UF,6.3V,20%,X6S,SA    I91 @T6G_MB_LIB.T6G(SCH_1):PAGE461
  J109   M7     M7 CONN112_10137002101LF-CONN112_10137002-101LF,THLF,A    I16 @T6G_MB_LIB.T6G(SCH_1):PAGE319

P5E_CPU1_P3_TX_BUF_C_DP<15> @T6G_MB_LIB.T6G(SCH_1):P5E_CPU1_P3_TX_BUF_C_DP(15)
 C6755    1      1 Q_CAP_DIFFBUS_C0201-DIFF BUS_0.22UF,6.3V,20%,X6S,SA    I89 @T6G_MB_LIB.T6G(SCH_1):PAGE461
  J109   L8     L8 CONN112_10137002101LF-CONN112_10137002-101LF,THLF,A    I16 @T6G_MB_LIB.T6G(SCH_1):PAGE319

P5E_CPU1_P3_TX_BUF_C_DP<1> @T6G_MB_LIB.T6G(SCH_1):P5E_CPU1_P3_TX_BUF_C_DP(1)
 C6727    1      1 Q_CAP_DIFFBUS_C0201-DIFF BUS_0.22UF,6.3V,20%,X6S,SA    I32 @T6G_MB_LIB.T6G(SCH_1):PAGE461
  J110   L2     L2 CONN112_10137002101LF-CONN112_10137002-101LF,THLF,A    I76 @T6G_MB_LIB.T6G(SCH_1):PAGE318

P5E_CPU1_P3_TX_BUF_C_DP<2> @T6G_MB_LIB.T6G(SCH_1):P5E_CPU1_P3_TX_BUF_C_DP(2)
 C6729    1      1 Q_CAP_DIFFBUS_C0201-DIFF BUS_0.22UF,6.3V,20%,X6S,SA    I31 @T6G_MB_LIB.T6G(SCH_1):PAGE461
  J110   M3     M3 CONN112_10137002101LF-CONN112_10137002-101LF,THLF,A    I76 @T6G_MB_LIB.T6G(SCH_1):PAGE318

P5E_CPU1_P3_TX_BUF_C_DP<3> @T6G_MB_LIB.T6G(SCH_1):P5E_CPU1_P3_TX_BUF_C_DP(3)
 C6731    1      1 Q_CAP_DIFFBUS_C0201-DIFF BUS_0.22UF,6.3V,20%,X6S,SA    I27 @T6G_MB_LIB.T6G(SCH_1):PAGE461
  J110   L4     L4 CONN112_10137002101LF-CONN112_10137002-101LF,THLF,A    I76 @T6G_MB_LIB.T6G(SCH_1):PAGE318

P5E_CPU1_P3_TX_BUF_C_DP<4> @T6G_MB_LIB.T6G(SCH_1):P5E_CPU1_P3_TX_BUF_C_DP(4)
 C6733    1      1 Q_CAP_DIFFBUS_C0201-DIFF BUS_0.22UF,6.3V,20%,X6S,SA    I26 @T6G_MB_LIB.T6G(SCH_1):PAGE461
  J110   M5     M5 CONN112_10137002101LF-CONN112_10137002-101LF,THLF,A    I16 @T6G_MB_LIB.T6G(SCH_1):PAGE318

P5E_CPU1_P3_TX_BUF_C_DP<5> @T6G_MB_LIB.T6G(SCH_1):P5E_CPU1_P3_TX_BUF_C_DP(5)
 C6735    1      1 Q_CAP_DIFFBUS_C0201-DIFF BUS_0.22UF,6.3V,20%,X6S,SA    I24 @T6G_MB_LIB.T6G(SCH_1):PAGE461
  J110   L6     L6 CONN112_10137002101LF-CONN112_10137002-101LF,THLF,A    I16 @T6G_MB_LIB.T6G(SCH_1):PAGE318

P5E_CPU1_P3_TX_BUF_C_DP<6> @T6G_MB_LIB.T6G(SCH_1):P5E_CPU1_P3_TX_BUF_C_DP(6)
 C6737    1      1 Q_CAP_DIFFBUS_C0201-DIFF BUS_0.22UF,6.3V,20%,X6S,SA    I22 @T6G_MB_LIB.T6G(SCH_1):PAGE461
  J110   M7     M7 CONN112_10137002101LF-CONN112_10137002-101LF,THLF,A    I16 @T6G_MB_LIB.T6G(SCH_1):PAGE318

P5E_CPU1_P3_TX_BUF_C_DP<7> @T6G_MB_LIB.T6G(SCH_1):P5E_CPU1_P3_TX_BUF_C_DP(7)
 C6739    1      1 Q_CAP_DIFFBUS_C0201-DIFF BUS_0.22UF,6.3V,20%,X6S,SA    I17 @T6G_MB_LIB.T6G(SCH_1):PAGE461
  J110   L8     L8 CONN112_10137002101LF-CONN112_10137002-101LF,THLF,A    I16 @T6G_MB_LIB.T6G(SCH_1):PAGE318

P5E_CPU1_P3_TX_BUF_C_DP<8> @T6G_MB_LIB.T6G(SCH_1):P5E_CPU1_P3_TX_BUF_C_DP(8)
 C6741    1      1 Q_CAP_DIFFBUS_C0201-DIFF BUS_0.22UF,6.3V,20%,X6S,SA   I105 @T6G_MB_LIB.T6G(SCH_1):PAGE461
  J109   M1     M1 CONN112_10137002101LF-CONN112_10137002-101LF,THLF,A    I76 @T6G_MB_LIB.T6G(SCH_1):PAGE319

P5E_CPU1_P3_TX_BUF_C_DP<9> @T6G_MB_LIB.T6G(SCH_1):P5E_CPU1_P3_TX_BUF_C_DP(9)
 C6743    1      1 Q_CAP_DIFFBUS_C0201-DIFF BUS_0.22UF,6.3V,20%,X6S,SA   I101 @T6G_MB_LIB.T6G(SCH_1):PAGE461
  J109   L2     L2 CONN112_10137002101LF-CONN112_10137002-101LF,THLF,A    I76 @T6G_MB_LIB.T6G(SCH_1):PAGE319

P5E_CPU1_P3_TX_BUF_DN<0> @T6G_MB_LIB.T6G(SCH_1):P5E_CPU1_P3_TX_BUF_DN(0)
 C6726    2      2 Q_CAP_DIFFBUS_C0201-DIFF BUS_0.22UF,6.3V,20%,X6S,SA    I47 @T6G_MB_LIB.T6G(SCH_1):PAGE461
 U6017 EW10 B_PETN15 PT5161LRS-PT5161LRS,SMLF,IC,AJ051610U03   I142 @T6G_MB_LIB.T6G(SCH_1):PAGE461

P5E_CPU1_P3_TX_BUF_DN<10> @T6G_MB_LIB.T6G(SCH_1):P5E_CPU1_P3_TX_BUF_DN(10)
 U6017 BJ10 B_PETN5 PT5161LRS-PT5161LRS,SMLF,IC,AJ051610U03    I46 @T6G_MB_LIB.T6G(SCH_1):PAGE461
 C6746    2      2 Q_CAP_DIFFBUS_C0201-DIFF BUS_0.22UF,6.3V,20%,X6S,SA    I98 @T6G_MB_LIB.T6G(SCH_1):PAGE461

P5E_CPU1_P3_TX_BUF_DN<11> @T6G_MB_LIB.T6G(SCH_1):P5E_CPU1_P3_TX_BUF_DN(11)
 U6017 BB10 B_PETN4 PT5161LRS-PT5161LRS,SMLF,IC,AJ051610U03    I46 @T6G_MB_LIB.T6G(SCH_1):PAGE461
 C6748    2      2 Q_CAP_DIFFBUS_C0201-DIFF BUS_0.22UF,6.3V,20%,X6S,SA    I96 @T6G_MB_LIB.T6G(SCH_1):PAGE461

P5E_CPU1_P3_TX_BUF_DN<12> @T6G_MB_LIB.T6G(SCH_1):P5E_CPU1_P3_TX_BUF_DN(12)
 U6017 AR10 B_PETN3 PT5161LRS-PT5161LRS,SMLF,IC,AJ051610U03    I46 @T6G_MB_LIB.T6G(SCH_1):PAGE461
 C6750    2      2 Q_CAP_DIFFBUS_C0201-DIFF BUS_0.22UF,6.3V,20%,X6S,SA    I94 @T6G_MB_LIB.T6G(SCH_1):PAGE461

P5E_CPU1_P3_TX_BUF_DN<13> @T6G_MB_LIB.T6G(SCH_1):P5E_CPU1_P3_TX_BUF_DN(13)
 U6017 AH10 B_PETN2 PT5161LRS-PT5161LRS,SMLF,IC,AJ051610U03    I46 @T6G_MB_LIB.T6G(SCH_1):PAGE461
 C6752    2      2 Q_CAP_DIFFBUS_C0201-DIFF BUS_0.22UF,6.3V,20%,X6S,SA    I92 @T6G_MB_LIB.T6G(SCH_1):PAGE461

P5E_CPU1_P3_TX_BUF_DN<14> @T6G_MB_LIB.T6G(SCH_1):P5E_CPU1_P3_TX_BUF_DN(14)
 U6017 AA10 B_PETN1 PT5161LRS-PT5161LRS,SMLF,IC,AJ051610U03    I46 @T6G_MB_LIB.T6G(SCH_1):PAGE461
 C6754    2      2 Q_CAP_DIFFBUS_C0201-DIFF BUS_0.22UF,6.3V,20%,X6S,SA    I90 @T6G_MB_LIB.T6G(SCH_1):PAGE461

P5E_CPU1_P3_TX_BUF_DN<15> @T6G_MB_LIB.T6G(SCH_1):P5E_CPU1_P3_TX_BUF_DN(15)
 U6017  P10 B_PETN0 PT5161LRS-PT5161LRS,SMLF,IC,AJ051610U03    I46 @T6G_MB_LIB.T6G(SCH_1):PAGE461
 C6756    2      2 Q_CAP_DIFFBUS_C0201-DIFF BUS_0.22UF,6.3V,20%,X6S,SA    I88 @T6G_MB_LIB.T6G(SCH_1):PAGE461

P5E_CPU1_P3_TX_BUF_DN<1> @T6G_MB_LIB.T6G(SCH_1):P5E_CPU1_P3_TX_BUF_DN(1)
 C6728    2      2 Q_CAP_DIFFBUS_C0201-DIFF BUS_0.22UF,6.3V,20%,X6S,SA    I30 @T6G_MB_LIB.T6G(SCH_1):PAGE461
 U6017 EM10 B_PETN14 PT5161LRS-PT5161LRS,SMLF,IC,AJ051610U03   I142 @T6G_MB_LIB.T6G(SCH_1):PAGE461

P5E_CPU1_P3_TX_BUF_DN<2> @T6G_MB_LIB.T6G(SCH_1):P5E_CPU1_P3_TX_BUF_DN(2)
 C6730    2      2 Q_CAP_DIFFBUS_C0201-DIFF BUS_0.22UF,6.3V,20%,X6S,SA    I29 @T6G_MB_LIB.T6G(SCH_1):PAGE461
 U6017 EE10 B_PETN13 PT5161LRS-PT5161LRS,SMLF,IC,AJ051610U03   I142 @T6G_MB_LIB.T6G(SCH_1):PAGE461

P5E_CPU1_P3_TX_BUF_DN<3> @T6G_MB_LIB.T6G(SCH_1):P5E_CPU1_P3_TX_BUF_DN(3)
 C6732    2      2 Q_CAP_DIFFBUS_C0201-DIFF BUS_0.22UF,6.3V,20%,X6S,SA    I28 @T6G_MB_LIB.T6G(SCH_1):PAGE461
 U6017 DV10 B_PETN12 PT5161LRS-PT5161LRS,SMLF,IC,AJ051610U03   I142 @T6G_MB_LIB.T6G(SCH_1):PAGE461

P5E_CPU1_P3_TX_BUF_DN<4> @T6G_MB_LIB.T6G(SCH_1):P5E_CPU1_P3_TX_BUF_DN(4)
 C6734    2      2 Q_CAP_DIFFBUS_C0201-DIFF BUS_0.22UF,6.3V,20%,X6S,SA    I25 @T6G_MB_LIB.T6G(SCH_1):PAGE461
 U6017 DL10 B_PETN11 PT5161LRS-PT5161LRS,SMLF,IC,AJ051610U03   I142 @T6G_MB_LIB.T6G(SCH_1):PAGE461

P5E_CPU1_P3_TX_BUF_DN<5> @T6G_MB_LIB.T6G(SCH_1):P5E_CPU1_P3_TX_BUF_DN(5)
 C6736    2      2 Q_CAP_DIFFBUS_C0201-DIFF BUS_0.22UF,6.3V,20%,X6S,SA    I23 @T6G_MB_LIB.T6G(SCH_1):PAGE461
 U6017 DD10 B_PETN10 PT5161LRS-PT5161LRS,SMLF,IC,AJ051610U03   I142 @T6G_MB_LIB.T6G(SCH_1):PAGE461

P5E_CPU1_P3_TX_BUF_DN<6> @T6G_MB_LIB.T6G(SCH_1):P5E_CPU1_P3_TX_BUF_DN(6)
 C6738    2      2 Q_CAP_DIFFBUS_C0201-DIFF BUS_0.22UF,6.3V,20%,X6S,SA    I16 @T6G_MB_LIB.T6G(SCH_1):PAGE461
 U6017 CU10 B_PETN9 PT5161LRS-PT5161LRS,SMLF,IC,AJ051610U03   I142 @T6G_MB_LIB.T6G(SCH_1):PAGE461

P5E_CPU1_P3_TX_BUF_DN<7> @T6G_MB_LIB.T6G(SCH_1):P5E_CPU1_P3_TX_BUF_DN(7)
 C6740    2      2 Q_CAP_DIFFBUS_C0201-DIFF BUS_0.22UF,6.3V,20%,X6S,SA    I18 @T6G_MB_LIB.T6G(SCH_1):PAGE461
 U6017 CK10 B_PETN8 PT5161LRS-PT5161LRS,SMLF,IC,AJ051610U03   I142 @T6G_MB_LIB.T6G(SCH_1):PAGE461

P5E_CPU1_P3_TX_BUF_DN<8> @T6G_MB_LIB.T6G(SCH_1):P5E_CPU1_P3_TX_BUF_DN(8)
 U6017 CC10 B_PETN7 PT5161LRS-PT5161LRS,SMLF,IC,AJ051610U03    I46 @T6G_MB_LIB.T6G(SCH_1):PAGE461
 C6742    2      2 Q_CAP_DIFFBUS_C0201-DIFF BUS_0.22UF,6.3V,20%,X6S,SA   I104 @T6G_MB_LIB.T6G(SCH_1):PAGE461

P5E_CPU1_P3_TX_BUF_DN<9> @T6G_MB_LIB.T6G(SCH_1):P5E_CPU1_P3_TX_BUF_DN(9)
 U6017 BT10 B_PETN6 PT5161LRS-PT5161LRS,SMLF,IC,AJ051610U03    I46 @T6G_MB_LIB.T6G(SCH_1):PAGE461
 C6744    2      2 Q_CAP_DIFFBUS_C0201-DIFF BUS_0.22UF,6.3V,20%,X6S,SA   I100 @T6G_MB_LIB.T6G(SCH_1):PAGE461

P5E_CPU1_P3_TX_BUF_DP<0> @T6G_MB_LIB.T6G(SCH_1):P5E_CPU1_P3_TX_BUF_DP(0)
 C6725    2      2 Q_CAP_DIFFBUS_C0201-DIFF BUS_0.22UF,6.3V,20%,X6S,SA    I48 @T6G_MB_LIB.T6G(SCH_1):PAGE461
 U6017  EU7 B_PETP15 PT5161LRS-PT5161LRS,SMLF,IC,AJ051610U03   I142 @T6G_MB_LIB.T6G(SCH_1):PAGE461

P5E_CPU1_P3_TX_BUF_DP<10> @T6G_MB_LIB.T6G(SCH_1):P5E_CPU1_P3_TX_BUF_DP(10)
 U6017  BG7 B_PETP5 PT5161LRS-PT5161LRS,SMLF,IC,AJ051610U03    I46 @T6G_MB_LIB.T6G(SCH_1):PAGE461
 C6745    2      2 Q_CAP_DIFFBUS_C0201-DIFF BUS_0.22UF,6.3V,20%,X6S,SA    I99 @T6G_MB_LIB.T6G(SCH_1):PAGE461

P5E_CPU1_P3_TX_BUF_DP<11> @T6G_MB_LIB.T6G(SCH_1):P5E_CPU1_P3_TX_BUF_DP(11)
 U6017  AY7 B_PETP4 PT5161LRS-PT5161LRS,SMLF,IC,AJ051610U03    I46 @T6G_MB_LIB.T6G(SCH_1):PAGE461
 C6747    2      2 Q_CAP_DIFFBUS_C0201-DIFF BUS_0.22UF,6.3V,20%,X6S,SA    I97 @T6G_MB_LIB.T6G(SCH_1):PAGE461

P5E_CPU1_P3_TX_BUF_DP<12> @T6G_MB_LIB.T6G(SCH_1):P5E_CPU1_P3_TX_BUF_DP(12)
 U6017  AN7 B_PETP3 PT5161LRS-PT5161LRS,SMLF,IC,AJ051610U03    I46 @T6G_MB_LIB.T6G(SCH_1):PAGE461
 C6749    2      2 Q_CAP_DIFFBUS_C0201-DIFF BUS_0.22UF,6.3V,20%,X6S,SA    I95 @T6G_MB_LIB.T6G(SCH_1):PAGE461

P5E_CPU1_P3_TX_BUF_DP<13> @T6G_MB_LIB.T6G(SCH_1):P5E_CPU1_P3_TX_BUF_DP(13)
 U6017  AF7 B_PETP2 PT5161LRS-PT5161LRS,SMLF,IC,AJ051610U03    I46 @T6G_MB_LIB.T6G(SCH_1):PAGE461
 C6751    2      2 Q_CAP_DIFFBUS_C0201-DIFF BUS_0.22UF,6.3V,20%,X6S,SA    I93 @T6G_MB_LIB.T6G(SCH_1):PAGE461

P5E_CPU1_P3_TX_BUF_DP<14> @T6G_MB_LIB.T6G(SCH_1):P5E_CPU1_P3_TX_BUF_DP(14)
 U6017   W7 B_PETP1 PT5161LRS-PT5161LRS,SMLF,IC,AJ051610U03    I46 @T6G_MB_LIB.T6G(SCH_1):PAGE461
 C6753    2      2 Q_CAP_DIFFBUS_C0201-DIFF BUS_0.22UF,6.3V,20%,X6S,SA    I91 @T6G_MB_LIB.T6G(SCH_1):PAGE461

P5E_CPU1_P3_TX_BUF_DP<15> @T6G_MB_LIB.T6G(SCH_1):P5E_CPU1_P3_TX_BUF_DP(15)
 U6017   M7 B_PETP0 PT5161LRS-PT5161LRS,SMLF,IC,AJ051610U03    I46 @T6G_MB_LIB.T6G(SCH_1):PAGE461
 C6755    2      2 Q_CAP_DIFFBUS_C0201-DIFF BUS_0.22UF,6.3V,20%,X6S,SA    I89 @T6G_MB_LIB.T6G(SCH_1):PAGE461

P5E_CPU1_P3_TX_BUF_DP<1> @T6G_MB_LIB.T6G(SCH_1):P5E_CPU1_P3_TX_BUF_DP(1)
 C6727    2      2 Q_CAP_DIFFBUS_C0201-DIFF BUS_0.22UF,6.3V,20%,X6S,SA    I32 @T6G_MB_LIB.T6G(SCH_1):PAGE461
 U6017  EK7 B_PETP14 PT5161LRS-PT5161LRS,SMLF,IC,AJ051610U03   I142 @T6G_MB_LIB.T6G(SCH_1):PAGE461

P5E_CPU1_P3_TX_BUF_DP<2> @T6G_MB_LIB.T6G(SCH_1):P5E_CPU1_P3_TX_BUF_DP(2)
 C6729    2      2 Q_CAP_DIFFBUS_C0201-DIFF BUS_0.22UF,6.3V,20%,X6S,SA    I31 @T6G_MB_LIB.T6G(SCH_1):PAGE461
 U6017  EC7 B_PETP13 PT5161LRS-PT5161LRS,SMLF,IC,AJ051610U03   I142 @T6G_MB_LIB.T6G(SCH_1):PAGE461

P5E_CPU1_P3_TX_BUF_DP<3> @T6G_MB_LIB.T6G(SCH_1):P5E_CPU1_P3_TX_BUF_DP(3)
 C6731    2      2 Q_CAP_DIFFBUS_C0201-DIFF BUS_0.22UF,6.3V,20%,X6S,SA    I27 @T6G_MB_LIB.T6G(SCH_1):PAGE461
 U6017  DT7 B_PETP12 PT5161LRS-PT5161LRS,SMLF,IC,AJ051610U03   I142 @T6G_MB_LIB.T6G(SCH_1):PAGE461

P5E_CPU1_P3_TX_BUF_DP<4> @T6G_MB_LIB.T6G(SCH_1):P5E_CPU1_P3_TX_BUF_DP(4)
 C6733    2      2 Q_CAP_DIFFBUS_C0201-DIFF BUS_0.22UF,6.3V,20%,X6S,SA    I26 @T6G_MB_LIB.T6G(SCH_1):PAGE461
 U6017  DJ7 B_PETP11 PT5161LRS-PT5161LRS,SMLF,IC,AJ051610U03   I142 @T6G_MB_LIB.T6G(SCH_1):PAGE461

P5E_CPU1_P3_TX_BUF_DP<5> @T6G_MB_LIB.T6G(SCH_1):P5E_CPU1_P3_TX_BUF_DP(5)
 C6735    2      2 Q_CAP_DIFFBUS_C0201-DIFF BUS_0.22UF,6.3V,20%,X6S,SA    I24 @T6G_MB_LIB.T6G(SCH_1):PAGE461
 U6017  DB7 B_PETP10 PT5161LRS-PT5161LRS,SMLF,IC,AJ051610U03   I142 @T6G_MB_LIB.T6G(SCH_1):PAGE461

P5E_CPU1_P3_TX_BUF_DP<6> @T6G_MB_LIB.T6G(SCH_1):P5E_CPU1_P3_TX_BUF_DP(6)
 C6737    2      2 Q_CAP_DIFFBUS_C0201-DIFF BUS_0.22UF,6.3V,20%,X6S,SA    I22 @T6G_MB_LIB.T6G(SCH_1):PAGE461
 U6017  CR7 B_PETP9 PT5161LRS-PT5161LRS,SMLF,IC,AJ051610U03   I142 @T6G_MB_LIB.T6G(SCH_1):PAGE461

P5E_CPU1_P3_TX_BUF_DP<7> @T6G_MB_LIB.T6G(SCH_1):P5E_CPU1_P3_TX_BUF_DP(7)
 C6739    2      2 Q_CAP_DIFFBUS_C0201-DIFF BUS_0.22UF,6.3V,20%,X6S,SA    I17 @T6G_MB_LIB.T6G(SCH_1):PAGE461
 U6017  CH7 B_PETP8 PT5161LRS-PT5161LRS,SMLF,IC,AJ051610U03   I142 @T6G_MB_LIB.T6G(SCH_1):PAGE461

P5E_CPU1_P3_TX_BUF_DP<8> @T6G_MB_LIB.T6G(SCH_1):P5E_CPU1_P3_TX_BUF_DP(8)
 U6017  CA7 B_PETP7 PT5161LRS-PT5161LRS,SMLF,IC,AJ051610U03    I46 @T6G_MB_LIB.T6G(SCH_1):PAGE461
 C6741    2      2 Q_CAP_DIFFBUS_C0201-DIFF BUS_0.22UF,6.3V,20%,X6S,SA   I105 @T6G_MB_LIB.T6G(SCH_1):PAGE461

P5E_CPU1_P3_TX_BUF_DP<9> @T6G_MB_LIB.T6G(SCH_1):P5E_CPU1_P3_TX_BUF_DP(9)
 U6017  BP7 B_PETP6 PT5161LRS-PT5161LRS,SMLF,IC,AJ051610U03    I46 @T6G_MB_LIB.T6G(SCH_1):PAGE461
 C6743    2      2 Q_CAP_DIFFBUS_C0201-DIFF BUS_0.22UF,6.3V,20%,X6S,SA   I101 @T6G_MB_LIB.T6G(SCH_1):PAGE461

P5E_CPU1_P3_TX_C_DN<0> @T6G_MB_LIB.T6G(SCH_1):P5E_CPU1_P3_TX_C_DN(0)
 C1546    1      1 Q_CAP_DIFFBUS_C0201-DIFF BUS_0.22UF,6.3V,20%,X6S,SA    I54 @T6G_MB_LIB.T6G(SCH_1):PAGE355
 U6017 EV34 B_PERP15 PT5161LRS-PT5161LRS,SMLF,IC,AJ051610U03    I38 @T6G_MB_LIB.T6G(SCH_1):PAGE458

P5E_CPU1_P3_TX_C_DN<10> @T6G_MB_LIB.T6G(SCH_1):P5E_CPU1_P3_TX_C_DN(10)
 C1526    1      1 Q_CAP_DIFFBUS_C0201-DIFF BUS_0.22UF,6.3V,20%,X6S,SA    I81 @T6G_MB_LIB.T6G(SCH_1):PAGE355
 U6017 BH34 B_PERP5 PT5161LRS-PT5161LRS,SMLF,IC,AJ051610U03     I1 @T6G_MB_LIB.T6G(SCH_1):PAGE458

P5E_CPU1_P3_TX_C_DN<11> @T6G_MB_LIB.T6G(SCH_1):P5E_CPU1_P3_TX_C_DN(11)
 C1524    1      1 Q_CAP_DIFFBUS_C0201-DIFF BUS_0.22UF,6.3V,20%,X6S,SA    I84 @T6G_MB_LIB.T6G(SCH_1):PAGE355
 U6017 BA34 B_PERP4 PT5161LRS-PT5161LRS,SMLF,IC,AJ051610U03     I1 @T6G_MB_LIB.T6G(SCH_1):PAGE458

P5E_CPU1_P3_TX_C_DN<12> @T6G_MB_LIB.T6G(SCH_1):P5E_CPU1_P3_TX_C_DN(12)
   C54    1      1 Q_CAP_DIFFBUS_C0201-DIFF BUS_0.22UF,6.3V,20%,X6S,SA    I86 @T6G_MB_LIB.T6G(SCH_1):PAGE355
 U6017 AP34 B_PERP3 PT5161LRS-PT5161LRS,SMLF,IC,AJ051610U03     I1 @T6G_MB_LIB.T6G(SCH_1):PAGE458

P5E_CPU1_P3_TX_C_DN<13> @T6G_MB_LIB.T6G(SCH_1):P5E_CPU1_P3_TX_C_DN(13)
   C52    1      1 Q_CAP_DIFFBUS_C0201-DIFF BUS_0.22UF,6.3V,20%,X6S,SA   I116 @T6G_MB_LIB.T6G(SCH_1):PAGE355
 U6017 AG34 B_PERP2 PT5161LRS-PT5161LRS,SMLF,IC,AJ051610U03     I1 @T6G_MB_LIB.T6G(SCH_1):PAGE458

P5E_CPU1_P3_TX_C_DN<14> @T6G_MB_LIB.T6G(SCH_1):P5E_CPU1_P3_TX_C_DN(14)
   C50    1      1 Q_CAP_DIFFBUS_C0201-DIFF BUS_0.22UF,6.3V,20%,X6S,SA   I118 @T6G_MB_LIB.T6G(SCH_1):PAGE355
 U6017 AB35 B_PERN1 PT5161LRS-PT5161LRS,SMLF,IC,AJ051610U03     I1 @T6G_MB_LIB.T6G(SCH_1):PAGE458

P5E_CPU1_P3_TX_C_DN<15> @T6G_MB_LIB.T6G(SCH_1):P5E_CPU1_P3_TX_C_DN(15)
   C48    1      1 Q_CAP_DIFFBUS_C0201-DIFF BUS_0.22UF,6.3V,20%,X6S,SA   I119 @T6G_MB_LIB.T6G(SCH_1):PAGE355
 U6017  N34 B_PERP0 PT5161LRS-PT5161LRS,SMLF,IC,AJ051610U03     I1 @T6G_MB_LIB.T6G(SCH_1):PAGE458

P5E_CPU1_P3_TX_C_DN<1> @T6G_MB_LIB.T6G(SCH_1):P5E_CPU1_P3_TX_C_DN(1)
 C1544    1      1 Q_CAP_DIFFBUS_C0201-DIFF BUS_0.22UF,6.3V,20%,X6S,SA    I55 @T6G_MB_LIB.T6G(SCH_1):PAGE355
 U6017 EN35 B_PERN14 PT5161LRS-PT5161LRS,SMLF,IC,AJ051610U03    I38 @T6G_MB_LIB.T6G(SCH_1):PAGE458

P5E_CPU1_P3_TX_C_DN<2> @T6G_MB_LIB.T6G(SCH_1):P5E_CPU1_P3_TX_C_DN(2)
 C1542    1      1 Q_CAP_DIFFBUS_C0201-DIFF BUS_0.22UF,6.3V,20%,X6S,SA    I58 @T6G_MB_LIB.T6G(SCH_1):PAGE355
 U6017 ED34 B_PERP13 PT5161LRS-PT5161LRS,SMLF,IC,AJ051610U03    I38 @T6G_MB_LIB.T6G(SCH_1):PAGE458

P5E_CPU1_P3_TX_C_DN<3> @T6G_MB_LIB.T6G(SCH_1):P5E_CPU1_P3_TX_C_DN(3)
 C1540    1      1 Q_CAP_DIFFBUS_C0201-DIFF BUS_0.22UF,6.3V,20%,X6S,SA    I68 @T6G_MB_LIB.T6G(SCH_1):PAGE355
 U6017 DU34 B_PERP12 PT5161LRS-PT5161LRS,SMLF,IC,AJ051610U03    I38 @T6G_MB_LIB.T6G(SCH_1):PAGE458

P5E_CPU1_P3_TX_C_DN<4> @T6G_MB_LIB.T6G(SCH_1):P5E_CPU1_P3_TX_C_DN(4)
 C1538    1      1 Q_CAP_DIFFBUS_C0201-DIFF BUS_0.22UF,6.3V,20%,X6S,SA    I70 @T6G_MB_LIB.T6G(SCH_1):PAGE355
 U6017 DK34 B_PERP11 PT5161LRS-PT5161LRS,SMLF,IC,AJ051610U03    I38 @T6G_MB_LIB.T6G(SCH_1):PAGE458

P5E_CPU1_P3_TX_C_DN<5> @T6G_MB_LIB.T6G(SCH_1):P5E_CPU1_P3_TX_C_DN(5)
 C1536    1      1 Q_CAP_DIFFBUS_C0201-DIFF BUS_0.22UF,6.3V,20%,X6S,SA    I72 @T6G_MB_LIB.T6G(SCH_1):PAGE355
 U6017 DC34 B_PERP10 PT5161LRS-PT5161LRS,SMLF,IC,AJ051610U03    I38 @T6G_MB_LIB.T6G(SCH_1):PAGE458

P5E_CPU1_P3_TX_C_DN<6> @T6G_MB_LIB.T6G(SCH_1):P5E_CPU1_P3_TX_C_DN(6)
 C1534    1      1 Q_CAP_DIFFBUS_C0201-DIFF BUS_0.22UF,6.3V,20%,X6S,SA    I74 @T6G_MB_LIB.T6G(SCH_1):PAGE355
 U6017 CT34 B_PERP9 PT5161LRS-PT5161LRS,SMLF,IC,AJ051610U03    I38 @T6G_MB_LIB.T6G(SCH_1):PAGE458

P5E_CPU1_P3_TX_C_DN<7> @T6G_MB_LIB.T6G(SCH_1):P5E_CPU1_P3_TX_C_DN(7)
 C1532    1      1 Q_CAP_DIFFBUS_C0201-DIFF BUS_0.22UF,6.3V,20%,X6S,SA    I76 @T6G_MB_LIB.T6G(SCH_1):PAGE355
 U6017 CJ34 B_PERP8 PT5161LRS-PT5161LRS,SMLF,IC,AJ051610U03    I38 @T6G_MB_LIB.T6G(SCH_1):PAGE458

P5E_CPU1_P3_TX_C_DN<8> @T6G_MB_LIB.T6G(SCH_1):P5E_CPU1_P3_TX_C_DN(8)
 C1530    1      1 Q_CAP_DIFFBUS_C0201-DIFF BUS_0.22UF,6.3V,20%,X6S,SA    I78 @T6G_MB_LIB.T6G(SCH_1):PAGE355
 U6017 CB34 B_PERP7 PT5161LRS-PT5161LRS,SMLF,IC,AJ051610U03     I1 @T6G_MB_LIB.T6G(SCH_1):PAGE458

P5E_CPU1_P3_TX_C_DN<9> @T6G_MB_LIB.T6G(SCH_1):P5E_CPU1_P3_TX_C_DN(9)
 C1528    1      1 Q_CAP_DIFFBUS_C0201-DIFF BUS_0.22UF,6.3V,20%,X6S,SA    I80 @T6G_MB_LIB.T6G(SCH_1):PAGE355
 U6017 BR34 B_PERP6 PT5161LRS-PT5161LRS,SMLF,IC,AJ051610U03     I1 @T6G_MB_LIB.T6G(SCH_1):PAGE458

P5E_CPU1_P3_TX_C_DP<0> @T6G_MB_LIB.T6G(SCH_1):P5E_CPU1_P3_TX_C_DP(0)
 C1547    1      1 Q_CAP_DIFFBUS_C0201-DIFF BUS_0.22UF,6.3V,20%,X6S,SA    I53 @T6G_MB_LIB.T6G(SCH_1):PAGE355
 U6017 EY35 B_PERN15 PT5161LRS-PT5161LRS,SMLF,IC,AJ051610U03    I38 @T6G_MB_LIB.T6G(SCH_1):PAGE458

P5E_CPU1_P3_TX_C_DP<10> @T6G_MB_LIB.T6G(SCH_1):P5E_CPU1_P3_TX_C_DP(10)
 C1527    1      1 Q_CAP_DIFFBUS_C0201-DIFF BUS_0.22UF,6.3V,20%,X6S,SA    I82 @T6G_MB_LIB.T6G(SCH_1):PAGE355
 U6017 BK35 B_PERN5 PT5161LRS-PT5161LRS,SMLF,IC,AJ051610U03     I1 @T6G_MB_LIB.T6G(SCH_1):PAGE458

P5E_CPU1_P3_TX_C_DP<11> @T6G_MB_LIB.T6G(SCH_1):P5E_CPU1_P3_TX_C_DP(11)
 C1525    1      1 Q_CAP_DIFFBUS_C0201-DIFF BUS_0.22UF,6.3V,20%,X6S,SA    I83 @T6G_MB_LIB.T6G(SCH_1):PAGE355
 U6017 BC35 B_PERN4 PT5161LRS-PT5161LRS,SMLF,IC,AJ051610U03     I1 @T6G_MB_LIB.T6G(SCH_1):PAGE458

P5E_CPU1_P3_TX_C_DP<12> @T6G_MB_LIB.T6G(SCH_1):P5E_CPU1_P3_TX_C_DP(12)
   C55    1      1 Q_CAP_DIFFBUS_C0201-DIFF BUS_0.22UF,6.3V,20%,X6S,SA    I85 @T6G_MB_LIB.T6G(SCH_1):PAGE355
 U6017 AT35 B_PERN3 PT5161LRS-PT5161LRS,SMLF,IC,AJ051610U03     I1 @T6G_MB_LIB.T6G(SCH_1):PAGE458

P5E_CPU1_P3_TX_C_DP<13> @T6G_MB_LIB.T6G(SCH_1):P5E_CPU1_P3_TX_C_DP(13)
   C53    1      1 Q_CAP_DIFFBUS_C0201-DIFF BUS_0.22UF,6.3V,20%,X6S,SA   I107 @T6G_MB_LIB.T6G(SCH_1):PAGE355
 U6017 AJ35 B_PERN2 PT5161LRS-PT5161LRS,SMLF,IC,AJ051610U03     I1 @T6G_MB_LIB.T6G(SCH_1):PAGE458

P5E_CPU1_P3_TX_C_DP<14> @T6G_MB_LIB.T6G(SCH_1):P5E_CPU1_P3_TX_C_DP(14)
   C51    1      1 Q_CAP_DIFFBUS_C0201-DIFF BUS_0.22UF,6.3V,20%,X6S,SA   I117 @T6G_MB_LIB.T6G(SCH_1):PAGE355
 U6017  Y34 B_PERP1 PT5161LRS-PT5161LRS,SMLF,IC,AJ051610U03     I1 @T6G_MB_LIB.T6G(SCH_1):PAGE458

P5E_CPU1_P3_TX_C_DP<15> @T6G_MB_LIB.T6G(SCH_1):P5E_CPU1_P3_TX_C_DP(15)
   C49    1      1 Q_CAP_DIFFBUS_C0201-DIFF BUS_0.22UF,6.3V,20%,X6S,SA   I120 @T6G_MB_LIB.T6G(SCH_1):PAGE355
 U6017  R35 B_PERN0 PT5161LRS-PT5161LRS,SMLF,IC,AJ051610U03     I1 @T6G_MB_LIB.T6G(SCH_1):PAGE458

P5E_CPU1_P3_TX_C_DP<1> @T6G_MB_LIB.T6G(SCH_1):P5E_CPU1_P3_TX_C_DP(1)
 C1545    1      1 Q_CAP_DIFFBUS_C0201-DIFF BUS_0.22UF,6.3V,20%,X6S,SA    I56 @T6G_MB_LIB.T6G(SCH_1):PAGE355
 U6017 EL34 B_PERP14 PT5161LRS-PT5161LRS,SMLF,IC,AJ051610U03    I38 @T6G_MB_LIB.T6G(SCH_1):PAGE458

P5E_CPU1_P3_TX_C_DP<2> @T6G_MB_LIB.T6G(SCH_1):P5E_CPU1_P3_TX_C_DP(2)
 C1543    1      1 Q_CAP_DIFFBUS_C0201-DIFF BUS_0.22UF,6.3V,20%,X6S,SA    I57 @T6G_MB_LIB.T6G(SCH_1):PAGE355
 U6017 EF35 B_PERN13 PT5161LRS-PT5161LRS,SMLF,IC,AJ051610U03    I38 @T6G_MB_LIB.T6G(SCH_1):PAGE458

P5E_CPU1_P3_TX_C_DP<3> @T6G_MB_LIB.T6G(SCH_1):P5E_CPU1_P3_TX_C_DP(3)
 C1541    1      1 Q_CAP_DIFFBUS_C0201-DIFF BUS_0.22UF,6.3V,20%,X6S,SA    I67 @T6G_MB_LIB.T6G(SCH_1):PAGE355
 U6017 DW35 B_PERN12 PT5161LRS-PT5161LRS,SMLF,IC,AJ051610U03    I38 @T6G_MB_LIB.T6G(SCH_1):PAGE458

P5E_CPU1_P3_TX_C_DP<4> @T6G_MB_LIB.T6G(SCH_1):P5E_CPU1_P3_TX_C_DP(4)
 C1539    1      1 Q_CAP_DIFFBUS_C0201-DIFF BUS_0.22UF,6.3V,20%,X6S,SA    I69 @T6G_MB_LIB.T6G(SCH_1):PAGE355
 U6017 DM35 B_PERN11 PT5161LRS-PT5161LRS,SMLF,IC,AJ051610U03    I38 @T6G_MB_LIB.T6G(SCH_1):PAGE458

P5E_CPU1_P3_TX_C_DP<5> @T6G_MB_LIB.T6G(SCH_1):P5E_CPU1_P3_TX_C_DP(5)
 C1537    1      1 Q_CAP_DIFFBUS_C0201-DIFF BUS_0.22UF,6.3V,20%,X6S,SA    I71 @T6G_MB_LIB.T6G(SCH_1):PAGE355
 U6017 DE35 B_PERN10 PT5161LRS-PT5161LRS,SMLF,IC,AJ051610U03    I38 @T6G_MB_LIB.T6G(SCH_1):PAGE458

P5E_CPU1_P3_TX_C_DP<6> @T6G_MB_LIB.T6G(SCH_1):P5E_CPU1_P3_TX_C_DP(6)
 C1535    1      1 Q_CAP_DIFFBUS_C0201-DIFF BUS_0.22UF,6.3V,20%,X6S,SA    I73 @T6G_MB_LIB.T6G(SCH_1):PAGE355
 U6017 CV35 B_PERN9 PT5161LRS-PT5161LRS,SMLF,IC,AJ051610U03    I38 @T6G_MB_LIB.T6G(SCH_1):PAGE458

P5E_CPU1_P3_TX_C_DP<7> @T6G_MB_LIB.T6G(SCH_1):P5E_CPU1_P3_TX_C_DP(7)
 C1533    1      1 Q_CAP_DIFFBUS_C0201-DIFF BUS_0.22UF,6.3V,20%,X6S,SA    I75 @T6G_MB_LIB.T6G(SCH_1):PAGE355
 U6017 CL35 B_PERN8 PT5161LRS-PT5161LRS,SMLF,IC,AJ051610U03    I38 @T6G_MB_LIB.T6G(SCH_1):PAGE458

P5E_CPU1_P3_TX_C_DP<8> @T6G_MB_LIB.T6G(SCH_1):P5E_CPU1_P3_TX_C_DP(8)
 C1531    1      1 Q_CAP_DIFFBUS_C0201-DIFF BUS_0.22UF,6.3V,20%,X6S,SA    I77 @T6G_MB_LIB.T6G(SCH_1):PAGE355
 U6017 CD35 B_PERN7 PT5161LRS-PT5161LRS,SMLF,IC,AJ051610U03     I1 @T6G_MB_LIB.T6G(SCH_1):PAGE458

P5E_CPU1_P3_TX_C_DP<9> @T6G_MB_LIB.T6G(SCH_1):P5E_CPU1_P3_TX_C_DP(9)
 C1529    1      1 Q_CAP_DIFFBUS_C0201-DIFF BUS_0.22UF,6.3V,20%,X6S,SA    I79 @T6G_MB_LIB.T6G(SCH_1):PAGE355
 U6017 BU35 B_PERN6 PT5161LRS-PT5161LRS,SMLF,IC,AJ051610U03     I1 @T6G_MB_LIB.T6G(SCH_1):PAGE458

P5E_CPU1_P3_TX_DN<0> @T6G_MB_LIB.T6G(SCH_1):P5E_CPU1_P3_TX_DN(0)
   U26 CD35 P3_TXN0 GENOA_SP5-SOCKET6096_13568-001,SMLF,IO,DGA^6000030   I147 @T6G_MB_LIB.T6G(SCH_1):PAGE52
 C1546    2      2 Q_CAP_DIFFBUS_C0201-DIFF BUS_0.22UF,6.3V,20%,X6S,SA    I54 @T6G_MB_LIB.T6G(SCH_1):PAGE355

P5E_CPU1_P3_TX_DN<10> @T6G_MB_LIB.T6G(SCH_1):P5E_CPU1_P3_TX_DN(10)
   U26 CC26 P3_TXN10 GENOA_SP5-SOCKET6096_13568-001,SMLF,IO,DGA^6000030   I147 @T6G_MB_LIB.T6G(SCH_1):PAGE52
 C1526    2      2 Q_CAP_DIFFBUS_C0201-DIFF BUS_0.22UF,6.3V,20%,X6S,SA    I81 @T6G_MB_LIB.T6G(SCH_1):PAGE355

P5E_CPU1_P3_TX_DN<11> @T6G_MB_LIB.T6G(SCH_1):P5E_CPU1_P3_TX_DN(11)
   U26 CG26 P3_TXN11 GENOA_SP5-SOCKET6096_13568-001,SMLF,IO,DGA^6000030   I147 @T6G_MB_LIB.T6G(SCH_1):PAGE52
 C1524    2      2 Q_CAP_DIFFBUS_C0201-DIFF BUS_0.22UF,6.3V,20%,X6S,SA    I84 @T6G_MB_LIB.T6G(SCH_1):PAGE355

P5E_CPU1_P3_TX_DN<12> @T6G_MB_LIB.T6G(SCH_1):P5E_CPU1_P3_TX_DN(12)
   U26 CE26 P3_TXN12 GENOA_SP5-SOCKET6096_13568-001,SMLF,IO,DGA^6000030   I147 @T6G_MB_LIB.T6G(SCH_1):PAGE52
   C54    2      2 Q_CAP_DIFFBUS_C0201-DIFF BUS_0.22UF,6.3V,20%,X6S,SA    I86 @T6G_MB_LIB.T6G(SCH_1):PAGE355

P5E_CPU1_P3_TX_DN<13> @T6G_MB_LIB.T6G(SCH_1):P5E_CPU1_P3_TX_DN(13)
   U26 CC23 P3_TXN13 GENOA_SP5-SOCKET6096_13568-001,SMLF,IO,DGA^6000030   I147 @T6G_MB_LIB.T6G(SCH_1):PAGE52
   C52    2      2 Q_CAP_DIFFBUS_C0201-DIFF BUS_0.22UF,6.3V,20%,X6S,SA   I116 @T6G_MB_LIB.T6G(SCH_1):PAGE355

P5E_CPU1_P3_TX_DN<14> @T6G_MB_LIB.T6G(SCH_1):P5E_CPU1_P3_TX_DN(14)
   U26 CG23 P3_TXN14 GENOA_SP5-SOCKET6096_13568-001,SMLF,IO,DGA^6000030   I147 @T6G_MB_LIB.T6G(SCH_1):PAGE52
   C50    2      2 Q_CAP_DIFFBUS_C0201-DIFF BUS_0.22UF,6.3V,20%,X6S,SA   I118 @T6G_MB_LIB.T6G(SCH_1):PAGE355

P5E_CPU1_P3_TX_DN<15> @T6G_MB_LIB.T6G(SCH_1):P5E_CPU1_P3_TX_DN(15)
   U26 CE23 P3_TXN15 GENOA_SP5-SOCKET6096_13568-001,SMLF,IO,DGA^6000030   I147 @T6G_MB_LIB.T6G(SCH_1):PAGE52
   C48    2      2 Q_CAP_DIFFBUS_C0201-DIFF BUS_0.22UF,6.3V,20%,X6S,SA   I119 @T6G_MB_LIB.T6G(SCH_1):PAGE355

P5E_CPU1_P3_TX_DN<1> @T6G_MB_LIB.T6G(SCH_1):P5E_CPU1_P3_TX_DN(1)
   U26 CF35 P3_TXN1 GENOA_SP5-SOCKET6096_13568-001,SMLF,IO,DGA^6000030   I147 @T6G_MB_LIB.T6G(SCH_1):PAGE52
 C1544    2      2 Q_CAP_DIFFBUS_C0201-DIFF BUS_0.22UF,6.3V,20%,X6S,SA    I55 @T6G_MB_LIB.T6G(SCH_1):PAGE355

P5E_CPU1_P3_TX_DN<2> @T6G_MB_LIB.T6G(SCH_1):P5E_CPU1_P3_TX_DN(2)
   U26 CH35 P3_TXN2 GENOA_SP5-SOCKET6096_13568-001,SMLF,IO,DGA^6000030   I147 @T6G_MB_LIB.T6G(SCH_1):PAGE52
 C1542    2      2 Q_CAP_DIFFBUS_C0201-DIFF BUS_0.22UF,6.3V,20%,X6S,SA    I58 @T6G_MB_LIB.T6G(SCH_1):PAGE355

P5E_CPU1_P3_TX_DN<3> @T6G_MB_LIB.T6G(SCH_1):P5E_CPU1_P3_TX_DN(3)
   U26 CC32 P3_TXN3 GENOA_SP5-SOCKET6096_13568-001,SMLF,IO,DGA^6000030   I147 @T6G_MB_LIB.T6G(SCH_1):PAGE52
 C1540    2      2 Q_CAP_DIFFBUS_C0201-DIFF BUS_0.22UF,6.3V,20%,X6S,SA    I68 @T6G_MB_LIB.T6G(SCH_1):PAGE355

P5E_CPU1_P3_TX_DN<4> @T6G_MB_LIB.T6G(SCH_1):P5E_CPU1_P3_TX_DN(4)
   U26 CJ32 P3_TXN4 GENOA_SP5-SOCKET6096_13568-001,SMLF,IO,DGA^6000030   I147 @T6G_MB_LIB.T6G(SCH_1):PAGE52
 C1538    2      2 Q_CAP_DIFFBUS_C0201-DIFF BUS_0.22UF,6.3V,20%,X6S,SA    I70 @T6G_MB_LIB.T6G(SCH_1):PAGE355

P5E_CPU1_P3_TX_DN<5> @T6G_MB_LIB.T6G(SCH_1):P5E_CPU1_P3_TX_DN(5)
   U26 CG32 P3_TXN5 GENOA_SP5-SOCKET6096_13568-001,SMLF,IO,DGA^6000030   I147 @T6G_MB_LIB.T6G(SCH_1):PAGE52
 C1536    2      2 Q_CAP_DIFFBUS_C0201-DIFF BUS_0.22UF,6.3V,20%,X6S,SA    I72 @T6G_MB_LIB.T6G(SCH_1):PAGE355

P5E_CPU1_P3_TX_DN<6> @T6G_MB_LIB.T6G(SCH_1):P5E_CPU1_P3_TX_DN(6)
   U26 CE32 P3_TXN6 GENOA_SP5-SOCKET6096_13568-001,SMLF,IO,DGA^6000030   I147 @T6G_MB_LIB.T6G(SCH_1):PAGE52
 C1534    2      2 Q_CAP_DIFFBUS_C0201-DIFF BUS_0.22UF,6.3V,20%,X6S,SA    I74 @T6G_MB_LIB.T6G(SCH_1):PAGE355

P5E_CPU1_P3_TX_DN<7> @T6G_MB_LIB.T6G(SCH_1):P5E_CPU1_P3_TX_DN(7)
   U26 CC29 P3_TXN7 GENOA_SP5-SOCKET6096_13568-001,SMLF,IO,DGA^6000030   I147 @T6G_MB_LIB.T6G(SCH_1):PAGE52
 C1532    2      2 Q_CAP_DIFFBUS_C0201-DIFF BUS_0.22UF,6.3V,20%,X6S,SA    I76 @T6G_MB_LIB.T6G(SCH_1):PAGE355

P5E_CPU1_P3_TX_DN<8> @T6G_MB_LIB.T6G(SCH_1):P5E_CPU1_P3_TX_DN(8)
   U26 CG29 P3_TXN8 GENOA_SP5-SOCKET6096_13568-001,SMLF,IO,DGA^6000030   I147 @T6G_MB_LIB.T6G(SCH_1):PAGE52
 C1530    2      2 Q_CAP_DIFFBUS_C0201-DIFF BUS_0.22UF,6.3V,20%,X6S,SA    I78 @T6G_MB_LIB.T6G(SCH_1):PAGE355

P5E_CPU1_P3_TX_DN<9> @T6G_MB_LIB.T6G(SCH_1):P5E_CPU1_P3_TX_DN(9)
   U26 CE29 P3_TXN9 GENOA_SP5-SOCKET6096_13568-001,SMLF,IO,DGA^6000030   I147 @T6G_MB_LIB.T6G(SCH_1):PAGE52
 C1528    2      2 Q_CAP_DIFFBUS_C0201-DIFF BUS_0.22UF,6.3V,20%,X6S,SA    I80 @T6G_MB_LIB.T6G(SCH_1):PAGE355

P5E_CPU1_P3_TX_DP<0> @T6G_MB_LIB.T6G(SCH_1):P5E_CPU1_P3_TX_DP(0)
   U26 CD36 P3_TXP0 GENOA_SP5-SOCKET6096_13568-001,SMLF,IO,DGA^6000030   I147 @T6G_MB_LIB.T6G(SCH_1):PAGE52
 C1547    2      2 Q_CAP_DIFFBUS_C0201-DIFF BUS_0.22UF,6.3V,20%,X6S,SA    I53 @T6G_MB_LIB.T6G(SCH_1):PAGE355

P5E_CPU1_P3_TX_DP<10> @T6G_MB_LIB.T6G(SCH_1):P5E_CPU1_P3_TX_DP(10)
   U26 CC27 P3_TXP10 GENOA_SP5-SOCKET6096_13568-001,SMLF,IO,DGA^6000030   I147 @T6G_MB_LIB.T6G(SCH_1):PAGE52
 C1527    2      2 Q_CAP_DIFFBUS_C0201-DIFF BUS_0.22UF,6.3V,20%,X6S,SA    I82 @T6G_MB_LIB.T6G(SCH_1):PAGE355

P5E_CPU1_P3_TX_DP<11> @T6G_MB_LIB.T6G(SCH_1):P5E_CPU1_P3_TX_DP(11)
   U26 CG27 P3_TXP11 GENOA_SP5-SOCKET6096_13568-001,SMLF,IO,DGA^6000030   I147 @T6G_MB_LIB.T6G(SCH_1):PAGE52
 C1525    2      2 Q_CAP_DIFFBUS_C0201-DIFF BUS_0.22UF,6.3V,20%,X6S,SA    I83 @T6G_MB_LIB.T6G(SCH_1):PAGE355

P5E_CPU1_P3_TX_DP<12> @T6G_MB_LIB.T6G(SCH_1):P5E_CPU1_P3_TX_DP(12)
   U26 CE27 P3_TXP12 GENOA_SP5-SOCKET6096_13568-001,SMLF,IO,DGA^6000030   I147 @T6G_MB_LIB.T6G(SCH_1):PAGE52
   C55    2      2 Q_CAP_DIFFBUS_C0201-DIFF BUS_0.22UF,6.3V,20%,X6S,SA    I85 @T6G_MB_LIB.T6G(SCH_1):PAGE355

P5E_CPU1_P3_TX_DP<13> @T6G_MB_LIB.T6G(SCH_1):P5E_CPU1_P3_TX_DP(13)
   U26 CC24 P3_TXP13 GENOA_SP5-SOCKET6096_13568-001,SMLF,IO,DGA^6000030   I147 @T6G_MB_LIB.T6G(SCH_1):PAGE52
   C53    2      2 Q_CAP_DIFFBUS_C0201-DIFF BUS_0.22UF,6.3V,20%,X6S,SA   I107 @T6G_MB_LIB.T6G(SCH_1):PAGE355

P5E_CPU1_P3_TX_DP<14> @T6G_MB_LIB.T6G(SCH_1):P5E_CPU1_P3_TX_DP(14)
   U26 CG24 P3_TXP14 GENOA_SP5-SOCKET6096_13568-001,SMLF,IO,DGA^6000030   I147 @T6G_MB_LIB.T6G(SCH_1):PAGE52
   C51    2      2 Q_CAP_DIFFBUS_C0201-DIFF BUS_0.22UF,6.3V,20%,X6S,SA   I117 @T6G_MB_LIB.T6G(SCH_1):PAGE355

P5E_CPU1_P3_TX_DP<15> @T6G_MB_LIB.T6G(SCH_1):P5E_CPU1_P3_TX_DP(15)
   U26 CE24 P3_TXP15 GENOA_SP5-SOCKET6096_13568-001,SMLF,IO,DGA^6000030   I147 @T6G_MB_LIB.T6G(SCH_1):PAGE52
   C49    2      2 Q_CAP_DIFFBUS_C0201-DIFF BUS_0.22UF,6.3V,20%,X6S,SA   I120 @T6G_MB_LIB.T6G(SCH_1):PAGE355

P5E_CPU1_P3_TX_DP<1> @T6G_MB_LIB.T6G(SCH_1):P5E_CPU1_P3_TX_DP(1)
   U26 CF36 P3_TXP1 GENOA_SP5-SOCKET6096_13568-001,SMLF,IO,DGA^6000030   I147 @T6G_MB_LIB.T6G(SCH_1):PAGE52
 C1545    2      2 Q_CAP_DIFFBUS_C0201-DIFF BUS_0.22UF,6.3V,20%,X6S,SA    I56 @T6G_MB_LIB.T6G(SCH_1):PAGE355

P5E_CPU1_P3_TX_DP<2> @T6G_MB_LIB.T6G(SCH_1):P5E_CPU1_P3_TX_DP(2)
   U26 CH36 P3_TXP2 GENOA_SP5-SOCKET6096_13568-001,SMLF,IO,DGA^6000030   I147 @T6G_MB_LIB.T6G(SCH_1):PAGE52
 C1543    2      2 Q_CAP_DIFFBUS_C0201-DIFF BUS_0.22UF,6.3V,20%,X6S,SA    I57 @T6G_MB_LIB.T6G(SCH_1):PAGE355

P5E_CPU1_P3_TX_DP<3> @T6G_MB_LIB.T6G(SCH_1):P5E_CPU1_P3_TX_DP(3)
   U26 CC33 P3_TXP3 GENOA_SP5-SOCKET6096_13568-001,SMLF,IO,DGA^6000030   I147 @T6G_MB_LIB.T6G(SCH_1):PAGE52
 C1541    2      2 Q_CAP_DIFFBUS_C0201-DIFF BUS_0.22UF,6.3V,20%,X6S,SA    I67 @T6G_MB_LIB.T6G(SCH_1):PAGE355

P5E_CPU1_P3_TX_DP<4> @T6G_MB_LIB.T6G(SCH_1):P5E_CPU1_P3_TX_DP(4)
   U26 CJ33 P3_TXP4 GENOA_SP5-SOCKET6096_13568-001,SMLF,IO,DGA^6000030   I147 @T6G_MB_LIB.T6G(SCH_1):PAGE52
 C1539    2      2 Q_CAP_DIFFBUS_C0201-DIFF BUS_0.22UF,6.3V,20%,X6S,SA    I69 @T6G_MB_LIB.T6G(SCH_1):PAGE355

P5E_CPU1_P3_TX_DP<5> @T6G_MB_LIB.T6G(SCH_1):P5E_CPU1_P3_TX_DP(5)
   U26 CG33 P3_TXP5 GENOA_SP5-SOCKET6096_13568-001,SMLF,IO,DGA^6000030   I147 @T6G_MB_LIB.T6G(SCH_1):PAGE52
 C1537    2      2 Q_CAP_DIFFBUS_C0201-DIFF BUS_0.22UF,6.3V,20%,X6S,SA    I71 @T6G_MB_LIB.T6G(SCH_1):PAGE355

P5E_CPU1_P3_TX_DP<6> @T6G_MB_LIB.T6G(SCH_1):P5E_CPU1_P3_TX_DP(6)
   U26 CE33 P3_TXP6 GENOA_SP5-SOCKET6096_13568-001,SMLF,IO,DGA^6000030   I147 @T6G_MB_LIB.T6G(SCH_1):PAGE52
 C1535    2      2 Q_CAP_DIFFBUS_C0201-DIFF BUS_0.22UF,6.3V,20%,X6S,SA    I73 @T6G_MB_LIB.T6G(SCH_1):PAGE355

P5E_CPU1_P3_TX_DP<7> @T6G_MB_LIB.T6G(SCH_1):P5E_CPU1_P3_TX_DP(7)
   U26 CC30 P3_TXP7 GENOA_SP5-SOCKET6096_13568-001,SMLF,IO,DGA^6000030   I147 @T6G_MB_LIB.T6G(SCH_1):PAGE52
 C1533    2      2 Q_CAP_DIFFBUS_C0201-DIFF BUS_0.22UF,6.3V,20%,X6S,SA    I75 @T6G_MB_LIB.T6G(SCH_1):PAGE355

P5E_CPU1_P3_TX_DP<8> @T6G_MB_LIB.T6G(SCH_1):P5E_CPU1_P3_TX_DP(8)
   U26 CG30 P3_TXP8 GENOA_SP5-SOCKET6096_13568-001,SMLF,IO,DGA^6000030   I147 @T6G_MB_LIB.T6G(SCH_1):PAGE52
 C1531    2      2 Q_CAP_DIFFBUS_C0201-DIFF BUS_0.22UF,6.3V,20%,X6S,SA    I77 @T6G_MB_LIB.T6G(SCH_1):PAGE355

P5E_CPU1_P3_TX_DP<9> @T6G_MB_LIB.T6G(SCH_1):P5E_CPU1_P3_TX_DP(9)
   U26 CE30 P3_TXP9 GENOA_SP5-SOCKET6096_13568-001,SMLF,IO,DGA^6000030   I147 @T6G_MB_LIB.T6G(SCH_1):PAGE52
 C1529    2      2 Q_CAP_DIFFBUS_C0201-DIFF BUS_0.22UF,6.3V,20%,X6S,SA    I79 @T6G_MB_LIB.T6G(SCH_1):PAGE355

P5V @T6G_MB_LIB.T6G(SCH_1):P5V
    D1    3      3 BAT547F-BAT547F,SMLF,IC,BC0BAT54Z53    I27 @T6G_MB_LIB.T6G(SCH_1):PAGE273
 C1227    1      A Q_CAP_C0402-100NF,50V,10%,X7R,CH4106K1B01    I41 @T6G_MB_LIB.T6G(SCH_1):PAGE273
 R4638    1      A Q_RES_1206LF-243,1%,1/4W,CHIP,CS12436F201    I45 @T6G_MB_LIB.T6G(SCH_1):PAGE273
 R3102    2      B Q_RES_0402LF-470,1%,1/16W,CHIP,CS14702FB04     I9 @T6G_MB_LIB.T6G(SCH_1):PAGE254
   Q57    1      1 MOSFET_NCH_1D3S-PSMNR58-30YLH,SMLF,IC,BAMNR580000    I23 @T6G_MB_LIB.T6G(SCH_1):PAGE273
   Q57    2      2 MOSFET_NCH_1D3S-PSMNR58-30YLH,SMLF,IC,BAMNR580000    I23 @T6G_MB_LIB.T6G(SCH_1):PAGE273
   Q57    3      3 MOSFET_NCH_1D3S-PSMNR58-30YLH,SMLF,IC,BAMNR580000    I23 @T6G_MB_LIB.T6G(SCH_1):PAGE273
 C1331    1      A Q_CAP_C0805-10UF,16V,10%,X6S,CH6103KEA00    I43 @T6G_MB_LIB.T6G(SCH_1):PAGE273
 R3005    1      A Q_RES_0402LF-18K,1%,1/16W,CHIP,CS31802FB04    I15 @T6G_MB_LIB.T6G(SCH_1):PAGE369
 R4639    1      A Q_RES_1206LF-243,1%,1/4W,CHIP,CS12436F201    I74 @T6G_MB_LIB.T6G(SCH_1):PAGE273
 R4640    1      A Q_RES_1206LF-243,1%,1/4W,CHIP,CS12436F201    I75 @T6G_MB_LIB.T6G(SCH_1):PAGE273
 R4641    1      A Q_RES_1206LF-243,1%,1/4W,CHIP,CS12436F201    I76 @T6G_MB_LIB.T6G(SCH_1):PAGE273
  U100    3    VDD RT9818C44GV-RT9818C-44GV,SMLF,IC,AL009818001    I77 @T6G_MB_LIB.T6G(SCH_1):PAGE273
 C6122    1      A Q_CAP_C0402-100NF,50V,10%,X7R,CH4106K1B01    I79 @T6G_MB_LIB.T6G(SCH_1):PAGE273
  R479    1      A Q_RES_0402LF-10K,1%,1/16W,CHIP,CS31002FB08    I83 @T6G_MB_LIB.T6G(SCH_1):PAGE273

P5V_ADC @T6G_MB_LIB.T6G(SCH_1):P5V_ADC
 R1791    1      A Q_RES_0402LF-9.09K,1%,1/16W,CHIP,CS29092FB05    I14 @T6G_MB_LIB.T6G(SCH_1):PAGE369
 R3005    2      B Q_RES_0402LF-18K,1%,1/16W,CHIP,CS31802FB04    I15 @T6G_MB_LIB.T6G(SCH_1):PAGE369
 R3686    1      A Q_RES_0402LF-0,5%,1/16W,CHIP,CS00002JB13    I16 @T6G_MB_LIB.T6G(SCH_1):PAGE369
 R3685    1      A Q_RES_0402LF-0,5%,1/16W,EMPTY,CS00002JB13    I18 @T6G_MB_LIB.T6G(SCH_1):PAGE369

P5V_ADC_MAM @T6G_MB_LIB.T6G(SCH_1):P5V_ADC_MAM
 R3685    2      B Q_RES_0402LF-0,5%,1/16W,EMPTY,CS00002JB13    I18 @T6G_MB_LIB.T6G(SCH_1):PAGE369
 C2044    1      A Q_CAP_0402-100PF,50V,5%,EMPTY,CH11006JB18    I52 @T6G_MB_LIB.T6G(SCH_1):PAGE369
  U193    8   AIN3 MAX11617EEET-MAX11617EEE+T,SMLF,EMPTY,AL011617W00   I169 @T6G_MB_LIB.T6G(SCH_1):PAGE369

P5V_ADC_TIC @T6G_MB_LIB.T6G(SCH_1):P5V_ADC_TIC
 R3686    2      B Q_RES_0402LF-0,5%,1/16W,CHIP,CS00002JB13    I16 @T6G_MB_LIB.T6G(SCH_1):PAGE369
 C2049    1      A Q_CAP_0402-0.1UF,25V,10%,X7R,CH4104K1B00    I17 @T6G_MB_LIB.T6G(SCH_1):PAGE369
  U269   13    IN3 ADC128D818CIMTXNOPB-ADC128D818CIMTX/NOPB,SMLF,IC,AA   I142 @T6G_MB_LIB.T6G(SCH_1):PAGE369

P5V_AUX @T6G_MB_LIB.T6G(SCH_1):P5V_AUX
  R820    2      B Q_RES_0402LF-10K,5%,1/16W,EMPTY,CS31002JB08   I186 @T6G_MB_LIB.T6G(SCH_1):PAGE141
 R1207    2      B Q_RES_0402LF-470,1%,1/16W,CHIP,CS14702FB04    I41 @T6G_MB_LIB.T6G(SCH_1):PAGE143
 R1208    2      B Q_RES_0402LF-470,1%,1/16W,CHIP,CS14702FB04    I42 @T6G_MB_LIB.T6G(SCH_1):PAGE143
 PR445    2      B Q_RES_0402LF-0,5%,1/16W,CHIP,CS00002JB13     I3 @T6G_MB_LIB.T6G(SCH_1):PAGE169
 PR442    2      B Q_RES_0402LF-0,5%,1/16W,CHIP,CS00002JB13    I21 @T6G_MB_LIB.T6G(SCH_1):PAGE176
 PR335    2      B Q_RES_0402LF-0,5%,1/16W,CHIP,CS00002JB13     I3 @T6G_MB_LIB.T6G(SCH_1):PAGE186
 C1042    1      A Q_CAP_C0402-100NF,50V,10%,X7R,CH4106K1B01    I18 @T6G_MB_LIB.T6G(SCH_1):PAGE273
 C1170    1      A Q_CAP_C0805-10UF,16V,10%,X6S,CH6103KEA00    I19 @T6G_MB_LIB.T6G(SCH_1):PAGE273
   C57    1      A Q_CAP_C0805-10UF,16V,10%,EMPTY,CH6103KEA00    I20 @T6G_MB_LIB.T6G(SCH_1):PAGE273
   Q57    5      5 MOSFET_NCH_1D3S-PSMNR58-30YLH,SMLF,IC,BAMNR580000    I23 @T6G_MB_LIB.T6G(SCH_1):PAGE273
PC1877    2      B Q_CAP_0402-47PF,50V,5%,NPO,TMP_QCH04706JB01    I20 @T6G_MB_LIB.T6G(SCH_1):PAGE244
PR8092    2      B Q_RES_0402LF-86.6K,1%,1/16W,CHIP,CS38662FB05    I27 @T6G_MB_LIB.T6G(SCH_1):PAGE244
PL8065    2      2 Q_INDUCTOR_SMLF-4.7UH,IND,CV-47A0MZ10    I28 @T6G_MB_LIB.T6G(SCH_1):PAGE244
PC1845    1      A Q_CAPP_SMLF-220UF,6.3V,20%,ALUM,CC72201MZ28    I30 @T6G_MB_LIB.T6G(SCH_1):PAGE244
PC1855    1      A Q_CAP_C0805-22UF,10V,20%,X6S,CH6222MEA01    I31 @T6G_MB_LIB.T6G(SCH_1):PAGE244
PC1856    1      A Q_CAP_C0805-22UF,10V,20%,X6S,CH6222MEA01    I32 @T6G_MB_LIB.T6G(SCH_1):PAGE244
PC1852    1      A Q_CAP_0402-0.1UF,25V,10%,X7R,CH4104K1B00    I34 @T6G_MB_LIB.T6G(SCH_1):PAGE244
 PR290    1      A Q_RES_0402LF-40.2K,1%,1/16W,CHIP,CS34022FB04    I15 @T6G_MB_LIB.T6G(SCH_1):PAGE168
  PR53    1      A Q_RES_0402LF-40.2K,1%,1/16W,CHIP,CS34022FB04     I9 @T6G_MB_LIB.T6G(SCH_1):PAGE175
 PR113    1      A Q_RES_0402LF-40.2K,1%,1/16W,CHIP,CS34022FB04     I2 @T6G_MB_LIB.T6G(SCH_1):PAGE182
 PR411    2      B Q_RES_0402LF-0,5%,1/16W,CHIP,CS00002JB13    I85 @T6G_MB_LIB.T6G(SCH_1):PAGE183
 PR157    1      A Q_RES_0402LF-40.2K,1%,1/16W,CHIP,CS34022FB04    I14 @T6G_MB_LIB.T6G(SCH_1):PAGE185
 PR230    1      A Q_RES_0402LF-40.2K,1%,1/16W,CHIP,CS34022FB04     I9 @T6G_MB_LIB.T6G(SCH_1):PAGE192
 PR340    2      B Q_RES_0402LF-0,5%,1/16W,CHIP,CS00002JB13    I89 @T6G_MB_LIB.T6G(SCH_1):PAGE193
 PR376    1      A Q_RES_0402LF-40.2K,1%,1/16W,CHIP,CS34022FB04     I2 @T6G_MB_LIB.T6G(SCH_1):PAGE199
 PR387    2      B Q_RES_0402LF-0,5%,1/16W,CHIP,CS00002JB13     I3 @T6G_MB_LIB.T6G(SCH_1):PAGE200
  R130    2      B Q_RES_0402LF-10K,5%,1/16W,EMPTY,CS31002JB08   I113 @T6G_MB_LIB.T6G(SCH_1):PAGE349
 R4450    2      B Q_RES_0402LF-0,5%,1/16W,CHIP,CS00002JB13    I27 @T6G_MB_LIB.T6G(SCH_1):PAGE153
 C6027    1      A Q_CAP_C0805-22UF,16V,20%,X6S,CH6223MEA00    I28 @T6G_MB_LIB.T6G(SCH_1):PAGE153
 C6028    1      A Q_CAP_0402-470PF,50V,10%,X7R,TMP_QCH14706KB18    I29 @T6G_MB_LIB.T6G(SCH_1):PAGE153
 R6208    1      A Q_RES_0402LF-10K,1%,1/16W,CHIP,CS31002FB08    I47 @T6G_MB_LIB.T6G(SCH_1):PAGE153
 R6318    1      A Q_RES_0402LF-90.9K,1%,1/16W,CHIP,CS39092FB04   I123 @T6G_MB_LIB.T6G(SCH_1):PAGE155
PR6604    1      A Q_RES_0402LF-5.36K,1%,1/16W,EMPTY,CS25362FB02   I178 @T6G_MB_LIB.T6G(SCH_1):PAGE475
PR6550    1      A Q_RES_0402LF-0,5%,1/16W,CHIP,CS00002JB13   I183 @T6G_MB_LIB.T6G(SCH_1):PAGE476
 PR885    1      A Q_RES_0402LF-5.36K,1%,1/16W,EMPTY,CS25362FB02     I7 @T6G_MB_LIB.T6G(SCH_1):PAGE477
PR6619    1      A Q_RES_0402LF-0,5%,1/16W,CHIP,CS00002JB13    I42 @T6G_MB_LIB.T6G(SCH_1):PAGE478
 R1238    1      A Q_RES_0402LF-18K,1%,1/16W,CHIP,CS31802FB04    I13 @T6G_MB_LIB.T6G(SCH_1):PAGE263

P5V_AUX_ADC @T6G_MB_LIB.T6G(SCH_1):P5V_AUX_ADC
 R1226    1      A Q_RES_0402LF-9.09K,1%,1/16W,CHIP,CS29092FB05    I12 @T6G_MB_LIB.T6G(SCH_1):PAGE263
 R1238    2      B Q_RES_0402LF-18K,1%,1/16W,CHIP,CS31802FB04    I13 @T6G_MB_LIB.T6G(SCH_1):PAGE263
 R1263    1      A Q_RES_0402LF-0,5%,1/16W,CHIP,CS00002JB13    I15 @T6G_MB_LIB.T6G(SCH_1):PAGE263
 R1260    1      A Q_RES_0402LF-0,5%,1/16W,EMPTY,CS00002JB13    I16 @T6G_MB_LIB.T6G(SCH_1):PAGE263

P5V_AUX_ADC_MAM @T6G_MB_LIB.T6G(SCH_1):P5V_AUX_ADC_MAM
 R1260    2      B Q_RES_0402LF-0,5%,1/16W,EMPTY,CS00002JB13    I16 @T6G_MB_LIB.T6G(SCH_1):PAGE263
 C1085    1      A Q_CAP_0402-100PF,50V,5%,EMPTY,CH11006JB18    I45 @T6G_MB_LIB.T6G(SCH_1):PAGE263
   U50    5   AIN0 MAX11617EEET-MAX11617EEE+T,SMLF,EMPTY,AL011617W00   I156 @T6G_MB_LIB.T6G(SCH_1):PAGE263

P5V_AUX_ADC_TIC @T6G_MB_LIB.T6G(SCH_1):P5V_AUX_ADC_TIC
 R1263    2      B Q_RES_0402LF-0,5%,1/16W,CHIP,CS00002JB13    I15 @T6G_MB_LIB.T6G(SCH_1):PAGE263
 C1093    1      A Q_CAP_0402-0.1UF,25V,10%,X7R,CH4104K1B00    I43 @T6G_MB_LIB.T6G(SCH_1):PAGE263
   U51   16    IN0 ADC128D818CIMTXNOPB-ADC128D818CIMTX/NOPB,SMLF,IC,AA   I142 @T6G_MB_LIB.T6G(SCH_1):PAGE263

P5V_AUX_CS @T6G_MB_LIB.T6G(SCH_1):P5V_AUX_CS
PR8089    1      A Q_RES_0402LF-16.9K,1%,1/16W,CHIP,CS31692FB03    I15 @T6G_MB_LIB.T6G(SCH_1):PAGE244
  U326    3     CS MPQ8633AGLEC807Z-MPQ8633AGLE-C807-Z,SMLF,IC,AL0086A    I38 @T6G_MB_LIB.T6G(SCH_1):PAGE244

P5V_AUX_EN @T6G_MB_LIB.T6G(SCH_1):P5V_AUX_EN
  U326    8     EN MPQ8633AGLEC807Z-MPQ8633AGLE-C807-Z,SMLF,IC,AL0086A    I38 @T6G_MB_LIB.T6G(SCH_1):PAGE244
 R6097    2      B Q_RES_0402LF-0,5%,1/16W,CHIP,CS00002JB13    I40 @T6G_MB_LIB.T6G(SCH_1):PAGE244

P5V_AUX_FB @T6G_MB_LIB.T6G(SCH_1):P5V_AUX_FB
PC1877    1      A Q_CAP_0402-47PF,50V,5%,NPO,TMP_QCH04706JB01    I20 @T6G_MB_LIB.T6G(SCH_1):PAGE244
PR8091    1      A Q_RES_0402LF-11.8K,0.1%,1/16W,CHIP,CS31182BB06    I23 @T6G_MB_LIB.T6G(SCH_1):PAGE244
PR8092    1      A Q_RES_0402LF-86.6K,1%,1/16W,CHIP,CS38662FB05    I27 @T6G_MB_LIB.T6G(SCH_1):PAGE244
  U326    7     FB MPQ8633AGLEC807Z-MPQ8633AGLE-C807-Z,SMLF,IC,AL0086A    I38 @T6G_MB_LIB.T6G(SCH_1):PAGE244

P5V_AUX_MODE @T6G_MB_LIB.T6G(SCH_1):P5V_AUX_MODE
PR3337    1      A Q_RES_0402LF-0,5%,1/16W,CHIP,CS00002JB13    I37 @T6G_MB_LIB.T6G(SCH_1):PAGE244
  U326    4   MODE MPQ8633AGLEC807Z-MPQ8633AGLE-C807-Z,SMLF,IC,AL0086A    I38 @T6G_MB_LIB.T6G(SCH_1):PAGE244

P5V_AUX_REF @T6G_MB_LIB.T6G(SCH_1):P5V_AUX_REF
PC1853    1      A Q_CAP_0402-0.1UF,25V,10%,X7R,CH4104K1B00    I19 @T6G_MB_LIB.T6G(SCH_1):PAGE244
  U326    5 TRK_REF MPQ8633AGLEC807Z-MPQ8633AGLE-C807-Z,SMLF,IC,AL0086A    I38 @T6G_MB_LIB.T6G(SCH_1):PAGE244

P5V_AUX_VCC @T6G_MB_LIB.T6G(SCH_1):P5V_AUX_VCC
PC1848    1      A Q_CAP_C0402-1UF,25V,10%,X6S,CH5104KEB02     I8 @T6G_MB_LIB.T6G(SCH_1):PAGE244
 R2356    1      A Q_RES_0402LF-10K,1%,1/16W,CHIP,CS31002FB08    I25 @T6G_MB_LIB.T6G(SCH_1):PAGE244
  U326   19    VCC MPQ8633AGLEC807Z-MPQ8633AGLE-C807-Z,SMLF,IC,AL0086A    I38 @T6G_MB_LIB.T6G(SCH_1):PAGE244
 R2343    1      A Q_RES_0402LF-10K,1%,1/16W,EMPTY,CS31002FB08    I63 @T6G_MB_LIB.T6G(SCH_1):PAGE84

P5V_STBY_PWR_LED @T6G_MB_LIB.T6G(SCH_1):P5V_STBY_PWR_LED
   D49    A      A Q_LED_SMLF-LED_BLUE,LTST-C281TBKT-5A,IC,BEBL0172Z00    I38 @T6G_MB_LIB.T6G(SCH_1):PAGE143
 R1207    1      A Q_RES_0402LF-470,1%,1/16W,CHIP,CS14702FB04    I41 @T6G_MB_LIB.T6G(SCH_1):PAGE143

PCA9548_PCIE0_ADDR0 @T6G_MB_LIB.T6G(SCH_1):PCA9548_PCIE0_ADDR0
 R3709    1      A Q_RES_0402LF-1K,1%,1/16W,CHIP,CS21002FB06     I6 @T6G_MB_LIB.T6G(SCH_1):PAGE251
 R3708    2      B Q_RES_0402LF-10K,1%,1/16W,EMPTY,CS31002FB08    I10 @T6G_MB_LIB.T6G(SCH_1):PAGE251
   U39    1     A0 TCA9548APWR-TCA9548APWR,SMLF,IC,AL009548K02    I74 @T6G_MB_LIB.T6G(SCH_1):PAGE251

PCA9548_PCIE0_ADDR1 @T6G_MB_LIB.T6G(SCH_1):PCA9548_PCIE0_ADDR1
 R3707    1      A Q_RES_0402LF-1K,1%,1/16W,CHIP,CS21002FB06     I4 @T6G_MB_LIB.T6G(SCH_1):PAGE251
 R3706    2      B Q_RES_0402LF-10K,1%,1/16W,EMPTY,CS31002FB08     I8 @T6G_MB_LIB.T6G(SCH_1):PAGE251
   U39    2     A1 TCA9548APWR-TCA9548APWR,SMLF,IC,AL009548K02    I74 @T6G_MB_LIB.T6G(SCH_1):PAGE251

PCA9548_PCIE0_ADDR2 @T6G_MB_LIB.T6G(SCH_1):PCA9548_PCIE0_ADDR2
 R3704    1      A Q_RES_0402LF-1K,1%,1/16W,CHIP,CS21002FB06     I1 @T6G_MB_LIB.T6G(SCH_1):PAGE251
 R3703    2      B Q_RES_0402LF-10K,1%,1/16W,EMPTY,CS31002FB08     I7 @T6G_MB_LIB.T6G(SCH_1):PAGE251
   U39   21     A2 TCA9548APWR-TCA9548APWR,SMLF,IC,AL009548K02    I74 @T6G_MB_LIB.T6G(SCH_1):PAGE251

PCA9548_PCIE3_ADDR0 @T6G_MB_LIB.T6G(SCH_1):PCA9548_PCIE3_ADDR0
  R587    1      A Q_RES_0402LF-1K,1%,1/16W,CHIP,CS21002FB06     I6 @T6G_MB_LIB.T6G(SCH_1):PAGE252
  R320    2      B Q_RES_0402LF-10K,1%,1/16W,EMPTY,CS31002FB08    I10 @T6G_MB_LIB.T6G(SCH_1):PAGE252
   U36    1     A0 TCA9548APWR-TCA9548APWR,SMLF,IC,AL009548K02    I33 @T6G_MB_LIB.T6G(SCH_1):PAGE252

PCA9548_PCIE3_ADDR1 @T6G_MB_LIB.T6G(SCH_1):PCA9548_PCIE3_ADDR1
  R319    1      A Q_RES_0402LF-1K,1%,1/16W,CHIP,CS21002FB06     I4 @T6G_MB_LIB.T6G(SCH_1):PAGE252
  R318    2      B Q_RES_0402LF-10K,1%,1/16W,EMPTY,CS31002FB08     I8 @T6G_MB_LIB.T6G(SCH_1):PAGE252
   U36    2     A1 TCA9548APWR-TCA9548APWR,SMLF,IC,AL009548K02    I33 @T6G_MB_LIB.T6G(SCH_1):PAGE252

PCA9548_PCIE3_ADDR2 @T6G_MB_LIB.T6G(SCH_1):PCA9548_PCIE3_ADDR2
  R317    1      A Q_RES_0402LF-1K,1%,1/16W,CHIP,CS21002FB06     I2 @T6G_MB_LIB.T6G(SCH_1):PAGE252
  R316    2      B Q_RES_0402LF-10K,1%,1/16W,EMPTY,CS31002FB08     I7 @T6G_MB_LIB.T6G(SCH_1):PAGE252
   U36   21     A2 TCA9548APWR-TCA9548APWR,SMLF,IC,AL009548K02    I33 @T6G_MB_LIB.T6G(SCH_1):PAGE252

PCIE_M2_SSD0_PRSNT_N @T6G_MB_LIB.T6G(SCH_1):PCIE_M2_SSD0_PRSNT_N
   J59    1   GND1 SCONN75K_APCI0155P004A-SCONN75K_APCI0155-P004A,SMLA    I88 @T6G_MB_LIB.T6G(SCH_1):PAGE345
  R178    2      B Q_RES_0402LF-1K,1%,1/16W,CHIP,CS21002FB06    I24 @T6G_MB_LIB.T6G(SCH_1):PAGE345
   U18   C8  PT15A LCMXO3LF9400C5BG484C-LCMXO3LF-9400C-5BG484C,SMLF,IA    I94 @T6G_MB_LIB.T6G(SCH_1):PAGE79

PDB_PRSNT_N @T6G_MB_LIB.T6G(SCH_1):PDB_PRSNT_N
   C64    1      A Q_CAP_0402-0.1UF,25V,10%,EMPTY,CH4104K1B00   I453 @T6G_MB_LIB.T6G(SCH_1):PAGE363
   J45   D3     D3 CONN60_101062636003K02LF-CONN60_10106263-6003K02LFA   I466 @T6G_MB_LIB.T6G(SCH_1):PAGE363
 R1526    1      A Q_RES_0402LF-0,5%,1/16W,CHIP,CS00002JB13   I476 @T6G_MB_LIB.T6G(SCH_1):PAGE363

PDB_PRSNT_R_N @T6G_MB_LIB.T6G(SCH_1):PDB_PRSNT_R_N
 C1797    1      A Q_CAP_0402-0.1UF,25V,10%,X7R,CH4104K1B00     I9 @T6G_MB_LIB.T6G(SCH_1):PAGE372
 R3907    1      A Q_RES_0402LF-33K,1%,1/16W,CHIP,CS33302FB00    I10 @T6G_MB_LIB.T6G(SCH_1):PAGE372
  U290    G      G MOSFET_NCH_GDS_ESD_PROTECTED-2N7002K,SMLF,IC,BAM70A    I11 @T6G_MB_LIB.T6G(SCH_1):PAGE372
 R3923    2      B Q_RES_0402LF-63.4K,1%,1/16W,CHIP,CS36342FB04    I16 @T6G_MB_LIB.T6G(SCH_1):PAGE372
JP4003    2      2 CONN3_210HP1030BR1-CONN3_210-HP1-030BR1,THLF,IO,DFA    I18 @T6G_MB_LIB.T6G(SCH_1):PAGE372
 R1526    2      B Q_RES_0402LF-0,5%,1/16W,CHIP,CS00002JB13   I476 @T6G_MB_LIB.T6G(SCH_1):PAGE363
 C1115    1      A Q_CAP_C0805-22UF,16V,20%,EMPTY,CH6223MEA00   I478 @T6G_MB_LIB.T6G(SCH_1):PAGE363

PD_BIOS_DEBUG_MODE @T6G_MB_LIB.T6G(SCH_1):PD_BIOS_DEBUG_MODE
 R1508    2      B Q_RES_0402LF-100,1%,1/16W,CHIP,CS11002FB07     I6 @T6G_MB_LIB.T6G(SCH_1):PAGE144
   SW1    6      6 SW20S_DHNF10FQTR-SW20S_DHNF-10F-Q-T/R,SMLF,MECH,DHA    I90 @T6G_MB_LIB.T6G(SCH_1):PAGE144

PD_CHA_CPU0_DIMM0_SAA @T6G_MB_LIB.T6G(SCH_1):PD_CHA_CPU0_DIMM0_SAA
    R7    1      A Q_RES_0402LF-10K,1%,1/16W,CHIP,CS31002FB08   I499 @T6G_MB_LIB.T6G(SCH_1):PAGE85
    J1  148    HAS SCONN288_DDR506112002KQ-SCONN288_DDR506112002KQ,SMA   I536 @T6G_MB_LIB.T6G(SCH_1):PAGE85

PD_CHA_CPU1_DIMM0_SAA @T6G_MB_LIB.T6G(SCH_1):PD_CHA_CPU1_DIMM0_SAA
   J24  148    HAS SCONN288_DDR506112002KQ-SCONN288_DDR506112002KQ,SMA    I22 @T6G_MB_LIB.T6G(SCH_1):PAGE97
   R36    1      A Q_RES_0402LF-10K,1%,1/16W,CHIP,CS31002FB08   I129 @T6G_MB_LIB.T6G(SCH_1):PAGE97

PD_CHB_CPU0_DIMM_SAA @T6G_MB_LIB.T6G(SCH_1):PD_CHB_CPU0_DIMM_SAA
  R761    1      A Q_RES_0402LF-15.4K,1%,1/16W,CHIP,CS31542FB02   I349 @T6G_MB_LIB.T6G(SCH_1):PAGE86
   J15  148    HAS SCONN288_DDR506112002KQ-SCONN288_DDR506112002KQ,SMA   I350 @T6G_MB_LIB.T6G(SCH_1):PAGE86

PD_CHB_CPU1_DIMM_SAA @T6G_MB_LIB.T6G(SCH_1):PD_CHB_CPU1_DIMM_SAA
   J26  148    HAS SCONN288_DDR506112002KQ-SCONN288_DDR506112002KQ,SMA    I22 @T6G_MB_LIB.T6G(SCH_1):PAGE98
  R770    1      A Q_RES_0402LF-15.4K,1%,1/16W,CHIP,CS31542FB02   I127 @T6G_MB_LIB.T6G(SCH_1):PAGE98

PD_CHC_CPU0_DIMM_SAA @T6G_MB_LIB.T6G(SCH_1):PD_CHC_CPU0_DIMM_SAA
  R762    1      A Q_RES_0402LF-23.2K,1%,1/16W,CHIP,CS32322FB03   I349 @T6G_MB_LIB.T6G(SCH_1):PAGE87
   J17  148    HAS SCONN288_DDR506112002KQ-SCONN288_DDR506112002KQ,SMA   I350 @T6G_MB_LIB.T6G(SCH_1):PAGE87

PD_CHC_CPU1_DIMM_SAA @T6G_MB_LIB.T6G(SCH_1):PD_CHC_CPU1_DIMM_SAA
   J28  148    HAS SCONN288_DDR506112002KQ-SCONN288_DDR506112002KQ,SMA    I22 @T6G_MB_LIB.T6G(SCH_1):PAGE99
  R771    1      A Q_RES_0402LF-23.2K,1%,1/16W,CHIP,CS32322FB03   I148 @T6G_MB_LIB.T6G(SCH_1):PAGE99

PD_CHD_CPU0_DIMM_SAA @T6G_MB_LIB.T6G(SCH_1):PD_CHD_CPU0_DIMM_SAA
  R763    1      A Q_RES_0402LF-35.7K,1%,1/16W,CHIP,CS33572FB01   I349 @T6G_MB_LIB.T6G(SCH_1):PAGE88
   J19  148    HAS SCONN288_DDR506112002KQ-SCONN288_DDR506112002KQ,SMA   I350 @T6G_MB_LIB.T6G(SCH_1):PAGE88

PD_CHD_CPU1_DIMM_SAA @T6G_MB_LIB.T6G(SCH_1):PD_CHD_CPU1_DIMM_SAA
   J30  148    HAS SCONN288_DDR506112002KQ-SCONN288_DDR506112002KQ,SMA    I52 @T6G_MB_LIB.T6G(SCH_1):PAGE100
  R772    1      A Q_RES_0402LF-35.7K,1%,1/16W,CHIP,CS33572FB01   I146 @T6G_MB_LIB.T6G(SCH_1):PAGE100

PD_CHE_CPU0_DIMM_SAA @T6G_MB_LIB.T6G(SCH_1):PD_CHE_CPU0_DIMM_SAA
    R5    1      A Q_RES_0402LF-54.9K,1%,1/16W,CHIP,CS35492FB03   I331 @T6G_MB_LIB.T6G(SCH_1):PAGE89
   J21  148    HAS SCONN288_DDR506112002KQ-SCONN288_DDR506112002KQ,SMA   I348 @T6G_MB_LIB.T6G(SCH_1):PAGE89

PD_CHE_CPU1_DIMM_SAA @T6G_MB_LIB.T6G(SCH_1):PD_CHE_CPU1_DIMM_SAA
   J32  148    HAS SCONN288_DDR506112002KQ-SCONN288_DDR506112002KQ,SMA    I52 @T6G_MB_LIB.T6G(SCH_1):PAGE101
    R6    1      A Q_RES_0402LF-54.9K,1%,1/16W,CHIP,CS35492FB03   I127 @T6G_MB_LIB.T6G(SCH_1):PAGE101

PD_CHF_CPU0_DIMM_SAA @T6G_MB_LIB.T6G(SCH_1):PD_CHF_CPU0_DIMM_SAA
  R764    1      A Q_RES_0402LF-84.5K,1%,1/16W,CHIP,CS38452FB05   I349 @T6G_MB_LIB.T6G(SCH_1):PAGE90
   J23  148    HAS SCONN288_DDR506112002KQ-SCONN288_DDR506112002KQ,SMA   I350 @T6G_MB_LIB.T6G(SCH_1):PAGE90

PD_CHF_CPU1_DIMM_SAA @T6G_MB_LIB.T6G(SCH_1):PD_CHF_CPU1_DIMM_SAA
   J33  148    HAS SCONN288_DDR506112002KQ-SCONN288_DDR506112002KQ,SMA    I22 @T6G_MB_LIB.T6G(SCH_1):PAGE102
  R773    1      A Q_RES_0402LF-84.5K,1%,1/16W,CHIP,CS38452FB05   I129 @T6G_MB_LIB.T6G(SCH_1):PAGE102

PD_CHG_CPU0_DIMM0_SAA @T6G_MB_LIB.T6G(SCH_1):PD_CHG_CPU0_DIMM0_SAA
   J16  148    HAS SCONN288_DDR506112002KQ-SCONN288_DDR506112002KQ,SMA    I22 @T6G_MB_LIB.T6G(SCH_1):PAGE91
   R35    1      A Q_RES_0402LF-10K,1%,1/16W,CHIP,CS31002FB08   I129 @T6G_MB_LIB.T6G(SCH_1):PAGE91

PD_CHG_CPU1_DIMM0_SAA @T6G_MB_LIB.T6G(SCH_1):PD_CHG_CPU1_DIMM0_SAA
  J102  148    HAS SCONN288_DDR506112002KQ-SCONN288_DDR506112002KQ,SMA    I22 @T6G_MB_LIB.T6G(SCH_1):PAGE103
   R37    1      A Q_RES_0402LF-10K,1%,1/16W,CHIP,CS31002FB08   I129 @T6G_MB_LIB.T6G(SCH_1):PAGE103

PD_CHH_CPU0_DIMM_SAA @T6G_MB_LIB.T6G(SCH_1):PD_CHH_CPU0_DIMM_SAA
   J69  148    HAS SCONN288_DDR506112002KQ-SCONN288_DDR506112002KQ,SMA    I22 @T6G_MB_LIB.T6G(SCH_1):PAGE92
  R765    1      A Q_RES_0402LF-15.4K,1%,1/16W,CHIP,CS31542FB02   I129 @T6G_MB_LIB.T6G(SCH_1):PAGE92

PD_CHH_CPU1_DIMM_SAA @T6G_MB_LIB.T6G(SCH_1):PD_CHH_CPU1_DIMM_SAA
   J27  148    HAS SCONN288_DDR506112002KQ-SCONN288_DDR506112002KQ,SMA    I22 @T6G_MB_LIB.T6G(SCH_1):PAGE104
  R774    1      A Q_RES_0402LF-15.4K,1%,1/16W,CHIP,CS31542FB02   I128 @T6G_MB_LIB.T6G(SCH_1):PAGE104

PD_CHI_CPU0_DIMM_SAA @T6G_MB_LIB.T6G(SCH_1):PD_CHI_CPU0_DIMM_SAA
   J18  148    HAS SCONN288_DDR506112002KQ-SCONN288_DDR506112002KQ,SMA    I22 @T6G_MB_LIB.T6G(SCH_1):PAGE93
  R766    1      A Q_RES_0402LF-23.2K,1%,1/16W,CHIP,CS32322FB03   I128 @T6G_MB_LIB.T6G(SCH_1):PAGE93

PD_CHI_CPU1_DIMM_SAA @T6G_MB_LIB.T6G(SCH_1):PD_CHI_CPU1_DIMM_SAA
  J100  148    HAS SCONN288_DDR506112002KQ-SCONN288_DDR506112002KQ,SMA    I22 @T6G_MB_LIB.T6G(SCH_1):PAGE105
  R775    1      A Q_RES_0402LF-23.2K,1%,1/16W,CHIP,CS32322FB03   I128 @T6G_MB_LIB.T6G(SCH_1):PAGE105

PD_CHJ_CPU0_DIMM_SAA @T6G_MB_LIB.T6G(SCH_1):PD_CHJ_CPU0_DIMM_SAA
   J68  148    HAS SCONN288_DDR506112002KQ-SCONN288_DDR506112002KQ,SMA    I22 @T6G_MB_LIB.T6G(SCH_1):PAGE94
  R767    1      A Q_RES_0402LF-35.7K,1%,1/16W,CHIP,CS33572FB01   I129 @T6G_MB_LIB.T6G(SCH_1):PAGE94

PD_CHJ_CPU1_DIMM_SAA @T6G_MB_LIB.T6G(SCH_1):PD_CHJ_CPU1_DIMM_SAA
   J29  148    HAS SCONN288_DDR506112002KQ-SCONN288_DDR506112002KQ,SMA    I22 @T6G_MB_LIB.T6G(SCH_1):PAGE106
  R776    1      A Q_RES_0402LF-35.7K,1%,1/16W,CHIP,CS33572FB01   I127 @T6G_MB_LIB.T6G(SCH_1):PAGE106

PD_CHK_CPU0_DIMM_SAA @T6G_MB_LIB.T6G(SCH_1):PD_CHK_CPU0_DIMM_SAA
   J20  148    HAS SCONN288_DDR506112002KQ-SCONN288_DDR506112002KQ,SMA    I22 @T6G_MB_LIB.T6G(SCH_1):PAGE95
  R768    1      A Q_RES_0402LF-54.9K,1%,1/16W,CHIP,CS35492FB03   I129 @T6G_MB_LIB.T6G(SCH_1):PAGE95

PD_CHK_CPU1_DIMM_SAA @T6G_MB_LIB.T6G(SCH_1):PD_CHK_CPU1_DIMM_SAA
   J99  148    HAS SCONN288_DDR506112002KQ-SCONN288_DDR506112002KQ,SMA    I22 @T6G_MB_LIB.T6G(SCH_1):PAGE107
  R777    1      A Q_RES_0402LF-54.9K,1%,1/16W,CHIP,CS35492FB03   I136 @T6G_MB_LIB.T6G(SCH_1):PAGE107

PD_CHL_CPU0_DIMM_SAA @T6G_MB_LIB.T6G(SCH_1):PD_CHL_CPU0_DIMM_SAA
   J67  148    HAS SCONN288_DDR506112002KQ-SCONN288_DDR506112002KQ,SMA    I22 @T6G_MB_LIB.T6G(SCH_1):PAGE96
  R769    1      A Q_RES_0402LF-84.5K,1%,1/16W,CHIP,CS38452FB05   I127 @T6G_MB_LIB.T6G(SCH_1):PAGE96

PD_CHL_CPU1_DIMM_SAA @T6G_MB_LIB.T6G(SCH_1):PD_CHL_CPU1_DIMM_SAA
   J37  148    HAS SCONN288_DDR506112002KQ-SCONN288_DDR506112002KQ,SMA    I22 @T6G_MB_LIB.T6G(SCH_1):PAGE108
  R778    1      A Q_RES_0402LF-84.5K,1%,1/16W,CHIP,CS38452FB05   I136 @T6G_MB_LIB.T6G(SCH_1):PAGE108

PD_CPU_FRU_WP @T6G_MB_LIB.T6G(SCH_1):PD_CPU_FRU_WP
   R44    1      A Q_RES_0402LF-1K,1%,1/16W,CHIP,CS21002FB06   I115 @T6G_MB_LIB.T6G(SCH_1):PAGE361
    U1    7    WC# M24128BWMN6TP-M24128-BWMN6TP,SMLF,IC,AKE30Z00613    I97 @T6G_MB_LIB.T6G(SCH_1):PAGE361

PD_ESPI_CPU0_CLK2 @T6G_MB_LIB.T6G(SCH_1):PD_ESPI_CPU0_CLK2
   U25 DF27 ESPI_CLK2||AGPIO74 GENOA_SP5-SOCKET6096_13568-001,SMLF,IO,DGA^6000030   I287 @T6G_MB_LIB.T6G(SCH_1):PAGE29
  R742    2      B Q_RES_0402LF-10K,5%,1/16W,EMPTY,CS31002JB08    I46 @T6G_MB_LIB.T6G(SCH_1):PAGE75
  R753    2      B Q_RES_0402LF-10K,5%,1/16W,CHIP,CS31002JB08    I75 @T6G_MB_LIB.T6G(SCH_1):PAGE75

PD_ESPI_CPU1_CLK2 @T6G_MB_LIB.T6G(SCH_1):PD_ESPI_CPU1_CLK2
   U26 DF27 ESPI_CLK2||AGPIO74 GENOA_SP5-SOCKET6096_13568-001,SMLF,IO,DGA^6000030     I8 @T6G_MB_LIB.T6G(SCH_1):PAGE56
  R736    2      B Q_RES_0402LF-10K,5%,1/16W,EMPTY,CS31002JB08    I89 @T6G_MB_LIB.T6G(SCH_1):PAGE75
  R760    2      B Q_RES_0402LF-10K,5%,1/16W,CHIP,CS31002JB08    I92 @T6G_MB_LIB.T6G(SCH_1):PAGE75

PD_M2_0_DEVSLP @T6G_MB_LIB.T6G(SCH_1):PD_M2_0_DEVSLP
   J59   38 DEVSLP SCONN75K_APCI0155P004A-SCONN75K_APCI0155-P004A,SMLA    I88 @T6G_MB_LIB.T6G(SCH_1):PAGE345
 R1605    1      A Q_RES_0402LF-1K,1%,1/16W,CHIP,CS21002FB06    I83 @T6G_MB_LIB.T6G(SCH_1):PAGE345

PD_MB_FRU_WP @T6G_MB_LIB.T6G(SCH_1):PD_MB_FRU_WP
   U64    7    WC# M24128BWMN6TP-M24128-BWMN6TP,SMLF,IC,AKE30Z00613    I35 @T6G_MB_LIB.T6G(SCH_1):PAGE361
  R710    1      A Q_RES_0402LF-1K,1%,1/16W,CHIP,CS21002FB06    I57 @T6G_MB_LIB.T6G(SCH_1):PAGE361

PD_P2E_BUF2_ENSMB @T6G_MB_LIB.T6G(SCH_1):PD_P2E_BUF2_ENSMB
 U6000    3  ENSMB DS125BR111RTWR-DS125BR111RTWR,SMLF,IC,AL000125003     I1 @T6G_MB_LIB.T6G(SCH_1):PAGE111
 R6160    1      A Q_RES_0402LF-1K,1%,1/16W,CHIP,CS21002FB06    I12 @T6G_MB_LIB.T6G(SCH_1):PAGE111

PD_U160_EN_N @T6G_MB_LIB.T6G(SCH_1):PD_U160_EN_N
 R1313    1      A Q_RES_0402LF-4.7K,5%,1/16W,CHIP,CS24702JB10   I383 @T6G_MB_LIB.T6G(SCH_1):PAGE148
JP6001    3      3 CONN3_210HP1030BR1-CONN3_210-HP1-030BR1,THLF,IO,DFA   I387 @T6G_MB_LIB.T6G(SCH_1):PAGE148

PD_U212_EN_N @T6G_MB_LIB.T6G(SCH_1):PD_U212_EN_N
 R1318    1      A Q_RES_0402LF-4.7K,5%,1/16W,CHIP,CS24702JB10   I378 @T6G_MB_LIB.T6G(SCH_1):PAGE148
JP6000    3      3 CONN3_210HP1030BR1-CONN3_210-HP1-030BR1,THLF,IO,DFA   I386 @T6G_MB_LIB.T6G(SCH_1):PAGE148

PD_U5201_EQ @T6G_MB_LIB.T6G(SCH_1):PD_U5201_EQ
 R5238    1      A Q_RES_0402LF-3.9K,5%,1/16W,EMPTY,CS23902JB04    I83 @T6G_MB_LIB.T6G(SCH_1):PAGE358
 U5201    6     EQ TUSB211IRWBR-TUSB211IRWBR,SMLF,EMPTY,AL000211007    I84 @T6G_MB_LIB.T6G(SCH_1):PAGE358

PD_U5201_RSTN @T6G_MB_LIB.T6G(SCH_1):PD_U5201_RSTN
 C5232    1      A Q_CAP_C0402-0.1UF,25V,10%,EMPTY,CH4104KEB00    I81 @T6G_MB_LIB.T6G(SCH_1):PAGE358
 U5201    5   RSTN TUSB211IRWBR-TUSB211IRWBR,SMLF,EMPTY,AL000211007    I84 @T6G_MB_LIB.T6G(SCH_1):PAGE358

PD_U5201_VREG @T6G_MB_LIB.T6G(SCH_1):PD_U5201_VREG
 U5201   11   VREG TUSB211IRWBR-TUSB211IRWBR,SMLF,EMPTY,AL000211007    I84 @T6G_MB_LIB.T6G(SCH_1):PAGE358
 C5236    1      A Q_CAP_C0402-0.1UF,25V,10%,EMPTY,CH4104KEB00    I87 @T6G_MB_LIB.T6G(SCH_1):PAGE358

PD_USB_CPU0_WP @T6G_MB_LIB.T6G(SCH_1):PD_USB_CPU0_WP
 U6003    7    WC# M24128BWMN6TP-M24128-BWMN6TP,SMLF,IC,AKE30Z00613    I64 @T6G_MB_LIB.T6G(SCH_1):PAGE153
 R6223    1      A Q_RES_0402LF-1K,1%,1/16W,CHIP,CS21002FB06    I77 @T6G_MB_LIB.T6G(SCH_1):PAGE153

PRSNT0_N @T6G_MB_LIB.T6G(SCH_1):PRSNT0_N
 R1801    1      A Q_RES_0402LF-0,5%,1/16W,CHIP,CS00002JB13   I171 @T6G_MB_LIB.T6G(SCH_1):PAGE348
   J41  OB3    LD# SCONN168_ME1016810202011-SCONN168_ME1016810202011,A   I176 @T6G_MB_LIB.T6G(SCH_1):PAGE348

PRSNT_CABLE_GPU_A1 @T6G_MB_LIB.T6G(SCH_1):PRSNT_CABLE_GPU_A1
  Q134    6     D1 MOSFET_NCH_DUAL-PJT138K,SMLF,IC,BAM138K0003     I6 @T6G_MB_LIB.T6G(SCH_1):PAGE332
 R4155    2      B Q_RES_0402LF-4.7K,5%,1/16W,CHIP,CS24702JB10     I8 @T6G_MB_LIB.T6G(SCH_1):PAGE332
  Q134    5     G2 MOSFET_NCH_DUAL-PJT138K,SMLF,IC,BAM138K0003    I10 @T6G_MB_LIB.T6G(SCH_1):PAGE332

PRSNT_CABLE_GPU_A1_ISO_N @T6G_MB_LIB.T6G(SCH_1):PRSNT_CABLE_GPU_A1_ISO_N
 R4157    2      B Q_RES_0402LF-33.2,1%,1/16W,CHIP,CS03322FB03   I246 @T6G_MB_LIB.T6G(SCH_1):PAGE80
 R9019    1      A Q_RES_0402LF-0,5%,1/16W,CHIP,CS00002JB13    I42 @T6G_MB_LIB.T6G(SCH_1):PAGE246
  Q134    3     D2 MOSFET_NCH_DUAL-PJT138K,SMLF,IC,BAM138K0003    I10 @T6G_MB_LIB.T6G(SCH_1):PAGE332
 R4574    2      B Q_RES_0402LF-0,5%,1/16W,EMPTY,CS00002JB13    I31 @T6G_MB_LIB.T6G(SCH_1):PAGE332
 R4156    2      B Q_RES_0402LF-100K,1%,1/16W,CHIP,CS41002FB09    I48 @T6G_MB_LIB.T6G(SCH_1):PAGE332
   C15    1      A Q_CAP_0402-0.1UF,25V,10%,X7R,CH4104K1B00    I50 @T6G_MB_LIB.T6G(SCH_1):PAGE332

PRSNT_CABLE_GPU_A1_ISO_R1_N @T6G_MB_LIB.T6G(SCH_1):PRSNT_CABLE_GPU_A1_ISO_R1_N
 R9019    2      B Q_RES_0402LF-0,5%,1/16W,CHIP,CS00002JB13    I42 @T6G_MB_LIB.T6G(SCH_1):PAGE246
  U181   19  IO1_6 PCA9539RPW-PCA9539RPW,SMLF,IC,AL009539K07    I83 @T6G_MB_LIB.T6G(SCH_1):PAGE246

PRSNT_CABLE_GPU_A1_ISO_R_N @T6G_MB_LIB.T6G(SCH_1):PRSNT_CABLE_GPU_A1_ISO_R_N
   U18 AA14  PB33B LCMXO3LF9400C5BG484C-LCMXO3LF-9400C-5BG484C,SMLF,IA   I216 @T6G_MB_LIB.T6G(SCH_1):PAGE80
 R4157    1      A Q_RES_0402LF-33.2,1%,1/16W,CHIP,CS03322FB03   I246 @T6G_MB_LIB.T6G(SCH_1):PAGE80

PRSNT_CABLE_GPU_A1_N @T6G_MB_LIB.T6G(SCH_1):PRSNT_CABLE_GPU_A1_N
  J106   A7     A7 CONN112_10137002101LF-CONN112_10137002-101LF,THLF,A    I19 @T6G_MB_LIB.T6G(SCH_1):PAGE327
 R4154    1      A Q_RES_0402LF-100K,1%,1/16W,EMPTY,CS41002FB09     I2 @T6G_MB_LIB.T6G(SCH_1):PAGE332
 R4153    2      B Q_RES_0402LF-10K,1%,1/16W,CHIP,CS31002FB08     I4 @T6G_MB_LIB.T6G(SCH_1):PAGE332
  Q134    2     G1 MOSFET_NCH_DUAL-PJT138K,SMLF,IC,BAM138K0003     I6 @T6G_MB_LIB.T6G(SCH_1):PAGE332
 R4574    1      A Q_RES_0402LF-0,5%,1/16W,EMPTY,CS00002JB13    I31 @T6G_MB_LIB.T6G(SCH_1):PAGE332

PRSNT_CABLE_GPU_A2 @T6G_MB_LIB.T6G(SCH_1):PRSNT_CABLE_GPU_A2
  Q133    6     D1 MOSFET_NCH_DUAL-PJT138K,SMLF,IC,BAM138K0003    I98 @T6G_MB_LIB.T6G(SCH_1):PAGE332
 R4139    2      B Q_RES_0402LF-4.7K,5%,1/16W,CHIP,CS24702JB10    I99 @T6G_MB_LIB.T6G(SCH_1):PAGE332
  Q133    5     G2 MOSFET_NCH_DUAL-PJT138K,SMLF,IC,BAM138K0003   I120 @T6G_MB_LIB.T6G(SCH_1):PAGE332

PRSNT_CABLE_GPU_A2_ISO_N @T6G_MB_LIB.T6G(SCH_1):PRSNT_CABLE_GPU_A2_ISO_N
 R4147    2      B Q_RES_0402LF-33.2,1%,1/16W,CHIP,CS03322FB03   I240 @T6G_MB_LIB.T6G(SCH_1):PAGE80
 R9013    1      A Q_RES_0402LF-0,5%,1/16W,CHIP,CS00002JB13    I43 @T6G_MB_LIB.T6G(SCH_1):PAGE246
 R4578    2      B Q_RES_0402LF-0,5%,1/16W,EMPTY,CS00002JB13   I103 @T6G_MB_LIB.T6G(SCH_1):PAGE332
  Q133    3     D2 MOSFET_NCH_DUAL-PJT138K,SMLF,IC,BAM138K0003   I120 @T6G_MB_LIB.T6G(SCH_1):PAGE332
 R4142    2      B Q_RES_0402LF-100K,1%,1/16W,CHIP,CS41002FB09   I122 @T6G_MB_LIB.T6G(SCH_1):PAGE332
   C19    1      A Q_CAP_0402-0.1UF,25V,10%,X7R,CH4104K1B00   I127 @T6G_MB_LIB.T6G(SCH_1):PAGE332

PRSNT_CABLE_GPU_A2_ISO_R1_N @T6G_MB_LIB.T6G(SCH_1):PRSNT_CABLE_GPU_A2_ISO_R1_N
 R9013    2      B Q_RES_0402LF-0,5%,1/16W,CHIP,CS00002JB13    I43 @T6G_MB_LIB.T6G(SCH_1):PAGE246
  U181   13  IO1_0 PCA9539RPW-PCA9539RPW,SMLF,IC,AL009539K07    I83 @T6G_MB_LIB.T6G(SCH_1):PAGE246

PRSNT_CABLE_GPU_A2_ISO_R_N @T6G_MB_LIB.T6G(SCH_1):PRSNT_CABLE_GPU_A2_ISO_R_N
   U18  V14  PB32D LCMXO3LF9400C5BG484C-LCMXO3LF-9400C-5BG484C,SMLF,IA   I216 @T6G_MB_LIB.T6G(SCH_1):PAGE80
 R4147    1      A Q_RES_0402LF-33.2,1%,1/16W,CHIP,CS03322FB03   I240 @T6G_MB_LIB.T6G(SCH_1):PAGE80

PRSNT_CABLE_GPU_A2_N @T6G_MB_LIB.T6G(SCH_1):PRSNT_CABLE_GPU_A2_N
  J108   A3     A3 CONN112_10137002101LF-CONN112_10137002-101LF,THLF,A    I72 @T6G_MB_LIB.T6G(SCH_1):PAGE320
 R4136    1      A Q_RES_0402LF-100K,1%,1/16W,EMPTY,CS41002FB09    I92 @T6G_MB_LIB.T6G(SCH_1):PAGE332
 R4135    2      B Q_RES_0402LF-10K,1%,1/16W,CHIP,CS31002FB08    I93 @T6G_MB_LIB.T6G(SCH_1):PAGE332
  Q133    2     G1 MOSFET_NCH_DUAL-PJT138K,SMLF,IC,BAM138K0003    I98 @T6G_MB_LIB.T6G(SCH_1):PAGE332
 R4578    1      A Q_RES_0402LF-0,5%,1/16W,EMPTY,CS00002JB13   I103 @T6G_MB_LIB.T6G(SCH_1):PAGE332

PRSNT_CABLE_GPU_A3 @T6G_MB_LIB.T6G(SCH_1):PRSNT_CABLE_GPU_A3
 Q9002    6     D1 MOSFET_NCH_DUAL-PJT138K,SMLF,IC,BAM138K0003    I52 @T6G_MB_LIB.T6G(SCH_1):PAGE330
 R9016    2      B Q_RES_0402LF-4.7K,5%,1/16W,CHIP,CS24702JB10    I61 @T6G_MB_LIB.T6G(SCH_1):PAGE330
 Q9002    5     G2 MOSFET_NCH_DUAL-PJT138K,SMLF,IC,BAM138K0003    I75 @T6G_MB_LIB.T6G(SCH_1):PAGE330

PRSNT_CABLE_GPU_A3_ISO_N @T6G_MB_LIB.T6G(SCH_1):PRSNT_CABLE_GPU_A3_ISO_N
 R9018    1      A Q_RES_0402LF-0,5%,1/16W,CHIP,CS00002JB13    I44 @T6G_MB_LIB.T6G(SCH_1):PAGE246
 C9002    1      A Q_CAP_0402-1000PF,50V,5%,EMPTY,TMP_QCH21006JB10    I71 @T6G_MB_LIB.T6G(SCH_1):PAGE330
 R9017    2      B Q_RES_0402LF-4.7K,5%,1/16W,CHIP,CS24702JB10    I72 @T6G_MB_LIB.T6G(SCH_1):PAGE330
 Q9002    3     D2 MOSFET_NCH_DUAL-PJT138K,SMLF,IC,BAM138K0003    I75 @T6G_MB_LIB.T6G(SCH_1):PAGE330

PRSNT_CABLE_GPU_A3_ISO_R_N @T6G_MB_LIB.T6G(SCH_1):PRSNT_CABLE_GPU_A3_ISO_R_N
 R9018    2      B Q_RES_0402LF-0,5%,1/16W,CHIP,CS00002JB13    I44 @T6G_MB_LIB.T6G(SCH_1):PAGE246
  U181   20  IO1_7 PCA9539RPW-PCA9539RPW,SMLF,IC,AL009539K07    I83 @T6G_MB_LIB.T6G(SCH_1):PAGE246

PRSNT_CABLE_GPU_A3_N @T6G_MB_LIB.T6G(SCH_1):PRSNT_CABLE_GPU_A3_N
  J108   N8     N8 CONN112_10137002101LF-CONN112_10137002-101LF,THLF,A    I15 @T6G_MB_LIB.T6G(SCH_1):PAGE320
 R9015    1      A Q_RES_0402LF-100K,1%,1/16W,EMPTY,CS41002FB09    I50 @T6G_MB_LIB.T6G(SCH_1):PAGE330
 R9014    2      B Q_RES_0402LF-10K,1%,1/16W,CHIP,CS31002FB08    I51 @T6G_MB_LIB.T6G(SCH_1):PAGE330
 Q9002    2     G1 MOSFET_NCH_DUAL-PJT138K,SMLF,IC,BAM138K0003    I52 @T6G_MB_LIB.T6G(SCH_1):PAGE330

PRSNT_CABLE_GPU_B3 @T6G_MB_LIB.T6G(SCH_1):PRSNT_CABLE_GPU_B3
  Q132    6     D1 MOSFET_NCH_DUAL-PJT138K,SMLF,IC,BAM138K0003    I25 @T6G_MB_LIB.T6G(SCH_1):PAGE332
 R4126    2      B Q_RES_0402LF-4.7K,5%,1/16W,CHIP,CS24702JB10    I27 @T6G_MB_LIB.T6G(SCH_1):PAGE332
  Q132    5     G2 MOSFET_NCH_DUAL-PJT138K,SMLF,IC,BAM138K0003    I32 @T6G_MB_LIB.T6G(SCH_1):PAGE332

PRSNT_CABLE_GPU_B3_ISO_N @T6G_MB_LIB.T6G(SCH_1):PRSNT_CABLE_GPU_B3_ISO_N
 R4145    2      B Q_RES_0402LF-33.2,1%,1/16W,CHIP,CS03322FB03   I121 @T6G_MB_LIB.T6G(SCH_1):PAGE79
 R9011    1      A Q_RES_0402LF-0,5%,1/16W,CHIP,CS00002JB13    I45 @T6G_MB_LIB.T6G(SCH_1):PAGE246
  Q132    3     D2 MOSFET_NCH_DUAL-PJT138K,SMLF,IC,BAM138K0003    I32 @T6G_MB_LIB.T6G(SCH_1):PAGE332
 R4573    2      B Q_RES_0402LF-0,5%,1/16W,EMPTY,CS00002JB13    I33 @T6G_MB_LIB.T6G(SCH_1):PAGE332
   C13    1      A Q_CAP_0402-0.1UF,25V,10%,X7R,CH4104K1B00    I64 @T6G_MB_LIB.T6G(SCH_1):PAGE332
 R4129    2      B Q_RES_0402LF-100K,1%,1/16W,CHIP,CS41002FB09    I66 @T6G_MB_LIB.T6G(SCH_1):PAGE332

PRSNT_CABLE_GPU_B3_ISO_R1_N @T6G_MB_LIB.T6G(SCH_1):PRSNT_CABLE_GPU_B3_ISO_R1_N
 R9011    2      B Q_RES_0402LF-0,5%,1/16W,CHIP,CS00002JB13    I45 @T6G_MB_LIB.T6G(SCH_1):PAGE246
  U181   10  IO0_6 PCA9539RPW-PCA9539RPW,SMLF,IC,AL009539K07    I83 @T6G_MB_LIB.T6G(SCH_1):PAGE246

PRSNT_CABLE_GPU_B3_ISO_R_N @T6G_MB_LIB.T6G(SCH_1):PRSNT_CABLE_GPU_B3_ISO_R_N
   U18  G12  PT28A LCMXO3LF9400C5BG484C-LCMXO3LF-9400C-5BG484C,SMLF,IA    I94 @T6G_MB_LIB.T6G(SCH_1):PAGE79
 R4145    1      A Q_RES_0402LF-33.2,1%,1/16W,CHIP,CS03322FB03   I121 @T6G_MB_LIB.T6G(SCH_1):PAGE79

PRSNT_CABLE_GPU_B3_N @T6G_MB_LIB.T6G(SCH_1):PRSNT_CABLE_GPU_B3_N
  J109   N8     N8 CONN112_10137002101LF-CONN112_10137002-101LF,THLF,A    I16 @T6G_MB_LIB.T6G(SCH_1):PAGE319
 R4122    1      A Q_RES_0402LF-100K,1%,1/16W,EMPTY,CS41002FB09    I13 @T6G_MB_LIB.T6G(SCH_1):PAGE332
 R4121    2      B Q_RES_0402LF-10K,1%,1/16W,CHIP,CS31002FB08    I14 @T6G_MB_LIB.T6G(SCH_1):PAGE332
  Q132    2     G1 MOSFET_NCH_DUAL-PJT138K,SMLF,IC,BAM138K0003    I25 @T6G_MB_LIB.T6G(SCH_1):PAGE332
 R4573    1      A Q_RES_0402LF-0,5%,1/16W,EMPTY,CS00002JB13    I33 @T6G_MB_LIB.T6G(SCH_1):PAGE332

PRSNT_CABLE_SWB_B1 @T6G_MB_LIB.T6G(SCH_1):PRSNT_CABLE_SWB_B1
 Q9000    6     D1 MOSFET_NCH_DUAL-PJT138K,SMLF,IC,BAM138K0003    I21 @T6G_MB_LIB.T6G(SCH_1):PAGE330
 R9004    2      B Q_RES_0402LF-4.7K,5%,1/16W,CHIP,CS24702JB10    I26 @T6G_MB_LIB.T6G(SCH_1):PAGE330
 Q9000    5     G2 MOSFET_NCH_DUAL-PJT138K,SMLF,IC,BAM138K0003    I31 @T6G_MB_LIB.T6G(SCH_1):PAGE330

PRSNT_CABLE_SWB_B1_ISO_N @T6G_MB_LIB.T6G(SCH_1):PRSNT_CABLE_SWB_B1_ISO_N
 R9010    1      A Q_RES_0402LF-0,5%,1/16W,CHIP,CS00002JB13    I40 @T6G_MB_LIB.T6G(SCH_1):PAGE246
 Q9000    3     D2 MOSFET_NCH_DUAL-PJT138K,SMLF,IC,BAM138K0003    I31 @T6G_MB_LIB.T6G(SCH_1):PAGE330
 R9005    2      B Q_RES_0402LF-4.7K,5%,1/16W,CHIP,CS24702JB10    I32 @T6G_MB_LIB.T6G(SCH_1):PAGE330
 C9000    1      A Q_CAP_0402-1000PF,50V,5%,EMPTY,TMP_QCH21006JB10    I45 @T6G_MB_LIB.T6G(SCH_1):PAGE330

PRSNT_CABLE_SWB_B1_ISO_R_N @T6G_MB_LIB.T6G(SCH_1):PRSNT_CABLE_SWB_B1_ISO_R_N
 R9010    2      B Q_RES_0402LF-0,5%,1/16W,CHIP,CS00002JB13    I40 @T6G_MB_LIB.T6G(SCH_1):PAGE246
  U181   14  IO1_1 PCA9539RPW-PCA9539RPW,SMLF,IC,AL009539K07    I83 @T6G_MB_LIB.T6G(SCH_1):PAGE246

PRSNT_CABLE_SWB_B1_N @T6G_MB_LIB.T6G(SCH_1):PRSNT_CABLE_SWB_B1_N
 R9002    2      B Q_RES_0402LF-10K,1%,1/16W,CHIP,CS31002FB08     I8 @T6G_MB_LIB.T6G(SCH_1):PAGE330
 Q9000    2     G1 MOSFET_NCH_DUAL-PJT138K,SMLF,IC,BAM138K0003    I21 @T6G_MB_LIB.T6G(SCH_1):PAGE330
  J106   A1     A1 CONN112_10137002101LF-CONN112_10137002-101LF,THLF,A    I74 @T6G_MB_LIB.T6G(SCH_1):PAGE327
 R9003    1      A Q_RES_0402LF-100K,1%,1/16W,EMPTY,CS41002FB09    I20 @T6G_MB_LIB.T6G(SCH_1):PAGE330

PRSNT_CABLE_SWB_B2 @T6G_MB_LIB.T6G(SCH_1):PRSNT_CABLE_SWB_B2
 R9008    2      B Q_RES_0402LF-4.7K,5%,1/16W,CHIP,CS24702JB10    I17 @T6G_MB_LIB.T6G(SCH_1):PAGE330
 Q9001    6     D1 MOSFET_NCH_DUAL-PJT138K,SMLF,IC,BAM138K0003     I3 @T6G_MB_LIB.T6G(SCH_1):PAGE330
 Q9001    5     G2 MOSFET_NCH_DUAL-PJT138K,SMLF,IC,BAM138K0003    I22 @T6G_MB_LIB.T6G(SCH_1):PAGE330

PRSNT_CABLE_SWB_B2_ISO_N @T6G_MB_LIB.T6G(SCH_1):PRSNT_CABLE_SWB_B2_ISO_N
 R9009    2      B Q_RES_0402LF-4.7K,5%,1/16W,CHIP,CS24702JB10    I23 @T6G_MB_LIB.T6G(SCH_1):PAGE330
 R9012    1      A Q_RES_0402LF-0,5%,1/16W,CHIP,CS00002JB13    I39 @T6G_MB_LIB.T6G(SCH_1):PAGE246
 Q9001    3     D2 MOSFET_NCH_DUAL-PJT138K,SMLF,IC,BAM138K0003    I22 @T6G_MB_LIB.T6G(SCH_1):PAGE330
 C9001    1      A Q_CAP_0402-1000PF,50V,5%,EMPTY,TMP_QCH21006JB10    I42 @T6G_MB_LIB.T6G(SCH_1):PAGE330

PRSNT_CABLE_SWB_B2_ISO_R_N @T6G_MB_LIB.T6G(SCH_1):PRSNT_CABLE_SWB_B2_ISO_R_N
 R9012    2      B Q_RES_0402LF-0,5%,1/16W,CHIP,CS00002JB13    I39 @T6G_MB_LIB.T6G(SCH_1):PAGE246
  U181   11  IO0_7 PCA9539RPW-PCA9539RPW,SMLF,IC,AL009539K07    I83 @T6G_MB_LIB.T6G(SCH_1):PAGE246

PRSNT_CABLE_SWB_B2_N @T6G_MB_LIB.T6G(SCH_1):PRSNT_CABLE_SWB_B2_N
  J107   N2     N2 CONN112_10137002101LF-CONN112_10137002-101LF,THLF,A    I49 @T6G_MB_LIB.T6G(SCH_1):PAGE317
 R9007    1      A Q_RES_0402LF-100K,1%,1/16W,EMPTY,CS41002FB09     I2 @T6G_MB_LIB.T6G(SCH_1):PAGE330
 Q9001    2     G1 MOSFET_NCH_DUAL-PJT138K,SMLF,IC,BAM138K0003     I3 @T6G_MB_LIB.T6G(SCH_1):PAGE330
 R9006    2      B Q_RES_0402LF-10K,1%,1/16W,CHIP,CS31002FB08    I15 @T6G_MB_LIB.T6G(SCH_1):PAGE330

PRSNT_CPU0_N @T6G_MB_LIB.T6G(SCH_1):PRSNT_CPU0_N
   U25  B66 CPU_PRESENT_L GENOA_SP5-SOCKET6096_13568-001,SMLF,IO,DGA^6000030   I227 @T6G_MB_LIB.T6G(SCH_1):PAGE27
  R734    1      A Q_RES_0402LF-0,5%,1/16W,CHIP,CS00002JB13    I19 @T6G_MB_LIB.T6G(SCH_1):PAGE144
   SW1    7      7 SW20S_DHNF10FQTR-SW20S_DHNF-10F-Q-T/R,SMLF,MECH,DHA    I90 @T6G_MB_LIB.T6G(SCH_1):PAGE144

PRSNT_CPU1_N @T6G_MB_LIB.T6G(SCH_1):PRSNT_CPU1_N
   U26  B66 CPU_PRESENT_L GENOA_SP5-SOCKET6096_13568-001,SMLF,IO,DGA^6000030   I190 @T6G_MB_LIB.T6G(SCH_1):PAGE54
  R744    1      A Q_RES_0402LF-0,5%,1/16W,CHIP,CS00002JB13    I17 @T6G_MB_LIB.T6G(SCH_1):PAGE144
   SW1    8      8 SW20S_DHNF10FQTR-SW20S_DHNF-10F-Q-T/R,SMLF,MECH,DHA    I90 @T6G_MB_LIB.T6G(SCH_1):PAGE144

PRSNT_HDT_N @T6G_MB_LIB.T6G(SCH_1):PRSNT_HDT_N
 R1528    1      A Q_RES_0402LF-33,5%,1/16W,CHIP,CS03302JB10   I157 @T6G_MB_LIB.T6G(SCH_1):PAGE149
 R1527    1      A Q_RES_0402LF-1K,1%,1/16W,CHIP,CS21002FB06    I56 @T6G_MB_LIB.T6G(SCH_1):PAGE82
   U18 AB20  PB44A LCMXO3LF9400C5BG484C-LCMXO3LF-9400C-5BG484C,SMLF,IA   I216 @T6G_MB_LIB.T6G(SCH_1):PAGE80

PRSNT_HDT_R_N @T6G_MB_LIB.T6G(SCH_1):PRSNT_HDT_R_N
   J54    3      3 SCONN20_HSU2101L00007H-SCONN20_HSU2101-L0000-7H,SMA   I142 @T6G_MB_LIB.T6G(SCH_1):PAGE149
 R1528    2      B Q_RES_0402LF-33,5%,1/16W,CHIP,CS03302JB10   I157 @T6G_MB_LIB.T6G(SCH_1):PAGE149

PRSNT_OCP_SFF_N @T6G_MB_LIB.T6G(SCH_1):PRSNT_OCP_SFF_N
 R6046    2      B Q_RES_0402LF-100,1%,1/16W,CHIP,CS11002FB07    I64 @T6G_MB_LIB.T6G(SCH_1):PAGE80
   U18  AA3 PB7A||CSSPIN LCMXO3LF9400C5BG484C-LCMXO3LF-9400C-5BG484C,SMLF,IA   I216 @T6G_MB_LIB.T6G(SCH_1):PAGE80

PRSNT_OCP_V3_2_N @T6G_MB_LIB.T6G(SCH_1):PRSNT_OCP_V3_2_N
   U18  D15  PT38D LCMXO3LF9400C5BG484C-LCMXO3LF-9400C-5BG484C,SMLF,IA    I94 @T6G_MB_LIB.T6G(SCH_1):PAGE79
 R6117    2      B Q_RES_0402LF-100,1%,1/16W,CHIP,CS11002FB07   I131 @T6G_MB_LIB.T6G(SCH_1):PAGE79

PRSNT_SWB @T6G_MB_LIB.T6G(SCH_1):PRSNT_SWB
 Q8000    5     G2 MOSFET_NCH_DUAL-PJT138K,SMLF,IC,BAM138K0003    I30 @T6G_MB_LIB.T6G(SCH_1):PAGE330
 Q8000    6     D1 MOSFET_NCH_DUAL-PJT138K,SMLF,IC,BAM138K0003    I29 @T6G_MB_LIB.T6G(SCH_1):PAGE330
 R8002    2      B Q_RES_0402LF-4.7K,5%,1/16W,CHIP,CS24702JB10    I55 @T6G_MB_LIB.T6G(SCH_1):PAGE330

PRSNT_SWB_ISO_N @T6G_MB_LIB.T6G(SCH_1):PRSNT_SWB_ISO_N
 Q8000    3     D2 MOSFET_NCH_DUAL-PJT138K,SMLF,IC,BAM138K0003    I30 @T6G_MB_LIB.T6G(SCH_1):PAGE330
 R8000    1      A Q_RES_0402LF-33.2,1%,1/16W,CHIP,CS03322FB03   I315 @T6G_MB_LIB.T6G(SCH_1):PAGE80
 R8004    1      A Q_RES_0402LF-0,5%,1/16W,CHIP,CS00002JB13    I41 @T6G_MB_LIB.T6G(SCH_1):PAGE246
 C8000    1      A Q_CAP_0402-1000PF,50V,5%,EMPTY,TMP_QCH21006JB10    I36 @T6G_MB_LIB.T6G(SCH_1):PAGE330
 R8003    2      B Q_RES_0402LF-4.7K,5%,1/16W,CHIP,CS24702JB10    I57 @T6G_MB_LIB.T6G(SCH_1):PAGE330

PRSNT_SWB_ISO_R1_N @T6G_MB_LIB.T6G(SCH_1):PRSNT_SWB_ISO_R1_N
 R8004    2      B Q_RES_0402LF-0,5%,1/16W,CHIP,CS00002JB13    I41 @T6G_MB_LIB.T6G(SCH_1):PAGE246
  U181    8  IO0_4 PCA9539RPW-PCA9539RPW,SMLF,IC,AL009539K07    I83 @T6G_MB_LIB.T6G(SCH_1):PAGE246

PRSNT_SWB_ISO_R_N @T6G_MB_LIB.T6G(SCH_1):PRSNT_SWB_ISO_R_N
   U18  AB4   PB8B LCMXO3LF9400C5BG484C-LCMXO3LF-9400C-5BG484C,SMLF,IA   I216 @T6G_MB_LIB.T6G(SCH_1):PAGE80
 R8000    2      B Q_RES_0402LF-33.2,1%,1/16W,CHIP,CS03322FB03   I315 @T6G_MB_LIB.T6G(SCH_1):PAGE80

PRSNT_SWB_N @T6G_MB_LIB.T6G(SCH_1):PRSNT_SWB_N
  J112   A7     A7 CONN160_10131762101LF-CONN160_10131762-101LF,THLF,A     I7 @T6G_MB_LIB.T6G(SCH_1):PAGE329
 R8001    1      A Q_RES_0402LF-100K,1%,1/16W,EMPTY,CS41002FB09    I12 @T6G_MB_LIB.T6G(SCH_1):PAGE330
 R4058    2      B Q_RES_0402LF-10K,1%,1/16W,CHIP,CS31002FB08    I13 @T6G_MB_LIB.T6G(SCH_1):PAGE330
 Q8000    2     G1 MOSFET_NCH_DUAL-PJT138K,SMLF,IC,BAM138K0003    I29 @T6G_MB_LIB.T6G(SCH_1):PAGE330

PU_BIOS_USB_RECOVERY @T6G_MB_LIB.T6G(SCH_1):PU_BIOS_USB_RECOVERY
   R22    2      B Q_RES_0402LF-100,1%,1/16W,CHIP,CS11002FB07    I54 @T6G_MB_LIB.T6G(SCH_1):PAGE144
   SW1    4      4 SW20S_DHNF10FQTR-SW20S_DHNF-10F-Q-T/R,SMLF,MECH,DHA    I90 @T6G_MB_LIB.T6G(SCH_1):PAGE144

PU_BOOT_RDY_LED @T6G_MB_LIB.T6G(SCH_1):PU_BOOT_RDY_LED
  R948    1      A Q_RES_0402LF-130,1%,1/16W,CHIP,CS11302FB03     I7 @T6G_MB_LIB.T6G(SCH_1):PAGE143
    D5    A      A Q_LED_SMLF-LED_BLUE,LTST-C281TBKT-5A,IC,BEBL0172Z00     I8 @T6G_MB_LIB.T6G(SCH_1):PAGE143

PU_BUFFER_HDD_ACTIVITY @T6G_MB_LIB.T6G(SCH_1):PU_BUFFER_HDD_ACTIVITY
  U239    1     OE 74LVC1G126SE7-74LVC1G126SE-7,SMLF,IC,AL1G0126009    I53 @T6G_MB_LIB.T6G(SCH_1):PAGE345
 R5377    2      B Q_RES_0402LF-0,5%,1/16W,CHIP,CS00002JB13    I62 @T6G_MB_LIB.T6G(SCH_1):PAGE345

PU_CPU0_USB_HUB_OVRCURR @T6G_MB_LIB.T6G(SCH_1):PU_CPU0_USB_HUB_OVRCURR
 U6001   30 OVRCURR CYUSB330468LTXI-CYUSB3304-68LTXI,SMLF,IC,AJ0330400A     I1 @T6G_MB_LIB.T6G(SCH_1):PAGE153
 R6205    2      B Q_RES_0402LF-10K,1%,1/16W,CHIP,CS31002FB08    I43 @T6G_MB_LIB.T6G(SCH_1):PAGE153

PU_CPU0_USB_HUB_PWR_EN @T6G_MB_LIB.T6G(SCH_1):PU_CPU0_USB_HUB_PWR_EN
 U6001   29 PWR_EN CYUSB330468LTXI-CYUSB3304-68LTXI,SMLF,IC,AJ0330400A     I1 @T6G_MB_LIB.T6G(SCH_1):PAGE153
 R6204    2      B Q_RES_0402LF-10K,1%,1/16W,CHIP,CS31002FB08    I41 @T6G_MB_LIB.T6G(SCH_1):PAGE153

PU_CPU0_USB_HUB_RESERVED1 @T6G_MB_LIB.T6G(SCH_1):PU_CPU0_USB_HUB_RESERVED1
 U6001   21 RESERVED1 CYUSB330468LTXI-CYUSB3304-68LTXI,SMLF,IC,AJ0330400A     I1 @T6G_MB_LIB.T6G(SCH_1):PAGE153
 R6207    2      B Q_RES_0402LF-10K,1%,1/16W,CHIP,CS31002FB08    I45 @T6G_MB_LIB.T6G(SCH_1):PAGE153

PU_CPU0_USB_HUB_RESERVED2 @T6G_MB_LIB.T6G(SCH_1):PU_CPU0_USB_HUB_RESERVED2
 U6001   22 RESERVED2 CYUSB330468LTXI-CYUSB3304-68LTXI,SMLF,IC,AJ0330400A     I1 @T6G_MB_LIB.T6G(SCH_1):PAGE153
 R6206    2      B Q_RES_0402LF-10K,1%,1/16W,CHIP,CS31002FB08    I44 @T6G_MB_LIB.T6G(SCH_1):PAGE153

PU_E1S_0_DUALPORT_EN_N @T6G_MB_LIB.T6G(SCH_1):PU_E1S_0_DUALPORT_EN_N
 R2317    2      B Q_RES_0402LF-10K,1%,1/16W,CHIP,CS31002FB08    I31 @T6G_MB_LIB.T6G(SCH_1):PAGE297
   J90   B9 DUALPORTEN# SCONN56_123276793-SCONN56_1-2327679-3,SMLF,IO,DFHSA    I90 @T6G_MB_LIB.T6G(SCH_1):PAGE297

PU_FPGA_DEBUG_LED_CTRL @T6G_MB_LIB.T6G(SCH_1):PU_FPGA_DEBUG_LED_CTRL
 R6040    2      B Q_RES_0402LF-10K,5%,1/16W,CHIP,CS31002JB08    I70 @T6G_MB_LIB.T6G(SCH_1):PAGE144
   SW1   10     10 SW20S_DHNF10FQTR-SW20S_DHNF-10F-Q-T/R,SMLF,MECH,DHA    I90 @T6G_MB_LIB.T6G(SCH_1):PAGE144

PU_FPGA_DEBUG_SW_SPARE @T6G_MB_LIB.T6G(SCH_1):PU_FPGA_DEBUG_SW_SPARE
 R6042    2      B Q_RES_0402LF-10K,5%,1/16W,CHIP,CS31002JB08    I62 @T6G_MB_LIB.T6G(SCH_1):PAGE144
   SW1    5      5 SW20S_DHNF10FQTR-SW20S_DHNF-10F-Q-T/R,SMLF,MECH,DHA    I90 @T6G_MB_LIB.T6G(SCH_1):PAGE144

PU_JTAG_DBP_BMC_PRDY_N @T6G_MB_LIB.T6G(SCH_1):PU_JTAG_DBP_BMC_PRDY_N
   J41  A50 PERN10 SCONN168_ME1016810202011-SCONN168_ME1016810202011,A   I176 @T6G_MB_LIB.T6G(SCH_1):PAGE348
 R6071    2      B Q_RES_0402LF-4.7K,5%,1/16W,EMPTY,CS24702JB10   I214 @T6G_MB_LIB.T6G(SCH_1):PAGE348

PU_OCP_SFF_WAKE_OE @T6G_MB_LIB.T6G(SCH_1):PU_OCP_SFF_WAKE_OE
 U8082    1     OE 74LVC1G126SE7-74LVC1G126SE-7,SMLF,IC,AL1G0126009     I8 @T6G_MB_LIB.T6G(SCH_1):PAGE337
   R45    2      B Q_RES_0402LF-10K,1%,1/16W,CHIP,CS31002FB08    I12 @T6G_MB_LIB.T6G(SCH_1):PAGE337

PU_OCP_V3_2_WAKE_OE @T6G_MB_LIB.T6G(SCH_1):PU_OCP_V3_2_WAKE_OE
 R3183    2      B Q_RES_0402LF-10K,1%,1/16W,CHIP,CS31002FB08     I4 @T6G_MB_LIB.T6G(SCH_1):PAGE342
  U217    1     OE 74LVC1G126SE7-74LVC1G126SE-7,SMLF,IC,AL1G0126009    I14 @T6G_MB_LIB.T6G(SCH_1):PAGE342

PU_P12V_ALL_PWROK_LED @T6G_MB_LIB.T6G(SCH_1):PU_P12V_ALL_PWROK_LED
 R1208    1      A Q_RES_0402LF-470,1%,1/16W,CHIP,CS14702FB04    I42 @T6G_MB_LIB.T6G(SCH_1):PAGE143
   D46    A      A Q_LED_SMLF-LED_BLUE,LTST-C281TBKT-5A,IC,BEBL0172Z00    I43 @T6G_MB_LIB.T6G(SCH_1):PAGE143

PU_RST_SMB_PCIE0_N @T6G_MB_LIB.T6G(SCH_1):PU_RST_SMB_PCIE0_N
 R2268    2      B Q_RES_0402LF-0,5%,1/16W,CHIP,CS00002JB13    I28 @T6G_MB_LIB.T6G(SCH_1):PAGE252
   U36    3 RESET# TCA9548APWR-TCA9548APWR,SMLF,IC,AL009548K02    I33 @T6G_MB_LIB.T6G(SCH_1):PAGE252

PU_RST_SMB_PCIE2_N @T6G_MB_LIB.T6G(SCH_1):PU_RST_SMB_PCIE2_N
 R3710    2      B Q_RES_0402LF-0,5%,1/16W,CHIP,CS00002JB13    I29 @T6G_MB_LIB.T6G(SCH_1):PAGE251
   U39    3 RESET# TCA9548APWR-TCA9548APWR,SMLF,IC,AL009548K02    I74 @T6G_MB_LIB.T6G(SCH_1):PAGE251

PU_RST_SMB_U181_N @T6G_MB_LIB.T6G(SCH_1):PU_RST_SMB_U181_N
 R2922    2      B Q_RES_0402LF-0,5%,1/16W,CHIP,CS00002JB13    I31 @T6G_MB_LIB.T6G(SCH_1):PAGE246
  U181    3  RESET PCA9539RPW-PCA9539RPW,SMLF,IC,AL009539K07    I83 @T6G_MB_LIB.T6G(SCH_1):PAGE246

PU_SMERR_LED @T6G_MB_LIB.T6G(SCH_1):PU_SMERR_LED
  R950    1      A Q_RES_0402LF-249,1%,1/16W,CHIP,CS12492FB02     I3 @T6G_MB_LIB.T6G(SCH_1):PAGE143
    D6    A      A Q_LED_SMLF-LED_YELLOW,LTST-C190KSKT-P,IC,BEYL0159ZA     I9 @T6G_MB_LIB.T6G(SCH_1):PAGE143

PU_SPI_PLD_CS_N @T6G_MB_LIB.T6G(SCH_1):PU_SPI_PLD_CS_N
   U18 AB21 PB46A||SN LCMXO3LF9400C5BG484C-LCMXO3LF-9400C-5BG484C,SMLF,IA   I216 @T6G_MB_LIB.T6G(SCH_1):PAGE80
 R6085    2      B Q_RES_0402LF-10K,1%,1/16W,CHIP,CS31002FB08   I298 @T6G_MB_LIB.T6G(SCH_1):PAGE80

PU_TEST @T6G_MB_LIB.T6G(SCH_1):PU_TEST
  U237    5  TEST# PI3EQX12902AZLEX-PI3EQX12902AZLEX,SMLF,IC,AL012902A    I63 @T6G_MB_LIB.T6G(SCH_1):PAGE110
 R3291    1      A Q_RES_0402LF-4.7K,1%,1/16W,EMPTY,CS24702FB06    I88 @T6G_MB_LIB.T6G(SCH_1):PAGE110

PU_U160_EN_N @T6G_MB_LIB.T6G(SCH_1):PU_U160_EN_N
 R6182    2      B Q_RES_0402LF-4.7K,5%,1/16W,CHIP,CS24702JB10   I384 @T6G_MB_LIB.T6G(SCH_1):PAGE148
JP6001    1      1 CONN3_210HP1030BR1-CONN3_210-HP1-030BR1,THLF,IO,DFA   I387 @T6G_MB_LIB.T6G(SCH_1):PAGE148

PU_U181_INT @T6G_MB_LIB.T6G(SCH_1):PU_U181_INT
 R2923    2      B Q_RES_0402LF-4.7K,5%,1/16W,EMPTY,CS24702JB10    I37 @T6G_MB_LIB.T6G(SCH_1):PAGE246
  U181    1    INT PCA9539RPW-PCA9539RPW,SMLF,IC,AL009539K07    I83 @T6G_MB_LIB.T6G(SCH_1):PAGE246

PU_U212_EN_N @T6G_MB_LIB.T6G(SCH_1):PU_U212_EN_N
 R6181    2      B Q_RES_0402LF-4.7K,5%,1/16W,CHIP,CS24702JB10   I381 @T6G_MB_LIB.T6G(SCH_1):PAGE148
JP6000    1      1 CONN3_210HP1030BR1-CONN3_210-HP1-030BR1,THLF,IO,DFA   I386 @T6G_MB_LIB.T6G(SCH_1):PAGE148

PU_U2_EN @T6G_MB_LIB.T6G(SCH_1):PU_U2_EN
  R201    2      B Q_RES_0402LF-4.7K,5%,1/16W,EMPTY,CS24702JB10    I62 @T6G_MB_LIB.T6G(SCH_1):PAGE137
    U2    5     EN PCA9617ADP-PCA9617ADP,SMLF,IC,AL009617K02    I99 @T6G_MB_LIB.T6G(SCH_1):PAGE137

PU_U38_6 @T6G_MB_LIB.T6G(SCH_1):PU_U38_6
   U38    6      C SN74LVC1G11DCKR-SN74LVC1G11DCKR,SMLF,IC,ALLVC1G1000     I8 @T6G_MB_LIB.T6G(SCH_1):PAGE264
 R6504    2      B Q_RES_0402LF-10K,1%,1/16W,CHIP,CS31002FB08    I51 @T6G_MB_LIB.T6G(SCH_1):PAGE264

PU_U5_EN @T6G_MB_LIB.T6G(SCH_1):PU_U5_EN
   R78    2      B Q_RES_0402LF-4.7K,5%,1/16W,EMPTY,CS24702JB10    I31 @T6G_MB_LIB.T6G(SCH_1):PAGE137
    U5    5     EN PCA9617ADP-PCA9617ADP,SMLF,EMPTY,AL009617K02    I48 @T6G_MB_LIB.T6G(SCH_1):PAGE137

PU_U96_EN @T6G_MB_LIB.T6G(SCH_1):PU_U96_EN
  R200    2      B Q_RES_0402LF-4.7K,5%,1/16W,EMPTY,CS24702JB10    I13 @T6G_MB_LIB.T6G(SCH_1):PAGE137
   U96    5     EN PCA9617ADP-PCA9617ADP,SMLF,IC,AL009617K02    I51 @T6G_MB_LIB.T6G(SCH_1):PAGE137

PV09_RETIMER_CPU0_VCCS @T6G_MB_LIB.T6G(SCH_1):PV09_RETIMER_CPU0_VCCS
PU6502   40   VCCS ISL69260IRAZT-ISL69260IRAZ-T,SMLF,IC,AL069260000    I42 @T6G_MB_LIB.T6G(SCH_1):PAGE475
PC6606    1      A Q_CAP_C0402-10UF,6.3V,20%,X6S,CH6101MEB03   I145 @T6G_MB_LIB.T6G(SCH_1):PAGE475
PC6605    1      A Q_CAP_C0402-1UF,16V,10%,X6S,CH5103KEB01   I146 @T6G_MB_LIB.T6G(SCH_1):PAGE475
PU6503   39  REFIN ISL99390FRZTR5935-ISL99390FRZ-TR5935,SMLF,IC,AL099A    I53 @T6G_MB_LIB.T6G(SCH_1):PAGE476
PC6553_1    1      A Q_CAP_C0402-100NF,50V,10%,X7R,CH4106K1B01    I68 @T6G_MB_LIB.T6G(SCH_1):PAGE476
PU6504   39  REFIN ISL99390FRZTR5935-ISL99390FRZ-TR5935,SMLF,IC,AL099A   I270 @T6G_MB_LIB.T6G(SCH_1):PAGE476
PC6576    1      A Q_CAP_C0402-100NF,50V,10%,X7R,CH4106K1B01   I281 @T6G_MB_LIB.T6G(SCH_1):PAGE476

PV09_RETIMER_CPU1_VCCS @T6G_MB_LIB.T6G(SCH_1):PV09_RETIMER_CPU1_VCCS
PC6546    1      A Q_CAP_C0402-10UF,6.3V,20%,X6S,CH6101MEB03    I72 @T6G_MB_LIB.T6G(SCH_1):PAGE477
PC6545    1      A Q_CAP_C0402-1UF,16V,10%,X6S,CH5103KEB01    I73 @T6G_MB_LIB.T6G(SCH_1):PAGE477
PU6510   40   VCCS ISL69260IRAZT-ISL69260IRAZ-T,SMLF,IC,AL069260000    I88 @T6G_MB_LIB.T6G(SCH_1):PAGE477
PC6646    1      A Q_CAP_C0402-100NF,50V,10%,X7R,CH4106K1B01     I2 @T6G_MB_LIB.T6G(SCH_1):PAGE478
PU6512   39  REFIN ISL99390FRZTR5935-ISL99390FRZ-TR5935,SMLF,IC,AL099A    I12 @T6G_MB_LIB.T6G(SCH_1):PAGE478
PC6611_1    1      A Q_CAP_C0402-100NF,50V,10%,X7R,CH4106K1B01    I39 @T6G_MB_LIB.T6G(SCH_1):PAGE478
PU6511   39  REFIN ISL99390FRZTR5935-ISL99390FRZ-TR5935,SMLF,IC,AL099A    I51 @T6G_MB_LIB.T6G(SCH_1):PAGE478

PVDD11_S3_P0 @T6G_MB_LIB.T6G(SCH_1):PVDD11_S3_P0
   U25 BJ18 VDD_11_S3_BJ18 GENOA_SP5-SOCKET6096_13568-001,SMLF,IO,DGA^6000030    I28 @T6G_MB_LIB.T6G(SCH_1):PAGE30
   U25 BJ23 VDD_11_S3_BJ23 GENOA_SP5-SOCKET6096_13568-001,SMLF,IO,DGA^6000030    I28 @T6G_MB_LIB.T6G(SCH_1):PAGE30
   U25 BJ25 VDD_11_S3_BJ25 GENOA_SP5-SOCKET6096_13568-001,SMLF,IO,DGA^6000030    I28 @T6G_MB_LIB.T6G(SCH_1):PAGE30
   U25 BJ27 VDD_11_S3_BJ27 GENOA_SP5-SOCKET6096_13568-001,SMLF,IO,DGA^6000030    I28 @T6G_MB_LIB.T6G(SCH_1):PAGE30
   U25 BK22 VDD_11_S3_BK22 GENOA_SP5-SOCKET6096_13568-001,SMLF,IO,DGA^6000030    I28 @T6G_MB_LIB.T6G(SCH_1):PAGE30
   U25 BK24 VDD_11_S3_BK24 GENOA_SP5-SOCKET6096_13568-001,SMLF,IO,DGA^6000030    I28 @T6G_MB_LIB.T6G(SCH_1):PAGE30
   U25 BK26 VDD_11_S3_BK26 GENOA_SP5-SOCKET6096_13568-001,SMLF,IO,DGA^6000030    I28 @T6G_MB_LIB.T6G(SCH_1):PAGE30
   U25 BK28 VDD_11_S3_BK28 GENOA_SP5-SOCKET6096_13568-001,SMLF,IO,DGA^6000030    I28 @T6G_MB_LIB.T6G(SCH_1):PAGE30
   U25 BK49 VDD_11_S3_BK49 GENOA_SP5-SOCKET6096_13568-001,SMLF,IO,DGA^6000030    I28 @T6G_MB_LIB.T6G(SCH_1):PAGE30
   U25 BL23 VDD_11_S3_BL23 GENOA_SP5-SOCKET6096_13568-001,SMLF,IO,DGA^6000030    I28 @T6G_MB_LIB.T6G(SCH_1):PAGE30
   U25 BL25 VDD_11_S3_BL25 GENOA_SP5-SOCKET6096_13568-001,SMLF,IO,DGA^6000030    I28 @T6G_MB_LIB.T6G(SCH_1):PAGE30
   U25 BL27 VDD_11_S3_BL27 GENOA_SP5-SOCKET6096_13568-001,SMLF,IO,DGA^6000030    I28 @T6G_MB_LIB.T6G(SCH_1):PAGE30
   U25 BL48 VDD_11_S3_BL48 GENOA_SP5-SOCKET6096_13568-001,SMLF,IO,DGA^6000030    I28 @T6G_MB_LIB.T6G(SCH_1):PAGE30
   U25 BM12 VDD_11_S3_BM12 GENOA_SP5-SOCKET6096_13568-001,SMLF,IO,DGA^6000030    I28 @T6G_MB_LIB.T6G(SCH_1):PAGE30
   U25 BM19 VDD_11_S3_BM19 GENOA_SP5-SOCKET6096_13568-001,SMLF,IO,DGA^6000030    I28 @T6G_MB_LIB.T6G(SCH_1):PAGE30
   U25 BM22 VDD_11_S3_BM22 GENOA_SP5-SOCKET6096_13568-001,SMLF,IO,DGA^6000030    I28 @T6G_MB_LIB.T6G(SCH_1):PAGE30
   U25 BM24 VDD_11_S3_BM24 GENOA_SP5-SOCKET6096_13568-001,SMLF,IO,DGA^6000030    I28 @T6G_MB_LIB.T6G(SCH_1):PAGE30
   U25 BM26 VDD_11_S3_BM26 GENOA_SP5-SOCKET6096_13568-001,SMLF,IO,DGA^6000030    I28 @T6G_MB_LIB.T6G(SCH_1):PAGE30
   U25 BM28 VDD_11_S3_BM28 GENOA_SP5-SOCKET6096_13568-001,SMLF,IO,DGA^6000030    I28 @T6G_MB_LIB.T6G(SCH_1):PAGE30
   U25 BM30 VDD_11_S3_BM30 GENOA_SP5-SOCKET6096_13568-001,SMLF,IO,DGA^6000030    I28 @T6G_MB_LIB.T6G(SCH_1):PAGE30
   U25 BM32 VDD_11_S3_BM32 GENOA_SP5-SOCKET6096_13568-001,SMLF,IO,DGA^6000030    I28 @T6G_MB_LIB.T6G(SCH_1):PAGE30
   U25 BM34 VDD_11_S3_BM34 GENOA_SP5-SOCKET6096_13568-001,SMLF,IO,DGA^6000030    I28 @T6G_MB_LIB.T6G(SCH_1):PAGE30
   U25 BM36 VDD_11_S3_BM36 GENOA_SP5-SOCKET6096_13568-001,SMLF,IO,DGA^6000030    I28 @T6G_MB_LIB.T6G(SCH_1):PAGE30
   U25 BM39 VDD_11_S3_BM39 GENOA_SP5-SOCKET6096_13568-001,SMLF,IO,DGA^6000030    I28 @T6G_MB_LIB.T6G(SCH_1):PAGE30
   U25 BM41 VDD_11_S3_BM41 GENOA_SP5-SOCKET6096_13568-001,SMLF,IO,DGA^6000030    I28 @T6G_MB_LIB.T6G(SCH_1):PAGE30
   U25 BM43 VDD_11_S3_BM43 GENOA_SP5-SOCKET6096_13568-001,SMLF,IO,DGA^6000030    I28 @T6G_MB_LIB.T6G(SCH_1):PAGE30
   U25 BM45 VDD_11_S3_BM45 GENOA_SP5-SOCKET6096_13568-001,SMLF,IO,DGA^6000030    I28 @T6G_MB_LIB.T6G(SCH_1):PAGE30
   U25 BM47 VDD_11_S3_BM47 GENOA_SP5-SOCKET6096_13568-001,SMLF,IO,DGA^6000030    I28 @T6G_MB_LIB.T6G(SCH_1):PAGE30
   U25 BM49 VDD_11_S3_BM49 GENOA_SP5-SOCKET6096_13568-001,SMLF,IO,DGA^6000030    I28 @T6G_MB_LIB.T6G(SCH_1):PAGE30
   U25 BN25 VDD_11_S3_BN25 GENOA_SP5-SOCKET6096_13568-001,SMLF,IO,DGA^6000030    I28 @T6G_MB_LIB.T6G(SCH_1):PAGE30
   U25 BN29 VDD_11_S3_BN29 GENOA_SP5-SOCKET6096_13568-001,SMLF,IO,DGA^6000030    I28 @T6G_MB_LIB.T6G(SCH_1):PAGE30
   U25 BN33 VDD_11_S3_BN33 GENOA_SP5-SOCKET6096_13568-001,SMLF,IO,DGA^6000030    I28 @T6G_MB_LIB.T6G(SCH_1):PAGE30
   U25 BN40 VDD_11_S3_BN40 GENOA_SP5-SOCKET6096_13568-001,SMLF,IO,DGA^6000030    I28 @T6G_MB_LIB.T6G(SCH_1):PAGE30
   U25 BN44 VDD_11_S3_BN44 GENOA_SP5-SOCKET6096_13568-001,SMLF,IO,DGA^6000030    I28 @T6G_MB_LIB.T6G(SCH_1):PAGE30
   U25 BN48 VDD_11_S3_BN48 GENOA_SP5-SOCKET6096_13568-001,SMLF,IO,DGA^6000030    I28 @T6G_MB_LIB.T6G(SCH_1):PAGE30
   U25 BP22 VDD_11_S3_BP22 GENOA_SP5-SOCKET6096_13568-001,SMLF,IO,DGA^6000030    I28 @T6G_MB_LIB.T6G(SCH_1):PAGE30
   U25  BR4 VDD_11_S3_BR4 GENOA_SP5-SOCKET6096_13568-001,SMLF,IO,DGA^6000030    I28 @T6G_MB_LIB.T6G(SCH_1):PAGE30
   U25 BR11 VDD_11_S3_BR11 GENOA_SP5-SOCKET6096_13568-001,SMLF,IO,DGA^6000030    I28 @T6G_MB_LIB.T6G(SCH_1):PAGE30
   U25 BR18 VDD_11_S3_BR18 GENOA_SP5-SOCKET6096_13568-001,SMLF,IO,DGA^6000030    I28 @T6G_MB_LIB.T6G(SCH_1):PAGE30
   U25  BV5 VDD_11_S3_BV5 GENOA_SP5-SOCKET6096_13568-001,SMLF,IO,DGA^6000030    I28 @T6G_MB_LIB.T6G(SCH_1):PAGE30
   U25 BV12 VDD_11_S3_BV12 GENOA_SP5-SOCKET6096_13568-001,SMLF,IO,DGA^6000030    I28 @T6G_MB_LIB.T6G(SCH_1):PAGE30
   U25 BV19 VDD_11_S3_BV19 GENOA_SP5-SOCKET6096_13568-001,SMLF,IO,DGA^6000030    I28 @T6G_MB_LIB.T6G(SCH_1):PAGE30
   U25 BV22 VDD_11_S3_BV22 GENOA_SP5-SOCKET6096_13568-001,SMLF,IO,DGA^6000030    I28 @T6G_MB_LIB.T6G(SCH_1):PAGE30
   U25  CA4 VDD_11_S3_CA4 GENOA_SP5-SOCKET6096_13568-001,SMLF,IO,DGA^6000030    I28 @T6G_MB_LIB.T6G(SCH_1):PAGE30
   U25 CA11 VDD_11_S3_CA11 GENOA_SP5-SOCKET6096_13568-001,SMLF,IO,DGA^6000030    I28 @T6G_MB_LIB.T6G(SCH_1):PAGE30
   U25 CA18 VDD_11_S3_CA18 GENOA_SP5-SOCKET6096_13568-001,SMLF,IO,DGA^6000030    I28 @T6G_MB_LIB.T6G(SCH_1):PAGE30
   U25 CB22 VDD_11_S3_CB22 GENOA_SP5-SOCKET6096_13568-001,SMLF,IO,DGA^6000030    I28 @T6G_MB_LIB.T6G(SCH_1):PAGE30
   U25  CD5 VDD_11_S3_CD5 GENOA_SP5-SOCKET6096_13568-001,SMLF,IO,DGA^6000030    I28 @T6G_MB_LIB.T6G(SCH_1):PAGE30
   U25 CD12 VDD_11_S3_CD12 GENOA_SP5-SOCKET6096_13568-001,SMLF,IO,DGA^6000030    I28 @T6G_MB_LIB.T6G(SCH_1):PAGE30
   U25 CD19 VDD_11_S3_CD19 GENOA_SP5-SOCKET6096_13568-001,SMLF,IO,DGA^6000030    I28 @T6G_MB_LIB.T6G(SCH_1):PAGE30
   U25 CF22 VDD_11_S3_CF22 GENOA_SP5-SOCKET6096_13568-001,SMLF,IO,DGA^6000030    I28 @T6G_MB_LIB.T6G(SCH_1):PAGE30
   U25  CG4 VDD_11_S3_CG4 GENOA_SP5-SOCKET6096_13568-001,SMLF,IO,DGA^6000030    I28 @T6G_MB_LIB.T6G(SCH_1):PAGE30
   U25 CG11 VDD_11_S3_CG11 GENOA_SP5-SOCKET6096_13568-001,SMLF,IO,DGA^6000030    I28 @T6G_MB_LIB.T6G(SCH_1):PAGE30
   U25 CG18 VDD_11_S3_CG18 GENOA_SP5-SOCKET6096_13568-001,SMLF,IO,DGA^6000030    I28 @T6G_MB_LIB.T6G(SCH_1):PAGE30
   U25 CJ22 VDD_11_S3_CJ22 GENOA_SP5-SOCKET6096_13568-001,SMLF,IO,DGA^6000030    I28 @T6G_MB_LIB.T6G(SCH_1):PAGE30
   U25  CK5 VDD_11_S3_CK5 GENOA_SP5-SOCKET6096_13568-001,SMLF,IO,DGA^6000030    I28 @T6G_MB_LIB.T6G(SCH_1):PAGE30
   U25 CK12 VDD_11_S3_CK12 GENOA_SP5-SOCKET6096_13568-001,SMLF,IO,DGA^6000030    I28 @T6G_MB_LIB.T6G(SCH_1):PAGE30
   U25 CK19 VDD_11_S3_CK19 GENOA_SP5-SOCKET6096_13568-001,SMLF,IO,DGA^6000030    I28 @T6G_MB_LIB.T6G(SCH_1):PAGE30
   U25 CM22 VDD_11_S3_CM22 GENOA_SP5-SOCKET6096_13568-001,SMLF,IO,DGA^6000030    I28 @T6G_MB_LIB.T6G(SCH_1):PAGE30
   U25  CN4 VDD_11_S3_CN4 GENOA_SP5-SOCKET6096_13568-001,SMLF,IO,DGA^6000030    I28 @T6G_MB_LIB.T6G(SCH_1):PAGE30
   U25 CN11 VDD_11_S3_CN11 GENOA_SP5-SOCKET6096_13568-001,SMLF,IO,DGA^6000030    I28 @T6G_MB_LIB.T6G(SCH_1):PAGE30
   U25 CN18 VDD_11_S3_CN18 GENOA_SP5-SOCKET6096_13568-001,SMLF,IO,DGA^6000030    I28 @T6G_MB_LIB.T6G(SCH_1):PAGE30
   U25  CT5 VDD_11_S3_CT5 GENOA_SP5-SOCKET6096_13568-001,SMLF,IO,DGA^6000030    I28 @T6G_MB_LIB.T6G(SCH_1):PAGE30
   U25 CT12 VDD_11_S3_CT12 GENOA_SP5-SOCKET6096_13568-001,SMLF,IO,DGA^6000030    I28 @T6G_MB_LIB.T6G(SCH_1):PAGE30
   U25 CT19 VDD_11_S3_CT19 GENOA_SP5-SOCKET6096_13568-001,SMLF,IO,DGA^6000030    I28 @T6G_MB_LIB.T6G(SCH_1):PAGE30
   U25 CT22 VDD_11_S3_CT22 GENOA_SP5-SOCKET6096_13568-001,SMLF,IO,DGA^6000030    I28 @T6G_MB_LIB.T6G(SCH_1):PAGE30
   U25  CW4 VDD_11_S3_CW4 GENOA_SP5-SOCKET6096_13568-001,SMLF,IO,DGA^6000030    I28 @T6G_MB_LIB.T6G(SCH_1):PAGE30
   U25 CW11 VDD_11_S3_CW11 GENOA_SP5-SOCKET6096_13568-001,SMLF,IO,DGA^6000030    I28 @T6G_MB_LIB.T6G(SCH_1):PAGE30
   U25 CW18 VDD_11_S3_CW18 GENOA_SP5-SOCKET6096_13568-001,SMLF,IO,DGA^6000030    I28 @T6G_MB_LIB.T6G(SCH_1):PAGE30
   U25 CY22 VDD_11_S3_CY22 GENOA_SP5-SOCKET6096_13568-001,SMLF,IO,DGA^6000030    I28 @T6G_MB_LIB.T6G(SCH_1):PAGE30
   U25  DB5 VDD_11_S3_DB5 GENOA_SP5-SOCKET6096_13568-001,SMLF,IO,DGA^6000030    I28 @T6G_MB_LIB.T6G(SCH_1):PAGE30
   U25 DB12 VDD_11_S3_DB12 GENOA_SP5-SOCKET6096_13568-001,SMLF,IO,DGA^6000030    I28 @T6G_MB_LIB.T6G(SCH_1):PAGE30
   U25 DB19 VDD_11_S3_DB19 GENOA_SP5-SOCKET6096_13568-001,SMLF,IO,DGA^6000030    I28 @T6G_MB_LIB.T6G(SCH_1):PAGE30
   U25  DE4 VDD_11_S3_DE4 GENOA_SP5-SOCKET6096_13568-001,SMLF,IO,DGA^6000030    I28 @T6G_MB_LIB.T6G(SCH_1):PAGE30
   U25 DE11 VDD_11_S3_DE11 GENOA_SP5-SOCKET6096_13568-001,SMLF,IO,DGA^6000030    I28 @T6G_MB_LIB.T6G(SCH_1):PAGE30
   U25 DE18 VDD_11_S3_DE18 GENOA_SP5-SOCKET6096_13568-001,SMLF,IO,DGA^6000030    I28 @T6G_MB_LIB.T6G(SCH_1):PAGE30
   U25  DG5 VDD_11_S3_DG5 GENOA_SP5-SOCKET6096_13568-001,SMLF,IO,DGA^6000030    I28 @T6G_MB_LIB.T6G(SCH_1):PAGE30
 C2133    1      A Q_CAP_C0402-22UF,4V,20%,X6S,CH622KMEB02   I110 @T6G_MB_LIB.T6G(SCH_1):PAGE67
 C2138    1      A Q_CAP_C0402-22UF,4V,20%,X6S,CH622KMEB02   I112 @T6G_MB_LIB.T6G(SCH_1):PAGE67
 C2132    1      A Q_CAP_C0402-22UF,4V,20%,X6S,CH622KMEB02   I113 @T6G_MB_LIB.T6G(SCH_1):PAGE67
 C2137    1      A Q_CAP_C0402-22UF,4V,20%,X6S,CH622KMEB02   I115 @T6G_MB_LIB.T6G(SCH_1):PAGE67
 C3890    1      A Q_CAP_C0402-22UF,4V,20%,X6S,CH622KMEB02   I116 @T6G_MB_LIB.T6G(SCH_1):PAGE67
 C3891    1      A Q_CAP_C0402-22UF,4V,20%,X6S,CH622KMEB02   I117 @T6G_MB_LIB.T6G(SCH_1):PAGE67
 C3892    1      A Q_CAP_C0402-22UF,4V,20%,X6S,CH622KMEB02   I118 @T6G_MB_LIB.T6G(SCH_1):PAGE67
 C3893    1      A Q_CAP_C0402-22UF,4V,20%,X6S,CH622KMEB02   I120 @T6G_MB_LIB.T6G(SCH_1):PAGE67
 C2142    1      A Q_CAP_C0402-22UF,4V,20%,X6S,CH622KMEB02   I121 @T6G_MB_LIB.T6G(SCH_1):PAGE67
 C2146    1      A Q_CAP_C0402-22UF,4V,20%,X6S,CH622KMEB02   I122 @T6G_MB_LIB.T6G(SCH_1):PAGE67
 C2150    1      A Q_CAP_C0402-22UF,4V,20%,X6S,CH622KMEB02   I123 @T6G_MB_LIB.T6G(SCH_1):PAGE67
 C2153    1      A Q_CAP_C0402-22UF,4V,20%,X6S,CH622KMEB02   I124 @T6G_MB_LIB.T6G(SCH_1):PAGE67
 C2156    1      A Q_CAP_C0402-22UF,4V,20%,X6S,CH622KMEB02   I125 @T6G_MB_LIB.T6G(SCH_1):PAGE67
 C2158    1      A Q_CAP_C0402-22UF,4V,20%,X6S,CH622KMEB02   I127 @T6G_MB_LIB.T6G(SCH_1):PAGE67
 C2160    1      A Q_CAP_C0402-22UF,4V,20%,X6S,CH622KMEB02   I128 @T6G_MB_LIB.T6G(SCH_1):PAGE67
 C2162    1      A Q_CAP_C0402-22UF,4V,20%,X6S,CH622KMEB02   I129 @T6G_MB_LIB.T6G(SCH_1):PAGE67
 C3932    1      A Q_CAP_C0402-22UF,4V,20%,X6S,CH622KMEB02    I53 @T6G_MB_LIB.T6G(SCH_1):PAGE69
 C2603    1      A Q_CAP_C0402-22UF,4V,20%,X6S,CH622KMEB02    I58 @T6G_MB_LIB.T6G(SCH_1):PAGE69
 C2602    1      A Q_CAP_C0402-22UF,4V,20%,X6S,CH622KMEB02    I60 @T6G_MB_LIB.T6G(SCH_1):PAGE69
 C2601    1      A Q_CAP_C0402-22UF,4V,20%,X6S,CH622KMEB02    I71 @T6G_MB_LIB.T6G(SCH_1):PAGE69
 C2600    1      A Q_CAP_C0402-22UF,4V,20%,X6S,CH622KMEB02    I76 @T6G_MB_LIB.T6G(SCH_1):PAGE69
 C3933    1      A Q_CAP_C0402-22UF,4V,20%,X6S,CH622KMEB02   I111 @T6G_MB_LIB.T6G(SCH_1):PAGE69
 C2610    1      A Q_CAP_C0402-22UF,4V,20%,X6S,CH622KMEB02   I112 @T6G_MB_LIB.T6G(SCH_1):PAGE69
 C2609    1      A Q_CAP_C0402-22UF,4V,20%,X6S,CH622KMEB02   I113 @T6G_MB_LIB.T6G(SCH_1):PAGE69
 C2617    1      A Q_CAP_C0402-22UF,4V,20%,X6S,CH622KMEB02   I114 @T6G_MB_LIB.T6G(SCH_1):PAGE69
 C2616    1      A Q_CAP_C0402-22UF,4V,20%,X6S,CH622KMEB02   I115 @T6G_MB_LIB.T6G(SCH_1):PAGE69
 C2624    1      A Q_CAP_C0402-22UF,4V,20%,X6S,CH622KMEB02   I116 @T6G_MB_LIB.T6G(SCH_1):PAGE69
 C2623    1      A Q_CAP_C0402-22UF,4V,20%,X6S,CH622KMEB02   I117 @T6G_MB_LIB.T6G(SCH_1):PAGE69
 C2630    1      A Q_CAP_C0402-22UF,4V,20%,X6S,CH622KMEB02   I118 @T6G_MB_LIB.T6G(SCH_1):PAGE69
 C2629    1      A Q_CAP_C0402-22UF,4V,20%,X6S,CH622KMEB02   I119 @T6G_MB_LIB.T6G(SCH_1):PAGE69
 C2636    1      A Q_CAP_C0402-22UF,4V,20%,X6S,CH622KMEB02   I120 @T6G_MB_LIB.T6G(SCH_1):PAGE69
 C2635    1      A Q_CAP_C0402-22UF,4V,20%,X6S,CH622KMEB02   I121 @T6G_MB_LIB.T6G(SCH_1):PAGE69
 C2608    1      A Q_CAP_C0402-22UF,4V,20%,X6S,CH622KMEB02   I122 @T6G_MB_LIB.T6G(SCH_1):PAGE69
 C2615    1      A Q_CAP_C0402-22UF,4V,20%,X6S,CH622KMEB02   I123 @T6G_MB_LIB.T6G(SCH_1):PAGE69
 C2607    1      A Q_CAP_C0402-22UF,4V,20%,X6S,CH622KMEB02   I124 @T6G_MB_LIB.T6G(SCH_1):PAGE69
 C2614    1      A Q_CAP_C0402-22UF,4V,20%,X6S,CH622KMEB02   I125 @T6G_MB_LIB.T6G(SCH_1):PAGE69
 C2622    1      A Q_CAP_C0402-22UF,4V,20%,X6S,CH622KMEB02   I126 @T6G_MB_LIB.T6G(SCH_1):PAGE69
 C2621    1      A Q_CAP_C0402-22UF,4V,20%,X6S,CH622KMEB02   I127 @T6G_MB_LIB.T6G(SCH_1):PAGE69
 C2628    1      A Q_CAP_C0402-22UF,4V,20%,X6S,CH622KMEB02   I129 @T6G_MB_LIB.T6G(SCH_1):PAGE69
 C2634    1      A Q_CAP_C0402-22UF,4V,20%,X6S,CH622KMEB02   I130 @T6G_MB_LIB.T6G(SCH_1):PAGE69
 C2627    1      A Q_CAP_C0402-22UF,4V,20%,X6S,CH622KMEB02   I131 @T6G_MB_LIB.T6G(SCH_1):PAGE69
 C2633    1      A Q_CAP_C0402-22UF,4V,20%,X6S,CH622KMEB02   I132 @T6G_MB_LIB.T6G(SCH_1):PAGE69
 C2642    1      A Q_CAP_C0402-22UF,4V,20%,X6S,CH622KMEB02   I133 @T6G_MB_LIB.T6G(SCH_1):PAGE69
 C2641    1      A Q_CAP_C0402-22UF,4V,20%,X6S,CH622KMEB02   I134 @T6G_MB_LIB.T6G(SCH_1):PAGE69
 C2648    1      A Q_CAP_C0402-22UF,4V,20%,X6S,CH622KMEB02   I135 @T6G_MB_LIB.T6G(SCH_1):PAGE69
 C2647    1      A Q_CAP_C0402-22UF,4V,20%,X6S,CH622KMEB02   I136 @T6G_MB_LIB.T6G(SCH_1):PAGE69
 C3934    1      A Q_CAP_C0402-22UF,4V,20%,X6S,CH622KMEB02   I138 @T6G_MB_LIB.T6G(SCH_1):PAGE69
 C2653    1      A Q_CAP_C0402-22UF,4V,20%,X6S,CH622KMEB02   I139 @T6G_MB_LIB.T6G(SCH_1):PAGE69
 C3935    1      A Q_CAP_C0402-22UF,4V,20%,X6S,CH622KMEB02   I140 @T6G_MB_LIB.T6G(SCH_1):PAGE69
 C2658    1      A Q_CAP_C0402-22UF,4V,20%,X6S,CH622KMEB02   I142 @T6G_MB_LIB.T6G(SCH_1):PAGE69
 C2640    1      A Q_CAP_C0402-22UF,4V,20%,X6S,CH622KMEB02   I143 @T6G_MB_LIB.T6G(SCH_1):PAGE69
 C2646    1      A Q_CAP_C0402-22UF,4V,20%,X6S,CH622KMEB02   I144 @T6G_MB_LIB.T6G(SCH_1):PAGE69
 C2639    1      A Q_CAP_C0402-22UF,4V,20%,X6S,CH622KMEB02   I145 @T6G_MB_LIB.T6G(SCH_1):PAGE69
 C2645    1      A Q_CAP_C0402-22UF,4V,20%,X6S,CH622KMEB02   I146 @T6G_MB_LIB.T6G(SCH_1):PAGE69
 C2652    1      A Q_CAP_C0402-22UF,4V,20%,X6S,CH622KMEB02   I147 @T6G_MB_LIB.T6G(SCH_1):PAGE69
 C2657    1      A Q_CAP_C0402-22UF,4V,20%,X6S,CH622KMEB02   I149 @T6G_MB_LIB.T6G(SCH_1):PAGE69
 C2651    1      A Q_CAP_C0402-22UF,4V,20%,X6S,CH622KMEB02   I151 @T6G_MB_LIB.T6G(SCH_1):PAGE69
 C2656    1      A Q_CAP_C0402-22UF,4V,20%,X6S,CH622KMEB02   I152 @T6G_MB_LIB.T6G(SCH_1):PAGE69
  R363    1      A Q_RES_0402LF-1K,1%,1/16W,CHIP,CS21002FB06    I56 @T6G_MB_LIB.T6G(SCH_1):PAGE138
  PL22    2      2 Q_INDUCTOR_SMLF-90NH/155A,IND,CVA90^0KZ13    I52 @T6G_MB_LIB.T6G(SCH_1):PAGE183
 PC229    1      A Q_CAPP_SMLF-390UF,2.5V,20%,ALUM,CC7390JMZ13    I66 @T6G_MB_LIB.T6G(SCH_1):PAGE183
 PC230    1      A Q_CAPP_SMLF-390UF,2.5V,20%,ALUM,CC7390JMZ13    I67 @T6G_MB_LIB.T6G(SCH_1):PAGE183
 PC801    1      A Q_CAPP_SMLF-390UF,2.5V,20%,ALUM,CC7390JMZ13    I70 @T6G_MB_LIB.T6G(SCH_1):PAGE183
PC224_1    1      A Q_CAP_C0805-22UF,4V,20%,X6S,CH622KMEA03    I81 @T6G_MB_LIB.T6G(SCH_1):PAGE183
 R5006    1      A Q_RES_0402LF-1K,1%,1/16W,EMPTY,CS21002FB06   I145 @T6G_MB_LIB.T6G(SCH_1):PAGE136
 R5007    1      A Q_RES_0402LF-1K,1%,1/16W,EMPTY,CS21002FB06   I147 @T6G_MB_LIB.T6G(SCH_1):PAGE136
 R5008    1      A Q_RES_0402LF-1K,1%,1/16W,EMPTY,CS21002FB06   I148 @T6G_MB_LIB.T6G(SCH_1):PAGE136
 R5009    1      A Q_RES_0402LF-1K,1%,1/16W,EMPTY,CS21002FB06   I150 @T6G_MB_LIB.T6G(SCH_1):PAGE136
 R5015    1      A Q_RES_0402LF-1K,1%,1/16W,EMPTY,CS21002FB06   I157 @T6G_MB_LIB.T6G(SCH_1):PAGE136
 R5014    1      A Q_RES_0402LF-1K,1%,1/16W,EMPTY,CS21002FB06   I159 @T6G_MB_LIB.T6G(SCH_1):PAGE136
 R5017    1      A Q_RES_0402LF-1K,1%,1/16W,EMPTY,CS21002FB06   I161 @T6G_MB_LIB.T6G(SCH_1):PAGE136
 R5016    1      A Q_RES_0402LF-1K,1%,1/16W,EMPTY,CS21002FB06   I162 @T6G_MB_LIB.T6G(SCH_1):PAGE136
  R360    1      A Q_RES_0402LF-1K,1%,1/16W,CHIP,CS21002FB06    I55 @T6G_MB_LIB.T6G(SCH_1):PAGE138
  R420    1      A Q_RES_0402LF-1K,1%,1/16W,EMPTY,CS21002FB06    I22 @T6G_MB_LIB.T6G(SCH_1):PAGE28
  R425    1      A Q_RES_0402LF-1K,1%,1/16W,EMPTY,CS21002FB06    I25 @T6G_MB_LIB.T6G(SCH_1):PAGE28
 PR114    1      A Q_RES_0402LF-49.9,1%,1/16W,CHIP,CS04992FB07    I30 @T6G_MB_LIB.T6G(SCH_1):PAGE182
 PR137    2      B Q_RES_0402LF-0,5%,1/16W,CHIP,CS00002JB13    I56 @T6G_MB_LIB.T6G(SCH_1):PAGE183
 PC223    1      A Q_CAPP_SMLF-470UF,2.5V,20%,SPCAP,CH747LM8825    I58 @T6G_MB_LIB.T6G(SCH_1):PAGE183
 PC226    1      A Q_CAPP_SMLF-470UF,2.5V,20%,SPCAP,CH747LM8825    I59 @T6G_MB_LIB.T6G(SCH_1):PAGE183
PC225_2    1      A Q_CAP_C0805-22UF,4V,20%,X6S,CH622KMEA03    I62 @T6G_MB_LIB.T6G(SCH_1):PAGE183
 PC228    1      A Q_CAPP_SMLF-390UF,2.5V,20%,ALUM,CC7390JMZ13    I65 @T6G_MB_LIB.T6G(SCH_1):PAGE183
  PL23    2      2 Q_INDUCTOR_SMLF-90NH/155A,IND,CVA90^0KZ13    I73 @T6G_MB_LIB.T6G(SCH_1):PAGE183
 PC222    1      A Q_CAP_0402-0.1UF,25V,10%,X7R,CH4104K1B00    I76 @T6G_MB_LIB.T6G(SCH_1):PAGE183
PC227_1    1      A Q_CAP_C0805-22UF,4V,20%,X6S,CH622KMEA03    I82 @T6G_MB_LIB.T6G(SCH_1):PAGE183
 PR414    1      A Q_RES_0402LF-1K,1%,1/16W,CHIP,CS21002FB06    I83 @T6G_MB_LIB.T6G(SCH_1):PAGE183
 PC800    1      A Q_CAPP_SMLF-470UF,2.5V,20%,SPCAP,CH747LM8825    I89 @T6G_MB_LIB.T6G(SCH_1):PAGE183
PC221_2    1      A Q_CAP_C0805-22UF,4V,20%,X6S,CH622KMEA03    I90 @T6G_MB_LIB.T6G(SCH_1):PAGE183
 PR138    2      B Q_RES_0402LF-0,5%,1/16W,CHIP,CS00002JB13    I91 @T6G_MB_LIB.T6G(SCH_1):PAGE183
  R421    1      A Q_RES_0402LF-1K,1%,1/16W,EMPTY,CS21002FB06    I23 @T6G_MB_LIB.T6G(SCH_1):PAGE28
  R423    1      A Q_RES_0402LF-1K,1%,1/16W,EMPTY,CS21002FB06    I24 @T6G_MB_LIB.T6G(SCH_1):PAGE28
 R6081    1      A Q_RES_0402LF-4.7K,5%,1/16W,CHIP,CS24702JB10   I210 @T6G_MB_LIB.T6G(SCH_1):PAGE28
 R6082    1      A Q_RES_0402LF-4.7K,5%,1/16W,CHIP,CS24702JB10   I212 @T6G_MB_LIB.T6G(SCH_1):PAGE28
 R6083    1      A Q_RES_0402LF-4.7K,5%,1/16W,CHIP,CS24702JB10   I213 @T6G_MB_LIB.T6G(SCH_1):PAGE28
 R6084    1      A Q_RES_0402LF-4.7K,5%,1/16W,CHIP,CS24702JB10   I214 @T6G_MB_LIB.T6G(SCH_1):PAGE28
    C3    1      A Q_CAP_0402-0.1UF,25V,10%,X7R,CH4104K1B00    I56 @T6G_MB_LIB.T6G(SCH_1):PAGE137
  R322    1      A Q_RES_0402LF-1K,1%,1/16W,EMPTY,CS21002FB06    I73 @T6G_MB_LIB.T6G(SCH_1):PAGE137
  R290    1      A Q_RES_0402LF-1K,1%,1/16W,EMPTY,CS21002FB06    I78 @T6G_MB_LIB.T6G(SCH_1):PAGE137
    U2    1   VCCA PCA9617ADP-PCA9617ADP,SMLF,IC,AL009617K02    I99 @T6G_MB_LIB.T6G(SCH_1):PAGE137

PVDD11_S3_P0_ADDR_CFG @T6G_MB_LIB.T6G(SCH_1):PVDD11_S3_P0_ADDR_CFG
 PR126    1      A Q_RES_0402LF-3.09K,1%,1/16W,CHIP,CS23092FB04    I22 @T6G_MB_LIB.T6G(SCH_1):PAGE182
  PU21   34 EN1||ADDR_CFG RAA229621GNPHA0-RAA229621GNP#HA0,SMLF,IC,ARF0TGP40A    I24 @T6G_MB_LIB.T6G(SCH_1):PAGE182

PVDD11_S3_P0_EN @T6G_MB_LIB.T6G(SCH_1):PVDD11_S3_P0_EN
  R227    2      B Q_RES_0402LF-33,5%,1/16W,CHIP,CS03302JB10   I103 @T6G_MB_LIB.T6G(SCH_1):PAGE81
  R123    1      A Q_RES_0402LF-0,5%,1/16W,CHIP,CS00002JB13    I43 @T6G_MB_LIB.T6G(SCH_1):PAGE182

PVDD11_S3_P0_EN_R @T6G_MB_LIB.T6G(SCH_1):PVDD11_S3_P0_EN_R
  PU21   13    EN0 RAA229621GNPHA0-RAA229621GNP#HA0,SMLF,IC,ARF0TGP40A    I24 @T6G_MB_LIB.T6G(SCH_1):PAGE182
  R123    2      B Q_RES_0402LF-0,5%,1/16W,CHIP,CS00002JB13    I43 @T6G_MB_LIB.T6G(SCH_1):PAGE182
  C197    1      A Q_CAP_0402-1000PF,50V,5%,X7R,TMP_QCH21006JB10    I45 @T6G_MB_LIB.T6G(SCH_1):PAGE182

PVDD11_S3_P0_IMON1 @T6G_MB_LIB.T6G(SCH_1):PVDD11_S3_P0_IMON1
  PU21   23    CS7 RAA229621GNPHA0-RAA229621GNP#HA0,SMLF,IC,ARF0TGP40A    I24 @T6G_MB_LIB.T6G(SCH_1):PAGE182
  PU22   38   IOUT ISL99390FRZTR5935-ISL99390FRZ-TR5935,SMLF,IC,AL099A    I92 @T6G_MB_LIB.T6G(SCH_1):PAGE183

PVDD11_S3_P0_IMON2 @T6G_MB_LIB.T6G(SCH_1):PVDD11_S3_P0_IMON2
  PU21   24    CS6 RAA229621GNPHA0-RAA229621GNP#HA0,SMLF,IC,ARF0TGP40A    I24 @T6G_MB_LIB.T6G(SCH_1):PAGE182
  PU23   38   IOUT ISL99390FRZTR5935-ISL99390FRZ-TR5935,SMLF,IC,AL099A    I13 @T6G_MB_LIB.T6G(SCH_1):PAGE183

PVDD11_S3_P0_LSET1 @T6G_MB_LIB.T6G(SCH_1):PVDD11_S3_P0_LSET1
 PR133    2      B Q_RES_0402LF-4.87K,1%,1/16W,EMPTY,CS24872FB01    I37 @T6G_MB_LIB.T6G(SCH_1):PAGE183
  PU22   37   LSET ISL99390FRZTR5935-ISL99390FRZ-TR5935,SMLF,IC,AL099A    I92 @T6G_MB_LIB.T6G(SCH_1):PAGE183

PVDD11_S3_P0_LSET2 @T6G_MB_LIB.T6G(SCH_1):PVDD11_S3_P0_LSET2
 PR134    2      B Q_RES_0402LF-4.87K,1%,1/16W,EMPTY,CS24872FB01    I11 @T6G_MB_LIB.T6G(SCH_1):PAGE183
  PU23   37   LSET ISL99390FRZTR5935-ISL99390FRZ-TR5935,SMLF,IC,AL099A    I13 @T6G_MB_LIB.T6G(SCH_1):PAGE183

PVDD11_S3_P0_OCP_N @T6G_MB_LIB.T6G(SCH_1):PVDD11_S3_P0_OCP_N
 R8116    1      A Q_RES_0402LF-0,5%,1/16W,EMPTY,CS00002JB13    I13 @T6G_MB_LIB.T6G(SCH_1):PAGE182
  R226    2      B Q_RES_0402LF-0,5%,1/16W,CHIP,CS00002JB13   I111 @T6G_MB_LIB.T6G(SCH_1):PAGE81

PVDD11_S3_P0_OCP_N_R @T6G_MB_LIB.T6G(SCH_1):PVDD11_S3_P0_OCP_N_R
 R8116    2      B Q_RES_0402LF-0,5%,1/16W,EMPTY,CS00002JB13    I13 @T6G_MB_LIB.T6G(SCH_1):PAGE182
  PU21   33  OCP_L RAA229621GNPHA0-RAA229621GNP#HA0,SMLF,IC,ARF0TGP40A    I24 @T6G_MB_LIB.T6G(SCH_1):PAGE182
  R124    2      B Q_RES_0402LF-1K,1%,1/16W,EMPTY,CS21002FB06    I25 @T6G_MB_LIB.T6G(SCH_1):PAGE182

PVDD11_S3_P0_PMALERT @T6G_MB_LIB.T6G(SCH_1):PVDD11_S3_P0_PMALERT
 R1189    1      A Q_RES_0402LF-1K,1%,1/16W,CHIP,CS21002FB06    I57 @T6G_MB_LIB.T6G(SCH_1):PAGE82
   U18   L7  PL13A LCMXO3LF9400C5BG484C-LCMXO3LF-9400C-5BG484C,SMLF,IA   I143 @T6G_MB_LIB.T6G(SCH_1):PAGE81
  R120    1      A Q_RES_0402LF-33,5%,1/16W,CHIP,CS03302JB10    I39 @T6G_MB_LIB.T6G(SCH_1):PAGE182
 C5009    1      A Q_CAP_0402-1000PF,50V,5%,X7R,TMP_QCH21006JB10    I88 @T6G_MB_LIB.T6G(SCH_1):PAGE182

PVDD11_S3_P0_PMALERT_R @T6G_MB_LIB.T6G(SCH_1):PVDD11_S3_P0_PMALERT_R
  PU21   11 NPMALERT RAA229621GNPHA0-RAA229621GNP#HA0,SMLF,IC,ARF0TGP40A    I24 @T6G_MB_LIB.T6G(SCH_1):PAGE182
  R120    2      B Q_RES_0402LF-33,5%,1/16W,CHIP,CS03302JB10    I39 @T6G_MB_LIB.T6G(SCH_1):PAGE182

PVDD11_S3_P0_PMSCL_R @T6G_MB_LIB.T6G(SCH_1):PVDD11_S3_P0_PMSCL_R
  PU21   10  PMSCL RAA229621GNPHA0-RAA229621GNP#HA0,SMLF,IC,ARF0TGP40A    I24 @T6G_MB_LIB.T6G(SCH_1):PAGE182
  R118    2      B Q_RES_0402LF-0,5%,1/16W,CHIP,CS00002JB13    I41 @T6G_MB_LIB.T6G(SCH_1):PAGE182

PVDD11_S3_P0_PMSDA_R @T6G_MB_LIB.T6G(SCH_1):PVDD11_S3_P0_PMSDA_R
  PU21    9  PMSDA RAA229621GNPHA0-RAA229621GNP#HA0,SMLF,IC,ARF0TGP40A    I24 @T6G_MB_LIB.T6G(SCH_1):PAGE182
  R119    2      B Q_RES_0402LF-0,5%,1/16W,CHIP,CS00002JB13    I40 @T6G_MB_LIB.T6G(SCH_1):PAGE182

PVDD11_S3_P0_PVCC @T6G_MB_LIB.T6G(SCH_1):PVDD11_S3_P0_PVCC
  PU23    4   PVCC ISL99390FRZTR5935-ISL99390FRZ-TR5935,SMLF,IC,AL099A    I13 @T6G_MB_LIB.T6G(SCH_1):PAGE183
 PR132    1      A Q_RES_0402LF-2.2,1%,1/16W,CHIP,CS-2202FB01    I14 @T6G_MB_LIB.T6G(SCH_1):PAGE183
PC206_11P0_2    1      A Q_CAP_C0402-2.2UF,10V,10%,X6S,CH5222KEB01    I17 @T6G_MB_LIB.T6G(SCH_1):PAGE183
 PR131    1      A Q_RES_0402LF-2.2,1%,1/16W,CHIP,CS-2202FB01    I40 @T6G_MB_LIB.T6G(SCH_1):PAGE183
PC205_11P0_1    1      A Q_CAP_C0402-2.2UF,10V,10%,X6S,CH5222KEB01    I42 @T6G_MB_LIB.T6G(SCH_1):PAGE183
 PR411    1      A Q_RES_0402LF-0,5%,1/16W,CHIP,CS00002JB13    I85 @T6G_MB_LIB.T6G(SCH_1):PAGE183
 PR413    1      A Q_RES_0402LF-0,5%,1/16W,EMPTY,CS00002JB13    I86 @T6G_MB_LIB.T6G(SCH_1):PAGE183
  PU22    4   PVCC ISL99390FRZTR5935-ISL99390FRZ-TR5935,SMLF,IC,AL099A    I92 @T6G_MB_LIB.T6G(SCH_1):PAGE183

PVDD11_S3_P0_PWM1 @T6G_MB_LIB.T6G(SCH_1):PVDD11_S3_P0_PWM1
  PU21    8   PWM7 RAA229621GNPHA0-RAA229621GNP#HA0,SMLF,IC,ARF0TGP40A    I24 @T6G_MB_LIB.T6G(SCH_1):PAGE182
  PU22   34    PWM ISL99390FRZTR5935-ISL99390FRZ-TR5935,SMLF,IC,AL099A    I92 @T6G_MB_LIB.T6G(SCH_1):PAGE183

PVDD11_S3_P0_PWM2 @T6G_MB_LIB.T6G(SCH_1):PVDD11_S3_P0_PWM2
  PU21    7   PWM6 RAA229621GNPHA0-RAA229621GNP#HA0,SMLF,IC,ARF0TGP40A    I24 @T6G_MB_LIB.T6G(SCH_1):PAGE182
  PU23   34    PWM ISL99390FRZTR5935-ISL99390FRZ-TR5935,SMLF,IC,AL099A    I13 @T6G_MB_LIB.T6G(SCH_1):PAGE183

PVDD11_S3_P0_RESET_N @T6G_MB_LIB.T6G(SCH_1):PVDD11_S3_P0_RESET_N
 PR129    2      B Q_RES_0402LF-0,5%,1/16W,EMPTY,CS00002JB13    I67 @T6G_MB_LIB.T6G(SCH_1):PAGE182
   U18  H17  PR10C LCMXO3LF9400C5BG484C-LCMXO3LF-9400C-5BG484C,SMLF,IA   I217 @T6G_MB_LIB.T6G(SCH_1):PAGE80

PVDD11_S3_P0_RESET_N_R @T6G_MB_LIB.T6G(SCH_1):PVDD11_S3_P0_RESET_N_R
 PR129    1      A Q_RES_0402LF-0,5%,1/16W,EMPTY,CS00002JB13    I67 @T6G_MB_LIB.T6G(SCH_1):PAGE182
 PR128    1      A Q_RES_0402LF-1K,1%,1/16W,EMPTY,CS21002FB06    I68 @T6G_MB_LIB.T6G(SCH_1):PAGE182
  PU21   14 RESET_L RAA229621GNPHA0-RAA229621GNP#HA0,SMLF,IC,ARF0TGP40A    I24 @T6G_MB_LIB.T6G(SCH_1):PAGE182
 PR127    1      A Q_RES_0402LF-0,5%,1/16W,EMPTY,CS00002JB13    I57 @T6G_MB_LIB.T6G(SCH_1):PAGE182

PVDD11_S3_P0_TEMP0 @T6G_MB_LIB.T6G(SCH_1):PVDD11_S3_P0_TEMP0
  PU21   36  TEMP0 RAA229621GNPHA0-RAA229621GNP#HA0,SMLF,IC,ARF0TGP40A    I24 @T6G_MB_LIB.T6G(SCH_1):PAGE182
 PC198    1      A Q_CAP_0402-470PF,50V,10%,X7R,TMP_QCH14706KB18    I50 @T6G_MB_LIB.T6G(SCH_1):PAGE182
  PU23   36 TOUT_FLT ISL99390FRZTR5935-ISL99390FRZ-TR5935,SMLF,IC,AL099A    I13 @T6G_MB_LIB.T6G(SCH_1):PAGE183
  PU22   36 TOUT_FLT ISL99390FRZTR5935-ISL99390FRZ-TR5935,SMLF,IC,AL099A    I92 @T6G_MB_LIB.T6G(SCH_1):PAGE183

PVDD11_S3_P0_TEMP1 @T6G_MB_LIB.T6G(SCH_1):PVDD11_S3_P0_TEMP1
  PU21   35  TEMP1 RAA229621GNPHA0-RAA229621GNP#HA0,SMLF,IC,ARF0TGP40A    I24 @T6G_MB_LIB.T6G(SCH_1):PAGE182
 PR412    1      A Q_RES_0402LF-0,5%,1/16W,CHIP,CS00002JB13    I52 @T6G_MB_LIB.T6G(SCH_1):PAGE182

PVDD11_S3_P0_VCC @T6G_MB_LIB.T6G(SCH_1):PVDD11_S3_P0_VCC
 PC200    1      A Q_CAP_C0402-1UF,16V,10%,X6S,CH5103KEB01    I82 @T6G_MB_LIB.T6G(SCH_1):PAGE182
  PU21   39    VCC RAA229621GNPHA0-RAA229621GNP#HA0,SMLF,IC,ARF0TGP40A    I24 @T6G_MB_LIB.T6G(SCH_1):PAGE182
   PC4    1      A Q_CAP_0402-0.1UF,25V,10%,X7R,CH4104K1B00    I79 @T6G_MB_LIB.T6G(SCH_1):PAGE182
 PR130    1      A Q_RES_0402LF-1,1%,1/16W,CHIP,CS-1002FB04    I85 @T6G_MB_LIB.T6G(SCH_1):PAGE182

PVDD11_S3_P0_VCC1 @T6G_MB_LIB.T6G(SCH_1):PVDD11_S3_P0_VCC1
 PC203    1      A Q_CAP_C0402-2.2UF,10V,10%,X6S,CH5222KEB01    I36 @T6G_MB_LIB.T6G(SCH_1):PAGE183
 PR131    2      B Q_RES_0402LF-2.2,1%,1/16W,CHIP,CS-2202FB01    I40 @T6G_MB_LIB.T6G(SCH_1):PAGE183
  PU22   35     EN ISL99390FRZTR5935-ISL99390FRZ-TR5935,SMLF,IC,AL099A    I92 @T6G_MB_LIB.T6G(SCH_1):PAGE183
  PU22    3    VCC ISL99390FRZTR5935-ISL99390FRZ-TR5935,SMLF,IC,AL099A    I92 @T6G_MB_LIB.T6G(SCH_1):PAGE183

PVDD11_S3_P0_VCC2 @T6G_MB_LIB.T6G(SCH_1):PVDD11_S3_P0_VCC2
 PC204    1      A Q_CAP_C0402-2.2UF,10V,10%,X6S,CH5222KEB01     I9 @T6G_MB_LIB.T6G(SCH_1):PAGE183
  PU23   35     EN ISL99390FRZTR5935-ISL99390FRZ-TR5935,SMLF,IC,AL099A    I13 @T6G_MB_LIB.T6G(SCH_1):PAGE183
  PU23    3    VCC ISL99390FRZTR5935-ISL99390FRZ-TR5935,SMLF,IC,AL099A    I13 @T6G_MB_LIB.T6G(SCH_1):PAGE183
 PR132    2      B Q_RES_0402LF-2.2,1%,1/16W,CHIP,CS-2202FB01    I14 @T6G_MB_LIB.T6G(SCH_1):PAGE183

PVDD11_S3_P0_VCCS @T6G_MB_LIB.T6G(SCH_1):PVDD11_S3_P0_VCCS
   PC9    1      A Q_CAP_0402-0.1UF,25V,10%,X7R,CH4104K1B00    I77 @T6G_MB_LIB.T6G(SCH_1):PAGE182
PC201_1    1      A Q_CAP_0402-0.1UF,25V,10%,X7R,CH4104K1B00    I34 @T6G_MB_LIB.T6G(SCH_1):PAGE183
  PU21   40   VCCS RAA229621GNPHA0-RAA229621GNP#HA0,SMLF,IC,ARF0TGP40A    I24 @T6G_MB_LIB.T6G(SCH_1):PAGE182
 PC199    1      A Q_CAP_C0402-10UF,6.3V,20%,X6S,CH6101MEB03    I80 @T6G_MB_LIB.T6G(SCH_1):PAGE182
PC202_2    1      A Q_CAP_0402-0.1UF,25V,10%,X7R,CH4104K1B00     I7 @T6G_MB_LIB.T6G(SCH_1):PAGE183
  PU23   39  REFIN ISL99390FRZTR5935-ISL99390FRZ-TR5935,SMLF,IC,AL099A    I13 @T6G_MB_LIB.T6G(SCH_1):PAGE183
  PU22   39  REFIN ISL99390FRZTR5935-ISL99390FRZ-TR5935,SMLF,IC,AL099A    I92 @T6G_MB_LIB.T6G(SCH_1):PAGE183

PVDD11_S3_P0_VDDIO @T6G_MB_LIB.T6G(SCH_1):PVDD11_S3_P0_VDDIO
 R8458    2      B Q_RES_0402LF-0,5%,1/16W,EMPTY,CS00002JB13     I9 @T6G_MB_LIB.T6G(SCH_1):PAGE182
  PU21   15  VDDIO RAA229621GNPHA0-RAA229621GNP#HA0,SMLF,IC,ARF0TGP40A    I24 @T6G_MB_LIB.T6G(SCH_1):PAGE182

PVDD11_S3_P0_VINSEN @T6G_MB_LIB.T6G(SCH_1):PVDD11_S3_P0_VINSEN
 PR125    2      B Q_RES_0402LF-0,5%,1/16W,CHIP,CS00002JB13    I16 @T6G_MB_LIB.T6G(SCH_1):PAGE182
 PR601    1      A Q_RES_0402LF-4.99K,1%,1/16W,EMPTY,CS24992FB07    I18 @T6G_MB_LIB.T6G(SCH_1):PAGE182
   PC5    1      A Q_CAP_0402-0.1UF,25V,10%,X7R,CH4104K1B00    I20 @T6G_MB_LIB.T6G(SCH_1):PAGE182
  PU21   38 VINSEN RAA229621GNPHA0-RAA229621GNP#HA0,SMLF,IC,ARF0TGP40A    I24 @T6G_MB_LIB.T6G(SCH_1):PAGE182

PVDD11_S3_P0_VMON @T6G_MB_LIB.T6G(SCH_1):PVDD11_S3_P0_VMON
 PR113    2      B Q_RES_0402LF-40.2K,1%,1/16W,CHIP,CS34022FB04     I2 @T6G_MB_LIB.T6G(SCH_1):PAGE182
 PC193    1      A Q_CAP_0402-0.1UF,25V,10%,X7R,CH4104K1B00     I4 @T6G_MB_LIB.T6G(SCH_1):PAGE182
   PR3    1      A Q_RES_0402LF-10K,1%,1/16W,CHIP,CS31002FB08     I6 @T6G_MB_LIB.T6G(SCH_1):PAGE182
  PU21   37 VMON||IINSEN RAA229621GNPHA0-RAA229621GNP#HA0,SMLF,IC,ARF0TGP40A    I24 @T6G_MB_LIB.T6G(SCH_1):PAGE182

PVDD11_S3_P0_VOS1 @T6G_MB_LIB.T6G(SCH_1):PVDD11_S3_P0_VOS1
 PR137    1      A Q_RES_0402LF-0,5%,1/16W,CHIP,CS00002JB13    I56 @T6G_MB_LIB.T6G(SCH_1):PAGE183
  PU22    1    VOS ISL99390FRZTR5935-ISL99390FRZ-TR5935,SMLF,IC,AL099A    I92 @T6G_MB_LIB.T6G(SCH_1):PAGE183

PVDD11_S3_P0_VOS2 @T6G_MB_LIB.T6G(SCH_1):PVDD11_S3_P0_VOS2
  PU23    1    VOS ISL99390FRZTR5935-ISL99390FRZ-TR5935,SMLF,IC,AL099A    I13 @T6G_MB_LIB.T6G(SCH_1):PAGE183
 PR138    1      A Q_RES_0402LF-0,5%,1/16W,CHIP,CS00002JB13    I91 @T6G_MB_LIB.T6G(SCH_1):PAGE183

PVDD11_S3_P1 @T6G_MB_LIB.T6G(SCH_1):PVDD11_S3_P1
   U26 BJ18 VDD_11_S3_BJ18 GENOA_SP5-SOCKET6096_13568-001,SMLF,IO,DGA^6000030    I45 @T6G_MB_LIB.T6G(SCH_1):PAGE57
   U26 BJ23 VDD_11_S3_BJ23 GENOA_SP5-SOCKET6096_13568-001,SMLF,IO,DGA^6000030    I45 @T6G_MB_LIB.T6G(SCH_1):PAGE57
   U26 BJ25 VDD_11_S3_BJ25 GENOA_SP5-SOCKET6096_13568-001,SMLF,IO,DGA^6000030    I45 @T6G_MB_LIB.T6G(SCH_1):PAGE57
   U26 BJ27 VDD_11_S3_BJ27 GENOA_SP5-SOCKET6096_13568-001,SMLF,IO,DGA^6000030    I45 @T6G_MB_LIB.T6G(SCH_1):PAGE57
   U26 BK22 VDD_11_S3_BK22 GENOA_SP5-SOCKET6096_13568-001,SMLF,IO,DGA^6000030    I45 @T6G_MB_LIB.T6G(SCH_1):PAGE57
   U26 BK24 VDD_11_S3_BK24 GENOA_SP5-SOCKET6096_13568-001,SMLF,IO,DGA^6000030    I45 @T6G_MB_LIB.T6G(SCH_1):PAGE57
   U26 BK26 VDD_11_S3_BK26 GENOA_SP5-SOCKET6096_13568-001,SMLF,IO,DGA^6000030    I45 @T6G_MB_LIB.T6G(SCH_1):PAGE57
   U26 BK28 VDD_11_S3_BK28 GENOA_SP5-SOCKET6096_13568-001,SMLF,IO,DGA^6000030    I45 @T6G_MB_LIB.T6G(SCH_1):PAGE57
   U26 BK49 VDD_11_S3_BK49 GENOA_SP5-SOCKET6096_13568-001,SMLF,IO,DGA^6000030    I45 @T6G_MB_LIB.T6G(SCH_1):PAGE57
   U26 BL23 VDD_11_S3_BL23 GENOA_SP5-SOCKET6096_13568-001,SMLF,IO,DGA^6000030    I45 @T6G_MB_LIB.T6G(SCH_1):PAGE57
   U26 BL25 VDD_11_S3_BL25 GENOA_SP5-SOCKET6096_13568-001,SMLF,IO,DGA^6000030    I45 @T6G_MB_LIB.T6G(SCH_1):PAGE57
   U26 BL27 VDD_11_S3_BL27 GENOA_SP5-SOCKET6096_13568-001,SMLF,IO,DGA^6000030    I45 @T6G_MB_LIB.T6G(SCH_1):PAGE57
   U26 BL48 VDD_11_S3_BL48 GENOA_SP5-SOCKET6096_13568-001,SMLF,IO,DGA^6000030    I45 @T6G_MB_LIB.T6G(SCH_1):PAGE57
   U26 BM12 VDD_11_S3_BM12 GENOA_SP5-SOCKET6096_13568-001,SMLF,IO,DGA^6000030    I45 @T6G_MB_LIB.T6G(SCH_1):PAGE57
   U26 BM19 VDD_11_S3_BM19 GENOA_SP5-SOCKET6096_13568-001,SMLF,IO,DGA^6000030    I45 @T6G_MB_LIB.T6G(SCH_1):PAGE57
   U26 BM22 VDD_11_S3_BM22 GENOA_SP5-SOCKET6096_13568-001,SMLF,IO,DGA^6000030    I45 @T6G_MB_LIB.T6G(SCH_1):PAGE57
   U26 BM24 VDD_11_S3_BM24 GENOA_SP5-SOCKET6096_13568-001,SMLF,IO,DGA^6000030    I45 @T6G_MB_LIB.T6G(SCH_1):PAGE57
   U26 BM26 VDD_11_S3_BM26 GENOA_SP5-SOCKET6096_13568-001,SMLF,IO,DGA^6000030    I45 @T6G_MB_LIB.T6G(SCH_1):PAGE57
   U26 BM28 VDD_11_S3_BM28 GENOA_SP5-SOCKET6096_13568-001,SMLF,IO,DGA^6000030    I45 @T6G_MB_LIB.T6G(SCH_1):PAGE57
   U26 BM30 VDD_11_S3_BM30 GENOA_SP5-SOCKET6096_13568-001,SMLF,IO,DGA^6000030    I45 @T6G_MB_LIB.T6G(SCH_1):PAGE57
   U26 BM32 VDD_11_S3_BM32 GENOA_SP5-SOCKET6096_13568-001,SMLF,IO,DGA^6000030    I45 @T6G_MB_LIB.T6G(SCH_1):PAGE57
   U26 BM34 VDD_11_S3_BM34 GENOA_SP5-SOCKET6096_13568-001,SMLF,IO,DGA^6000030    I45 @T6G_MB_LIB.T6G(SCH_1):PAGE57
   U26 BM36 VDD_11_S3_BM36 GENOA_SP5-SOCKET6096_13568-001,SMLF,IO,DGA^6000030    I45 @T6G_MB_LIB.T6G(SCH_1):PAGE57
   U26 BM39 VDD_11_S3_BM39 GENOA_SP5-SOCKET6096_13568-001,SMLF,IO,DGA^6000030    I45 @T6G_MB_LIB.T6G(SCH_1):PAGE57
   U26 BM41 VDD_11_S3_BM41 GENOA_SP5-SOCKET6096_13568-001,SMLF,IO,DGA^6000030    I45 @T6G_MB_LIB.T6G(SCH_1):PAGE57
   U26 BM43 VDD_11_S3_BM43 GENOA_SP5-SOCKET6096_13568-001,SMLF,IO,DGA^6000030    I45 @T6G_MB_LIB.T6G(SCH_1):PAGE57
   U26 BM45 VDD_11_S3_BM45 GENOA_SP5-SOCKET6096_13568-001,SMLF,IO,DGA^6000030    I45 @T6G_MB_LIB.T6G(SCH_1):PAGE57
   U26 BM47 VDD_11_S3_BM47 GENOA_SP5-SOCKET6096_13568-001,SMLF,IO,DGA^6000030    I45 @T6G_MB_LIB.T6G(SCH_1):PAGE57
   U26 BM49 VDD_11_S3_BM49 GENOA_SP5-SOCKET6096_13568-001,SMLF,IO,DGA^6000030    I45 @T6G_MB_LIB.T6G(SCH_1):PAGE57
   U26 BN25 VDD_11_S3_BN25 GENOA_SP5-SOCKET6096_13568-001,SMLF,IO,DGA^6000030    I45 @T6G_MB_LIB.T6G(SCH_1):PAGE57
   U26 BN29 VDD_11_S3_BN29 GENOA_SP5-SOCKET6096_13568-001,SMLF,IO,DGA^6000030    I45 @T6G_MB_LIB.T6G(SCH_1):PAGE57
   U26 BN33 VDD_11_S3_BN33 GENOA_SP5-SOCKET6096_13568-001,SMLF,IO,DGA^6000030    I45 @T6G_MB_LIB.T6G(SCH_1):PAGE57
   U26 BN40 VDD_11_S3_BN40 GENOA_SP5-SOCKET6096_13568-001,SMLF,IO,DGA^6000030    I45 @T6G_MB_LIB.T6G(SCH_1):PAGE57
   U26 BN44 VDD_11_S3_BN44 GENOA_SP5-SOCKET6096_13568-001,SMLF,IO,DGA^6000030    I45 @T6G_MB_LIB.T6G(SCH_1):PAGE57
   U26 BN48 VDD_11_S3_BN48 GENOA_SP5-SOCKET6096_13568-001,SMLF,IO,DGA^6000030    I45 @T6G_MB_LIB.T6G(SCH_1):PAGE57
   U26 BP22 VDD_11_S3_BP22 GENOA_SP5-SOCKET6096_13568-001,SMLF,IO,DGA^6000030    I45 @T6G_MB_LIB.T6G(SCH_1):PAGE57
   U26  BR4 VDD_11_S3_BR4 GENOA_SP5-SOCKET6096_13568-001,SMLF,IO,DGA^6000030    I45 @T6G_MB_LIB.T6G(SCH_1):PAGE57
   U26 BR11 VDD_11_S3_BR11 GENOA_SP5-SOCKET6096_13568-001,SMLF,IO,DGA^6000030    I45 @T6G_MB_LIB.T6G(SCH_1):PAGE57
   U26 BR18 VDD_11_S3_BR18 GENOA_SP5-SOCKET6096_13568-001,SMLF,IO,DGA^6000030    I45 @T6G_MB_LIB.T6G(SCH_1):PAGE57
   U26  BV5 VDD_11_S3_BV5 GENOA_SP5-SOCKET6096_13568-001,SMLF,IO,DGA^6000030    I45 @T6G_MB_LIB.T6G(SCH_1):PAGE57
   U26 BV12 VDD_11_S3_BV12 GENOA_SP5-SOCKET6096_13568-001,SMLF,IO,DGA^6000030    I45 @T6G_MB_LIB.T6G(SCH_1):PAGE57
   U26 BV19 VDD_11_S3_BV19 GENOA_SP5-SOCKET6096_13568-001,SMLF,IO,DGA^6000030    I45 @T6G_MB_LIB.T6G(SCH_1):PAGE57
   U26 BV22 VDD_11_S3_BV22 GENOA_SP5-SOCKET6096_13568-001,SMLF,IO,DGA^6000030    I45 @T6G_MB_LIB.T6G(SCH_1):PAGE57
   U26  CA4 VDD_11_S3_CA4 GENOA_SP5-SOCKET6096_13568-001,SMLF,IO,DGA^6000030    I45 @T6G_MB_LIB.T6G(SCH_1):PAGE57
   U26 CA11 VDD_11_S3_CA11 GENOA_SP5-SOCKET6096_13568-001,SMLF,IO,DGA^6000030    I45 @T6G_MB_LIB.T6G(SCH_1):PAGE57
   U26 CA18 VDD_11_S3_CA18 GENOA_SP5-SOCKET6096_13568-001,SMLF,IO,DGA^6000030    I45 @T6G_MB_LIB.T6G(SCH_1):PAGE57
   U26 CB22 VDD_11_S3_CB22 GENOA_SP5-SOCKET6096_13568-001,SMLF,IO,DGA^6000030    I45 @T6G_MB_LIB.T6G(SCH_1):PAGE57
   U26  CD5 VDD_11_S3_CD5 GENOA_SP5-SOCKET6096_13568-001,SMLF,IO,DGA^6000030    I45 @T6G_MB_LIB.T6G(SCH_1):PAGE57
   U26 CD12 VDD_11_S3_CD12 GENOA_SP5-SOCKET6096_13568-001,SMLF,IO,DGA^6000030    I45 @T6G_MB_LIB.T6G(SCH_1):PAGE57
   U26 CD19 VDD_11_S3_CD19 GENOA_SP5-SOCKET6096_13568-001,SMLF,IO,DGA^6000030    I45 @T6G_MB_LIB.T6G(SCH_1):PAGE57
   U26 CF22 VDD_11_S3_CF22 GENOA_SP5-SOCKET6096_13568-001,SMLF,IO,DGA^6000030    I45 @T6G_MB_LIB.T6G(SCH_1):PAGE57
   U26  CG4 VDD_11_S3_CG4 GENOA_SP5-SOCKET6096_13568-001,SMLF,IO,DGA^6000030    I45 @T6G_MB_LIB.T6G(SCH_1):PAGE57
   U26 CG11 VDD_11_S3_CG11 GENOA_SP5-SOCKET6096_13568-001,SMLF,IO,DGA^6000030    I45 @T6G_MB_LIB.T6G(SCH_1):PAGE57
   U26 CG18 VDD_11_S3_CG18 GENOA_SP5-SOCKET6096_13568-001,SMLF,IO,DGA^6000030    I45 @T6G_MB_LIB.T6G(SCH_1):PAGE57
   U26 CJ22 VDD_11_S3_CJ22 GENOA_SP5-SOCKET6096_13568-001,SMLF,IO,DGA^6000030    I45 @T6G_MB_LIB.T6G(SCH_1):PAGE57
   U26  CK5 VDD_11_S3_CK5 GENOA_SP5-SOCKET6096_13568-001,SMLF,IO,DGA^6000030    I45 @T6G_MB_LIB.T6G(SCH_1):PAGE57
   U26 CK12 VDD_11_S3_CK12 GENOA_SP5-SOCKET6096_13568-001,SMLF,IO,DGA^6000030    I45 @T6G_MB_LIB.T6G(SCH_1):PAGE57
   U26 CK19 VDD_11_S3_CK19 GENOA_SP5-SOCKET6096_13568-001,SMLF,IO,DGA^6000030    I45 @T6G_MB_LIB.T6G(SCH_1):PAGE57
   U26 CM22 VDD_11_S3_CM22 GENOA_SP5-SOCKET6096_13568-001,SMLF,IO,DGA^6000030    I45 @T6G_MB_LIB.T6G(SCH_1):PAGE57
   U26  CN4 VDD_11_S3_CN4 GENOA_SP5-SOCKET6096_13568-001,SMLF,IO,DGA^6000030    I45 @T6G_MB_LIB.T6G(SCH_1):PAGE57
   U26 CN11 VDD_11_S3_CN11 GENOA_SP5-SOCKET6096_13568-001,SMLF,IO,DGA^6000030    I45 @T6G_MB_LIB.T6G(SCH_1):PAGE57
   U26 CN18 VDD_11_S3_CN18 GENOA_SP5-SOCKET6096_13568-001,SMLF,IO,DGA^6000030    I45 @T6G_MB_LIB.T6G(SCH_1):PAGE57
   U26  CT5 VDD_11_S3_CT5 GENOA_SP5-SOCKET6096_13568-001,SMLF,IO,DGA^6000030    I45 @T6G_MB_LIB.T6G(SCH_1):PAGE57
   U26 CT12 VDD_11_S3_CT12 GENOA_SP5-SOCKET6096_13568-001,SMLF,IO,DGA^6000030    I45 @T6G_MB_LIB.T6G(SCH_1):PAGE57
   U26 CT19 VDD_11_S3_CT19 GENOA_SP5-SOCKET6096_13568-001,SMLF,IO,DGA^6000030    I45 @T6G_MB_LIB.T6G(SCH_1):PAGE57
   U26 CT22 VDD_11_S3_CT22 GENOA_SP5-SOCKET6096_13568-001,SMLF,IO,DGA^6000030    I45 @T6G_MB_LIB.T6G(SCH_1):PAGE57
   U26  CW4 VDD_11_S3_CW4 GENOA_SP5-SOCKET6096_13568-001,SMLF,IO,DGA^6000030    I45 @T6G_MB_LIB.T6G(SCH_1):PAGE57
   U26 CW11 VDD_11_S3_CW11 GENOA_SP5-SOCKET6096_13568-001,SMLF,IO,DGA^6000030    I45 @T6G_MB_LIB.T6G(SCH_1):PAGE57
   U26 CW18 VDD_11_S3_CW18 GENOA_SP5-SOCKET6096_13568-001,SMLF,IO,DGA^6000030    I45 @T6G_MB_LIB.T6G(SCH_1):PAGE57
   U26 CY22 VDD_11_S3_CY22 GENOA_SP5-SOCKET6096_13568-001,SMLF,IO,DGA^6000030    I45 @T6G_MB_LIB.T6G(SCH_1):PAGE57
   U26  DB5 VDD_11_S3_DB5 GENOA_SP5-SOCKET6096_13568-001,SMLF,IO,DGA^6000030    I45 @T6G_MB_LIB.T6G(SCH_1):PAGE57
   U26 DB12 VDD_11_S3_DB12 GENOA_SP5-SOCKET6096_13568-001,SMLF,IO,DGA^6000030    I45 @T6G_MB_LIB.T6G(SCH_1):PAGE57
   U26 DB19 VDD_11_S3_DB19 GENOA_SP5-SOCKET6096_13568-001,SMLF,IO,DGA^6000030    I45 @T6G_MB_LIB.T6G(SCH_1):PAGE57
   U26  DE4 VDD_11_S3_DE4 GENOA_SP5-SOCKET6096_13568-001,SMLF,IO,DGA^6000030    I45 @T6G_MB_LIB.T6G(SCH_1):PAGE57
   U26 DE11 VDD_11_S3_DE11 GENOA_SP5-SOCKET6096_13568-001,SMLF,IO,DGA^6000030    I45 @T6G_MB_LIB.T6G(SCH_1):PAGE57
   U26 DE18 VDD_11_S3_DE18 GENOA_SP5-SOCKET6096_13568-001,SMLF,IO,DGA^6000030    I45 @T6G_MB_LIB.T6G(SCH_1):PAGE57
   U26  DG5 VDD_11_S3_DG5 GENOA_SP5-SOCKET6096_13568-001,SMLF,IO,DGA^6000030    I45 @T6G_MB_LIB.T6G(SCH_1):PAGE57
 C2262    1      A Q_CAP_C0402-22UF,4V,20%,X6S,CH622KMEB02     I1 @T6G_MB_LIB.T6G(SCH_1):PAGE71
 C2261    1      A Q_CAP_C0402-22UF,4V,20%,X6S,CH622KMEB02     I3 @T6G_MB_LIB.T6G(SCH_1):PAGE71
 C2267    1      A Q_CAP_C0402-22UF,4V,20%,X6S,CH622KMEB02    I11 @T6G_MB_LIB.T6G(SCH_1):PAGE71
 C3902    1      A Q_CAP_C0402-22UF,4V,20%,X6S,CH622KMEB02    I12 @T6G_MB_LIB.T6G(SCH_1):PAGE71
 C2266    1      A Q_CAP_C0402-22UF,4V,20%,X6S,CH622KMEB02    I13 @T6G_MB_LIB.T6G(SCH_1):PAGE71
 C2271    1      A Q_CAP_C0402-22UF,4V,20%,X6S,CH622KMEB02    I14 @T6G_MB_LIB.T6G(SCH_1):PAGE71
 C3903    1      A Q_CAP_C0402-22UF,4V,20%,X6S,CH622KMEB02    I15 @T6G_MB_LIB.T6G(SCH_1):PAGE71
 C3904    1      A Q_CAP_C0402-22UF,4V,20%,X6S,CH622KMEB02    I16 @T6G_MB_LIB.T6G(SCH_1):PAGE71
 C3905    1      A Q_CAP_C0402-22UF,4V,20%,X6S,CH622KMEB02    I18 @T6G_MB_LIB.T6G(SCH_1):PAGE71
 C2275    1      A Q_CAP_C0402-22UF,4V,20%,X6S,CH622KMEB02    I19 @T6G_MB_LIB.T6G(SCH_1):PAGE71
 C2279    1      A Q_CAP_C0402-22UF,4V,20%,X6S,CH622KMEB02    I20 @T6G_MB_LIB.T6G(SCH_1):PAGE71
 C2282    1      A Q_CAP_C0402-22UF,4V,20%,X6S,CH622KMEB02    I21 @T6G_MB_LIB.T6G(SCH_1):PAGE71
 C2285    1      A Q_CAP_C0402-22UF,4V,20%,X6S,CH622KMEB02    I24 @T6G_MB_LIB.T6G(SCH_1):PAGE71
 C2287    1      A Q_CAP_C0402-22UF,4V,20%,X6S,CH622KMEB02    I25 @T6G_MB_LIB.T6G(SCH_1):PAGE71
 C2289    1      A Q_CAP_C0402-22UF,4V,20%,X6S,CH622KMEB02    I26 @T6G_MB_LIB.T6G(SCH_1):PAGE71
 C2291    1      A Q_CAP_C0402-22UF,4V,20%,X6S,CH622KMEB02    I28 @T6G_MB_LIB.T6G(SCH_1):PAGE71
 C3919    1      A Q_CAP_C0402-22UF,4V,20%,X6S,CH622KMEB02    I77 @T6G_MB_LIB.T6G(SCH_1):PAGE73
 C2483    1      A Q_CAP_C0402-22UF,4V,20%,X6S,CH622KMEB02    I81 @T6G_MB_LIB.T6G(SCH_1):PAGE73
 C3920    1      A Q_CAP_C0402-22UF,4V,20%,X6S,CH622KMEB02    I84 @T6G_MB_LIB.T6G(SCH_1):PAGE73
 C2488    1      A Q_CAP_C0402-22UF,4V,20%,X6S,CH622KMEB02    I85 @T6G_MB_LIB.T6G(SCH_1):PAGE73
 C2492    1      A Q_CAP_C0402-22UF,4V,20%,X6S,CH622KMEB02    I86 @T6G_MB_LIB.T6G(SCH_1):PAGE73
 C2482    1      A Q_CAP_C0402-22UF,4V,20%,X6S,CH622KMEB02    I90 @T6G_MB_LIB.T6G(SCH_1):PAGE73
 C2481    1      A Q_CAP_C0402-22UF,4V,20%,X6S,CH622KMEB02    I92 @T6G_MB_LIB.T6G(SCH_1):PAGE73
 C2480    1      A Q_CAP_C0402-22UF,4V,20%,X6S,CH622KMEB02    I97 @T6G_MB_LIB.T6G(SCH_1):PAGE73
 C2487    1      A Q_CAP_C0402-22UF,4V,20%,X6S,CH622KMEB02    I99 @T6G_MB_LIB.T6G(SCH_1):PAGE73
 C2486    1      A Q_CAP_C0402-22UF,4V,20%,X6S,CH622KMEB02   I100 @T6G_MB_LIB.T6G(SCH_1):PAGE73
 C2491    1      A Q_CAP_C0402-22UF,4V,20%,X6S,CH622KMEB02   I101 @T6G_MB_LIB.T6G(SCH_1):PAGE73
 C2490    1      A Q_CAP_C0402-22UF,4V,20%,X6S,CH622KMEB02   I102 @T6G_MB_LIB.T6G(SCH_1):PAGE73
 C2485    1      A Q_CAP_C0402-22UF,4V,20%,X6S,CH622KMEB02   I103 @T6G_MB_LIB.T6G(SCH_1):PAGE73
 C2489    1      A Q_CAP_C0402-22UF,4V,20%,X6S,CH622KMEB02   I104 @T6G_MB_LIB.T6G(SCH_1):PAGE73
 C2497    1      A Q_CAP_C0402-22UF,4V,20%,X6S,CH622KMEB02   I105 @T6G_MB_LIB.T6G(SCH_1):PAGE73
 C2502    1      A Q_CAP_C0402-22UF,4V,20%,X6S,CH622KMEB02   I106 @T6G_MB_LIB.T6G(SCH_1):PAGE73
 C2506    1      A Q_CAP_C0402-22UF,4V,20%,X6S,CH622KMEB02   I107 @T6G_MB_LIB.T6G(SCH_1):PAGE73
 C2115    1      A Q_CAP_C0402-22UF,4V,20%,X6S,CH622KMEB02   I108 @T6G_MB_LIB.T6G(SCH_1):PAGE73
 C2121    1      A Q_CAP_C0402-22UF,4V,20%,X6S,CH622KMEB02   I109 @T6G_MB_LIB.T6G(SCH_1):PAGE73
 C2496    1      A Q_CAP_C0402-22UF,4V,20%,X6S,CH622KMEB02   I110 @T6G_MB_LIB.T6G(SCH_1):PAGE73
 C2495    1      A Q_CAP_C0402-22UF,4V,20%,X6S,CH622KMEB02   I111 @T6G_MB_LIB.T6G(SCH_1):PAGE73
 C2501    1      A Q_CAP_C0402-22UF,4V,20%,X6S,CH622KMEB02   I112 @T6G_MB_LIB.T6G(SCH_1):PAGE73
 C2500    1      A Q_CAP_C0402-22UF,4V,20%,X6S,CH622KMEB02   I113 @T6G_MB_LIB.T6G(SCH_1):PAGE73
 C2494    1      A Q_CAP_C0402-22UF,4V,20%,X6S,CH622KMEB02   I114 @T6G_MB_LIB.T6G(SCH_1):PAGE73
 C2499    1      A Q_CAP_C0402-22UF,4V,20%,X6S,CH622KMEB02   I116 @T6G_MB_LIB.T6G(SCH_1):PAGE73
 C2505    1      A Q_CAP_C0402-22UF,4V,20%,X6S,CH622KMEB02   I117 @T6G_MB_LIB.T6G(SCH_1):PAGE73
 C2504    1      A Q_CAP_C0402-22UF,4V,20%,X6S,CH622KMEB02   I118 @T6G_MB_LIB.T6G(SCH_1):PAGE73
 C2113    1      A Q_CAP_C0402-22UF,4V,20%,X6S,CH622KMEB02   I119 @T6G_MB_LIB.T6G(SCH_1):PAGE73
 C2114    1      A Q_CAP_C0402-22UF,4V,20%,X6S,CH622KMEB02   I120 @T6G_MB_LIB.T6G(SCH_1):PAGE73
 C2120    1      A Q_CAP_C0402-22UF,4V,20%,X6S,CH622KMEB02   I121 @T6G_MB_LIB.T6G(SCH_1):PAGE73
 C2119    1      A Q_CAP_C0402-22UF,4V,20%,X6S,CH622KMEB02   I122 @T6G_MB_LIB.T6G(SCH_1):PAGE73
 C2503    1      A Q_CAP_C0402-22UF,4V,20%,X6S,CH622KMEB02   I123 @T6G_MB_LIB.T6G(SCH_1):PAGE73
 C2508    1      A Q_CAP_C0402-22UF,4V,20%,X6S,CH622KMEB02   I124 @T6G_MB_LIB.T6G(SCH_1):PAGE73
 C2118    1      A Q_CAP_C0402-22UF,4V,20%,X6S,CH622KMEB02   I125 @T6G_MB_LIB.T6G(SCH_1):PAGE73
 C3921    1      A Q_CAP_C0402-22UF,4V,20%,X6S,CH622KMEB02   I155 @T6G_MB_LIB.T6G(SCH_1):PAGE73
 C3922    1      A Q_CAP_C0402-22UF,4V,20%,X6S,CH622KMEB02   I157 @T6G_MB_LIB.T6G(SCH_1):PAGE73
 C2126    1      A Q_CAP_C0402-22UF,4V,20%,X6S,CH622KMEB02   I159 @T6G_MB_LIB.T6G(SCH_1):PAGE73
 C2125    1      A Q_CAP_C0402-22UF,4V,20%,X6S,CH622KMEB02   I160 @T6G_MB_LIB.T6G(SCH_1):PAGE73
 C2511    1      A Q_CAP_C0402-22UF,4V,20%,X6S,CH622KMEB02   I161 @T6G_MB_LIB.T6G(SCH_1):PAGE73
 C2510    1      A Q_CAP_C0402-22UF,4V,20%,X6S,CH622KMEB02   I163 @T6G_MB_LIB.T6G(SCH_1):PAGE73
 C2124    1      A Q_CAP_C0402-22UF,4V,20%,X6S,CH622KMEB02   I164 @T6G_MB_LIB.T6G(SCH_1):PAGE73
 C2128    1      A Q_CAP_C0402-22UF,4V,20%,X6S,CH622KMEB02   I166 @T6G_MB_LIB.T6G(SCH_1):PAGE73
  R359    1      A Q_RES_0402LF-1K,1%,1/16W,CHIP,CS21002FB06    I52 @T6G_MB_LIB.T6G(SCH_1):PAGE138
 PC528    1      A Q_CAPP_SMLF-470UF,2.5V,20%,SPCAP,CH747LM8825    I63 @T6G_MB_LIB.T6G(SCH_1):PAGE200
PC527_2    1      A Q_CAP_C0805-22UF,4V,20%,X6S,CH622KMEA03    I67 @T6G_MB_LIB.T6G(SCH_1):PAGE200
 PC530    1      A Q_CAPP_SMLF-390UF,2.5V,20%,ALUM,CC7390JMZ13    I69 @T6G_MB_LIB.T6G(SCH_1):PAGE200
 R5010    1      A Q_RES_0402LF-1K,1%,1/16W,EMPTY,CS21002FB06   I151 @T6G_MB_LIB.T6G(SCH_1):PAGE136
 R5011    1      A Q_RES_0402LF-1K,1%,1/16W,EMPTY,CS21002FB06   I152 @T6G_MB_LIB.T6G(SCH_1):PAGE136
 R5013    1      A Q_RES_0402LF-1K,1%,1/16W,EMPTY,CS21002FB06   I154 @T6G_MB_LIB.T6G(SCH_1):PAGE136
 R5012    1      A Q_RES_0402LF-1K,1%,1/16W,EMPTY,CS21002FB06   I156 @T6G_MB_LIB.T6G(SCH_1):PAGE136
 R5018    1      A Q_RES_0402LF-1K,1%,1/16W,EMPTY,CS21002FB06   I163 @T6G_MB_LIB.T6G(SCH_1):PAGE136
 R5019    1      A Q_RES_0402LF-1K,1%,1/16W,EMPTY,CS21002FB06   I164 @T6G_MB_LIB.T6G(SCH_1):PAGE136
 R5021    1      A Q_RES_0402LF-1K,1%,1/16W,EMPTY,CS21002FB06   I166 @T6G_MB_LIB.T6G(SCH_1):PAGE136
 R5020    1      A Q_RES_0402LF-1K,1%,1/16W,EMPTY,CS21002FB06   I167 @T6G_MB_LIB.T6G(SCH_1):PAGE136
  R362    1      A Q_RES_0402LF-1K,1%,1/16W,CHIP,CS21002FB06    I53 @T6G_MB_LIB.T6G(SCH_1):PAGE138
  R541    1      A Q_RES_0402LF-1K,1%,1/16W,EMPTY,CS21002FB06   I365 @T6G_MB_LIB.T6G(SCH_1):PAGE55
  R542    1      A Q_RES_0402LF-1K,1%,1/16W,EMPTY,CS21002FB06   I366 @T6G_MB_LIB.T6G(SCH_1):PAGE55
  R543    1      A Q_RES_0402LF-1K,1%,1/16W,EMPTY,CS21002FB06   I367 @T6G_MB_LIB.T6G(SCH_1):PAGE55
  R563    1      A Q_RES_0402LF-1K,1%,1/16W,EMPTY,CS21002FB06   I368 @T6G_MB_LIB.T6G(SCH_1):PAGE55
 PR229    1      A Q_RES_0402LF-49.9,1%,1/16W,CHIP,CS04992FB07    I29 @T6G_MB_LIB.T6G(SCH_1):PAGE199
 PR333    2      B Q_RES_0402LF-0,5%,1/16W,CHIP,CS00002JB13    I53 @T6G_MB_LIB.T6G(SCH_1):PAGE200
  PL55    2      2 Q_INDUCTOR_SMLF-90NH/155A,IND,CVA90^0KZ13    I55 @T6G_MB_LIB.T6G(SCH_1):PAGE200
PC523_2    1      A Q_CAP_C0805-22UF,4V,20%,X6S,CH622KMEA03    I56 @T6G_MB_LIB.T6G(SCH_1):PAGE200
 PR332    2      B Q_RES_0402LF-0,5%,1/16W,CHIP,CS00002JB13    I60 @T6G_MB_LIB.T6G(SCH_1):PAGE200
 PC525    1      A Q_CAPP_SMLF-470UF,2.5V,20%,SPCAP,CH747LM8825    I62 @T6G_MB_LIB.T6G(SCH_1):PAGE200
 PC802    1      A Q_CAPP_SMLF-470UF,2.5V,20%,SPCAP,CH747LM8825    I65 @T6G_MB_LIB.T6G(SCH_1):PAGE200
 PC531    1      A Q_CAPP_SMLF-390UF,2.5V,20%,ALUM,CC7390JMZ13    I72 @T6G_MB_LIB.T6G(SCH_1):PAGE200
 PC532    1      A Q_CAPP_SMLF-390UF,2.5V,20%,ALUM,CC7390JMZ13    I73 @T6G_MB_LIB.T6G(SCH_1):PAGE200
 PC803    1      A Q_CAPP_SMLF-390UF,2.5V,20%,ALUM,CC7390JMZ13    I75 @T6G_MB_LIB.T6G(SCH_1):PAGE200
  PL54    2      2 Q_INDUCTOR_SMLF-90NH/155A,IND,CVA90^0KZ13    I78 @T6G_MB_LIB.T6G(SCH_1):PAGE200
 PC524    1      A Q_CAP_C0402-100NF,50V,10%,X7R,CH4106K1B01    I82 @T6G_MB_LIB.T6G(SCH_1):PAGE200
PC526_1    1      A Q_CAP_C0805-22UF,4V,20%,X6S,CH622KMEA03    I87 @T6G_MB_LIB.T6G(SCH_1):PAGE200
PC529_1    1      A Q_CAP_C0805-22UF,4V,20%,X6S,CH622KMEA03    I88 @T6G_MB_LIB.T6G(SCH_1):PAGE200
 PR395    1      A Q_RES_0402LF-1K,1%,1/16W,CHIP,CS21002FB06    I89 @T6G_MB_LIB.T6G(SCH_1):PAGE200

PVDD11_S3_P1_ADDR_CFG @T6G_MB_LIB.T6G(SCH_1):PVDD11_S3_P1_ADDR_CFG
  PU54   34 EN1||ADDR_CFG RAA229621GNPHA0-RAA229621GNP#HA0,SMLF,IC,ARF0TGP40A    I86 @T6G_MB_LIB.T6G(SCH_1):PAGE199
 PR464    2      B Q_RES_0402LF-13.7K,1%,1/16W,CHIP,CS31372FB03    I89 @T6G_MB_LIB.T6G(SCH_1):PAGE199

PVDD11_S3_P1_EN @T6G_MB_LIB.T6G(SCH_1):PVDD11_S3_P1_EN
  R279    1      A Q_RES_0402LF-33,5%,1/16W,CHIP,CS03302JB10    I58 @T6G_MB_LIB.T6G(SCH_1):PAGE80
 R8386    1      A Q_RES_0402LF-0,5%,1/16W,CHIP,CS00002JB13    I42 @T6G_MB_LIB.T6G(SCH_1):PAGE199

PVDD11_S3_P1_EN_R @T6G_MB_LIB.T6G(SCH_1):PVDD11_S3_P1_EN_R
 R8386    2      B Q_RES_0402LF-0,5%,1/16W,CHIP,CS00002JB13    I42 @T6G_MB_LIB.T6G(SCH_1):PAGE199
  C642    1      A Q_CAP_0402-1000PF,50V,5%,X7R,TMP_QCH21006JB10    I44 @T6G_MB_LIB.T6G(SCH_1):PAGE199
  PU54   13    EN0 RAA229621GNPHA0-RAA229621GNP#HA0,SMLF,IC,ARF0TGP40A    I86 @T6G_MB_LIB.T6G(SCH_1):PAGE199

PVDD11_S3_P1_IMON1 @T6G_MB_LIB.T6G(SCH_1):PVDD11_S3_P1_IMON1
  PU54   23    CS7 RAA229621GNPHA0-RAA229621GNP#HA0,SMLF,IC,ARF0TGP40A    I86 @T6G_MB_LIB.T6G(SCH_1):PAGE199
  PU44   38   IOUT ISL99390FRZTR5935-ISL99390FRZ-TR5935,SMLF,IC,AL099A    I22 @T6G_MB_LIB.T6G(SCH_1):PAGE200

PVDD11_S3_P1_IMON2 @T6G_MB_LIB.T6G(SCH_1):PVDD11_S3_P1_IMON2
  PU54   24    CS6 RAA229621GNPHA0-RAA229621GNP#HA0,SMLF,IC,ARF0TGP40A    I86 @T6G_MB_LIB.T6G(SCH_1):PAGE199
  PU45   38   IOUT ISL99390FRZTR5935-ISL99390FRZ-TR5935,SMLF,IC,AL099A    I92 @T6G_MB_LIB.T6G(SCH_1):PAGE200

PVDD11_S3_P1_LSET1 @T6G_MB_LIB.T6G(SCH_1):PVDD11_S3_P1_LSET1
 PR328    2      B Q_RES_0402LF-4.87K,1%,1/16W,EMPTY,CS24872FB07    I37 @T6G_MB_LIB.T6G(SCH_1):PAGE200
  PU44   37   LSET ISL99390FRZTR5935-ISL99390FRZ-TR5935,SMLF,IC,AL099A    I22 @T6G_MB_LIB.T6G(SCH_1):PAGE200

PVDD11_S3_P1_LSET2 @T6G_MB_LIB.T6G(SCH_1):PVDD11_S3_P1_LSET2
 PR329    2      B Q_RES_0402LF-4.87K,1%,1/16W,EMPTY,CS24872FB07    I12 @T6G_MB_LIB.T6G(SCH_1):PAGE200
  PU45   37   LSET ISL99390FRZTR5935-ISL99390FRZ-TR5935,SMLF,IC,AL099A    I92 @T6G_MB_LIB.T6G(SCH_1):PAGE200

PVDD11_S3_P1_OCP_N @T6G_MB_LIB.T6G(SCH_1):PVDD11_S3_P1_OCP_N
 R8010    1      A Q_RES_0402LF-0,5%,1/16W,EMPTY,CS00002JB13    I13 @T6G_MB_LIB.T6G(SCH_1):PAGE199
  R278    2      B Q_RES_0402LF-0,5%,1/16W,CHIP,CS00002JB13   I113 @T6G_MB_LIB.T6G(SCH_1):PAGE81

PVDD11_S3_P1_OCP_N_R @T6G_MB_LIB.T6G(SCH_1):PVDD11_S3_P1_OCP_N_R
 R8010    2      B Q_RES_0402LF-0,5%,1/16W,EMPTY,CS00002JB13    I13 @T6G_MB_LIB.T6G(SCH_1):PAGE199
 R8011    2      B Q_RES_0402LF-1K,1%,1/16W,EMPTY,CS21002FB06    I24 @T6G_MB_LIB.T6G(SCH_1):PAGE199
  PU54   33  OCP_L RAA229621GNPHA0-RAA229621GNP#HA0,SMLF,IC,ARF0TGP40A    I86 @T6G_MB_LIB.T6G(SCH_1):PAGE199

PVDD11_S3_P1_PMALERT @T6G_MB_LIB.T6G(SCH_1):PVDD11_S3_P1_PMALERT
 R1190    1      A Q_RES_0402LF-1K,1%,1/16W,CHIP,CS21002FB06    I58 @T6G_MB_LIB.T6G(SCH_1):PAGE82
   U18   N1  PL17B LCMXO3LF9400C5BG484C-LCMXO3LF-9400C-5BG484C,SMLF,IA   I143 @T6G_MB_LIB.T6G(SCH_1):PAGE81
 R8383    1      A Q_RES_0402LF-33,5%,1/16W,CHIP,CS03302JB10    I38 @T6G_MB_LIB.T6G(SCH_1):PAGE199
 C5010    1      A Q_CAP_0402-1000PF,50V,5%,X7R,TMP_QCH21006JB10    I88 @T6G_MB_LIB.T6G(SCH_1):PAGE199

PVDD11_S3_P1_PMALERT_R @T6G_MB_LIB.T6G(SCH_1):PVDD11_S3_P1_PMALERT_R
 R8383    2      B Q_RES_0402LF-33,5%,1/16W,CHIP,CS03302JB10    I38 @T6G_MB_LIB.T6G(SCH_1):PAGE199
  PU54   11 NPMALERT RAA229621GNPHA0-RAA229621GNP#HA0,SMLF,IC,ARF0TGP40A    I86 @T6G_MB_LIB.T6G(SCH_1):PAGE199

PVDD11_S3_P1_PMSCL_R @T6G_MB_LIB.T6G(SCH_1):PVDD11_S3_P1_PMSCL_R
 R8381    2      B Q_RES_0402LF-0,5%,1/16W,CHIP,CS00002JB13    I40 @T6G_MB_LIB.T6G(SCH_1):PAGE199
  PU54   10  PMSCL RAA229621GNPHA0-RAA229621GNP#HA0,SMLF,IC,ARF0TGP40A    I86 @T6G_MB_LIB.T6G(SCH_1):PAGE199

PVDD11_S3_P1_PMSDA_R @T6G_MB_LIB.T6G(SCH_1):PVDD11_S3_P1_PMSDA_R
 R8382    2      B Q_RES_0402LF-0,5%,1/16W,CHIP,CS00002JB13    I39 @T6G_MB_LIB.T6G(SCH_1):PAGE199
  PU54    9  PMSDA RAA229621GNPHA0-RAA229621GNP#HA0,SMLF,IC,ARF0TGP40A    I86 @T6G_MB_LIB.T6G(SCH_1):PAGE199

PVDD11_S3_P1_PVCC @T6G_MB_LIB.T6G(SCH_1):PVDD11_S3_P1_PVCC
PC507_11P1_1    1      A Q_CAP_C0402-2.2UF,10V,10%,X6S,CH5222KEB01    I43 @T6G_MB_LIB.T6G(SCH_1):PAGE200
 PR387    1      A Q_RES_0402LF-0,5%,1/16W,CHIP,CS00002JB13     I3 @T6G_MB_LIB.T6G(SCH_1):PAGE200
 PR327    1      A Q_RES_0402LF-2.2,1%,1/16W,CHIP,CS-2202FB01    I14 @T6G_MB_LIB.T6G(SCH_1):PAGE200
PC508_11P1_2    1      A Q_CAP_C0402-2.2UF,10V,10%,X6S,CH5222KEB01    I17 @T6G_MB_LIB.T6G(SCH_1):PAGE200
  PU44    4   PVCC ISL99390FRZTR5935-ISL99390FRZ-TR5935,SMLF,IC,AL099A    I22 @T6G_MB_LIB.T6G(SCH_1):PAGE200
 PR326    1      A Q_RES_0402LF-2.2,1%,1/16W,CHIP,CS-2202FB01    I40 @T6G_MB_LIB.T6G(SCH_1):PAGE200
 PR394    1      A Q_RES_0402LF-0,5%,1/16W,EMPTY,CS00002JB13    I41 @T6G_MB_LIB.T6G(SCH_1):PAGE200
  PU45    4   PVCC ISL99390FRZTR5935-ISL99390FRZ-TR5935,SMLF,IC,AL099A    I92 @T6G_MB_LIB.T6G(SCH_1):PAGE200

PVDD11_S3_P1_PWM1 @T6G_MB_LIB.T6G(SCH_1):PVDD11_S3_P1_PWM1
  PU54    8   PWM7 RAA229621GNPHA0-RAA229621GNP#HA0,SMLF,IC,ARF0TGP40A    I86 @T6G_MB_LIB.T6G(SCH_1):PAGE199
  PU44   34    PWM ISL99390FRZTR5935-ISL99390FRZ-TR5935,SMLF,IC,AL099A    I22 @T6G_MB_LIB.T6G(SCH_1):PAGE200

PVDD11_S3_P1_PWM2 @T6G_MB_LIB.T6G(SCH_1):PVDD11_S3_P1_PWM2
  PU54    7   PWM6 RAA229621GNPHA0-RAA229621GNP#HA0,SMLF,IC,ARF0TGP40A    I86 @T6G_MB_LIB.T6G(SCH_1):PAGE199
  PU45   34    PWM ISL99390FRZTR5935-ISL99390FRZ-TR5935,SMLF,IC,AL099A    I92 @T6G_MB_LIB.T6G(SCH_1):PAGE200

PVDD11_S3_P1_RESET_N @T6G_MB_LIB.T6G(SCH_1):PVDD11_S3_P1_RESET_N
 PR392    2      B Q_RES_0402LF-0,5%,1/16W,EMPTY,CS00002JB13    I66 @T6G_MB_LIB.T6G(SCH_1):PAGE199
   U18  H16  PR10D LCMXO3LF9400C5BG484C-LCMXO3LF-9400C-5BG484C,SMLF,IA   I217 @T6G_MB_LIB.T6G(SCH_1):PAGE80

PVDD11_S3_P1_RESET_N_R @T6G_MB_LIB.T6G(SCH_1):PVDD11_S3_P1_RESET_N_R
 PR390    1      A Q_RES_0402LF-0,5%,1/16W,EMPTY,CS00002JB13    I56 @T6G_MB_LIB.T6G(SCH_1):PAGE199
 PR392    1      A Q_RES_0402LF-0,5%,1/16W,EMPTY,CS00002JB13    I66 @T6G_MB_LIB.T6G(SCH_1):PAGE199
 PR391    1      A Q_RES_0402LF-1K,1%,1/16W,EMPTY,CS21002FB06    I67 @T6G_MB_LIB.T6G(SCH_1):PAGE199
  PU54   14 RESET_L RAA229621GNPHA0-RAA229621GNP#HA0,SMLF,IC,ARF0TGP40A    I86 @T6G_MB_LIB.T6G(SCH_1):PAGE199

PVDD11_S3_P1_TEMP0 @T6G_MB_LIB.T6G(SCH_1):PVDD11_S3_P1_TEMP0
 PC643    1      A Q_CAP_0402-470PF,50V,10%,X7R,TMP_QCH14706KB18    I49 @T6G_MB_LIB.T6G(SCH_1):PAGE199
  PU54   36  TEMP0 RAA229621GNPHA0-RAA229621GNP#HA0,SMLF,IC,ARF0TGP40A    I86 @T6G_MB_LIB.T6G(SCH_1):PAGE199
  PU44   36 TOUT_FLT ISL99390FRZTR5935-ISL99390FRZ-TR5935,SMLF,IC,AL099A    I22 @T6G_MB_LIB.T6G(SCH_1):PAGE200
  PU45   36 TOUT_FLT ISL99390FRZTR5935-ISL99390FRZ-TR5935,SMLF,IC,AL099A    I92 @T6G_MB_LIB.T6G(SCH_1):PAGE200

PVDD11_S3_P1_TEMP1 @T6G_MB_LIB.T6G(SCH_1):PVDD11_S3_P1_TEMP1
 PR415    1      A Q_RES_0402LF-0,5%,1/16W,CHIP,CS00002JB13    I51 @T6G_MB_LIB.T6G(SCH_1):PAGE199
  PU54   35  TEMP1 RAA229621GNPHA0-RAA229621GNP#HA0,SMLF,IC,ARF0TGP40A    I86 @T6G_MB_LIB.T6G(SCH_1):PAGE199

PVDD11_S3_P1_VCC @T6G_MB_LIB.T6G(SCH_1):PVDD11_S3_P1_VCC
  PC95    1      A Q_CAP_0402-0.1UF,25V,10%,X7R,CH4104K1B00    I73 @T6G_MB_LIB.T6G(SCH_1):PAGE199
 PC645    1      A Q_CAP_C0402-1UF,16V,10%,X6S,CH5103KEB01    I81 @T6G_MB_LIB.T6G(SCH_1):PAGE199
 PR393    1      A Q_RES_0402LF-1,1%,1/16W,CHIP,CS-1002FB04    I84 @T6G_MB_LIB.T6G(SCH_1):PAGE199
  PU54   39    VCC RAA229621GNPHA0-RAA229621GNP#HA0,SMLF,IC,ARF0TGP40A    I86 @T6G_MB_LIB.T6G(SCH_1):PAGE199

PVDD11_S3_P1_VCC1 @T6G_MB_LIB.T6G(SCH_1):PVDD11_S3_P1_VCC1
  PU44   35     EN ISL99390FRZTR5935-ISL99390FRZ-TR5935,SMLF,IC,AL099A    I22 @T6G_MB_LIB.T6G(SCH_1):PAGE200
  PU44    3    VCC ISL99390FRZTR5935-ISL99390FRZ-TR5935,SMLF,IC,AL099A    I22 @T6G_MB_LIB.T6G(SCH_1):PAGE200
 PC505    1      A Q_CAP_C0402-2.2UF,10V,10%,X6S,CH5222KEB01    I36 @T6G_MB_LIB.T6G(SCH_1):PAGE200
 PR326    2      B Q_RES_0402LF-2.2,1%,1/16W,CHIP,CS-2202FB01    I40 @T6G_MB_LIB.T6G(SCH_1):PAGE200

PVDD11_S3_P1_VCC2 @T6G_MB_LIB.T6G(SCH_1):PVDD11_S3_P1_VCC2
 PC506    1      A Q_CAP_C0402-2.2UF,10V,10%,X6S,CH5222KEB01    I10 @T6G_MB_LIB.T6G(SCH_1):PAGE200
 PR327    2      B Q_RES_0402LF-2.2,1%,1/16W,CHIP,CS-2202FB01    I14 @T6G_MB_LIB.T6G(SCH_1):PAGE200
  PU45   35     EN ISL99390FRZTR5935-ISL99390FRZ-TR5935,SMLF,IC,AL099A    I92 @T6G_MB_LIB.T6G(SCH_1):PAGE200
  PU45    3    VCC ISL99390FRZTR5935-ISL99390FRZ-TR5935,SMLF,IC,AL099A    I92 @T6G_MB_LIB.T6G(SCH_1):PAGE200

PVDD11_S3_P1_VCCS @T6G_MB_LIB.T6G(SCH_1):PVDD11_S3_P1_VCCS
PC503_1    1      A Q_CAP_0402-0.1UF,25V,10%,X7R,CH4104K1B00    I34 @T6G_MB_LIB.T6G(SCH_1):PAGE200
  PC96    1      A Q_CAP_0402-0.1UF,25V,10%,X7R,CH4104K1B00    I72 @T6G_MB_LIB.T6G(SCH_1):PAGE199
 PC644    1      A Q_CAP_C0402-10UF,6.3V,20%,X6S,CH6101MEB03    I80 @T6G_MB_LIB.T6G(SCH_1):PAGE199
  PU54   40   VCCS RAA229621GNPHA0-RAA229621GNP#HA0,SMLF,IC,ARF0TGP40A    I86 @T6G_MB_LIB.T6G(SCH_1):PAGE199
PC504_2    1      A Q_CAP_0402-0.1UF,25V,10%,X7R,CH4104K1B00     I8 @T6G_MB_LIB.T6G(SCH_1):PAGE200
  PU44   39  REFIN ISL99390FRZTR5935-ISL99390FRZ-TR5935,SMLF,IC,AL099A    I22 @T6G_MB_LIB.T6G(SCH_1):PAGE200
  PU45   39  REFIN ISL99390FRZTR5935-ISL99390FRZ-TR5935,SMLF,IC,AL099A    I92 @T6G_MB_LIB.T6G(SCH_1):PAGE200

PVDD11_S3_P1_VDDIO @T6G_MB_LIB.T6G(SCH_1):PVDD11_S3_P1_VDDIO
 R8146    2      B Q_RES_0402LF-0,5%,1/16W,EMPTY,CS00002JB13     I9 @T6G_MB_LIB.T6G(SCH_1):PAGE199
  PU54   15  VDDIO RAA229621GNPHA0-RAA229621GNP#HA0,SMLF,IC,ARF0TGP40A    I86 @T6G_MB_LIB.T6G(SCH_1):PAGE199

PVDD11_S3_P1_VINSEN @T6G_MB_LIB.T6G(SCH_1):PVDD11_S3_P1_VINSEN
 PR604    1      A Q_RES_0402LF-4.99K,1%,1/16W,EMPTY,CS24992FB07    I17 @T6G_MB_LIB.T6G(SCH_1):PAGE199
 PR388    2      B Q_RES_0402LF-0,5%,1/16W,CHIP,CS00002JB13    I18 @T6G_MB_LIB.T6G(SCH_1):PAGE199
   PC8    1      A Q_CAP_0402-0.1UF,25V,10%,X7R,CH4104K1B00    I20 @T6G_MB_LIB.T6G(SCH_1):PAGE199
  PU54   38 VINSEN RAA229621GNPHA0-RAA229621GNP#HA0,SMLF,IC,ARF0TGP40A    I86 @T6G_MB_LIB.T6G(SCH_1):PAGE199

PVDD11_S3_P1_VMON @T6G_MB_LIB.T6G(SCH_1):PVDD11_S3_P1_VMON
 PR376    2      B Q_RES_0402LF-40.2K,1%,1/16W,CHIP,CS34022FB04     I2 @T6G_MB_LIB.T6G(SCH_1):PAGE199
 PC638    1      A Q_CAP_0402-0.1UF,25V,10%,X7R,CH4104K1B00     I4 @T6G_MB_LIB.T6G(SCH_1):PAGE199
   PR6    1      A Q_RES_0402LF-10K,1%,1/16W,CHIP,CS31002FB08     I6 @T6G_MB_LIB.T6G(SCH_1):PAGE199
  PU54   37 VMON||IINSEN RAA229621GNPHA0-RAA229621GNP#HA0,SMLF,IC,ARF0TGP40A    I86 @T6G_MB_LIB.T6G(SCH_1):PAGE199

PVDD11_S3_P1_VOS1 @T6G_MB_LIB.T6G(SCH_1):PVDD11_S3_P1_VOS1
  PU44    1    VOS ISL99390FRZTR5935-ISL99390FRZ-TR5935,SMLF,IC,AL099A    I22 @T6G_MB_LIB.T6G(SCH_1):PAGE200
 PR332    1      A Q_RES_0402LF-0,5%,1/16W,CHIP,CS00002JB13    I60 @T6G_MB_LIB.T6G(SCH_1):PAGE200

PVDD11_S3_P1_VOS2 @T6G_MB_LIB.T6G(SCH_1):PVDD11_S3_P1_VOS2
 PR333    1      A Q_RES_0402LF-0,5%,1/16W,CHIP,CS00002JB13    I53 @T6G_MB_LIB.T6G(SCH_1):PAGE200
  PU45    1    VOS ISL99390FRZTR5935-ISL99390FRZ-TR5935,SMLF,IC,AL099A    I92 @T6G_MB_LIB.T6G(SCH_1):PAGE200

PVDD18_S5_P0 @T6G_MB_LIB.T6G(SCH_1):PVDD18_S5_P0
  R403    1      A Q_RES_0402LF-1K,1%,1/16W,CHIP,CS21002FB06   I294 @T6G_MB_LIB.T6G(SCH_1):PAGE27
  R402    1      A Q_RES_0402LF-1K,1%,1/16W,CHIP,CS21002FB06   I296 @T6G_MB_LIB.T6G(SCH_1):PAGE27
  R401    1      A Q_RES_0402LF-1K,1%,1/16W,CHIP,CS21002FB06   I300 @T6G_MB_LIB.T6G(SCH_1):PAGE27
  R400    1      A Q_RES_0402LF-1K,1%,1/16W,CHIP,CS21002FB06   I301 @T6G_MB_LIB.T6G(SCH_1):PAGE27
  R399    1      A Q_RES_0402LF-1K,1%,1/16W,CHIP,CS21002FB06   I304 @T6G_MB_LIB.T6G(SCH_1):PAGE27
  R398    1      A Q_RES_0402LF-1K,1%,1/16W,CHIP,CS21002FB06   I305 @T6G_MB_LIB.T6G(SCH_1):PAGE27
  R412    2      B Q_RES_0402LF-2.2K,5%,1/16W,CHIP,CS22202JB07   I377 @T6G_MB_LIB.T6G(SCH_1):PAGE27
  R418    2      B Q_RES_0402LF-2.2K,5%,1/16W,CHIP,CS22202JB07   I378 @T6G_MB_LIB.T6G(SCH_1):PAGE27
  R417    2      B Q_RES_0402LF-2.2K,5%,1/16W,CHIP,CS22202JB07   I379 @T6G_MB_LIB.T6G(SCH_1):PAGE27
  R408    2      B Q_RES_0402LF-2.2K,5%,1/16W,CHIP,CS22202JB07   I380 @T6G_MB_LIB.T6G(SCH_1):PAGE27
  R409    2      B Q_RES_0402LF-2.2K,5%,1/16W,CHIP,CS22202JB07   I381 @T6G_MB_LIB.T6G(SCH_1):PAGE27
  R410    2      B Q_RES_0402LF-2.2K,5%,1/16W,CHIP,CS22202JB07   I382 @T6G_MB_LIB.T6G(SCH_1):PAGE27
  R411    2      B Q_RES_0402LF-2.2K,5%,1/16W,CHIP,CS22202JB07   I383 @T6G_MB_LIB.T6G(SCH_1):PAGE27
  R413    2      B Q_RES_0402LF-2.2K,5%,1/16W,CHIP,CS22202JB07   I384 @T6G_MB_LIB.T6G(SCH_1):PAGE27
  R414    2      B Q_RES_0402LF-2.2K,5%,1/16W,CHIP,CS22202JB07   I385 @T6G_MB_LIB.T6G(SCH_1):PAGE27
  R415    2      B Q_RES_0402LF-2.2K,5%,1/16W,CHIP,CS22202JB07   I386 @T6G_MB_LIB.T6G(SCH_1):PAGE27
  R416    2      B Q_RES_0402LF-2.2K,5%,1/16W,CHIP,CS22202JB07   I387 @T6G_MB_LIB.T6G(SCH_1):PAGE27
  R392    1      A Q_RES_0402LF-2.2K,5%,1/16W,EMPTY,CS22202JB07   I395 @T6G_MB_LIB.T6G(SCH_1):PAGE27
  R457    1      A Q_RES_0402LF-4.7K,5%,1/16W,EMPTY,CS24702JB10   I282 @T6G_MB_LIB.T6G(SCH_1):PAGE29
  R455    1      A Q_RES_0402LF-4.7K,5%,1/16W,EMPTY,CS24702JB10   I284 @T6G_MB_LIB.T6G(SCH_1):PAGE29
  R454    1      A Q_RES_0402LF-10K,5%,1/16W,CHIP,CS31002JB08   I383 @T6G_MB_LIB.T6G(SCH_1):PAGE29
   U25 AR52 VDD_18_S5_AR52 GENOA_SP5-SOCKET6096_13568-001,SMLF,IO,DGA^6000030    I28 @T6G_MB_LIB.T6G(SCH_1):PAGE30
   U25 AR54 VDD_18_S5_AR54 GENOA_SP5-SOCKET6096_13568-001,SMLF,IO,DGA^6000030    I28 @T6G_MB_LIB.T6G(SCH_1):PAGE30
   U25 AT51 VDD_18_S5_AT51 GENOA_SP5-SOCKET6096_13568-001,SMLF,IO,DGA^6000030    I28 @T6G_MB_LIB.T6G(SCH_1):PAGE30
   U25 AT53 VDD_18_S5_AT53 GENOA_SP5-SOCKET6096_13568-001,SMLF,IO,DGA^6000030    I28 @T6G_MB_LIB.T6G(SCH_1):PAGE30
   U25 AU50 VDD_18_S5_AU50 GENOA_SP5-SOCKET6096_13568-001,SMLF,IO,DGA^6000030    I28 @T6G_MB_LIB.T6G(SCH_1):PAGE30
   U25 AU52 VDD_18_S5_AU52 GENOA_SP5-SOCKET6096_13568-001,SMLF,IO,DGA^6000030    I28 @T6G_MB_LIB.T6G(SCH_1):PAGE30
   U25 AU54 VDD_18_S5_AU54 GENOA_SP5-SOCKET6096_13568-001,SMLF,IO,DGA^6000030    I28 @T6G_MB_LIB.T6G(SCH_1):PAGE30
   U25 AV49 VDD_18_S5_AV49 GENOA_SP5-SOCKET6096_13568-001,SMLF,IO,DGA^6000030    I28 @T6G_MB_LIB.T6G(SCH_1):PAGE30
   U25 AV51 VDD_18_S5_AV51 GENOA_SP5-SOCKET6096_13568-001,SMLF,IO,DGA^6000030    I28 @T6G_MB_LIB.T6G(SCH_1):PAGE30
   U25 AV53 VDD_18_S5_AV53 GENOA_SP5-SOCKET6096_13568-001,SMLF,IO,DGA^6000030    I28 @T6G_MB_LIB.T6G(SCH_1):PAGE30
   U25 AW50 VDD_18_S5_AW50 GENOA_SP5-SOCKET6096_13568-001,SMLF,IO,DGA^6000030    I28 @T6G_MB_LIB.T6G(SCH_1):PAGE30
   U25 AW52 VDD_18_S5_AW52 GENOA_SP5-SOCKET6096_13568-001,SMLF,IO,DGA^6000030    I28 @T6G_MB_LIB.T6G(SCH_1):PAGE30
   U25 AW54 VDD_18_S5_AW54 GENOA_SP5-SOCKET6096_13568-001,SMLF,IO,DGA^6000030    I28 @T6G_MB_LIB.T6G(SCH_1):PAGE30
   U25 AY51 VDD_18_S5_AY51 GENOA_SP5-SOCKET6096_13568-001,SMLF,IO,DGA^6000030    I28 @T6G_MB_LIB.T6G(SCH_1):PAGE30
   U25 AY53 VDD_18_S5_AY53 GENOA_SP5-SOCKET6096_13568-001,SMLF,IO,DGA^6000030    I28 @T6G_MB_LIB.T6G(SCH_1):PAGE30
   U25 BA50 VDD_18_S5_BA50 GENOA_SP5-SOCKET6096_13568-001,SMLF,IO,DGA^6000030    I28 @T6G_MB_LIB.T6G(SCH_1):PAGE30
   U25 BA52 VDD_18_S5_BA52 GENOA_SP5-SOCKET6096_13568-001,SMLF,IO,DGA^6000030    I28 @T6G_MB_LIB.T6G(SCH_1):PAGE30
   U25 BA54 VDD_18_S5_BA54 GENOA_SP5-SOCKET6096_13568-001,SMLF,IO,DGA^6000030    I28 @T6G_MB_LIB.T6G(SCH_1):PAGE30
   U25 BB51 VDD_18_S5_BB51 GENOA_SP5-SOCKET6096_13568-001,SMLF,IO,DGA^6000030    I28 @T6G_MB_LIB.T6G(SCH_1):PAGE30
   U25 BB53 VDD_18_S5_BB53 GENOA_SP5-SOCKET6096_13568-001,SMLF,IO,DGA^6000030    I28 @T6G_MB_LIB.T6G(SCH_1):PAGE30
   U25 BC52 VDD_18_S5_BC52 GENOA_SP5-SOCKET6096_13568-001,SMLF,IO,DGA^6000030    I28 @T6G_MB_LIB.T6G(SCH_1):PAGE30
   U25 BC54 VDD_18_S5_BC54 GENOA_SP5-SOCKET6096_13568-001,SMLF,IO,DGA^6000030    I28 @T6G_MB_LIB.T6G(SCH_1):PAGE30
   U25 BH27 VDDIO_AUDIO GENOA_SP5-SOCKET6096_13568-001,SMLF,IO,DGA^6000030    I28 @T6G_MB_LIB.T6G(SCH_1):PAGE30
   U27    1   VCCA PCA9617ADP-PCA9617ADP,SMLF,IC,AL009617K02    I18 @T6G_MB_LIB.T6G(SCH_1):PAGE34
   C42    1      A Q_CAP_0402-0.1UF,25V,10%,X7R,CH4104K1B00    I44 @T6G_MB_LIB.T6G(SCH_1):PAGE34
  U101    5    VCC SN74LVC1G07DBVR_SMLF-SN74LVC1G07DBVR,IC,AL1G0007024    I55 @T6G_MB_LIB.T6G(SCH_1):PAGE34
  C226    1      A Q_CAP_0402-0.1UF,25V,10%,X7R,CH4104K1B00    I59 @T6G_MB_LIB.T6G(SCH_1):PAGE34
  R942    1      A Q_RES_0402LF-4.7K,5%,1/16W,CHIP,CS24702JB10    I60 @T6G_MB_LIB.T6G(SCH_1):PAGE34
  R495    1      A Q_RES_0402LF-4.7K,5%,1/16W,CHIP,CS24702JB10   I106 @T6G_MB_LIB.T6G(SCH_1):PAGE34
  R498    1      A Q_RES_0402LF-2.2K,5%,1/16W,CHIP,CS22202JB07   I107 @T6G_MB_LIB.T6G(SCH_1):PAGE34
 C2163    1      A Q_CAP_C0402-22UF,4V,20%,X6S,CH622KMEB02   I131 @T6G_MB_LIB.T6G(SCH_1):PAGE67
 C2164    1      A Q_CAP_C0402-22UF,4V,20%,X6S,CH622KMEB02   I133 @T6G_MB_LIB.T6G(SCH_1):PAGE67
 C3897    1      A Q_CAP_C0402-22UF,4V,20%,X6S,CH622KMEB02   I134 @T6G_MB_LIB.T6G(SCH_1):PAGE67
 C2514    1      A Q_CAP_C0402-22UF,4V,20%,X6S,CH622KMEB02     I1 @T6G_MB_LIB.T6G(SCH_1):PAGE70
 C2513    1      A Q_CAP_C0402-22UF,4V,20%,X6S,CH622KMEB02     I3 @T6G_MB_LIB.T6G(SCH_1):PAGE70
 C2517    1      A Q_CAP_C0402-22UF,4V,20%,X6S,CH622KMEB02     I8 @T6G_MB_LIB.T6G(SCH_1):PAGE70
 C2516    1      A Q_CAP_C0402-22UF,4V,20%,X6S,CH622KMEB02     I9 @T6G_MB_LIB.T6G(SCH_1):PAGE70
 C2518    1      A Q_CAP_C0402-22UF,4V,20%,X6S,CH622KMEB02    I10 @T6G_MB_LIB.T6G(SCH_1):PAGE70
 C2520    1      A Q_CAP_C0402-22UF,4V,20%,X6S,CH622KMEB02    I11 @T6G_MB_LIB.T6G(SCH_1):PAGE70
 C2521    1      A Q_CAP_C0402-22UF,4V,20%,X6S,CH622KMEB02    I12 @T6G_MB_LIB.T6G(SCH_1):PAGE70
 C2522    1      A Q_CAP_C0402-22UF,4V,20%,X6S,CH622KMEB02    I13 @T6G_MB_LIB.T6G(SCH_1):PAGE70
 C2523    1      A Q_CAP_C0402-22UF,4V,20%,X6S,CH622KMEB02    I14 @T6G_MB_LIB.T6G(SCH_1):PAGE70
 C2524    1      A Q_CAP_C0402-22UF,4V,20%,X6S,CH622KMEB02    I15 @T6G_MB_LIB.T6G(SCH_1):PAGE70
 C2525    1      A Q_CAP_C0402-22UF,4V,20%,X6S,CH622KMEB02    I16 @T6G_MB_LIB.T6G(SCH_1):PAGE70
 C2526    1      A Q_CAP_C0402-22UF,4V,20%,X6S,CH622KMEB02    I18 @T6G_MB_LIB.T6G(SCH_1):PAGE70
  R729    1      A Q_RES_0402LF-10K,5%,1/16W,EMPTY,CS31002JB08    I41 @T6G_MB_LIB.T6G(SCH_1):PAGE75
  R737    1      A Q_RES_0402LF-10K,5%,1/16W,CHIP,CS31002JB08    I43 @T6G_MB_LIB.T6G(SCH_1):PAGE75
  R740    1      A Q_RES_0402LF-10K,5%,1/16W,EMPTY,CS31002JB08    I44 @T6G_MB_LIB.T6G(SCH_1):PAGE75
  R739    1      A Q_RES_0402LF-10K,5%,1/16W,EMPTY,CS31002JB08    I45 @T6G_MB_LIB.T6G(SCH_1):PAGE75
  R742    1      A Q_RES_0402LF-10K,5%,1/16W,EMPTY,CS31002JB08    I46 @T6G_MB_LIB.T6G(SCH_1):PAGE75
 C1102    1      A Q_CAP_0402-0.1UF,25V,10%,X7R,CH4104K1B00    I53 @T6G_MB_LIB.T6G(SCH_1):PAGE76
   U53    1   DIR1 SN74AVC4T774PWR-SN74AVC4T774PWR,SMLF,IC,AL04T774K00    I63 @T6G_MB_LIB.T6G(SCH_1):PAGE76
   U53    2   DIR2 SN74AVC4T774PWR-SN74AVC4T774PWR,SMLF,IC,AL04T774K00    I63 @T6G_MB_LIB.T6G(SCH_1):PAGE76
   U53    7   DIR3 SN74AVC4T774PWR-SN74AVC4T774PWR,SMLF,IC,AL04T774K00    I63 @T6G_MB_LIB.T6G(SCH_1):PAGE76
   U53    8   DIR4 SN74AVC4T774PWR-SN74AVC4T774PWR,SMLF,IC,AL04T774K00    I63 @T6G_MB_LIB.T6G(SCH_1):PAGE76
   U53   16   VCCA SN74AVC4T774PWR-SN74AVC4T774PWR,SMLF,IC,AL04T774K00    I63 @T6G_MB_LIB.T6G(SCH_1):PAGE76
 C1103    1      A Q_CAP_0402-0.1UF,25V,10%,X7R,CH4104K1B00    I65 @T6G_MB_LIB.T6G(SCH_1):PAGE76
   U54    1   VCCA PI4ULS3V304AZMAEX-PI4ULS3V304AZMAEX,SMLF,IC,AL0003A    I67 @T6G_MB_LIB.T6G(SCH_1):PAGE76
  R811    1      A Q_RES_0402LF-1K,1%,1/16W,CHIP,CS21002FB06   I106 @T6G_MB_LIB.T6G(SCH_1):PAGE76
  R659    1      A Q_RES_0402LF-1K,1%,1/16W,CHIP,CS21002FB06   I107 @T6G_MB_LIB.T6G(SCH_1):PAGE76
  R601    1      A Q_RES_0402LF-1K,1%,1/16W,CHIP,CS21002FB06   I108 @T6G_MB_LIB.T6G(SCH_1):PAGE76
  R139    2      B Q_RES_0402LF-0,5%,1/16W,EMPTY,CS00002JB13    I30 @T6G_MB_LIB.T6G(SCH_1):PAGE138
  R370    1      A Q_RES_0402LF-1K,1%,1/16W,CHIP,CS21002FB06    I60 @T6G_MB_LIB.T6G(SCH_1):PAGE138
 R1419    1      A Q_RES_0402LF-4.7K,5%,1/16W,CHIP,CS24702JB10    I91 @T6G_MB_LIB.T6G(SCH_1):PAGE141
  U116    1   DIR1 SN74AVC4T774PWR-SN74AVC4T774PWR,SMLF,IC,AL04T774K00   I117 @T6G_MB_LIB.T6G(SCH_1):PAGE141
  U116    7   DIR3 SN74AVC4T774PWR-SN74AVC4T774PWR,SMLF,IC,AL04T774K00   I117 @T6G_MB_LIB.T6G(SCH_1):PAGE141
  U116   16   VCCA SN74AVC4T774PWR-SN74AVC4T774PWR,SMLF,IC,AL04T774K00   I117 @T6G_MB_LIB.T6G(SCH_1):PAGE141
 C1352    1      A Q_CAP_0402-0.1UF,25V,10%,X7R,CH4104K1B00   I137 @T6G_MB_LIB.T6G(SCH_1):PAGE141
  R816    1      A Q_RES_0402LF-10K,5%,1/16W,CHIP,CS31002JB08   I196 @T6G_MB_LIB.T6G(SCH_1):PAGE141
  R815    1      A Q_RES_0402LF-10K,5%,1/16W,EMPTY,CS31002JB08   I197 @T6G_MB_LIB.T6G(SCH_1):PAGE141
  R814    1      A Q_RES_0402LF-10K,5%,1/16W,EMPTY,CS31002JB08   I198 @T6G_MB_LIB.T6G(SCH_1):PAGE141
  R813    1      A Q_RES_0402LF-10K,5%,1/16W,CHIP,CS31002JB08   I199 @T6G_MB_LIB.T6G(SCH_1):PAGE141
  U147    6   VCCB SN74AVC2T245RSWR-SN74AVC2T245RSWR,SMLF,IC,AL02T245A     I1 @T6G_MB_LIB.T6G(SCH_1):PAGE149
 C1509    1      A Q_CAP_C0402-0.1UF,16V,10%,X7R,CH4103K1B08    I10 @T6G_MB_LIB.T6G(SCH_1):PAGE149
 C1508    1      A Q_CAP_C0402-0.1UF,16V,10%,X7R,CH4103K1B08    I29 @T6G_MB_LIB.T6G(SCH_1):PAGE149
  U149    1   DIR1 SN74AVC4T774PWR-SN74AVC4T774PWR,SMLF,IC,AL04T774K00    I31 @T6G_MB_LIB.T6G(SCH_1):PAGE149
  U149    2   DIR2 SN74AVC4T774PWR-SN74AVC4T774PWR,SMLF,IC,AL04T774K00    I31 @T6G_MB_LIB.T6G(SCH_1):PAGE149
  U149    7   DIR3 SN74AVC4T774PWR-SN74AVC4T774PWR,SMLF,IC,AL04T774K00    I31 @T6G_MB_LIB.T6G(SCH_1):PAGE149
  U149    8   DIR4 SN74AVC4T774PWR-SN74AVC4T774PWR,SMLF,IC,AL04T774K00    I31 @T6G_MB_LIB.T6G(SCH_1):PAGE149
  U149   16   VCCA SN74AVC4T774PWR-SN74AVC4T774PWR,SMLF,IC,AL04T774K00    I31 @T6G_MB_LIB.T6G(SCH_1):PAGE149
  U149   15   VCCB SN74AVC4T774PWR-SN74AVC4T774PWR,SMLF,IC,AL04T774K00    I31 @T6G_MB_LIB.T6G(SCH_1):PAGE149
  U148   15   VCCB SN74AVC4T774PWR-SN74AVC4T774PWR,SMLF,IC,AL04T774K00    I34 @T6G_MB_LIB.T6G(SCH_1):PAGE149
 C1507    1      A Q_CAP_C0402-0.1UF,16V,10%,X7R,CH4103K1B08    I41 @T6G_MB_LIB.T6G(SCH_1):PAGE149
 C1504    1      A Q_CAP_C0402-0.1UF,16V,10%,X7R,CH4103K1B08    I56 @T6G_MB_LIB.T6G(SCH_1):PAGE149
 C1505    1      A Q_CAP_C0402-0.1UF,16V,10%,X7R,CH4103K1B08    I74 @T6G_MB_LIB.T6G(SCH_1):PAGE149
  U146   10   DIR1 SN74AVC2T245RSWR-SN74AVC2T245RSWR,SMLF,IC,AL02T245A    I76 @T6G_MB_LIB.T6G(SCH_1):PAGE149
  U146    7   VCCA SN74AVC2T245RSWR-SN74AVC2T245RSWR,SMLF,IC,AL02T245A    I76 @T6G_MB_LIB.T6G(SCH_1):PAGE149
  U146    6   VCCB SN74AVC2T245RSWR-SN74AVC2T245RSWR,SMLF,IC,AL02T245A    I76 @T6G_MB_LIB.T6G(SCH_1):PAGE149
  R617    1      A Q_RES_0402LF-4.7K,5%,1/16W,CHIP,CS24702JB10   I101 @T6G_MB_LIB.T6G(SCH_1):PAGE149
 R1624    1      A Q_RES_0402LF-1K,1%,1/16W,CHIP,CS21002FB06   I111 @T6G_MB_LIB.T6G(SCH_1):PAGE149
 R1626    1      A Q_RES_0402LF-1K,1%,1/16W,CHIP,CS21002FB06   I115 @T6G_MB_LIB.T6G(SCH_1):PAGE149
 R1627    1      A Q_RES_0402LF-1K,1%,1/16W,CHIP,CS21002FB06   I116 @T6G_MB_LIB.T6G(SCH_1):PAGE149
 R1628    1      A Q_RES_0402LF-1K,1%,1/16W,CHIP,CS21002FB06   I117 @T6G_MB_LIB.T6G(SCH_1):PAGE149
 R1630    1      A Q_RES_0402LF-1K,1%,1/16W,CHIP,CS21002FB06   I118 @T6G_MB_LIB.T6G(SCH_1):PAGE149
   J54    1      1 SCONN20_HSU2101L00007H-SCONN20_HSU2101-L0000-7H,SMA   I142 @T6G_MB_LIB.T6G(SCH_1):PAGE149
   J54   19     19 SCONN20_HSU2101L00007H-SCONN20_HSU2101-L0000-7H,SMA   I142 @T6G_MB_LIB.T6G(SCH_1):PAGE149
 R1621    1      A Q_RES_0402LF-1K,1%,1/16W,CHIP,CS21002FB06   I146 @T6G_MB_LIB.T6G(SCH_1):PAGE149
  U150    1   DIR1 SN74AVC4T774PWR-SN74AVC4T774PWR,SMLF,IC,AL04T774K00     I8 @T6G_MB_LIB.T6G(SCH_1):PAGE150
  U150    2   DIR2 SN74AVC4T774PWR-SN74AVC4T774PWR,SMLF,IC,AL04T774K00     I8 @T6G_MB_LIB.T6G(SCH_1):PAGE150
  U150    7   DIR3 SN74AVC4T774PWR-SN74AVC4T774PWR,SMLF,IC,AL04T774K00     I8 @T6G_MB_LIB.T6G(SCH_1):PAGE150
  U150    8   DIR4 SN74AVC4T774PWR-SN74AVC4T774PWR,SMLF,IC,AL04T774K00     I8 @T6G_MB_LIB.T6G(SCH_1):PAGE150
  U150   16   VCCA SN74AVC4T774PWR-SN74AVC4T774PWR,SMLF,IC,AL04T774K00     I8 @T6G_MB_LIB.T6G(SCH_1):PAGE150
  U150   15   VCCB SN74AVC4T774PWR-SN74AVC4T774PWR,SMLF,IC,AL04T774K00     I8 @T6G_MB_LIB.T6G(SCH_1):PAGE150
 C1516    1      A Q_CAP_C0402-0.1UF,16V,10%,X7R,CH4103K1B08    I14 @T6G_MB_LIB.T6G(SCH_1):PAGE150
 C1514    1      A Q_CAP_C0402-0.1UF,16V,10%,X7R,CH4103K1B08    I19 @T6G_MB_LIB.T6G(SCH_1):PAGE150
  U151    1   DIR1 SN74AVC4T774PWR-SN74AVC4T774PWR,SMLF,IC,AL04T774K00    I28 @T6G_MB_LIB.T6G(SCH_1):PAGE150
  U151    2   DIR2 SN74AVC4T774PWR-SN74AVC4T774PWR,SMLF,IC,AL04T774K00    I28 @T6G_MB_LIB.T6G(SCH_1):PAGE150
  U151    7   DIR3 SN74AVC4T774PWR-SN74AVC4T774PWR,SMLF,IC,AL04T774K00    I28 @T6G_MB_LIB.T6G(SCH_1):PAGE150
  U151    8   DIR4 SN74AVC4T774PWR-SN74AVC4T774PWR,SMLF,IC,AL04T774K00    I28 @T6G_MB_LIB.T6G(SCH_1):PAGE150
  U151   16   VCCA SN74AVC4T774PWR-SN74AVC4T774PWR,SMLF,IC,AL04T774K00    I28 @T6G_MB_LIB.T6G(SCH_1):PAGE150
 C1515    1      A Q_CAP_C0402-0.1UF,16V,10%,X7R,CH4103K1B08    I43 @T6G_MB_LIB.T6G(SCH_1):PAGE150
  U152   10   DIR1 SN74AVC2T245RSWR-SN74AVC2T245RSWR,SMLF,IC,AL02T245A    I60 @T6G_MB_LIB.T6G(SCH_1):PAGE150
  U152    7   VCCA SN74AVC2T245RSWR-SN74AVC2T245RSWR,SMLF,IC,AL02T245A    I60 @T6G_MB_LIB.T6G(SCH_1):PAGE150
  U152    6   VCCB SN74AVC2T245RSWR-SN74AVC2T245RSWR,SMLF,IC,AL02T245A    I60 @T6G_MB_LIB.T6G(SCH_1):PAGE150
 C1518    1      A Q_CAP_C0402-0.1UF,16V,10%,X7R,CH4103K1B08    I66 @T6G_MB_LIB.T6G(SCH_1):PAGE150
 C1513    1      A Q_CAP_C0402-0.1UF,16V,10%,X7R,CH4103K1B08    I69 @T6G_MB_LIB.T6G(SCH_1):PAGE150
  U153    8    VCC SN74AUC2G66DCTR-SN74AUC2G66DCTR,SMLF,IC,AL2G0066C00     I1 @T6G_MB_LIB.T6G(SCH_1):PAGE151
 R1646    1      A Q_RES_0402LF-1K,1%,1/16W,CHIP,CS21002FB06    I10 @T6G_MB_LIB.T6G(SCH_1):PAGE151
 R1647    1      A Q_RES_0402LF-1K,1%,1/16W,CHIP,CS21002FB06    I11 @T6G_MB_LIB.T6G(SCH_1):PAGE151
 C1519    1      A Q_CAP_C0402-0.1UF,16V,10%,X7R,CH4103K1B08    I15 @T6G_MB_LIB.T6G(SCH_1):PAGE151
   U13    8    VCC SN74AUC2G66DCTR-SN74AUC2G66DCTR,SMLF,IC,AL2G0066C00    I17 @T6G_MB_LIB.T6G(SCH_1):PAGE151
 C1521    1      A Q_CAP_C0402-0.1UF,16V,10%,X7R,CH4103K1B08    I22 @T6G_MB_LIB.T6G(SCH_1):PAGE151
   U14    8    VCC SN74AUC2G66DCTR-SN74AUC2G66DCTR,SMLF,IC,AL2G0066C00    I23 @T6G_MB_LIB.T6G(SCH_1):PAGE151
 R1649    1      A Q_RES_0402LF-1K,1%,1/16W,CHIP,CS21002FB06    I25 @T6G_MB_LIB.T6G(SCH_1):PAGE151
 R1650    1      A Q_RES_0402LF-1K,1%,1/16W,CHIP,CS21002FB06    I27 @T6G_MB_LIB.T6G(SCH_1):PAGE151
  U154    8    VCC SN74AUC2G66DCTR-SN74AUC2G66DCTR,SMLF,IC,AL2G0066C00    I31 @T6G_MB_LIB.T6G(SCH_1):PAGE151
 C1522    1      A Q_CAP_C0402-0.1UF,16V,10%,X7R,CH4103K1B08    I36 @T6G_MB_LIB.T6G(SCH_1):PAGE151
 C1523    1      A Q_CAP_C0402-0.1UF,16V,10%,X7R,CH4103K1B08    I42 @T6G_MB_LIB.T6G(SCH_1):PAGE151
 R1503    1      A Q_RES_0402LF-30K,1%,1/16W,CHIP,CS33002FB02   I396 @T6G_MB_LIB.T6G(SCH_1):PAGE29
 R1504    1      A Q_RES_0402LF-30K,1%,1/16W,CHIP,CS33002FB02   I397 @T6G_MB_LIB.T6G(SCH_1):PAGE29
 R1505    1      A Q_RES_0402LF-30K,1%,1/16W,CHIP,CS33002FB02   I398 @T6G_MB_LIB.T6G(SCH_1):PAGE29
 R1506    1      A Q_RES_0402LF-30K,1%,1/16W,CHIP,CS33002FB02   I399 @T6G_MB_LIB.T6G(SCH_1):PAGE29
  R458    1      A Q_RES_0402LF-30K,1%,1/16W,EMPTY,CS33002FB02   I405 @T6G_MB_LIB.T6G(SCH_1):PAGE29
 R1532    1      A Q_RES_0402LF-1K,1%,1/16W,EMPTY,CS21002FB06   I131 @T6G_MB_LIB.T6G(SCH_1):PAGE76
 R1531    1      A Q_RES_0402LF-1K,1%,1/16W,EMPTY,CS21002FB06   I132 @T6G_MB_LIB.T6G(SCH_1):PAGE76
 R1530    1      A Q_RES_0402LF-1K,1%,1/16W,EMPTY,CS21002FB06   I133 @T6G_MB_LIB.T6G(SCH_1):PAGE76
 R1529    1      A Q_RES_0402LF-1K,1%,1/16W,EMPTY,CS21002FB06   I134 @T6G_MB_LIB.T6G(SCH_1):PAGE76
 R8317    1      A Q_RES_0402LF-1K,1%,1/16W,CHIP,CS21002FB06    I42 @T6G_MB_LIB.T6G(SCH_1):PAGE168
 PR128    2      B Q_RES_0402LF-1K,1%,1/16W,EMPTY,CS21002FB06    I68 @T6G_MB_LIB.T6G(SCH_1):PAGE182
 R1567    1      A Q_RES_0402LF-4.7K,5%,1/16W,CHIP,CS24702JB10   I150 @T6G_MB_LIB.T6G(SCH_1):PAGE76
  R367    1      A Q_RES_0402LF-1K,1%,1/16W,CHIP,CS21002FB06    I57 @T6G_MB_LIB.T6G(SCH_1):PAGE138
  C612    1      A Q_CAP_0402-0.1UF,25V,10%,X7R,CH4104K1B00     I8 @T6G_MB_LIB.T6G(SCH_1):PAGE137
  R368    1      A Q_RES_0402LF-4.7K,5%,1/16W,EMPTY,CS24702JB10    I44 @T6G_MB_LIB.T6G(SCH_1):PAGE137
  R406    1      A Q_RES_0402LF-4.7K,5%,1/16W,EMPTY,CS24702JB10    I46 @T6G_MB_LIB.T6G(SCH_1):PAGE137
  R443    2      B Q_RES_0402LF-1K,1%,1/16W,CHIP,CS21002FB06    I53 @T6G_MB_LIB.T6G(SCH_1):PAGE28
 PR284    1      A Q_RES_0402LF-1K,1%,1/16W,EMPTY,CS21002FB06    I10 @T6G_MB_LIB.T6G(SCH_1):PAGE168
 PC466    1      A Q_CAP_0402-1UF,6.3V,10%,X7R,CH5101K1B01    I52 @T6G_MB_LIB.T6G(SCH_1):PAGE168
 R8313    1      A Q_RES_0402LF-1K,1%,1/16W,CHIP,CS21002FB06    I54 @T6G_MB_LIB.T6G(SCH_1):PAGE168
 R8287    1      A Q_RES_0402LF-1K,1%,1/16W,EMPTY,CS21002FB06    I69 @T6G_MB_LIB.T6G(SCH_1):PAGE168
 R8289    1      A Q_RES_0402LF-1K,1%,1/16W,EMPTY,CS21002FB06    I70 @T6G_MB_LIB.T6G(SCH_1):PAGE168
 R8293    1      A Q_RES_0402LF-1K,1%,1/16W,EMPTY,CS21002FB06    I71 @T6G_MB_LIB.T6G(SCH_1):PAGE168
  PU42   19  VDDIO RAA229620GNPHA0-RAA229620GNP#HA0,SMLF,IC,ARF0TGP40A   I135 @T6G_MB_LIB.T6G(SCH_1):PAGE168
  PR41    1      A Q_RES_0402LF-1K,1%,1/16W,EMPTY,CS21002FB06    I40 @T6G_MB_LIB.T6G(SCH_1):PAGE175
 R8043    1      A Q_RES_0402LF-1K,1%,1/16W,EMPTY,CS21002FB06    I42 @T6G_MB_LIB.T6G(SCH_1):PAGE175
 R8045    1      A Q_RES_0402LF-1K,1%,1/16W,EMPTY,CS21002FB06    I43 @T6G_MB_LIB.T6G(SCH_1):PAGE175
 R8048    1      A Q_RES_0402LF-1K,1%,1/16W,EMPTY,CS21002FB06    I44 @T6G_MB_LIB.T6G(SCH_1):PAGE175
  PC73    1      A Q_CAP_0402-1UF,6.3V,10%,X7R,CH5101K1B01    I63 @T6G_MB_LIB.T6G(SCH_1):PAGE175
 R8070    1      A Q_RES_0402LF-1K,1%,1/16W,CHIP,CS21002FB06    I68 @T6G_MB_LIB.T6G(SCH_1):PAGE175
 R8075    1      A Q_RES_0402LF-1K,1%,1/16W,CHIP,CS21002FB06    I71 @T6G_MB_LIB.T6G(SCH_1):PAGE175
  PU12   19  VDDIO RAA229620GNPHA0-RAA229620GNP#HA0,SMLF,IC,ARF0TGP40A   I128 @T6G_MB_LIB.T6G(SCH_1):PAGE175
  R124    1      A Q_RES_0402LF-1K,1%,1/16W,EMPTY,CS21002FB06    I25 @T6G_MB_LIB.T6G(SCH_1):PAGE182
  PL78    2      2 Q_INDUCTOR_SMLF-1.0UH/18A,IND,CV-10I0MZ01    I36 @T6G_MB_LIB.T6G(SCH_1):PAGE184
 PC114    1      A Q_CAP_C0805-22UF,4V,20%,X6S,CH622KMEA03    I39 @T6G_MB_LIB.T6G(SCH_1):PAGE184
 PC288    1      A Q_CAP_C0805-22UF,4V,20%,X6S,CH622KMEA03    I40 @T6G_MB_LIB.T6G(SCH_1):PAGE184
 PC260    1      A Q_CAP_C0805-22UF,4V,20%,EMPTY,CH622KMEA03    I41 @T6G_MB_LIB.T6G(SCH_1):PAGE184
 PR438    2      B Q_RES_0402LF-49.9,1%,1/16W,CHIP,CS04992FB07    I42 @T6G_MB_LIB.T6G(SCH_1):PAGE184
 PC261    1      A Q_CAP_C0805-22UF,4V,20%,EMPTY,CH622KMEA03    I46 @T6G_MB_LIB.T6G(SCH_1):PAGE184
 PC115    1      A Q_CAPP_SMLF-390UF,2.5V,20%,ALUM,CC7390JMZ13    I47 @T6G_MB_LIB.T6G(SCH_1):PAGE184
 PC215    1      A Q_CAP_0402-0.1UF,25V,10%,X7R,CH4104K1B00    I48 @T6G_MB_LIB.T6G(SCH_1):PAGE184
 PR439    1      A Q_RES_0402LF-1K,1%,1/16W,CHIP,CS21002FB06    I51 @T6G_MB_LIB.T6G(SCH_1):PAGE184
 PC285    1      A Q_CAP_C0805-22UF,4V,20%,X6S,CH622KMEA03    I54 @T6G_MB_LIB.T6G(SCH_1):PAGE184
 R1351    2      B Q_RES_0402LF-2.2K,5%,1/16W,CHIP,CS22202JB07    I72 @T6G_MB_LIB.T6G(SCH_1):PAGE82
 R1288    2      B Q_RES_0402LF-4.7K,5%,1/16W,CHIP,CS24702JB10    I73 @T6G_MB_LIB.T6G(SCH_1):PAGE82
 R1287    2      B Q_RES_0402LF-4.7K,5%,1/16W,CHIP,CS24702JB10    I74 @T6G_MB_LIB.T6G(SCH_1):PAGE82
 R6122    1      A Q_RES_0402LF-1K,1%,1/16W,EMPTY,CS21002FB06    I50 @T6G_MB_LIB.T6G(SCH_1):PAGE83
  R633    1      A Q_RES_0402LF-2.2K,5%,1/16W,CHIP,CS22202JB07    I17 @T6G_MB_LIB.T6G(SCH_1):PAGE349
  R632    1      A Q_RES_0402LF-2.2K,5%,1/16W,CHIP,CS22202JB07    I18 @T6G_MB_LIB.T6G(SCH_1):PAGE349
  R422    1      A Q_RES_0402LF-2.2K,5%,1/16W,CHIP,CS22202JB07    I29 @T6G_MB_LIB.T6G(SCH_1):PAGE28
  R424    1      A Q_RES_0402LF-2.2K,5%,1/16W,CHIP,CS22202JB07    I30 @T6G_MB_LIB.T6G(SCH_1):PAGE28
  R581    2      B Q_RES_0402LF-4.7K,5%,1/16W,EMPTY,CS24702JB10    I34 @T6G_MB_LIB.T6G(SCH_1):PAGE28
  R276    2      B Q_RES_0402LF-4.7K,5%,1/16W,CHIP,CS24702JB10    I41 @T6G_MB_LIB.T6G(SCH_1):PAGE28
  R288    2      B Q_RES_0402LF-4.7K,5%,1/16W,EMPTY,CS24702JB10    I42 @T6G_MB_LIB.T6G(SCH_1):PAGE28
  R444    2      B Q_RES_0402LF-4.7K,5%,1/16W,CHIP,CS24702JB10    I43 @T6G_MB_LIB.T6G(SCH_1):PAGE28
  R207    2      B Q_RES_0402LF-2.2K,5%,1/16W,CHIP,CS22202JB07    I44 @T6G_MB_LIB.T6G(SCH_1):PAGE28
  R452    2      B Q_RES_0402LF-4.7K,5%,1/16W,CHIP,CS24702JB10    I45 @T6G_MB_LIB.T6G(SCH_1):PAGE28
  R451    2      B Q_RES_0402LF-4.7K,5%,1/16W,CHIP,CS24702JB10    I46 @T6G_MB_LIB.T6G(SCH_1):PAGE28
  R450    2      B Q_RES_0402LF-4.7K,5%,1/16W,CHIP,CS24702JB10    I47 @T6G_MB_LIB.T6G(SCH_1):PAGE28
  R449    2      B Q_RES_0402LF-4.7K,5%,1/16W,EMPTY,CS24702JB10    I48 @T6G_MB_LIB.T6G(SCH_1):PAGE28
  R448    2      B Q_RES_0402LF-4.7K,5%,1/16W,EMPTY,CS24702JB10    I49 @T6G_MB_LIB.T6G(SCH_1):PAGE28
  R441    2      B Q_RES_0402LF-2.2K,5%,1/16W,CHIP,CS22202JB07    I55 @T6G_MB_LIB.T6G(SCH_1):PAGE28
  R442    2      B Q_RES_0402LF-1K,1%,1/16W,CHIP,CS21002FB06    I56 @T6G_MB_LIB.T6G(SCH_1):PAGE28
  R446    2      B Q_RES_0402LF-4.7K,5%,1/16W,CHIP,CS24702JB10    I64 @T6G_MB_LIB.T6G(SCH_1):PAGE28
  R447    2      B Q_RES_0402LF-4.7K,5%,1/16W,CHIP,CS24702JB10    I65 @T6G_MB_LIB.T6G(SCH_1):PAGE28
  R445    2      B Q_RES_0402LF-4.7K,5%,1/16W,CHIP,CS24702JB10    I66 @T6G_MB_LIB.T6G(SCH_1):PAGE28
  R938    2      B Q_RES_0402LF-4.7K,5%,1/16W,CHIP,CS24702JB10    I69 @T6G_MB_LIB.T6G(SCH_1):PAGE28
  R437    1      A Q_RES_0402LF-2.2K,5%,1/16W,CHIP,CS22202JB07    I18 @T6G_MB_LIB.T6G(SCH_1):PAGE132
  R743    1      A Q_RES_0402LF-10K,5%,1/16W,CHIP,CS31002JB08    I97 @T6G_MB_LIB.T6G(SCH_1):PAGE75
 R6106    1      A Q_RES_0402LF-10K,5%,1/16W,CHIP,CS31002JB08    I81 @T6G_MB_LIB.T6G(SCH_1):PAGE144
 R6107    1      A Q_RES_0402LF-10K,5%,1/16W,CHIP,CS31002JB08    I83 @T6G_MB_LIB.T6G(SCH_1):PAGE144
 R6123    1      A Q_RES_0402LF-1K,1%,1/16W,EMPTY,CS21002FB06    I71 @T6G_MB_LIB.T6G(SCH_1):PAGE83
 R6124    1      A Q_RES_0402LF-1K,1%,1/16W,EMPTY,CS21002FB06    I72 @T6G_MB_LIB.T6G(SCH_1):PAGE83
   U96    1   VCCA PCA9617ADP-PCA9617ADP,SMLF,IC,AL009617K02    I51 @T6G_MB_LIB.T6G(SCH_1):PAGE137
 R6120    1      A Q_RES_0402LF-1K,1%,1/16W,CHIP,CS21002FB06   I115 @T6G_MB_LIB.T6G(SCH_1):PAGE83
 R6121    1      A Q_RES_0402LF-1K,1%,1/16W,EMPTY,CS21002FB06   I120 @T6G_MB_LIB.T6G(SCH_1):PAGE83
  R438    2      B Q_RES_0402LF-4.7K,5%,1/16W,EMPTY,CS24702JB10   I222 @T6G_MB_LIB.T6G(SCH_1):PAGE28
 R8036    1      A Q_RES_0402LF-4.7K,5%,1/16W,EMPTY,CS24702JB10    I12 @T6G_MB_LIB.T6G(SCH_1):PAGE130
 R1233    1      A Q_RES_0402LF-5.11K,1%,1/16W,CHIP,CS25112FB04   I227 @T6G_MB_LIB.T6G(SCH_1):PAGE263
  U213    5    VDD IML3112Y2B000NCG8-IML3112-Y2B000NCG8,SMLF,EMPTY,ALA   I111 @T6G_MB_LIB.T6G(SCH_1):PAGE138
   C24    1      A Q_CAP_C0402-10UF,6.3V,20%,EMPTY,CH6101MEB01   I112 @T6G_MB_LIB.T6G(SCH_1):PAGE138
 R6130    1      A Q_RES_0402LF-1K,1%,1/16W,CHIP,CS21002FB06   I131 @T6G_MB_LIB.T6G(SCH_1):PAGE83
 R6131    1      A Q_RES_0402LF-1K,1%,1/16W,EMPTY,CS21002FB06   I134 @T6G_MB_LIB.T6G(SCH_1):PAGE83
 R6132    1      A Q_RES_0402LF-1K,1%,1/16W,EMPTY,CS21002FB06   I135 @T6G_MB_LIB.T6G(SCH_1):PAGE83

PVDD18_S5_P0_ADC @T6G_MB_LIB.T6G(SCH_1):PVDD18_S5_P0_ADC
 R1247    1      A Q_RES_0402LF-0,5%,1/16W,EMPTY,CS00002JB13   I225 @T6G_MB_LIB.T6G(SCH_1):PAGE263
 R1254    1      A Q_RES_0402LF-0,5%,1/16W,CHIP,CS00002JB13   I226 @T6G_MB_LIB.T6G(SCH_1):PAGE263
 R1233    2      B Q_RES_0402LF-5.11K,1%,1/16W,CHIP,CS25112FB04   I227 @T6G_MB_LIB.T6G(SCH_1):PAGE263
 R1222    1      A Q_RES_0402LF-18K,1%,1/16W,CHIP,CS31802FB04   I246 @T6G_MB_LIB.T6G(SCH_1):PAGE263

PVDD18_S5_P0_ADC_MAM @T6G_MB_LIB.T6G(SCH_1):PVDD18_S5_P0_ADC_MAM
   U50   11   AIN6 MAX11617EEET-MAX11617EEE+T,SMLF,EMPTY,AL011617W00   I156 @T6G_MB_LIB.T6G(SCH_1):PAGE263
 C1080    1      A Q_CAP_0402-100PF,50V,5%,EMPTY,CH11006JB18   I221 @T6G_MB_LIB.T6G(SCH_1):PAGE263
 R1247    2      B Q_RES_0402LF-0,5%,1/16W,EMPTY,CS00002JB13   I225 @T6G_MB_LIB.T6G(SCH_1):PAGE263

PVDD18_S5_P0_ADC_TIC @T6G_MB_LIB.T6G(SCH_1):PVDD18_S5_P0_ADC_TIC
   U51   10    IN6 ADC128D818CIMTXNOPB-ADC128D818CIMTX/NOPB,SMLF,IC,AA   I142 @T6G_MB_LIB.T6G(SCH_1):PAGE263
 C1088    1      A Q_CAP_0402-0.1UF,25V,10%,X7R,CH4104K1B00   I223 @T6G_MB_LIB.T6G(SCH_1):PAGE263
 R1254    2      B Q_RES_0402LF-0,5%,1/16W,CHIP,CS00002JB13   I226 @T6G_MB_LIB.T6G(SCH_1):PAGE263

PVDD18_S5_P0_CS @T6G_MB_LIB.T6G(SCH_1):PVDD18_S5_P0_CS
 PR448    1      A Q_RES_0402LF-8.66K,1%,1/16W,CHIP,CS28662FB02    I17 @T6G_MB_LIB.T6G(SCH_1):PAGE184
  PU57    3     CS MPQ8633BGLEC838Z-MPQ8633BGLE-C838-Z,SMLF,IC,AL0086A    I18 @T6G_MB_LIB.T6G(SCH_1):PAGE184

PVDD18_S5_P0_EN @T6G_MB_LIB.T6G(SCH_1):PVDD18_S5_P0_EN
  R176    1      A Q_RES_0402LF-33,5%,1/16W,CHIP,CS03302JB10    I33 @T6G_MB_LIB.T6G(SCH_1):PAGE80
  C674    1      A Q_CAP_0402-0.1UF,25V,10%,EMPTY,CH4104K1B00     I4 @T6G_MB_LIB.T6G(SCH_1):PAGE184
  PU57    8     EN MPQ8633BGLEC838Z-MPQ8633BGLE-C838-Z,SMLF,IC,AL0086A    I18 @T6G_MB_LIB.T6G(SCH_1):PAGE184

PVDD18_S5_P0_FB @T6G_MB_LIB.T6G(SCH_1):PVDD18_S5_P0_FB
  PU57    7     FB MPQ8633BGLEC838Z-MPQ8633BGLE-C838-Z,SMLF,IC,AL0086A    I18 @T6G_MB_LIB.T6G(SCH_1):PAGE184
 PR470    1      A Q_RES_0402LF-10K,1%,1/16W,CHIP,CS31002FB08    I23 @T6G_MB_LIB.T6G(SCH_1):PAGE184
 PC259    1      A Q_CAP_0402-220PF,50V,10%,X7R,TMP_QCH12206KB14    I33 @T6G_MB_LIB.T6G(SCH_1):PAGE184
 PR471    1      A Q_RES_0402LF-20K,1%,1/16W,CHIP,CS32002FB06    I35 @T6G_MB_LIB.T6G(SCH_1):PAGE184

PVDD18_S5_P0_FB_RC @T6G_MB_LIB.T6G(SCH_1):PVDD18_S5_P0_FB_RC
 PC259    2      B Q_CAP_0402-220PF,50V,10%,X7R,TMP_QCH12206KB14    I33 @T6G_MB_LIB.T6G(SCH_1):PAGE184
PC6005    1      A Q_CAP_C0402-0.01UF,25V,10%,EMPTY,CH3104K1B11    I34 @T6G_MB_LIB.T6G(SCH_1):PAGE184
 PR471    2      B Q_RES_0402LF-20K,1%,1/16W,CHIP,CS32002FB06    I35 @T6G_MB_LIB.T6G(SCH_1):PAGE184
 PR434    1      A Q_RES_0402LF-10,1%,1/16W,CHIP,CS01002FB07    I38 @T6G_MB_LIB.T6G(SCH_1):PAGE184
 PR438    1      A Q_RES_0402LF-49.9,1%,1/16W,CHIP,CS04992FB07    I42 @T6G_MB_LIB.T6G(SCH_1):PAGE184

PVDD18_S5_P0_MODE @T6G_MB_LIB.T6G(SCH_1):PVDD18_S5_P0_MODE
 PR417    2      B Q_RES_0402LF-0,5%,1/16W,CHIP,CS00002JB13    I15 @T6G_MB_LIB.T6G(SCH_1):PAGE184
  PU57    4   MODE MPQ8633BGLEC838Z-MPQ8633BGLE-C838-Z,SMLF,IC,AL0086A    I18 @T6G_MB_LIB.T6G(SCH_1):PAGE184

PVDD18_S5_P0_REF @T6G_MB_LIB.T6G(SCH_1):PVDD18_S5_P0_REF
  PU57    5 TRK_REF MPQ8633BGLEC838Z-MPQ8633BGLE-C838-Z,SMLF,IC,AL0086A    I18 @T6G_MB_LIB.T6G(SCH_1):PAGE184
 PC258    1      A Q_CAP_0402-0.022UF,25V,10%,X7R,CH3224K1B01    I21 @T6G_MB_LIB.T6G(SCH_1):PAGE184
 PC113    1      A Q_CAP_0402-0.1UF,25V,10%,X7R,CH4104K1B00    I22 @T6G_MB_LIB.T6G(SCH_1):PAGE184

PVDD18_S5_P0_RGND @T6G_MB_LIB.T6G(SCH_1):PVDD18_S5_P0_RGND
  PU57    6   RGND MPQ8633BGLEC838Z-MPQ8633BGLE-C838-Z,SMLF,IC,AL0086A    I18 @T6G_MB_LIB.T6G(SCH_1):PAGE184
 PC113    2      B Q_CAP_0402-0.1UF,25V,10%,X7R,CH4104K1B00    I22 @T6G_MB_LIB.T6G(SCH_1):PAGE184
 PR470    2      B Q_RES_0402LF-10K,1%,1/16W,CHIP,CS31002FB08    I23 @T6G_MB_LIB.T6G(SCH_1):PAGE184
 PR418    2      B Q_RES_0402LF-49.9,1%,1/16W,CHIP,CS04992FB07    I31 @T6G_MB_LIB.T6G(SCH_1):PAGE184
PC6005    2      B Q_CAP_C0402-0.01UF,25V,10%,EMPTY,CH3104K1B11    I34 @T6G_MB_LIB.T6G(SCH_1):PAGE184
 PR435    1      A Q_RES_0402LF-0,5%,1/16W,CHIP,CS00002JB13    I37 @T6G_MB_LIB.T6G(SCH_1):PAGE184

PVDD18_S5_P0_VCC @T6G_MB_LIB.T6G(SCH_1):PVDD18_S5_P0_VCC
 PC212    1      A Q_CAP_C0402-1UF,25V,10%,X6S,CH5104KEB02    I11 @T6G_MB_LIB.T6G(SCH_1):PAGE184
 PR477    2      B Q_RES_0402LF-0,5%,1/16W,CHIP,CS00002JB13    I12 @T6G_MB_LIB.T6G(SCH_1):PAGE184
  PU57   19    VCC MPQ8633BGLEC838Z-MPQ8633BGLE-C838-Z,SMLF,IC,AL0086A    I18 @T6G_MB_LIB.T6G(SCH_1):PAGE184

PVDD18_S5_P1 @T6G_MB_LIB.T6G(SCH_1):PVDD18_S5_P1
  R528    1      A Q_RES_0402LF-1K,1%,1/16W,CHIP,CS21002FB06   I308 @T6G_MB_LIB.T6G(SCH_1):PAGE54
  R527    1      A Q_RES_0402LF-1K,1%,1/16W,CHIP,CS21002FB06   I309 @T6G_MB_LIB.T6G(SCH_1):PAGE54
  R526    1      A Q_RES_0402LF-1K,1%,1/16W,CHIP,CS21002FB06   I314 @T6G_MB_LIB.T6G(SCH_1):PAGE54
  R525    1      A Q_RES_0402LF-1K,1%,1/16W,CHIP,CS21002FB06   I316 @T6G_MB_LIB.T6G(SCH_1):PAGE54
  R524    1      A Q_RES_0402LF-1K,1%,1/16W,CHIP,CS21002FB06   I317 @T6G_MB_LIB.T6G(SCH_1):PAGE54
  R523    1      A Q_RES_0402LF-1K,1%,1/16W,CHIP,CS21002FB06   I324 @T6G_MB_LIB.T6G(SCH_1):PAGE54
  R520    2      B Q_RES_0402LF-2.2K,5%,1/16W,CHIP,CS22202JB07   I396 @T6G_MB_LIB.T6G(SCH_1):PAGE54
  R535    2      B Q_RES_0402LF-2.2K,5%,1/16W,CHIP,CS22202JB07   I398 @T6G_MB_LIB.T6G(SCH_1):PAGE54
  R518    1      A Q_RES_0402LF-2.2K,5%,1/16W,CHIP,CS22202JB07   I403 @T6G_MB_LIB.T6G(SCH_1):PAGE54
 R1424    1      A Q_RES_0402LF-2.2K,5%,1/16W,CHIP,CS22202JB07   I292 @T6G_MB_LIB.T6G(SCH_1):PAGE55
   U26 AR52 VDD_18_S5_AR52 GENOA_SP5-SOCKET6096_13568-001,SMLF,IO,DGA^6000030    I45 @T6G_MB_LIB.T6G(SCH_1):PAGE57
   U26 AR54 VDD_18_S5_AR54 GENOA_SP5-SOCKET6096_13568-001,SMLF,IO,DGA^6000030    I45 @T6G_MB_LIB.T6G(SCH_1):PAGE57
   U26 AT51 VDD_18_S5_AT51 GENOA_SP5-SOCKET6096_13568-001,SMLF,IO,DGA^6000030    I45 @T6G_MB_LIB.T6G(SCH_1):PAGE57
   U26 AT53 VDD_18_S5_AT53 GENOA_SP5-SOCKET6096_13568-001,SMLF,IO,DGA^6000030    I45 @T6G_MB_LIB.T6G(SCH_1):PAGE57
   U26 AU50 VDD_18_S5_AU50 GENOA_SP5-SOCKET6096_13568-001,SMLF,IO,DGA^6000030    I45 @T6G_MB_LIB.T6G(SCH_1):PAGE57
   U26 AU52 VDD_18_S5_AU52 GENOA_SP5-SOCKET6096_13568-001,SMLF,IO,DGA^6000030    I45 @T6G_MB_LIB.T6G(SCH_1):PAGE57
   U26 AU54 VDD_18_S5_AU54 GENOA_SP5-SOCKET6096_13568-001,SMLF,IO,DGA^6000030    I45 @T6G_MB_LIB.T6G(SCH_1):PAGE57
   U26 AV49 VDD_18_S5_AV49 GENOA_SP5-SOCKET6096_13568-001,SMLF,IO,DGA^6000030    I45 @T6G_MB_LIB.T6G(SCH_1):PAGE57
   U26 AV51 VDD_18_S5_AV51 GENOA_SP5-SOCKET6096_13568-001,SMLF,IO,DGA^6000030    I45 @T6G_MB_LIB.T6G(SCH_1):PAGE57
   U26 AV53 VDD_18_S5_AV53 GENOA_SP5-SOCKET6096_13568-001,SMLF,IO,DGA^6000030    I45 @T6G_MB_LIB.T6G(SCH_1):PAGE57
   U26 AW50 VDD_18_S5_AW50 GENOA_SP5-SOCKET6096_13568-001,SMLF,IO,DGA^6000030    I45 @T6G_MB_LIB.T6G(SCH_1):PAGE57
   U26 AW52 VDD_18_S5_AW52 GENOA_SP5-SOCKET6096_13568-001,SMLF,IO,DGA^6000030    I45 @T6G_MB_LIB.T6G(SCH_1):PAGE57
   U26 AW54 VDD_18_S5_AW54 GENOA_SP5-SOCKET6096_13568-001,SMLF,IO,DGA^6000030    I45 @T6G_MB_LIB.T6G(SCH_1):PAGE57
   U26 AY51 VDD_18_S5_AY51 GENOA_SP5-SOCKET6096_13568-001,SMLF,IO,DGA^6000030    I45 @T6G_MB_LIB.T6G(SCH_1):PAGE57
   U26 AY53 VDD_18_S5_AY53 GENOA_SP5-SOCKET6096_13568-001,SMLF,IO,DGA^6000030    I45 @T6G_MB_LIB.T6G(SCH_1):PAGE57
   U26 BA50 VDD_18_S5_BA50 GENOA_SP5-SOCKET6096_13568-001,SMLF,IO,DGA^6000030    I45 @T6G_MB_LIB.T6G(SCH_1):PAGE57
   U26 BA52 VDD_18_S5_BA52 GENOA_SP5-SOCKET6096_13568-001,SMLF,IO,DGA^6000030    I45 @T6G_MB_LIB.T6G(SCH_1):PAGE57
   U26 BA54 VDD_18_S5_BA54 GENOA_SP5-SOCKET6096_13568-001,SMLF,IO,DGA^6000030    I45 @T6G_MB_LIB.T6G(SCH_1):PAGE57
   U26 BB51 VDD_18_S5_BB51 GENOA_SP5-SOCKET6096_13568-001,SMLF,IO,DGA^6000030    I45 @T6G_MB_LIB.T6G(SCH_1):PAGE57
   U26 BB53 VDD_18_S5_BB53 GENOA_SP5-SOCKET6096_13568-001,SMLF,IO,DGA^6000030    I45 @T6G_MB_LIB.T6G(SCH_1):PAGE57
   U26 BC52 VDD_18_S5_BC52 GENOA_SP5-SOCKET6096_13568-001,SMLF,IO,DGA^6000030    I45 @T6G_MB_LIB.T6G(SCH_1):PAGE57
   U26 BC54 VDD_18_S5_BC54 GENOA_SP5-SOCKET6096_13568-001,SMLF,IO,DGA^6000030    I45 @T6G_MB_LIB.T6G(SCH_1):PAGE57
   U26 BH27 VDDIO_AUDIO GENOA_SP5-SOCKET6096_13568-001,SMLF,IO,DGA^6000030    I45 @T6G_MB_LIB.T6G(SCH_1):PAGE57
  R374    1      A Q_RES_0402LF-0,5%,1/16W,CHIP,CS00002JB13    I51 @T6G_MB_LIB.T6G(SCH_1):PAGE57
 C2292    1      A Q_CAP_C0402-22UF,4V,20%,X6S,CH622KMEB02    I49 @T6G_MB_LIB.T6G(SCH_1):PAGE71
 C2293    1      A Q_CAP_C0402-22UF,4V,20%,X6S,CH622KMEB02    I50 @T6G_MB_LIB.T6G(SCH_1):PAGE71
 C3909    1      A Q_CAP_C0402-22UF,4V,20%,X6S,CH622KMEB02    I52 @T6G_MB_LIB.T6G(SCH_1):PAGE71
 C2661    1      A Q_CAP_C0402-22UF,4V,20%,X6S,CH622KMEB02     I1 @T6G_MB_LIB.T6G(SCH_1):PAGE74
 C2660    1      A Q_CAP_C0402-22UF,4V,20%,X6S,CH622KMEB02     I3 @T6G_MB_LIB.T6G(SCH_1):PAGE74
 C2664    1      A Q_CAP_C0402-22UF,4V,20%,X6S,CH622KMEB02     I8 @T6G_MB_LIB.T6G(SCH_1):PAGE74
 C2663    1      A Q_CAP_C0402-22UF,4V,20%,X6S,CH622KMEB02     I9 @T6G_MB_LIB.T6G(SCH_1):PAGE74
 C2665    1      A Q_CAP_C0402-22UF,4V,20%,X6S,CH622KMEB02    I10 @T6G_MB_LIB.T6G(SCH_1):PAGE74
 C2667    1      A Q_CAP_C0402-22UF,4V,20%,X6S,CH622KMEB02    I11 @T6G_MB_LIB.T6G(SCH_1):PAGE74
 C2668    1      A Q_CAP_C0402-22UF,4V,20%,X6S,CH622KMEB02    I12 @T6G_MB_LIB.T6G(SCH_1):PAGE74
 C2669    1      A Q_CAP_C0402-22UF,4V,20%,X6S,CH622KMEB02    I13 @T6G_MB_LIB.T6G(SCH_1):PAGE74
 C2670    1      A Q_CAP_C0402-22UF,4V,20%,X6S,CH622KMEB02    I14 @T6G_MB_LIB.T6G(SCH_1):PAGE74
 C2671    1      A Q_CAP_C0402-22UF,4V,20%,X6S,CH622KMEB02    I15 @T6G_MB_LIB.T6G(SCH_1):PAGE74
 C2672    1      A Q_CAP_C0402-22UF,4V,20%,X6S,CH622KMEB02    I16 @T6G_MB_LIB.T6G(SCH_1):PAGE74
 C2673    1      A Q_CAP_C0402-22UF,4V,20%,X6S,CH622KMEB02    I18 @T6G_MB_LIB.T6G(SCH_1):PAGE74
  R366    1      A Q_RES_0402LF-1K,1%,1/16W,CHIP,CS21002FB06    I54 @T6G_MB_LIB.T6G(SCH_1):PAGE138
  R369    1      A Q_RES_0402LF-1K,1%,1/16W,CHIP,CS21002FB06    I58 @T6G_MB_LIB.T6G(SCH_1):PAGE138
  U151   15   VCCB SN74AVC4T774PWR-SN74AVC4T774PWR,SMLF,IC,AL04T774K00    I28 @T6G_MB_LIB.T6G(SCH_1):PAGE150
 C1517    1      A Q_CAP_C0402-0.1UF,16V,10%,X7R,CH4103K1B08    I40 @T6G_MB_LIB.T6G(SCH_1):PAGE150
  R531    2      B Q_RES_0402LF-2.2K,5%,1/16W,CHIP,CS22202JB07   I406 @T6G_MB_LIB.T6G(SCH_1):PAGE54
  R532    2      B Q_RES_0402LF-2.2K,5%,1/16W,CHIP,CS22202JB07   I407 @T6G_MB_LIB.T6G(SCH_1):PAGE54
  R533    2      B Q_RES_0402LF-2.2K,5%,1/16W,CHIP,CS22202JB07   I408 @T6G_MB_LIB.T6G(SCH_1):PAGE54
  R534    2      B Q_RES_0402LF-2.2K,5%,1/16W,CHIP,CS22202JB07   I409 @T6G_MB_LIB.T6G(SCH_1):PAGE54
  R537    2      B Q_RES_0402LF-2.2K,5%,1/16W,CHIP,CS22202JB07   I410 @T6G_MB_LIB.T6G(SCH_1):PAGE54
  R538    2      B Q_RES_0402LF-2.2K,5%,1/16W,CHIP,CS22202JB07   I411 @T6G_MB_LIB.T6G(SCH_1):PAGE54
  R539    2      B Q_RES_0402LF-2.2K,5%,1/16W,CHIP,CS22202JB07   I412 @T6G_MB_LIB.T6G(SCH_1):PAGE54
  R540    2      B Q_RES_0402LF-2.2K,5%,1/16W,CHIP,CS22202JB07   I413 @T6G_MB_LIB.T6G(SCH_1):PAGE54
  PC65    1      A Q_CAP_C0805-22UF,4V,20%,X6S,CH622KMEA03    I37 @T6G_MB_LIB.T6G(SCH_1):PAGE201
  PC83    1      A Q_CAP_C0805-22UF,4V,20%,X6S,CH622KMEA03    I38 @T6G_MB_LIB.T6G(SCH_1):PAGE201
 PR402    1      A Q_RES_0402LF-49.9,1%,1/16W,CHIP,CS04992FB07    I39 @T6G_MB_LIB.T6G(SCH_1):PAGE201
  PC88    1      A Q_CAP_C0805-22UF,4V,20%,EMPTY,CH622KMEA03    I42 @T6G_MB_LIB.T6G(SCH_1):PAGE201
  PC89    1      A Q_CAPP_SMLF-390UF,2.5V,20%,ALUM,CC7390JMZ13    I43 @T6G_MB_LIB.T6G(SCH_1):PAGE201
 PR403    1      A Q_RES_0402LF-1K,1%,1/16W,CHIP,CS21002FB06    I50 @T6G_MB_LIB.T6G(SCH_1):PAGE201
  R730    1      A Q_RES_0402LF-10K,5%,1/16W,CHIP,CS31002JB08    I87 @T6G_MB_LIB.T6G(SCH_1):PAGE75
  R736    1      A Q_RES_0402LF-10K,5%,1/16W,EMPTY,CS31002JB08    I89 @T6G_MB_LIB.T6G(SCH_1):PAGE75
 R1501    1      A Q_RES_0402LF-10K,5%,1/16W,EMPTY,CS31002JB08    I90 @T6G_MB_LIB.T6G(SCH_1):PAGE75
  R154    1      A Q_RES_0402LF-1K,1%,1/16W,EMPTY,CS21002FB06    I67 @T6G_MB_LIB.T6G(SCH_1):PAGE185
 R8156    1      A Q_RES_0402LF-1K,1%,1/16W,EMPTY,CS21002FB06    I68 @T6G_MB_LIB.T6G(SCH_1):PAGE185
 R1286    2      B Q_RES_0402LF-4.7K,5%,1/16W,CHIP,CS24702JB10    I76 @T6G_MB_LIB.T6G(SCH_1):PAGE82
 R1285    2      B Q_RES_0402LF-4.7K,5%,1/16W,CHIP,CS24702JB10    I77 @T6G_MB_LIB.T6G(SCH_1):PAGE82
  R544    2      B Q_RES_0402LF-4.7K,5%,1/16W,CHIP,CS24702JB10   I336 @T6G_MB_LIB.T6G(SCH_1):PAGE55
  R545    2      B Q_RES_0402LF-4.7K,5%,1/16W,CHIP,CS24702JB10   I337 @T6G_MB_LIB.T6G(SCH_1):PAGE55
  R546    2      B Q_RES_0402LF-4.7K,5%,1/16W,CHIP,CS24702JB10   I338 @T6G_MB_LIB.T6G(SCH_1):PAGE55
  R456    2      B Q_RES_0402LF-4.7K,5%,1/16W,EMPTY,CS24702JB10   I339 @T6G_MB_LIB.T6G(SCH_1):PAGE55
  R583    2      B Q_RES_0402LF-4.7K,5%,1/16W,EMPTY,CS24702JB10   I342 @T6G_MB_LIB.T6G(SCH_1):PAGE55
  R548    2      B Q_RES_0402LF-4.7K,5%,1/16W,EMPTY,CS24702JB10   I352 @T6G_MB_LIB.T6G(SCH_1):PAGE55
  R549    2      B Q_RES_0402LF-4.7K,5%,1/16W,EMPTY,CS24702JB10   I353 @T6G_MB_LIB.T6G(SCH_1):PAGE55
  R562    1      A Q_RES_0402LF-2.2K,5%,1/16W,CHIP,CS22202JB07   I355 @T6G_MB_LIB.T6G(SCH_1):PAGE55
  R559    1      A Q_RES_0402LF-2.2K,5%,1/16W,CHIP,CS22202JB07   I356 @T6G_MB_LIB.T6G(SCH_1):PAGE55
  R556    1      A Q_RES_0402LF-1K,1%,1/16W,EMPTY,CS21002FB06   I357 @T6G_MB_LIB.T6G(SCH_1):PAGE55
  R553    2      B Q_RES_0402LF-4.7K,5%,1/16W,CHIP,CS24702JB10   I359 @T6G_MB_LIB.T6G(SCH_1):PAGE55
  R551    2      B Q_RES_0402LF-4.7K,5%,1/16W,CHIP,CS24702JB10   I360 @T6G_MB_LIB.T6G(SCH_1):PAGE55
  R547    2      B Q_RES_0402LF-4.7K,5%,1/16W,CHIP,CS24702JB10   I362 @T6G_MB_LIB.T6G(SCH_1):PAGE55
  R550    2      B Q_RES_0402LF-4.7K,5%,1/16W,CHIP,CS24702JB10   I363 @T6G_MB_LIB.T6G(SCH_1):PAGE55
  R557    1      A Q_RES_0402LF-1K,1%,1/16W,EMPTY,CS21002FB06   I364 @T6G_MB_LIB.T6G(SCH_1):PAGE55
 PR151    1      A Q_RES_0402LF-1K,1%,1/16W,EMPTY,CS21002FB06    I10 @T6G_MB_LIB.T6G(SCH_1):PAGE185
 R8184    1      A Q_RES_0402LF-1K,1%,1/16W,CHIP,CS21002FB06    I41 @T6G_MB_LIB.T6G(SCH_1):PAGE185
 R8180    1      A Q_RES_0402LF-1K,1%,1/16W,CHIP,CS21002FB06    I54 @T6G_MB_LIB.T6G(SCH_1):PAGE185
 R8160    1      A Q_RES_0402LF-1K,1%,1/16W,EMPTY,CS21002FB06    I69 @T6G_MB_LIB.T6G(SCH_1):PAGE185
 PC247    1      A Q_CAP_0402-1UF,6.3V,10%,X7R,CH5101K1B01   I132 @T6G_MB_LIB.T6G(SCH_1):PAGE185
  PU25   19  VDDIO RAA229620GNPHA0-RAA229620GNP#HA0,SMLF,IC,ARF0TGP40A   I133 @T6G_MB_LIB.T6G(SCH_1):PAGE185
 PR218    1      A Q_RES_0402LF-1K,1%,1/16W,EMPTY,CS21002FB06    I38 @T6G_MB_LIB.T6G(SCH_1):PAGE192
 R8220    1      A Q_RES_0402LF-1K,1%,1/16W,EMPTY,CS21002FB06    I40 @T6G_MB_LIB.T6G(SCH_1):PAGE192
 R8222    1      A Q_RES_0402LF-1K,1%,1/16W,EMPTY,CS21002FB06    I41 @T6G_MB_LIB.T6G(SCH_1):PAGE192
 R8225    1      A Q_RES_0402LF-1K,1%,1/16W,EMPTY,CS21002FB06    I42 @T6G_MB_LIB.T6G(SCH_1):PAGE192
 PC363    1      A Q_CAP_0402-1UF,6.3V,10%,X7R,CH5101K1B01    I60 @T6G_MB_LIB.T6G(SCH_1):PAGE192
 R8247    1      A Q_RES_0402LF-1K,1%,1/16W,CHIP,CS21002FB06    I66 @T6G_MB_LIB.T6G(SCH_1):PAGE192
 R8252    1      A Q_RES_0402LF-1K,1%,1/16W,CHIP,CS21002FB06    I71 @T6G_MB_LIB.T6G(SCH_1):PAGE192
  PU34   19  VDDIO RAA229620GNPHA0-RAA229620GNP#HA0,SMLF,IC,ARF0TGP40A   I128 @T6G_MB_LIB.T6G(SCH_1):PAGE192
 R8011    1      A Q_RES_0402LF-1K,1%,1/16W,EMPTY,CS21002FB06    I24 @T6G_MB_LIB.T6G(SCH_1):PAGE199
 PR391    2      B Q_RES_0402LF-1K,1%,1/16W,EMPTY,CS21002FB06    I67 @T6G_MB_LIB.T6G(SCH_1):PAGE199
  PL57    2      2 Q_INDUCTOR_SMLF-1.0UH/18A,IND,CV-10I0MZ01    I33 @T6G_MB_LIB.T6G(SCH_1):PAGE201
  PC84    1      A Q_CAP_C0805-22UF,4V,20%,X6S,CH622KMEA03    I40 @T6G_MB_LIB.T6G(SCH_1):PAGE201
  PC87    1      A Q_CAP_C0805-22UF,4V,20%,EMPTY,CH622KMEA03    I41 @T6G_MB_LIB.T6G(SCH_1):PAGE201
  PC21    1      A Q_CAP_0402-0.1UF,25V,10%,X7R,CH4104K1B00    I47 @T6G_MB_LIB.T6G(SCH_1):PAGE201
  R558    2      B Q_RES_0402LF-4.7K,5%,1/16W,EMPTY,CS24702JB10   I390 @T6G_MB_LIB.T6G(SCH_1):PAGE55
 R1236    1      A Q_RES_0402LF-5.11K,1%,1/16W,CHIP,CS25112FB04   I230 @T6G_MB_LIB.T6G(SCH_1):PAGE263
  R536    2      B Q_RES_0402LF-2.2K,5%,1/16W,EMPTY,CS22202JB07   I421 @T6G_MB_LIB.T6G(SCH_1):PAGE54

PVDD18_S5_P1_ADC @T6G_MB_LIB.T6G(SCH_1):PVDD18_S5_P1_ADC
 R1236    2      B Q_RES_0402LF-5.11K,1%,1/16W,CHIP,CS25112FB04   I230 @T6G_MB_LIB.T6G(SCH_1):PAGE263
 R1249    1      A Q_RES_0402LF-0,5%,1/16W,EMPTY,CS00002JB13   I231 @T6G_MB_LIB.T6G(SCH_1):PAGE263
 R1256    1      A Q_RES_0402LF-0,5%,1/16W,CHIP,CS00002JB13   I239 @T6G_MB_LIB.T6G(SCH_1):PAGE263
 R1225    1      A Q_RES_0402LF-18K,1%,1/16W,CHIP,CS31802FB04   I247 @T6G_MB_LIB.T6G(SCH_1):PAGE263

PVDD18_S5_P1_ADC_MAM @T6G_MB_LIB.T6G(SCH_1):PVDD18_S5_P1_ADC_MAM
   U50   12   AIN7 MAX11617EEET-MAX11617EEE+T,SMLF,EMPTY,AL011617W00   I156 @T6G_MB_LIB.T6G(SCH_1):PAGE263
 R1249    2      B Q_RES_0402LF-0,5%,1/16W,EMPTY,CS00002JB13   I231 @T6G_MB_LIB.T6G(SCH_1):PAGE263
 C1081    1      A Q_CAP_0402-100PF,50V,5%,EMPTY,CH11006JB18   I232 @T6G_MB_LIB.T6G(SCH_1):PAGE263

PVDD18_S5_P1_ADC_TIC @T6G_MB_LIB.T6G(SCH_1):PVDD18_S5_P1_ADC_TIC
   U51    9    IN7 ADC128D818CIMTXNOPB-ADC128D818CIMTX/NOPB,SMLF,IC,AA   I142 @T6G_MB_LIB.T6G(SCH_1):PAGE263
 C1090    1      A Q_CAP_0402-0.1UF,25V,10%,X7R,CH4104K1B00   I237 @T6G_MB_LIB.T6G(SCH_1):PAGE263
 R1256    2      B Q_RES_0402LF-0,5%,1/16W,CHIP,CS00002JB13   I239 @T6G_MB_LIB.T6G(SCH_1):PAGE263

PVDD18_S5_P1_CS @T6G_MB_LIB.T6G(SCH_1):PVDD18_S5_P1_CS
   PR8    1      A Q_RES_0402LF-8.66K,1%,1/16W,CHIP,CS28662FB02    I11 @T6G_MB_LIB.T6G(SCH_1):PAGE201
   PU3    3     CS MPQ8633BGLEC838Z-MPQ8633BGLE-C838-Z,SMLF,IC,AL0086A    I15 @T6G_MB_LIB.T6G(SCH_1):PAGE201

PVDD18_S5_P1_EN @T6G_MB_LIB.T6G(SCH_1):PVDD18_S5_P1_EN
  C675    1      A Q_CAP_0402-0.1UF,25V,10%,EMPTY,CH4104K1B00     I6 @T6G_MB_LIB.T6G(SCH_1):PAGE201
   PU3    8     EN MPQ8633BGLEC838Z-MPQ8633BGLE-C838-Z,SMLF,IC,AL0086A    I15 @T6G_MB_LIB.T6G(SCH_1):PAGE201
  R289    1      A Q_RES_0402LF-33,5%,1/16W,CHIP,CS03302JB10    I57 @T6G_MB_LIB.T6G(SCH_1):PAGE80

PVDD18_S5_P1_FB @T6G_MB_LIB.T6G(SCH_1):PVDD18_S5_P1_FB
   PU3    7     FB MPQ8633BGLEC838Z-MPQ8633BGLE-C838-Z,SMLF,IC,AL0086A    I15 @T6G_MB_LIB.T6G(SCH_1):PAGE201
 PR147    1      A Q_RES_0402LF-10K,1%,1/16W,CHIP,CS31002FB08    I30 @T6G_MB_LIB.T6G(SCH_1):PAGE201
  PC64    1      A Q_CAP_0402-220PF,50V,10%,X7R,TMP_QCH12206KB14    I31 @T6G_MB_LIB.T6G(SCH_1):PAGE201
 PR148    1      A Q_RES_0402LF-20K,1%,1/16W,CHIP,CS32002FB06    I32 @T6G_MB_LIB.T6G(SCH_1):PAGE201

PVDD18_S5_P1_FB_RC @T6G_MB_LIB.T6G(SCH_1):PVDD18_S5_P1_FB_RC
 PR402    2      B Q_RES_0402LF-49.9,1%,1/16W,CHIP,CS04992FB07    I39 @T6G_MB_LIB.T6G(SCH_1):PAGE201
  PC64    2      B Q_CAP_0402-220PF,50V,10%,X7R,TMP_QCH12206KB14    I31 @T6G_MB_LIB.T6G(SCH_1):PAGE201
 PR148    2      B Q_RES_0402LF-20K,1%,1/16W,CHIP,CS32002FB06    I32 @T6G_MB_LIB.T6G(SCH_1):PAGE201
PC6006    1      A Q_CAP_C0402-0.01UF,25V,10%,EMPTY,CH3104K1B11    I34 @T6G_MB_LIB.T6G(SCH_1):PAGE201
 PR400    1      A Q_RES_0402LF-10,1%,1/16W,CHIP,CS01002FB07    I36 @T6G_MB_LIB.T6G(SCH_1):PAGE201

PVDD18_S5_P1_MODE @T6G_MB_LIB.T6G(SCH_1):PVDD18_S5_P1_MODE
   PU3    4   MODE MPQ8633BGLEC838Z-MPQ8633BGLE-C838-Z,SMLF,IC,AL0086A    I15 @T6G_MB_LIB.T6G(SCH_1):PAGE201
 PR398    2      B Q_RES_0402LF-0,5%,1/16W,CHIP,CS00002JB13    I14 @T6G_MB_LIB.T6G(SCH_1):PAGE201

PVDD18_S5_P1_REF @T6G_MB_LIB.T6G(SCH_1):PVDD18_S5_P1_REF
   PU3    5 TRK_REF MPQ8633BGLEC838Z-MPQ8633BGLE-C838-Z,SMLF,IC,AL0086A    I15 @T6G_MB_LIB.T6G(SCH_1):PAGE201
 PC153    1      A Q_CAP_0402-0.022UF,25V,10%,X7R,CH3224K1B01    I18 @T6G_MB_LIB.T6G(SCH_1):PAGE201
  PC62    1      A Q_CAP_0402-0.1UF,25V,10%,X7R,CH4104K1B00    I19 @T6G_MB_LIB.T6G(SCH_1):PAGE201

PVDD18_S5_P1_R_EN @T6G_MB_LIB.T6G(SCH_1):PVDD18_S5_P1_R_EN
  R289    2      B Q_RES_0402LF-33,5%,1/16W,CHIP,CS03302JB10    I57 @T6G_MB_LIB.T6G(SCH_1):PAGE80
   U18   V8  PB13C LCMXO3LF9400C5BG484C-LCMXO3LF-9400C-5BG484C,SMLF,IA   I216 @T6G_MB_LIB.T6G(SCH_1):PAGE80

PVDD18_S5_P1_VCC @T6G_MB_LIB.T6G(SCH_1):PVDD18_S5_P1_VCC
 PR397    2      B Q_RES_0402LF-0,5%,1/16W,CHIP,CS00002JB13    I12 @T6G_MB_LIB.T6G(SCH_1):PAGE201
   PU3   19    VCC MPQ8633BGLEC838Z-MPQ8633BGLE-C838-Z,SMLF,IC,AL0086A    I15 @T6G_MB_LIB.T6G(SCH_1):PAGE201
  PC20    1      A Q_CAP_C0402-1UF,25V,10%,X6S,CH5104KEB02    I53 @T6G_MB_LIB.T6G(SCH_1):PAGE201

PVDD18_SS_P1_RGND @T6G_MB_LIB.T6G(SCH_1):PVDD18_SS_P1_RGND
   PU3    6   RGND MPQ8633BGLEC838Z-MPQ8633BGLE-C838-Z,SMLF,IC,AL0086A    I15 @T6G_MB_LIB.T6G(SCH_1):PAGE201
  PC62    2      B Q_CAP_0402-0.1UF,25V,10%,X7R,CH4104K1B00    I19 @T6G_MB_LIB.T6G(SCH_1):PAGE201
 PR399    2      B Q_RES_0402LF-49.9,1%,1/16W,CHIP,CS04992FB07    I29 @T6G_MB_LIB.T6G(SCH_1):PAGE201
 PR147    2      B Q_RES_0402LF-10K,1%,1/16W,CHIP,CS31002FB08    I30 @T6G_MB_LIB.T6G(SCH_1):PAGE201
PC6006    2      B Q_CAP_C0402-0.01UF,25V,10%,EMPTY,CH3104K1B11    I34 @T6G_MB_LIB.T6G(SCH_1):PAGE201
 PR401    1      A Q_RES_0402LF-0,5%,1/16W,CHIP,CS00002JB13    I35 @T6G_MB_LIB.T6G(SCH_1):PAGE201

PVDD33_S5_EN @T6G_MB_LIB.T6G(SCH_1):PVDD33_S5_EN
  R224    1      A Q_RES_0402LF-33,5%,1/16W,CHIP,CS03302JB10    I36 @T6G_MB_LIB.T6G(SCH_1):PAGE80
  C348    1      A Q_CAP_0402-0.1UF,25V,10%,EMPTY,CH4104K1B00     I5 @T6G_MB_LIB.T6G(SCH_1):PAGE167
  PU55    8     EN MPQ8633AGLEC807Z-MPQ8633AGLE-C807-Z,SMLF,IC,AL0086A    I41 @T6G_MB_LIB.T6G(SCH_1):PAGE167

PVDDCR_CPU0_P0 @T6G_MB_LIB.T6G(SCH_1):PVDDCR_CPU0_P0
   U25 AB23 VDDCR_CPU0_AB23 GENOA_SP5-SOCKET6096_13568-001,SMLF,IO,DGA^6000030    I42 @T6G_MB_LIB.T6G(SCH_1):PAGE30
   U25 AB24 VDDCR_CPU0_AB24 GENOA_SP5-SOCKET6096_13568-001,SMLF,IO,DGA^6000030    I42 @T6G_MB_LIB.T6G(SCH_1):PAGE30
   U25 AB26 VDDCR_CPU0_AB26 GENOA_SP5-SOCKET6096_13568-001,SMLF,IO,DGA^6000030    I42 @T6G_MB_LIB.T6G(SCH_1):PAGE30
   U25 AB27 VDDCR_CPU0_AB27 GENOA_SP5-SOCKET6096_13568-001,SMLF,IO,DGA^6000030    I42 @T6G_MB_LIB.T6G(SCH_1):PAGE30
   U25 AB29 VDDCR_CPU0_AB29 GENOA_SP5-SOCKET6096_13568-001,SMLF,IO,DGA^6000030    I42 @T6G_MB_LIB.T6G(SCH_1):PAGE30
   U25 AB30 VDDCR_CPU0_AB30 GENOA_SP5-SOCKET6096_13568-001,SMLF,IO,DGA^6000030    I42 @T6G_MB_LIB.T6G(SCH_1):PAGE30
   U25 AB32 VDDCR_CPU0_AB32 GENOA_SP5-SOCKET6096_13568-001,SMLF,IO,DGA^6000030    I42 @T6G_MB_LIB.T6G(SCH_1):PAGE30
   U25 AB33 VDDCR_CPU0_AB33 GENOA_SP5-SOCKET6096_13568-001,SMLF,IO,DGA^6000030    I42 @T6G_MB_LIB.T6G(SCH_1):PAGE30
   U25 AB43 VDDCR_CPU0_AB43 GENOA_SP5-SOCKET6096_13568-001,SMLF,IO,DGA^6000030    I42 @T6G_MB_LIB.T6G(SCH_1):PAGE30
   U25 AB44 VDDCR_CPU0_AB44 GENOA_SP5-SOCKET6096_13568-001,SMLF,IO,DGA^6000030    I42 @T6G_MB_LIB.T6G(SCH_1):PAGE30
   U25 AB46 VDDCR_CPU0_AB46 GENOA_SP5-SOCKET6096_13568-001,SMLF,IO,DGA^6000030    I42 @T6G_MB_LIB.T6G(SCH_1):PAGE30
   U25 AB47 VDDCR_CPU0_AB47 GENOA_SP5-SOCKET6096_13568-001,SMLF,IO,DGA^6000030    I42 @T6G_MB_LIB.T6G(SCH_1):PAGE30
   U25 AB49 VDDCR_CPU0_AB49 GENOA_SP5-SOCKET6096_13568-001,SMLF,IO,DGA^6000030    I42 @T6G_MB_LIB.T6G(SCH_1):PAGE30
   U25 AB50 VDDCR_CPU0_AB50 GENOA_SP5-SOCKET6096_13568-001,SMLF,IO,DGA^6000030    I42 @T6G_MB_LIB.T6G(SCH_1):PAGE30
   U25 AB52 VDDCR_CPU0_AB52 GENOA_SP5-SOCKET6096_13568-001,SMLF,IO,DGA^6000030    I42 @T6G_MB_LIB.T6G(SCH_1):PAGE30
   U25 AB53 VDDCR_CPU0_AB53 GENOA_SP5-SOCKET6096_13568-001,SMLF,IO,DGA^6000030    I42 @T6G_MB_LIB.T6G(SCH_1):PAGE30
   U25 AC35 VDDCR_CPU0_AC35 GENOA_SP5-SOCKET6096_13568-001,SMLF,IO,DGA^6000030    I42 @T6G_MB_LIB.T6G(SCH_1):PAGE30
   U25 AC36 VDDCR_CPU0_AC36 GENOA_SP5-SOCKET6096_13568-001,SMLF,IO,DGA^6000030    I42 @T6G_MB_LIB.T6G(SCH_1):PAGE30
   U25 AC40 VDDCR_CPU0_AC40 GENOA_SP5-SOCKET6096_13568-001,SMLF,IO,DGA^6000030    I42 @T6G_MB_LIB.T6G(SCH_1):PAGE30
   U25 AC41 VDDCR_CPU0_AC41 GENOA_SP5-SOCKET6096_13568-001,SMLF,IO,DGA^6000030    I42 @T6G_MB_LIB.T6G(SCH_1):PAGE30
   U25 AF23 VDDCR_CPU0_AF23 GENOA_SP5-SOCKET6096_13568-001,SMLF,IO,DGA^6000030    I42 @T6G_MB_LIB.T6G(SCH_1):PAGE30
   U25 AF24 VDDCR_CPU0_AF24 GENOA_SP5-SOCKET6096_13568-001,SMLF,IO,DGA^6000030    I42 @T6G_MB_LIB.T6G(SCH_1):PAGE30
   U25 AF26 VDDCR_CPU0_AF26 GENOA_SP5-SOCKET6096_13568-001,SMLF,IO,DGA^6000030    I42 @T6G_MB_LIB.T6G(SCH_1):PAGE30
   U25 AF27 VDDCR_CPU0_AF27 GENOA_SP5-SOCKET6096_13568-001,SMLF,IO,DGA^6000030    I42 @T6G_MB_LIB.T6G(SCH_1):PAGE30
   U25 AF29 VDDCR_CPU0_AF29 GENOA_SP5-SOCKET6096_13568-001,SMLF,IO,DGA^6000030    I42 @T6G_MB_LIB.T6G(SCH_1):PAGE30
   U25 AF30 VDDCR_CPU0_AF30 GENOA_SP5-SOCKET6096_13568-001,SMLF,IO,DGA^6000030    I42 @T6G_MB_LIB.T6G(SCH_1):PAGE30
   U25 AF32 VDDCR_CPU0_AF32 GENOA_SP5-SOCKET6096_13568-001,SMLF,IO,DGA^6000030    I42 @T6G_MB_LIB.T6G(SCH_1):PAGE30
   U25 AF33 VDDCR_CPU0_AF33 GENOA_SP5-SOCKET6096_13568-001,SMLF,IO,DGA^6000030    I42 @T6G_MB_LIB.T6G(SCH_1):PAGE30
   U25 AF43 VDDCR_CPU0_AF43 GENOA_SP5-SOCKET6096_13568-001,SMLF,IO,DGA^6000030    I42 @T6G_MB_LIB.T6G(SCH_1):PAGE30
   U25 AF44 VDDCR_CPU0_AF44 GENOA_SP5-SOCKET6096_13568-001,SMLF,IO,DGA^6000030    I42 @T6G_MB_LIB.T6G(SCH_1):PAGE30
   U25 AF46 VDDCR_CPU0_AF46 GENOA_SP5-SOCKET6096_13568-001,SMLF,IO,DGA^6000030    I42 @T6G_MB_LIB.T6G(SCH_1):PAGE30
   U25 AF47 VDDCR_CPU0_AF47 GENOA_SP5-SOCKET6096_13568-001,SMLF,IO,DGA^6000030    I42 @T6G_MB_LIB.T6G(SCH_1):PAGE30
   U25 AF49 VDDCR_CPU0_AF49 GENOA_SP5-SOCKET6096_13568-001,SMLF,IO,DGA^6000030    I42 @T6G_MB_LIB.T6G(SCH_1):PAGE30
   U25 AF50 VDDCR_CPU0_AF50 GENOA_SP5-SOCKET6096_13568-001,SMLF,IO,DGA^6000030    I42 @T6G_MB_LIB.T6G(SCH_1):PAGE30
   U25 AF52 VDDCR_CPU0_AF52 GENOA_SP5-SOCKET6096_13568-001,SMLF,IO,DGA^6000030    I42 @T6G_MB_LIB.T6G(SCH_1):PAGE30
   U25 AF53 VDDCR_CPU0_AF53 GENOA_SP5-SOCKET6096_13568-001,SMLF,IO,DGA^6000030    I42 @T6G_MB_LIB.T6G(SCH_1):PAGE30
   U25 AG35 VDDCR_CPU0_AG35 GENOA_SP5-SOCKET6096_13568-001,SMLF,IO,DGA^6000030    I42 @T6G_MB_LIB.T6G(SCH_1):PAGE30
   U25 AG36 VDDCR_CPU0_AG36 GENOA_SP5-SOCKET6096_13568-001,SMLF,IO,DGA^6000030    I42 @T6G_MB_LIB.T6G(SCH_1):PAGE30
   U25 AG40 VDDCR_CPU0_AG40 GENOA_SP5-SOCKET6096_13568-001,SMLF,IO,DGA^6000030    I42 @T6G_MB_LIB.T6G(SCH_1):PAGE30
   U25 AG41 VDDCR_CPU0_AG41 GENOA_SP5-SOCKET6096_13568-001,SMLF,IO,DGA^6000030    I42 @T6G_MB_LIB.T6G(SCH_1):PAGE30
   U25 AK23 VDDCR_CPU0_AK23 GENOA_SP5-SOCKET6096_13568-001,SMLF,IO,DGA^6000030    I42 @T6G_MB_LIB.T6G(SCH_1):PAGE30
   U25 AK24 VDDCR_CPU0_AK24 GENOA_SP5-SOCKET6096_13568-001,SMLF,IO,DGA^6000030    I42 @T6G_MB_LIB.T6G(SCH_1):PAGE30
   U25 AK26 VDDCR_CPU0_AK26 GENOA_SP5-SOCKET6096_13568-001,SMLF,IO,DGA^6000030    I42 @T6G_MB_LIB.T6G(SCH_1):PAGE30
   U25 AK27 VDDCR_CPU0_AK27 GENOA_SP5-SOCKET6096_13568-001,SMLF,IO,DGA^6000030    I42 @T6G_MB_LIB.T6G(SCH_1):PAGE30
   U25 AK29 VDDCR_CPU0_AK29 GENOA_SP5-SOCKET6096_13568-001,SMLF,IO,DGA^6000030    I42 @T6G_MB_LIB.T6G(SCH_1):PAGE30
   U25 AK30 VDDCR_CPU0_AK30 GENOA_SP5-SOCKET6096_13568-001,SMLF,IO,DGA^6000030    I42 @T6G_MB_LIB.T6G(SCH_1):PAGE30
   U25 AK32 VDDCR_CPU0_AK32 GENOA_SP5-SOCKET6096_13568-001,SMLF,IO,DGA^6000030    I42 @T6G_MB_LIB.T6G(SCH_1):PAGE30
   U25 AK33 VDDCR_CPU0_AK33 GENOA_SP5-SOCKET6096_13568-001,SMLF,IO,DGA^6000030    I42 @T6G_MB_LIB.T6G(SCH_1):PAGE30
   U25 AK43 VDDCR_CPU0_AK43 GENOA_SP5-SOCKET6096_13568-001,SMLF,IO,DGA^6000030    I42 @T6G_MB_LIB.T6G(SCH_1):PAGE30
   U25 AK44 VDDCR_CPU0_AK44 GENOA_SP5-SOCKET6096_13568-001,SMLF,IO,DGA^6000030    I42 @T6G_MB_LIB.T6G(SCH_1):PAGE30
   U25 AK46 VDDCR_CPU0_AK46 GENOA_SP5-SOCKET6096_13568-001,SMLF,IO,DGA^6000030    I42 @T6G_MB_LIB.T6G(SCH_1):PAGE30
   U25 AK47 VDDCR_CPU0_AK47 GENOA_SP5-SOCKET6096_13568-001,SMLF,IO,DGA^6000030    I42 @T6G_MB_LIB.T6G(SCH_1):PAGE30
   U25 AK49 VDDCR_CPU0_AK49 GENOA_SP5-SOCKET6096_13568-001,SMLF,IO,DGA^6000030    I42 @T6G_MB_LIB.T6G(SCH_1):PAGE30
   U25 AK50 VDDCR_CPU0_AK50 GENOA_SP5-SOCKET6096_13568-001,SMLF,IO,DGA^6000030    I42 @T6G_MB_LIB.T6G(SCH_1):PAGE30
   U25 AK52 VDDCR_CPU0_AK52 GENOA_SP5-SOCKET6096_13568-001,SMLF,IO,DGA^6000030    I42 @T6G_MB_LIB.T6G(SCH_1):PAGE30
   U25 AK53 VDDCR_CPU0_AK53 GENOA_SP5-SOCKET6096_13568-001,SMLF,IO,DGA^6000030    I42 @T6G_MB_LIB.T6G(SCH_1):PAGE30
   U25 AL35 VDDCR_CPU0_AL35 GENOA_SP5-SOCKET6096_13568-001,SMLF,IO,DGA^6000030    I42 @T6G_MB_LIB.T6G(SCH_1):PAGE30
   U25 AL36 VDDCR_CPU0_AL36 GENOA_SP5-SOCKET6096_13568-001,SMLF,IO,DGA^6000030    I42 @T6G_MB_LIB.T6G(SCH_1):PAGE30
   U25 AL40 VDDCR_CPU0_AL40 GENOA_SP5-SOCKET6096_13568-001,SMLF,IO,DGA^6000030    I42 @T6G_MB_LIB.T6G(SCH_1):PAGE30
   U25 AL41 VDDCR_CPU0_AL41 GENOA_SP5-SOCKET6096_13568-001,SMLF,IO,DGA^6000030    I42 @T6G_MB_LIB.T6G(SCH_1):PAGE30
   U25 AP23 VDDCR_CPU0_AP23 GENOA_SP5-SOCKET6096_13568-001,SMLF,IO,DGA^6000030    I42 @T6G_MB_LIB.T6G(SCH_1):PAGE30
   U25 AP24 VDDCR_CPU0_AP24 GENOA_SP5-SOCKET6096_13568-001,SMLF,IO,DGA^6000030    I42 @T6G_MB_LIB.T6G(SCH_1):PAGE30
   U25 AP26 VDDCR_CPU0_AP26 GENOA_SP5-SOCKET6096_13568-001,SMLF,IO,DGA^6000030    I42 @T6G_MB_LIB.T6G(SCH_1):PAGE30
   U25 AP27 VDDCR_CPU0_AP27 GENOA_SP5-SOCKET6096_13568-001,SMLF,IO,DGA^6000030    I42 @T6G_MB_LIB.T6G(SCH_1):PAGE30
   U25 AP29 VDDCR_CPU0_AP29 GENOA_SP5-SOCKET6096_13568-001,SMLF,IO,DGA^6000030    I42 @T6G_MB_LIB.T6G(SCH_1):PAGE30
   U25 AP30 VDDCR_CPU0_AP30 GENOA_SP5-SOCKET6096_13568-001,SMLF,IO,DGA^6000030    I42 @T6G_MB_LIB.T6G(SCH_1):PAGE30
   U25 AP32 VDDCR_CPU0_AP32 GENOA_SP5-SOCKET6096_13568-001,SMLF,IO,DGA^6000030    I42 @T6G_MB_LIB.T6G(SCH_1):PAGE30
   U25 AP33 VDDCR_CPU0_AP33 GENOA_SP5-SOCKET6096_13568-001,SMLF,IO,DGA^6000030    I42 @T6G_MB_LIB.T6G(SCH_1):PAGE30
   U25 AP43 VDDCR_CPU0_AP43 GENOA_SP5-SOCKET6096_13568-001,SMLF,IO,DGA^6000030    I42 @T6G_MB_LIB.T6G(SCH_1):PAGE30
   U25 AP44 VDDCR_CPU0_AP44 GENOA_SP5-SOCKET6096_13568-001,SMLF,IO,DGA^6000030    I42 @T6G_MB_LIB.T6G(SCH_1):PAGE30
   U25 AP46 VDDCR_CPU0_AP46 GENOA_SP5-SOCKET6096_13568-001,SMLF,IO,DGA^6000030    I42 @T6G_MB_LIB.T6G(SCH_1):PAGE30
   U25 AP47 VDDCR_CPU0_AP47 GENOA_SP5-SOCKET6096_13568-001,SMLF,IO,DGA^6000030    I42 @T6G_MB_LIB.T6G(SCH_1):PAGE30
   U25 AP49 VDDCR_CPU0_AP49 GENOA_SP5-SOCKET6096_13568-001,SMLF,IO,DGA^6000030    I42 @T6G_MB_LIB.T6G(SCH_1):PAGE30
   U25 AP50 VDDCR_CPU0_AP50 GENOA_SP5-SOCKET6096_13568-001,SMLF,IO,DGA^6000030    I42 @T6G_MB_LIB.T6G(SCH_1):PAGE30
   U25 AP52 VDDCR_CPU0_AP52 GENOA_SP5-SOCKET6096_13568-001,SMLF,IO,DGA^6000030    I42 @T6G_MB_LIB.T6G(SCH_1):PAGE30
   U25 AP53 VDDCR_CPU0_AP53 GENOA_SP5-SOCKET6096_13568-001,SMLF,IO,DGA^6000030    I42 @T6G_MB_LIB.T6G(SCH_1):PAGE30
   U25 AR23 VDDCR_CPU0_AR23 GENOA_SP5-SOCKET6096_13568-001,SMLF,IO,DGA^6000030    I42 @T6G_MB_LIB.T6G(SCH_1):PAGE30
   U25 AR25 VDDCR_CPU0_AR25 GENOA_SP5-SOCKET6096_13568-001,SMLF,IO,DGA^6000030    I42 @T6G_MB_LIB.T6G(SCH_1):PAGE30
   U25 AR27 VDDCR_CPU0_AR27 GENOA_SP5-SOCKET6096_13568-001,SMLF,IO,DGA^6000030    I42 @T6G_MB_LIB.T6G(SCH_1):PAGE30
   U25 AR29 VDDCR_CPU0_AR29 GENOA_SP5-SOCKET6096_13568-001,SMLF,IO,DGA^6000030    I42 @T6G_MB_LIB.T6G(SCH_1):PAGE30
   U25 AR31 VDDCR_CPU0_AR31 GENOA_SP5-SOCKET6096_13568-001,SMLF,IO,DGA^6000030    I42 @T6G_MB_LIB.T6G(SCH_1):PAGE30
   U25 AR33 VDDCR_CPU0_AR33 GENOA_SP5-SOCKET6096_13568-001,SMLF,IO,DGA^6000030    I42 @T6G_MB_LIB.T6G(SCH_1):PAGE30
   U25 AR35 VDDCR_CPU0_AR35 GENOA_SP5-SOCKET6096_13568-001,SMLF,IO,DGA^6000030    I42 @T6G_MB_LIB.T6G(SCH_1):PAGE30
   U25 AR40 VDDCR_CPU0_AR40 GENOA_SP5-SOCKET6096_13568-001,SMLF,IO,DGA^6000030    I42 @T6G_MB_LIB.T6G(SCH_1):PAGE30
   U25 AR42 VDDCR_CPU0_AR42 GENOA_SP5-SOCKET6096_13568-001,SMLF,IO,DGA^6000030    I42 @T6G_MB_LIB.T6G(SCH_1):PAGE30
   U25 AR44 VDDCR_CPU0_AR44 GENOA_SP5-SOCKET6096_13568-001,SMLF,IO,DGA^6000030    I42 @T6G_MB_LIB.T6G(SCH_1):PAGE30
   U25 AR46 VDDCR_CPU0_AR46 GENOA_SP5-SOCKET6096_13568-001,SMLF,IO,DGA^6000030    I42 @T6G_MB_LIB.T6G(SCH_1):PAGE30
   U25 AR48 VDDCR_CPU0_AR48 GENOA_SP5-SOCKET6096_13568-001,SMLF,IO,DGA^6000030    I42 @T6G_MB_LIB.T6G(SCH_1):PAGE30
   U25 AR50 VDDCR_CPU0_AR50 GENOA_SP5-SOCKET6096_13568-001,SMLF,IO,DGA^6000030    I42 @T6G_MB_LIB.T6G(SCH_1):PAGE30
   U25 AT24 VDDCR_CPU0_AT24 GENOA_SP5-SOCKET6096_13568-001,SMLF,IO,DGA^6000030    I42 @T6G_MB_LIB.T6G(SCH_1):PAGE30
   U25 AT26 VDDCR_CPU0_AT26 GENOA_SP5-SOCKET6096_13568-001,SMLF,IO,DGA^6000030    I42 @T6G_MB_LIB.T6G(SCH_1):PAGE30
   U25 AT28 VDDCR_CPU0_AT28 GENOA_SP5-SOCKET6096_13568-001,SMLF,IO,DGA^6000030    I42 @T6G_MB_LIB.T6G(SCH_1):PAGE30
   U25 AT30 VDDCR_CPU0_AT30 GENOA_SP5-SOCKET6096_13568-001,SMLF,IO,DGA^6000030    I42 @T6G_MB_LIB.T6G(SCH_1):PAGE30
   U25 AT32 VDDCR_CPU0_AT32 GENOA_SP5-SOCKET6096_13568-001,SMLF,IO,DGA^6000030    I42 @T6G_MB_LIB.T6G(SCH_1):PAGE30
   U25 AT34 VDDCR_CPU0_AT34 GENOA_SP5-SOCKET6096_13568-001,SMLF,IO,DGA^6000030    I42 @T6G_MB_LIB.T6G(SCH_1):PAGE30
   U25 AT36 VDDCR_CPU0_AT36 GENOA_SP5-SOCKET6096_13568-001,SMLF,IO,DGA^6000030    I42 @T6G_MB_LIB.T6G(SCH_1):PAGE30
   U25 AT39 VDDCR_CPU0_AT39 GENOA_SP5-SOCKET6096_13568-001,SMLF,IO,DGA^6000030    I42 @T6G_MB_LIB.T6G(SCH_1):PAGE30
   U25 AT41 VDDCR_CPU0_AT41 GENOA_SP5-SOCKET6096_13568-001,SMLF,IO,DGA^6000030    I42 @T6G_MB_LIB.T6G(SCH_1):PAGE30
   U25 AT43 VDDCR_CPU0_AT43 GENOA_SP5-SOCKET6096_13568-001,SMLF,IO,DGA^6000030    I42 @T6G_MB_LIB.T6G(SCH_1):PAGE30
   U25 AT45 VDDCR_CPU0_AT45 GENOA_SP5-SOCKET6096_13568-001,SMLF,IO,DGA^6000030    I42 @T6G_MB_LIB.T6G(SCH_1):PAGE30
   U25 AT47 VDDCR_CPU0_AT47 GENOA_SP5-SOCKET6096_13568-001,SMLF,IO,DGA^6000030    I42 @T6G_MB_LIB.T6G(SCH_1):PAGE30
   U25 AT49 VDDCR_CPU0_AT49 GENOA_SP5-SOCKET6096_13568-001,SMLF,IO,DGA^6000030    I42 @T6G_MB_LIB.T6G(SCH_1):PAGE30
   U25 AU25 VDDCR_CPU0_AU25 GENOA_SP5-SOCKET6096_13568-001,SMLF,IO,DGA^6000030    I42 @T6G_MB_LIB.T6G(SCH_1):PAGE30
   U25 AU29 VDDCR_CPU0_AU29 GENOA_SP5-SOCKET6096_13568-001,SMLF,IO,DGA^6000030    I42 @T6G_MB_LIB.T6G(SCH_1):PAGE30
   U25 AU33 VDDCR_CPU0_AU33 GENOA_SP5-SOCKET6096_13568-001,SMLF,IO,DGA^6000030    I42 @T6G_MB_LIB.T6G(SCH_1):PAGE30
   U25 AU42 VDDCR_CPU0_AU42 GENOA_SP5-SOCKET6096_13568-001,SMLF,IO,DGA^6000030    I42 @T6G_MB_LIB.T6G(SCH_1):PAGE30
   U25 AU44 VDDCR_CPU0_AU44 GENOA_SP5-SOCKET6096_13568-001,SMLF,IO,DGA^6000030    I42 @T6G_MB_LIB.T6G(SCH_1):PAGE30
   U25 AU46 VDDCR_CPU0_AU46 GENOA_SP5-SOCKET6096_13568-001,SMLF,IO,DGA^6000030    I42 @T6G_MB_LIB.T6G(SCH_1):PAGE30
   U25 AU48 VDDCR_CPU0_AU48 GENOA_SP5-SOCKET6096_13568-001,SMLF,IO,DGA^6000030    I42 @T6G_MB_LIB.T6G(SCH_1):PAGE30
   U25  B19 VDDCR_CPU0_B19 GENOA_SP5-SOCKET6096_13568-001,SMLF,IO,DGA^6000030    I42 @T6G_MB_LIB.T6G(SCH_1):PAGE30
   U25  B20 VDDCR_CPU0_B20 GENOA_SP5-SOCKET6096_13568-001,SMLF,IO,DGA^6000030    I42 @T6G_MB_LIB.T6G(SCH_1):PAGE30
   U25  B22 VDDCR_CPU0_B22 GENOA_SP5-SOCKET6096_13568-001,SMLF,IO,DGA^6000030    I42 @T6G_MB_LIB.T6G(SCH_1):PAGE30
   U25  B23 VDDCR_CPU0_B23 GENOA_SP5-SOCKET6096_13568-001,SMLF,IO,DGA^6000030    I42 @T6G_MB_LIB.T6G(SCH_1):PAGE30
   U25  B25 VDDCR_CPU0_B25 GENOA_SP5-SOCKET6096_13568-001,SMLF,IO,DGA^6000030    I42 @T6G_MB_LIB.T6G(SCH_1):PAGE30
   U25  B26 VDDCR_CPU0_B26 GENOA_SP5-SOCKET6096_13568-001,SMLF,IO,DGA^6000030    I42 @T6G_MB_LIB.T6G(SCH_1):PAGE30
   U25  B28 VDDCR_CPU0_B28 GENOA_SP5-SOCKET6096_13568-001,SMLF,IO,DGA^6000030    I42 @T6G_MB_LIB.T6G(SCH_1):PAGE30
   U25  B29 VDDCR_CPU0_B29 GENOA_SP5-SOCKET6096_13568-001,SMLF,IO,DGA^6000030    I42 @T6G_MB_LIB.T6G(SCH_1):PAGE30
   U25  B31 VDDCR_CPU0_B31 GENOA_SP5-SOCKET6096_13568-001,SMLF,IO,DGA^6000030    I42 @T6G_MB_LIB.T6G(SCH_1):PAGE30
   U25  B32 VDDCR_CPU0_B32 GENOA_SP5-SOCKET6096_13568-001,SMLF,IO,DGA^6000030    I42 @T6G_MB_LIB.T6G(SCH_1):PAGE30
   U25  B34 VDDCR_CPU0_B34 GENOA_SP5-SOCKET6096_13568-001,SMLF,IO,DGA^6000030    I42 @T6G_MB_LIB.T6G(SCH_1):PAGE30
   U25  B35 VDDCR_CPU0_B35 GENOA_SP5-SOCKET6096_13568-001,SMLF,IO,DGA^6000030    I42 @T6G_MB_LIB.T6G(SCH_1):PAGE30
   U25  B41 VDDCR_CPU0_B41 GENOA_SP5-SOCKET6096_13568-001,SMLF,IO,DGA^6000030    I42 @T6G_MB_LIB.T6G(SCH_1):PAGE30
   U25  B42 VDDCR_CPU0_B42 GENOA_SP5-SOCKET6096_13568-001,SMLF,IO,DGA^6000030    I42 @T6G_MB_LIB.T6G(SCH_1):PAGE30
   U25  B44 VDDCR_CPU0_B44 GENOA_SP5-SOCKET6096_13568-001,SMLF,IO,DGA^6000030    I42 @T6G_MB_LIB.T6G(SCH_1):PAGE30
   U25  B45 VDDCR_CPU0_B45 GENOA_SP5-SOCKET6096_13568-001,SMLF,IO,DGA^6000030    I42 @T6G_MB_LIB.T6G(SCH_1):PAGE30
   U25  B47 VDDCR_CPU0_B47 GENOA_SP5-SOCKET6096_13568-001,SMLF,IO,DGA^6000030    I42 @T6G_MB_LIB.T6G(SCH_1):PAGE30
   U25  B48 VDDCR_CPU0_B48 GENOA_SP5-SOCKET6096_13568-001,SMLF,IO,DGA^6000030    I42 @T6G_MB_LIB.T6G(SCH_1):PAGE30
   U25  B50 VDDCR_CPU0_B50 GENOA_SP5-SOCKET6096_13568-001,SMLF,IO,DGA^6000030    I42 @T6G_MB_LIB.T6G(SCH_1):PAGE30
   U25  B51 VDDCR_CPU0_B51 GENOA_SP5-SOCKET6096_13568-001,SMLF,IO,DGA^6000030    I42 @T6G_MB_LIB.T6G(SCH_1):PAGE30
   U25  B53 VDDCR_CPU0_B53 GENOA_SP5-SOCKET6096_13568-001,SMLF,IO,DGA^6000030    I42 @T6G_MB_LIB.T6G(SCH_1):PAGE30
   U25  B54 VDDCR_CPU0_B54 GENOA_SP5-SOCKET6096_13568-001,SMLF,IO,DGA^6000030    I42 @T6G_MB_LIB.T6G(SCH_1):PAGE30
   U25  B56 VDDCR_CPU0_B56 GENOA_SP5-SOCKET6096_13568-001,SMLF,IO,DGA^6000030    I42 @T6G_MB_LIB.T6G(SCH_1):PAGE30
   U25  B57 VDDCR_CPU0_B57 GENOA_SP5-SOCKET6096_13568-001,SMLF,IO,DGA^6000030    I42 @T6G_MB_LIB.T6G(SCH_1):PAGE30
   U25  C20 VDDCR_CPU0_C20 GENOA_SP5-SOCKET6096_13568-001,SMLF,IO,DGA^6000030    I42 @T6G_MB_LIB.T6G(SCH_1):PAGE30
   U25  D55 VDDCR_CPU0_D55 GENOA_SP5-SOCKET6096_13568-001,SMLF,IO,DGA^6000030    I42 @T6G_MB_LIB.T6G(SCH_1):PAGE30
   U25  D56 VDDCR_CPU0_D56 GENOA_SP5-SOCKET6096_13568-001,SMLF,IO,DGA^6000030    I42 @T6G_MB_LIB.T6G(SCH_1):PAGE30
   U25  E22 VDDCR_CPU0_E22 GENOA_SP5-SOCKET6096_13568-001,SMLF,IO,DGA^6000030    I42 @T6G_MB_LIB.T6G(SCH_1):PAGE30
   U25  E25 VDDCR_CPU0_E25 GENOA_SP5-SOCKET6096_13568-001,SMLF,IO,DGA^6000030    I42 @T6G_MB_LIB.T6G(SCH_1):PAGE30
   U25  E28 VDDCR_CPU0_E28 GENOA_SP5-SOCKET6096_13568-001,SMLF,IO,DGA^6000030    I42 @T6G_MB_LIB.T6G(SCH_1):PAGE30
   U25  E31 VDDCR_CPU0_E31 GENOA_SP5-SOCKET6096_13568-001,SMLF,IO,DGA^6000030    I42 @T6G_MB_LIB.T6G(SCH_1):PAGE30
   U25  E34 VDDCR_CPU0_E34 GENOA_SP5-SOCKET6096_13568-001,SMLF,IO,DGA^6000030    I42 @T6G_MB_LIB.T6G(SCH_1):PAGE30
   U25  E35 VDDCR_CPU0_E35 GENOA_SP5-SOCKET6096_13568-001,SMLF,IO,DGA^6000030    I42 @T6G_MB_LIB.T6G(SCH_1):PAGE30
   U25  E42 VDDCR_CPU0_E42 GENOA_SP5-SOCKET6096_13568-001,SMLF,IO,DGA^6000030    I42 @T6G_MB_LIB.T6G(SCH_1):PAGE30
   U25  E45 VDDCR_CPU0_E45 GENOA_SP5-SOCKET6096_13568-001,SMLF,IO,DGA^6000030    I42 @T6G_MB_LIB.T6G(SCH_1):PAGE30
   U25  E48 VDDCR_CPU0_E48 GENOA_SP5-SOCKET6096_13568-001,SMLF,IO,DGA^6000030    I42 @T6G_MB_LIB.T6G(SCH_1):PAGE30
   U25  E51 VDDCR_CPU0_E51 GENOA_SP5-SOCKET6096_13568-001,SMLF,IO,DGA^6000030    I42 @T6G_MB_LIB.T6G(SCH_1):PAGE30
   U25  E54 VDDCR_CPU0_E54 GENOA_SP5-SOCKET6096_13568-001,SMLF,IO,DGA^6000030    I42 @T6G_MB_LIB.T6G(SCH_1):PAGE30
   U25  F22 VDDCR_CPU0_F22 GENOA_SP5-SOCKET6096_13568-001,SMLF,IO,DGA^6000030    I42 @T6G_MB_LIB.T6G(SCH_1):PAGE30
   U25  F25 VDDCR_CPU0_F25 GENOA_SP5-SOCKET6096_13568-001,SMLF,IO,DGA^6000030    I42 @T6G_MB_LIB.T6G(SCH_1):PAGE30
   U25  F28 VDDCR_CPU0_F28 GENOA_SP5-SOCKET6096_13568-001,SMLF,IO,DGA^6000030    I42 @T6G_MB_LIB.T6G(SCH_1):PAGE30
   U25  F31 VDDCR_CPU0_F31 GENOA_SP5-SOCKET6096_13568-001,SMLF,IO,DGA^6000030    I42 @T6G_MB_LIB.T6G(SCH_1):PAGE30
   U25  F34 VDDCR_CPU0_F34 GENOA_SP5-SOCKET6096_13568-001,SMLF,IO,DGA^6000030    I42 @T6G_MB_LIB.T6G(SCH_1):PAGE30
   U25  F42 VDDCR_CPU0_F42 GENOA_SP5-SOCKET6096_13568-001,SMLF,IO,DGA^6000030    I42 @T6G_MB_LIB.T6G(SCH_1):PAGE30
   U25  F45 VDDCR_CPU0_F45 GENOA_SP5-SOCKET6096_13568-001,SMLF,IO,DGA^6000030    I42 @T6G_MB_LIB.T6G(SCH_1):PAGE30
   U25  F48 VDDCR_CPU0_F48 GENOA_SP5-SOCKET6096_13568-001,SMLF,IO,DGA^6000030    I42 @T6G_MB_LIB.T6G(SCH_1):PAGE30
   U25  F51 VDDCR_CPU0_F51 GENOA_SP5-SOCKET6096_13568-001,SMLF,IO,DGA^6000030    I42 @T6G_MB_LIB.T6G(SCH_1):PAGE30
   U25  F54 VDDCR_CPU0_F54 GENOA_SP5-SOCKET6096_13568-001,SMLF,IO,DGA^6000030    I42 @T6G_MB_LIB.T6G(SCH_1):PAGE30
   U25  G35 VDDCR_CPU0_G35 GENOA_SP5-SOCKET6096_13568-001,SMLF,IO,DGA^6000030    I42 @T6G_MB_LIB.T6G(SCH_1):PAGE30
   U25  G36 VDDCR_CPU0_G36 GENOA_SP5-SOCKET6096_13568-001,SMLF,IO,DGA^6000030    I42 @T6G_MB_LIB.T6G(SCH_1):PAGE30
   U25  G40 VDDCR_CPU0_G40 GENOA_SP5-SOCKET6096_13568-001,SMLF,IO,DGA^6000030    I42 @T6G_MB_LIB.T6G(SCH_1):PAGE30
   U25  G41 VDDCR_CPU0_G41 GENOA_SP5-SOCKET6096_13568-001,SMLF,IO,DGA^6000030    I42 @T6G_MB_LIB.T6G(SCH_1):PAGE30
   U25  H23 VDDCR_CPU0_H23 GENOA_SP5-SOCKET6096_13568-001,SMLF,IO,DGA^6000030    I42 @T6G_MB_LIB.T6G(SCH_1):PAGE30
   U25  H24 VDDCR_CPU0_H24 GENOA_SP5-SOCKET6096_13568-001,SMLF,IO,DGA^6000030    I42 @T6G_MB_LIB.T6G(SCH_1):PAGE30
   U25  H26 VDDCR_CPU0_H26 GENOA_SP5-SOCKET6096_13568-001,SMLF,IO,DGA^6000030    I42 @T6G_MB_LIB.T6G(SCH_1):PAGE30
   U25  H27 VDDCR_CPU0_H27 GENOA_SP5-SOCKET6096_13568-001,SMLF,IO,DGA^6000030    I42 @T6G_MB_LIB.T6G(SCH_1):PAGE30
   U25  H29 VDDCR_CPU0_H29 GENOA_SP5-SOCKET6096_13568-001,SMLF,IO,DGA^6000030    I42 @T6G_MB_LIB.T6G(SCH_1):PAGE30
   U25  H30 VDDCR_CPU0_H30 GENOA_SP5-SOCKET6096_13568-001,SMLF,IO,DGA^6000030    I42 @T6G_MB_LIB.T6G(SCH_1):PAGE30
   U25  H32 VDDCR_CPU0_H32 GENOA_SP5-SOCKET6096_13568-001,SMLF,IO,DGA^6000030    I42 @T6G_MB_LIB.T6G(SCH_1):PAGE30
   U25  H33 VDDCR_CPU0_H33 GENOA_SP5-SOCKET6096_13568-001,SMLF,IO,DGA^6000030    I42 @T6G_MB_LIB.T6G(SCH_1):PAGE30
   U25  H43 VDDCR_CPU0_H43 GENOA_SP5-SOCKET6096_13568-001,SMLF,IO,DGA^6000030    I42 @T6G_MB_LIB.T6G(SCH_1):PAGE30
   U25  H44 VDDCR_CPU0_H44 GENOA_SP5-SOCKET6096_13568-001,SMLF,IO,DGA^6000030    I42 @T6G_MB_LIB.T6G(SCH_1):PAGE30
   U25  H46 VDDCR_CPU0_H46 GENOA_SP5-SOCKET6096_13568-001,SMLF,IO,DGA^6000030    I42 @T6G_MB_LIB.T6G(SCH_1):PAGE30
   U25  H47 VDDCR_CPU0_H47 GENOA_SP5-SOCKET6096_13568-001,SMLF,IO,DGA^6000030    I42 @T6G_MB_LIB.T6G(SCH_1):PAGE30
   U25  H49 VDDCR_CPU0_H49 GENOA_SP5-SOCKET6096_13568-001,SMLF,IO,DGA^6000030    I42 @T6G_MB_LIB.T6G(SCH_1):PAGE30
   U25  H50 VDDCR_CPU0_H50 GENOA_SP5-SOCKET6096_13568-001,SMLF,IO,DGA^6000030    I42 @T6G_MB_LIB.T6G(SCH_1):PAGE30
   U25  H52 VDDCR_CPU0_H52 GENOA_SP5-SOCKET6096_13568-001,SMLF,IO,DGA^6000030    I42 @T6G_MB_LIB.T6G(SCH_1):PAGE30
   U25  H53 VDDCR_CPU0_H53 GENOA_SP5-SOCKET6096_13568-001,SMLF,IO,DGA^6000030    I42 @T6G_MB_LIB.T6G(SCH_1):PAGE30
   U25  J35 VDDCR_CPU0_J35 GENOA_SP5-SOCKET6096_13568-001,SMLF,IO,DGA^6000030    I42 @T6G_MB_LIB.T6G(SCH_1):PAGE30
   U25  J36 VDDCR_CPU0_J36 GENOA_SP5-SOCKET6096_13568-001,SMLF,IO,DGA^6000030    I42 @T6G_MB_LIB.T6G(SCH_1):PAGE30
   U25  J40 VDDCR_CPU0_J40 GENOA_SP5-SOCKET6096_13568-001,SMLF,IO,DGA^6000030    I42 @T6G_MB_LIB.T6G(SCH_1):PAGE30
   U25  J41 VDDCR_CPU0_J41 GENOA_SP5-SOCKET6096_13568-001,SMLF,IO,DGA^6000030    I42 @T6G_MB_LIB.T6G(SCH_1):PAGE30
   U25  M23 VDDCR_CPU0_M23 GENOA_SP5-SOCKET6096_13568-001,SMLF,IO,DGA^6000030    I42 @T6G_MB_LIB.T6G(SCH_1):PAGE30
   U25  M24 VDDCR_CPU0_M24 GENOA_SP5-SOCKET6096_13568-001,SMLF,IO,DGA^6000030    I42 @T6G_MB_LIB.T6G(SCH_1):PAGE30
   U25  M26 VDDCR_CPU0_M26 GENOA_SP5-SOCKET6096_13568-001,SMLF,IO,DGA^6000030    I42 @T6G_MB_LIB.T6G(SCH_1):PAGE30
   U25  M27 VDDCR_CPU0_M27 GENOA_SP5-SOCKET6096_13568-001,SMLF,IO,DGA^6000030    I42 @T6G_MB_LIB.T6G(SCH_1):PAGE30
   U25  M29 VDDCR_CPU0_M29 GENOA_SP5-SOCKET6096_13568-001,SMLF,IO,DGA^6000030    I42 @T6G_MB_LIB.T6G(SCH_1):PAGE30
   U25  M30 VDDCR_CPU0_M30 GENOA_SP5-SOCKET6096_13568-001,SMLF,IO,DGA^6000030    I42 @T6G_MB_LIB.T6G(SCH_1):PAGE30
   U25  M32 VDDCR_CPU0_M32 GENOA_SP5-SOCKET6096_13568-001,SMLF,IO,DGA^6000030    I42 @T6G_MB_LIB.T6G(SCH_1):PAGE30
   U25  M33 VDDCR_CPU0_M33 GENOA_SP5-SOCKET6096_13568-001,SMLF,IO,DGA^6000030    I42 @T6G_MB_LIB.T6G(SCH_1):PAGE30
   U25  M43 VDDCR_CPU0_M43 GENOA_SP5-SOCKET6096_13568-001,SMLF,IO,DGA^6000030    I42 @T6G_MB_LIB.T6G(SCH_1):PAGE30
   U25  M44 VDDCR_CPU0_M44 GENOA_SP5-SOCKET6096_13568-001,SMLF,IO,DGA^6000030    I42 @T6G_MB_LIB.T6G(SCH_1):PAGE30
   U25  M46 VDDCR_CPU0_M46 GENOA_SP5-SOCKET6096_13568-001,SMLF,IO,DGA^6000030    I42 @T6G_MB_LIB.T6G(SCH_1):PAGE30
   U25  M47 VDDCR_CPU0_M47 GENOA_SP5-SOCKET6096_13568-001,SMLF,IO,DGA^6000030    I42 @T6G_MB_LIB.T6G(SCH_1):PAGE30
   U25  M49 VDDCR_CPU0_M49 GENOA_SP5-SOCKET6096_13568-001,SMLF,IO,DGA^6000030    I42 @T6G_MB_LIB.T6G(SCH_1):PAGE30
   U25  M50 VDDCR_CPU0_M50 GENOA_SP5-SOCKET6096_13568-001,SMLF,IO,DGA^6000030    I42 @T6G_MB_LIB.T6G(SCH_1):PAGE30
   U25  M52 VDDCR_CPU0_M52 GENOA_SP5-SOCKET6096_13568-001,SMLF,IO,DGA^6000030    I42 @T6G_MB_LIB.T6G(SCH_1):PAGE30
   U25  M53 VDDCR_CPU0_M53 GENOA_SP5-SOCKET6096_13568-001,SMLF,IO,DGA^6000030    I42 @T6G_MB_LIB.T6G(SCH_1):PAGE30
   U25  N35 VDDCR_CPU0_N35 GENOA_SP5-SOCKET6096_13568-001,SMLF,IO,DGA^6000030    I42 @T6G_MB_LIB.T6G(SCH_1):PAGE30
   U25  N36 VDDCR_CPU0_N36 GENOA_SP5-SOCKET6096_13568-001,SMLF,IO,DGA^6000030    I42 @T6G_MB_LIB.T6G(SCH_1):PAGE30
   U25  N40 VDDCR_CPU0_N40 GENOA_SP5-SOCKET6096_13568-001,SMLF,IO,DGA^6000030    I42 @T6G_MB_LIB.T6G(SCH_1):PAGE30
   U25  N41 VDDCR_CPU0_N41 GENOA_SP5-SOCKET6096_13568-001,SMLF,IO,DGA^6000030    I42 @T6G_MB_LIB.T6G(SCH_1):PAGE30
   U25  T23 VDDCR_CPU0_T23 GENOA_SP5-SOCKET6096_13568-001,SMLF,IO,DGA^6000030    I42 @T6G_MB_LIB.T6G(SCH_1):PAGE30
   U25  T24 VDDCR_CPU0_T24 GENOA_SP5-SOCKET6096_13568-001,SMLF,IO,DGA^6000030    I42 @T6G_MB_LIB.T6G(SCH_1):PAGE30
   U25  T26 VDDCR_CPU0_T26 GENOA_SP5-SOCKET6096_13568-001,SMLF,IO,DGA^6000030    I42 @T6G_MB_LIB.T6G(SCH_1):PAGE30
   U25  T27 VDDCR_CPU0_T27 GENOA_SP5-SOCKET6096_13568-001,SMLF,IO,DGA^6000030    I42 @T6G_MB_LIB.T6G(SCH_1):PAGE30
   U25  T29 VDDCR_CPU0_T29 GENOA_SP5-SOCKET6096_13568-001,SMLF,IO,DGA^6000030    I42 @T6G_MB_LIB.T6G(SCH_1):PAGE30
   U25  T30 VDDCR_CPU0_T30 GENOA_SP5-SOCKET6096_13568-001,SMLF,IO,DGA^6000030    I42 @T6G_MB_LIB.T6G(SCH_1):PAGE30
   U25  T32 VDDCR_CPU0_T32 GENOA_SP5-SOCKET6096_13568-001,SMLF,IO,DGA^6000030    I42 @T6G_MB_LIB.T6G(SCH_1):PAGE30
   U25  T33 VDDCR_CPU0_T33 GENOA_SP5-SOCKET6096_13568-001,SMLF,IO,DGA^6000030    I42 @T6G_MB_LIB.T6G(SCH_1):PAGE30
   U25  T43 VDDCR_CPU0_T43 GENOA_SP5-SOCKET6096_13568-001,SMLF,IO,DGA^6000030    I42 @T6G_MB_LIB.T6G(SCH_1):PAGE30
   U25  T44 VDDCR_CPU0_T44 GENOA_SP5-SOCKET6096_13568-001,SMLF,IO,DGA^6000030    I42 @T6G_MB_LIB.T6G(SCH_1):PAGE30
   U25  T46 VDDCR_CPU0_T46 GENOA_SP5-SOCKET6096_13568-001,SMLF,IO,DGA^6000030    I42 @T6G_MB_LIB.T6G(SCH_1):PAGE30
   U25  T47 VDDCR_CPU0_T47 GENOA_SP5-SOCKET6096_13568-001,SMLF,IO,DGA^6000030    I42 @T6G_MB_LIB.T6G(SCH_1):PAGE30
   U25  T49 VDDCR_CPU0_T49 GENOA_SP5-SOCKET6096_13568-001,SMLF,IO,DGA^6000030    I42 @T6G_MB_LIB.T6G(SCH_1):PAGE30
   U25  T50 VDDCR_CPU0_T50 GENOA_SP5-SOCKET6096_13568-001,SMLF,IO,DGA^6000030    I42 @T6G_MB_LIB.T6G(SCH_1):PAGE30
   U25  T52 VDDCR_CPU0_T52 GENOA_SP5-SOCKET6096_13568-001,SMLF,IO,DGA^6000030    I42 @T6G_MB_LIB.T6G(SCH_1):PAGE30
   U25  T53 VDDCR_CPU0_T53 GENOA_SP5-SOCKET6096_13568-001,SMLF,IO,DGA^6000030    I42 @T6G_MB_LIB.T6G(SCH_1):PAGE30
   U25  U35 VDDCR_CPU0_U35 GENOA_SP5-SOCKET6096_13568-001,SMLF,IO,DGA^6000030    I42 @T6G_MB_LIB.T6G(SCH_1):PAGE30
   U25  U36 VDDCR_CPU0_U36 GENOA_SP5-SOCKET6096_13568-001,SMLF,IO,DGA^6000030    I42 @T6G_MB_LIB.T6G(SCH_1):PAGE30
   U25  U40 VDDCR_CPU0_U40 GENOA_SP5-SOCKET6096_13568-001,SMLF,IO,DGA^6000030    I42 @T6G_MB_LIB.T6G(SCH_1):PAGE30
   U25  U41 VDDCR_CPU0_U41 GENOA_SP5-SOCKET6096_13568-001,SMLF,IO,DGA^6000030    I42 @T6G_MB_LIB.T6G(SCH_1):PAGE30
   U25  W29 VDDCR_CPU0_W29 GENOA_SP5-SOCKET6096_13568-001,SMLF,IO,DGA^6000030    I42 @T6G_MB_LIB.T6G(SCH_1):PAGE30
   U25  W30 VDDCR_CPU0_W30 GENOA_SP5-SOCKET6096_13568-001,SMLF,IO,DGA^6000030    I42 @T6G_MB_LIB.T6G(SCH_1):PAGE30
   U25  W32 VDDCR_CPU0_W32 GENOA_SP5-SOCKET6096_13568-001,SMLF,IO,DGA^6000030    I42 @T6G_MB_LIB.T6G(SCH_1):PAGE30
   U25  W33 VDDCR_CPU0_W33 GENOA_SP5-SOCKET6096_13568-001,SMLF,IO,DGA^6000030    I42 @T6G_MB_LIB.T6G(SCH_1):PAGE30
   U25  W43 VDDCR_CPU0_W43 GENOA_SP5-SOCKET6096_13568-001,SMLF,IO,DGA^6000030    I42 @T6G_MB_LIB.T6G(SCH_1):PAGE30
   U25  W44 VDDCR_CPU0_W44 GENOA_SP5-SOCKET6096_13568-001,SMLF,IO,DGA^6000030    I42 @T6G_MB_LIB.T6G(SCH_1):PAGE30
   U25  W46 VDDCR_CPU0_W46 GENOA_SP5-SOCKET6096_13568-001,SMLF,IO,DGA^6000030    I42 @T6G_MB_LIB.T6G(SCH_1):PAGE30
   U25  W47 VDDCR_CPU0_W47 GENOA_SP5-SOCKET6096_13568-001,SMLF,IO,DGA^6000030    I42 @T6G_MB_LIB.T6G(SCH_1):PAGE30
   U25  Y35 VDDCR_CPU0_Y35 GENOA_SP5-SOCKET6096_13568-001,SMLF,IO,DGA^6000030    I42 @T6G_MB_LIB.T6G(SCH_1):PAGE30
   U25  Y36 VDDCR_CPU0_Y36 GENOA_SP5-SOCKET6096_13568-001,SMLF,IO,DGA^6000030    I42 @T6G_MB_LIB.T6G(SCH_1):PAGE30
   U25  Y40 VDDCR_CPU0_Y40 GENOA_SP5-SOCKET6096_13568-001,SMLF,IO,DGA^6000030    I42 @T6G_MB_LIB.T6G(SCH_1):PAGE30
   U25  Y41 VDDCR_CPU0_Y41 GENOA_SP5-SOCKET6096_13568-001,SMLF,IO,DGA^6000030    I42 @T6G_MB_LIB.T6G(SCH_1):PAGE30
 C2167    1      A Q_CAP_C0402-22UF,4V,20%,X6S,CH622KMEB02     I1 @T6G_MB_LIB.T6G(SCH_1):PAGE68
 C2171    1      A Q_CAP_C0402-22UF,4V,20%,X6S,CH622KMEB02     I2 @T6G_MB_LIB.T6G(SCH_1):PAGE68
 C2166    1      A Q_CAP_C0402-22UF,4V,20%,X6S,CH622KMEB02     I4 @T6G_MB_LIB.T6G(SCH_1):PAGE68
 C2170    1      A Q_CAP_C0402-22UF,4V,20%,X6S,CH622KMEB02     I5 @T6G_MB_LIB.T6G(SCH_1):PAGE68
 C2165    1      A Q_CAP_C0402-22UF,4V,20%,X6S,CH622KMEB02     I7 @T6G_MB_LIB.T6G(SCH_1):PAGE68
 C2169    1      A Q_CAP_C0402-22UF,4V,20%,X6S,CH622KMEB02     I9 @T6G_MB_LIB.T6G(SCH_1):PAGE68
  C246    1      A Q_CAP_C0402-22UF,4V,20%,X6S,CH622KMEB02    I10 @T6G_MB_LIB.T6G(SCH_1):PAGE68
  C252    1      A Q_CAP_C0402-22UF,4V,20%,X6S,CH622KMEB02    I12 @T6G_MB_LIB.T6G(SCH_1):PAGE68
  C245    1      A Q_CAP_C0402-22UF,4V,20%,X6S,CH622KMEB02    I14 @T6G_MB_LIB.T6G(SCH_1):PAGE68
  C251    1      A Q_CAP_C0402-22UF,4V,20%,X6S,CH622KMEB02    I15 @T6G_MB_LIB.T6G(SCH_1):PAGE68
 C2175    1      A Q_CAP_C0402-22UF,4V,20%,X6S,CH622KMEB02    I16 @T6G_MB_LIB.T6G(SCH_1):PAGE68
C10179    1      A Q_CAP_C0402-22UF,4V,20%,X6S,CH622KMEB02    I17 @T6G_MB_LIB.T6G(SCH_1):PAGE68
 C2183    1      A Q_CAP_C0402-22UF,4V,20%,X6S,CH622KMEB02    I19 @T6G_MB_LIB.T6G(SCH_1):PAGE68
 C2174    1      A Q_CAP_C0402-22UF,4V,20%,X6S,CH622KMEB02    I20 @T6G_MB_LIB.T6G(SCH_1):PAGE68
 C2178    1      A Q_CAP_C0402-22UF,4V,20%,X6S,CH622KMEB02    I21 @T6G_MB_LIB.T6G(SCH_1):PAGE68
 C2173    1      A Q_CAP_C0402-22UF,4V,20%,X6S,CH622KMEB02    I22 @T6G_MB_LIB.T6G(SCH_1):PAGE68
 C2177    1      A Q_CAP_C0402-22UF,4V,20%,X6S,CH622KMEB02    I23 @T6G_MB_LIB.T6G(SCH_1):PAGE68
 C2182    1      A Q_CAP_C0402-22UF,4V,20%,X6S,CH622KMEB02    I24 @T6G_MB_LIB.T6G(SCH_1):PAGE68
 C2181    1      A Q_CAP_C0402-22UF,4V,20%,X6S,CH622KMEB02    I25 @T6G_MB_LIB.T6G(SCH_1):PAGE68
 C2186    1      A Q_CAP_C0402-22UF,4V,20%,X6S,CH622KMEB02    I26 @T6G_MB_LIB.T6G(SCH_1):PAGE68
 C2190    1      A Q_CAP_C0402-22UF,4V,20%,X6S,CH622KMEB02    I27 @T6G_MB_LIB.T6G(SCH_1):PAGE68
 C2185    1      A Q_CAP_C0402-22UF,4V,20%,X6S,CH622KMEB02    I28 @T6G_MB_LIB.T6G(SCH_1):PAGE68
 C2189    1      A Q_CAP_C0402-22UF,4V,20%,X6S,CH622KMEB02    I29 @T6G_MB_LIB.T6G(SCH_1):PAGE68
 C2193    1      A Q_CAP_C0402-22UF,4V,20%,X6S,CH622KMEB02    I31 @T6G_MB_LIB.T6G(SCH_1):PAGE68
 C2196    1      A Q_CAP_C0402-22UF,4V,20%,X6S,CH622KMEB02    I32 @T6G_MB_LIB.T6G(SCH_1):PAGE68
 C2192    1      A Q_CAP_C0402-22UF,4V,20%,X6S,CH622KMEB02    I33 @T6G_MB_LIB.T6G(SCH_1):PAGE68
 C2195    1      A Q_CAP_C0402-22UF,4V,20%,X6S,CH622KMEB02    I34 @T6G_MB_LIB.T6G(SCH_1):PAGE68
 C2199    1      A Q_CAP_C0402-22UF,4V,20%,X6S,CH622KMEB02    I36 @T6G_MB_LIB.T6G(SCH_1):PAGE68
 C2198    1      A Q_CAP_C0402-22UF,4V,20%,X6S,CH622KMEB02    I40 @T6G_MB_LIB.T6G(SCH_1):PAGE68
 C1922    1      A Q_CAP_C0402-22UF,4V,20%,X6S,CH622KMEB02    I45 @T6G_MB_LIB.T6G(SCH_1):PAGE68
  C263    1      A Q_CAP_C0402-22UF,4V,20%,X6S,CH622KMEB02    I46 @T6G_MB_LIB.T6G(SCH_1):PAGE68
 C4178    1      A Q_CAP_C0402-22UF,4V,20%,X6S,CH622KMEB02    I47 @T6G_MB_LIB.T6G(SCH_1):PAGE68
 C4179    1      A Q_CAP_C0402-22UF,4V,20%,X6S,CH622KMEB02    I48 @T6G_MB_LIB.T6G(SCH_1):PAGE68
  C268    1      A Q_CAP_C0402-22UF,4V,20%,X6S,CH622KMEB02    I49 @T6G_MB_LIB.T6G(SCH_1):PAGE68
  C267    1      A Q_CAP_C0402-22UF,4V,20%,X6S,CH622KMEB02    I50 @T6G_MB_LIB.T6G(SCH_1):PAGE68
  C271    1      A Q_CAP_C0402-22UF,4V,20%,X6S,CH622KMEB02    I51 @T6G_MB_LIB.T6G(SCH_1):PAGE68
  C273    1      A Q_CAP_C0402-22UF,4V,20%,X6S,CH622KMEB02    I52 @T6G_MB_LIB.T6G(SCH_1):PAGE68
  C270    1      A Q_CAP_C0402-22UF,4V,20%,X6S,CH622KMEB02    I53 @T6G_MB_LIB.T6G(SCH_1):PAGE68
  C275    1      A Q_CAP_C0402-22UF,4V,20%,X6S,CH622KMEB02    I54 @T6G_MB_LIB.T6G(SCH_1):PAGE68
  C277    1      A Q_CAP_C0402-22UF,4V,20%,X6S,CH622KMEB02    I55 @T6G_MB_LIB.T6G(SCH_1):PAGE68
  C274    1      A Q_CAP_C0402-22UF,4V,20%,X6S,CH622KMEB02    I56 @T6G_MB_LIB.T6G(SCH_1):PAGE68
  C276    1      A Q_CAP_C0402-22UF,4V,20%,X6S,CH622KMEB02    I57 @T6G_MB_LIB.T6G(SCH_1):PAGE68
  C279    1      A Q_CAP_C0402-22UF,4V,20%,X6S,CH622KMEB02    I58 @T6G_MB_LIB.T6G(SCH_1):PAGE68
  C278    1      A Q_CAP_C0402-22UF,4V,20%,X6S,CH622KMEB02    I62 @T6G_MB_LIB.T6G(SCH_1):PAGE68
  C272    1      A Q_CAP_C0402-22UF,4V,20%,X6S,CH622KMEB02   I110 @T6G_MB_LIB.T6G(SCH_1):PAGE68
  PL52    4      4 Q_INDUCTOR4P_14-150NH,SMLF,IND,CV+15^0TZ04    I62 @T6G_MB_LIB.T6G(SCH_1):PAGE169
 PC108    1      A Q_CAPP_SMLF-220UF,4V,20%,SPCAP,CH122KM8801    I64 @T6G_MB_LIB.T6G(SCH_1):PAGE169
 PC494    1      A Q_CAPP_SMLF-220UF,4V,20%,SPCAP,CH122KM8801    I65 @T6G_MB_LIB.T6G(SCH_1):PAGE169
 PC495    1      A Q_CAPP_SMLF-220UF,4V,20%,SPCAP,CH122KM8801    I66 @T6G_MB_LIB.T6G(SCH_1):PAGE169
 PC496    1      A Q_CAPP_SMLF-220UF,4V,20%,SPCAP,CH122KM8801    I67 @T6G_MB_LIB.T6G(SCH_1):PAGE169
PC499_2    1      A Q_CAP_C0805-22UF,4V,20%,X6S,CH622KMEA03    I68 @T6G_MB_LIB.T6G(SCH_1):PAGE169
 PR350    2      B Q_RES_0402LF-0,5%,1/16W,CHIP,CS00002JB13    I26 @T6G_MB_LIB.T6G(SCH_1):PAGE170
 PR294    1      A Q_RES_0402LF-49.9,1%,1/16W,CHIP,CS04992FB07    I72 @T6G_MB_LIB.T6G(SCH_1):PAGE168
 PR325    2      B Q_RES_0402LF-0,5%,1/16W,CHIP,CS00002JB13    I30 @T6G_MB_LIB.T6G(SCH_1):PAGE169
 PR324    2      B Q_RES_0402LF-0,5%,1/16W,CHIP,CS00002JB13    I43 @T6G_MB_LIB.T6G(SCH_1):PAGE169
PC501_2    1      A Q_CAP_C0805-22UF,4V,20%,X6S,CH622KMEA03    I70 @T6G_MB_LIB.T6G(SCH_1):PAGE169
 PC498    1      A Q_CAPP_SMLF-220UF,4V,20%,SPCAP,CH122KM8801    I73 @T6G_MB_LIB.T6G(SCH_1):PAGE169
  PL51    4      4 Q_INDUCTOR4P_14-150NH,SMLF,IND,CV+15^0TZ04    I77 @T6G_MB_LIB.T6G(SCH_1):PAGE169
 PC497    1      A Q_CAP_0402-0.1UF,25V,10%,X7R,CH4104K1B00    I87 @T6G_MB_LIB.T6G(SCH_1):PAGE169
PC500_1    1      A Q_CAP_C0805-22UF,4V,20%,X6S,CH622KMEA03    I88 @T6G_MB_LIB.T6G(SCH_1):PAGE169
PC502_1    1      A Q_CAP_C0805-22UF,4V,20%,X6S,CH622KMEA03    I89 @T6G_MB_LIB.T6G(SCH_1):PAGE169
 PR447    1      A Q_RES_0402LF-1K,1%,1/16W,CHIP,CS21002FB06    I90 @T6G_MB_LIB.T6G(SCH_1):PAGE169
 PR351    2      B Q_RES_0402LF-0,5%,1/16W,CHIP,CS00002JB13    I50 @T6G_MB_LIB.T6G(SCH_1):PAGE170
  PL60    4      4 Q_INDUCTOR4P_14-150NH,SMLF,IND,CV+15^0TZ04    I52 @T6G_MB_LIB.T6G(SCH_1):PAGE170
PC563_4    1      A Q_CAP_C0805-22UF,4V,20%,X6S,CH622KMEA03    I58 @T6G_MB_LIB.T6G(SCH_1):PAGE170
PC565_4    1      A Q_CAP_C0805-22UF,4V,20%,X6S,CH622KMEA03    I60 @T6G_MB_LIB.T6G(SCH_1):PAGE170
  PL59    4      4 Q_INDUCTOR4P_14-150NH,SMLF,IND,CV+15^0TZ04    I64 @T6G_MB_LIB.T6G(SCH_1):PAGE170
PC562_3    1      A Q_CAP_C0805-22UF,4V,20%,X6S,CH622KMEA03    I70 @T6G_MB_LIB.T6G(SCH_1):PAGE170
PC564_3    1      A Q_CAP_C0805-22UF,4V,20%,X6S,CH622KMEA03    I71 @T6G_MB_LIB.T6G(SCH_1):PAGE170
 PR433    2      B Q_RES_0402LF-0,5%,1/16W,CHIP,CS00002JB13    I21 @T6G_MB_LIB.T6G(SCH_1):PAGE171
 PR355    2      B Q_RES_0402LF-0,5%,1/16W,CHIP,CS00002JB13    I32 @T6G_MB_LIB.T6G(SCH_1):PAGE171
  PL70    4      4 Q_INDUCTOR4P_14-150NH,SMLF,IND,CV+15^0TZ04    I52 @T6G_MB_LIB.T6G(SCH_1):PAGE171
PC163_6    1      A Q_CAP_C0805-22UF,4V,20%,X6S,CH622KMEA03    I59 @T6G_MB_LIB.T6G(SCH_1):PAGE171
PC166_6    1      A Q_CAP_C0805-22UF,4V,20%,X6S,CH622KMEA03    I60 @T6G_MB_LIB.T6G(SCH_1):PAGE171
  PL61    4      4 Q_INDUCTOR4P_14-150NH,SMLF,IND,CV+15^0TZ04    I64 @T6G_MB_LIB.T6G(SCH_1):PAGE171
PC575_5    1      A Q_CAP_C0805-22UF,4V,20%,X6S,CH622KMEA03    I69 @T6G_MB_LIB.T6G(SCH_1):PAGE171
PC576_5    1      A Q_CAP_C0805-22UF,4V,20%,X6S,CH622KMEA03    I71 @T6G_MB_LIB.T6G(SCH_1):PAGE171

PVDDCR_CPU0_P0_EN @T6G_MB_LIB.T6G(SCH_1):PVDDCR_CPU0_P0_EN
 R8312    1      A Q_RES_0402LF-0,5%,1/16W,CHIP,CS00002JB13    I88 @T6G_MB_LIB.T6G(SCH_1):PAGE168
   U18  B17  PT39B LCMXO3LF9400C5BG484C-LCMXO3LF-9400C-5BG484C,SMLF,IA    I94 @T6G_MB_LIB.T6G(SCH_1):PAGE79

PVDDCR_CPU0_P0_EN_R @T6G_MB_LIB.T6G(SCH_1):PVDDCR_CPU0_P0_EN_R
 R8312    2      B Q_RES_0402LF-0,5%,1/16W,CHIP,CS00002JB13    I88 @T6G_MB_LIB.T6G(SCH_1):PAGE168
  C468    1      A Q_CAP_0402-1000PF,50V,5%,X7R,TMP_QCH21006JB10    I90 @T6G_MB_LIB.T6G(SCH_1):PAGE168
  PU42   17    EN0 RAA229620GNPHA0-RAA229620GNP#HA0,SMLF,IC,ARF0TGP40A   I135 @T6G_MB_LIB.T6G(SCH_1):PAGE168

PVDDCR_CPU0_P0_IMON1 @T6G_MB_LIB.T6G(SCH_1):PVDDCR_CPU0_P0_IMON1
   PU6   38   IOUT ISL99390FRZTR5935-ISL99390FRZ-TR5935,SMLF,IC,AL099A    I26 @T6G_MB_LIB.T6G(SCH_1):PAGE169
  PU42   27   CS11 RAA229620GNPHA0-RAA229620GNP#HA0,SMLF,IC,ARF0TGP40A   I135 @T6G_MB_LIB.T6G(SCH_1):PAGE168

PVDDCR_CPU0_P0_IMON2 @T6G_MB_LIB.T6G(SCH_1):PVDDCR_CPU0_P0_IMON2
  PU43   38   IOUT ISL99390FRZTR5935-ISL99390FRZ-TR5935,SMLF,IC,AL099A    I16 @T6G_MB_LIB.T6G(SCH_1):PAGE169
  PU42   28   CS10 RAA229620GNPHA0-RAA229620GNP#HA0,SMLF,IC,ARF0TGP40A   I135 @T6G_MB_LIB.T6G(SCH_1):PAGE168

PVDDCR_CPU0_P0_IMON3 @T6G_MB_LIB.T6G(SCH_1):PVDDCR_CPU0_P0_IMON3
  PU42   29    CS9 RAA229620GNPHA0-RAA229620GNP#HA0,SMLF,IC,ARF0TGP40A   I135 @T6G_MB_LIB.T6G(SCH_1):PAGE168
  PU46   38   IOUT ISL99390FRZTR5935-ISL99390FRZ-TR5935,SMLF,IC,AL099A    I38 @T6G_MB_LIB.T6G(SCH_1):PAGE170

PVDDCR_CPU0_P0_IMON4 @T6G_MB_LIB.T6G(SCH_1):PVDDCR_CPU0_P0_IMON4
  PU42   30    CS8 RAA229620GNPHA0-RAA229620GNP#HA0,SMLF,IC,ARF0TGP40A   I135 @T6G_MB_LIB.T6G(SCH_1):PAGE168
  PU47   38   IOUT ISL99390FRZTR5935-ISL99390FRZ-TR5935,SMLF,IC,AL099A     I9 @T6G_MB_LIB.T6G(SCH_1):PAGE170

PVDDCR_CPU0_P0_IMON5 @T6G_MB_LIB.T6G(SCH_1):PVDDCR_CPU0_P0_IMON5
  PU42   31    CS7 RAA229620GNPHA0-RAA229620GNP#HA0,SMLF,IC,ARF0TGP40A   I135 @T6G_MB_LIB.T6G(SCH_1):PAGE168
  PU48   38   IOUT ISL99390FRZTR5935-ISL99390FRZ-TR5935,SMLF,IC,AL099A    I18 @T6G_MB_LIB.T6G(SCH_1):PAGE171

PVDDCR_CPU0_P0_IMON6 @T6G_MB_LIB.T6G(SCH_1):PVDDCR_CPU0_P0_IMON6
  PU42   32    CS6 RAA229620GNPHA0-RAA229620GNP#HA0,SMLF,IC,ARF0TGP40A   I135 @T6G_MB_LIB.T6G(SCH_1):PAGE168
  PU10   38   IOUT ISL99390FRZTR5935-ISL99390FRZ-TR5935,SMLF,IC,AL099A    I73 @T6G_MB_LIB.T6G(SCH_1):PAGE171

PVDDCR_CPU0_P0_LSET1 @T6G_MB_LIB.T6G(SCH_1):PVDDCR_CPU0_P0_LSET1
   PU6   37   LSET ISL99390FRZTR5935-ISL99390FRZ-TR5935,SMLF,IC,AL099A    I26 @T6G_MB_LIB.T6G(SCH_1):PAGE169
 PR320    2      B Q_RES_0402LF-8.87K,1%,1/16W,EMPTY,CS28872FB01    I46 @T6G_MB_LIB.T6G(SCH_1):PAGE169

PVDDCR_CPU0_P0_LSET2 @T6G_MB_LIB.T6G(SCH_1):PVDDCR_CPU0_P0_LSET2
  PU43   37   LSET ISL99390FRZTR5935-ISL99390FRZ-TR5935,SMLF,IC,AL099A    I16 @T6G_MB_LIB.T6G(SCH_1):PAGE169
 PR321    2      B Q_RES_0402LF-8.87K,1%,1/16W,EMPTY,CS28872FB01    I10 @T6G_MB_LIB.T6G(SCH_1):PAGE169

PVDDCR_CPU0_P0_LSET3 @T6G_MB_LIB.T6G(SCH_1):PVDDCR_CPU0_P0_LSET3
 PR346    2      B Q_RES_0402LF-8.87K,1%,1/16W,EMPTY,CS28872FB01    I33 @T6G_MB_LIB.T6G(SCH_1):PAGE170
  PU46   37   LSET ISL99390FRZTR5935-ISL99390FRZ-TR5935,SMLF,IC,AL099A    I38 @T6G_MB_LIB.T6G(SCH_1):PAGE170

PVDDCR_CPU0_P0_LSET4 @T6G_MB_LIB.T6G(SCH_1):PVDDCR_CPU0_P0_LSET4
  PU47   37   LSET ISL99390FRZTR5935-ISL99390FRZ-TR5935,SMLF,IC,AL099A     I9 @T6G_MB_LIB.T6G(SCH_1):PAGE170
 PR347    2      B Q_RES_0402LF-8.87K,1%,1/16W,EMPTY,CS28872FB01    I11 @T6G_MB_LIB.T6G(SCH_1):PAGE170

PVDDCR_CPU0_P0_LSET5 @T6G_MB_LIB.T6G(SCH_1):PVDDCR_CPU0_P0_LSET5
  PU48   37   LSET ISL99390FRZTR5935-ISL99390FRZ-TR5935,SMLF,IC,AL099A    I18 @T6G_MB_LIB.T6G(SCH_1):PAGE171
 PR353    2      B Q_RES_0402LF-8.87K,1%,1/16W,EMPTY,CS28872FB01    I36 @T6G_MB_LIB.T6G(SCH_1):PAGE171

PVDDCR_CPU0_P0_LSET6 @T6G_MB_LIB.T6G(SCH_1):PVDDCR_CPU0_P0_LSET6
 PR431    2      B Q_RES_0402LF-8.87K,1%,1/16W,EMPTY,CS28872FB01     I8 @T6G_MB_LIB.T6G(SCH_1):PAGE171
  PU10   37   LSET ISL99390FRZTR5935-ISL99390FRZ-TR5935,SMLF,IC,AL099A    I73 @T6G_MB_LIB.T6G(SCH_1):PAGE171

PVDDCR_CPU0_P0_OCP_N @T6G_MB_LIB.T6G(SCH_1):PVDDCR_CPU0_P0_OCP_N
 R8301    1      A Q_RES_0402LF-0,5%,1/16W,CHIP,CS00002JB13    I58 @T6G_MB_LIB.T6G(SCH_1):PAGE168
  R231    1      A Q_RES_0402LF-0,5%,1/16W,CHIP,CS00002JB13    I60 @T6G_MB_LIB.T6G(SCH_1):PAGE81

PVDDCR_CPU0_P0_OCP_N_R @T6G_MB_LIB.T6G(SCH_1):PVDDCR_CPU0_P0_OCP_N_R
 R8301    2      B Q_RES_0402LF-0,5%,1/16W,CHIP,CS00002JB13    I58 @T6G_MB_LIB.T6G(SCH_1):PAGE168
 R8313    2      B Q_RES_0402LF-1K,1%,1/16W,CHIP,CS21002FB06    I54 @T6G_MB_LIB.T6G(SCH_1):PAGE168
  PU42   41  OCP_L RAA229620GNPHA0-RAA229620GNP#HA0,SMLF,IC,ARF0TGP40A   I135 @T6G_MB_LIB.T6G(SCH_1):PAGE168

PVDDCR_CPU0_P0_PMALERT @T6G_MB_LIB.T6G(SCH_1):PVDDCR_CPU0_P0_PMALERT
 R1185    1      A Q_RES_0402LF-1K,1%,1/16W,CHIP,CS21002FB06    I62 @T6G_MB_LIB.T6G(SCH_1):PAGE82
 R8310    1      A Q_RES_0402LF-33,5%,1/16W,CHIP,CS03302JB10    I83 @T6G_MB_LIB.T6G(SCH_1):PAGE168
   U18  AB3   PB7B LCMXO3LF9400C5BG484C-LCMXO3LF-9400C-5BG484C,SMLF,IA   I216 @T6G_MB_LIB.T6G(SCH_1):PAGE80
 C5011    1      A Q_CAP_0402-1000PF,50V,5%,X7R,TMP_QCH21006JB10   I142 @T6G_MB_LIB.T6G(SCH_1):PAGE168

PVDDCR_CPU0_P0_PMALERT_R @T6G_MB_LIB.T6G(SCH_1):PVDDCR_CPU0_P0_PMALERT_R
 R8310    2      B Q_RES_0402LF-33,5%,1/16W,CHIP,CS03302JB10    I83 @T6G_MB_LIB.T6G(SCH_1):PAGE168
  PU42   15 NPMALERT RAA229620GNPHA0-RAA229620GNP#HA0,SMLF,IC,ARF0TGP40A   I135 @T6G_MB_LIB.T6G(SCH_1):PAGE168

PVDDCR_CPU0_P0_PMSCL_R @T6G_MB_LIB.T6G(SCH_1):PVDDCR_CPU0_P0_PMSCL_R
 R8308    2      B Q_RES_0402LF-0,5%,1/16W,CHIP,CS00002JB13    I85 @T6G_MB_LIB.T6G(SCH_1):PAGE168
  PU42   14  PMSCL RAA229620GNPHA0-RAA229620GNP#HA0,SMLF,IC,ARF0TGP40A   I135 @T6G_MB_LIB.T6G(SCH_1):PAGE168

PVDDCR_CPU0_P0_PMSDA_R @T6G_MB_LIB.T6G(SCH_1):PVDDCR_CPU0_P0_PMSDA_R
 R8309    2      B Q_RES_0402LF-0,5%,1/16W,CHIP,CS00002JB13    I84 @T6G_MB_LIB.T6G(SCH_1):PAGE168
  PU42   13  PMSDA RAA229620GNPHA0-RAA229620GNP#HA0,SMLF,IC,ARF0TGP40A   I135 @T6G_MB_LIB.T6G(SCH_1):PAGE168

PVDDCR_CPU0_P0_PVCC @T6G_MB_LIB.T6G(SCH_1):PVDDCR_CPU0_P0_PVCC
 PR445    1      A Q_RES_0402LF-0,5%,1/16W,CHIP,CS00002JB13     I3 @T6G_MB_LIB.T6G(SCH_1):PAGE169
 PR446    1      A Q_RES_0402LF-0,5%,1/16W,EMPTY,CS00002JB13     I4 @T6G_MB_LIB.T6G(SCH_1):PAGE169
  PU43    4   PVCC ISL99390FRZTR5935-ISL99390FRZ-TR5935,SMLF,IC,AL099A    I16 @T6G_MB_LIB.T6G(SCH_1):PAGE169
 PR319    1      A Q_RES_0402LF-2.2,1%,1/16W,CHIP,CS-2202FB01    I17 @T6G_MB_LIB.T6G(SCH_1):PAGE169
PC478_C0P0_2    1      A Q_CAP_C0402-2.2UF,10V,10%,X6S,CH5222KEB01    I19 @T6G_MB_LIB.T6G(SCH_1):PAGE169
   PU6    4   PVCC ISL99390FRZTR5935-ISL99390FRZ-TR5935,SMLF,IC,AL099A    I26 @T6G_MB_LIB.T6G(SCH_1):PAGE169
  PU51    4   PVCC ISL99390FRZTR5935-ISL99390FRZ-TR5935,SMLF,IC,AL099A    I38 @T6G_MB_LIB.T6G(SCH_1):PAGE174
 PR318    1      A Q_RES_0402LF-2.2,1%,1/16W,CHIP,CS-2202FB01    I49 @T6G_MB_LIB.T6G(SCH_1):PAGE169
PC477_C0P0_1    1      A Q_CAP_C0402-2.2UF,10V,10%,X6S,CH5222KEB01    I51 @T6G_MB_LIB.T6G(SCH_1):PAGE169
  PU47    4   PVCC ISL99390FRZTR5935-ISL99390FRZ-TR5935,SMLF,IC,AL099A     I9 @T6G_MB_LIB.T6G(SCH_1):PAGE170
 PR345    1      A Q_RES_0402LF-2.2,1%,1/16W,CHIP,CS-2202FB01    I12 @T6G_MB_LIB.T6G(SCH_1):PAGE170
PC549_C0P0_4    1      A Q_CAP_C0402-2.2UF,10V,10%,X6S,CH5222KEB01    I15 @T6G_MB_LIB.T6G(SCH_1):PAGE170
 PR344    1      A Q_RES_0402LF-2.2,1%,1/16W,CHIP,CS-2202FB01    I37 @T6G_MB_LIB.T6G(SCH_1):PAGE170
  PU46    4   PVCC ISL99390FRZTR5935-ISL99390FRZ-TR5935,SMLF,IC,AL099A    I38 @T6G_MB_LIB.T6G(SCH_1):PAGE170
PC548_C0P0_3    1      A Q_CAP_C0402-2.2UF,10V,10%,X6S,CH5222KEB01    I40 @T6G_MB_LIB.T6G(SCH_1):PAGE170
 PR430    1      A Q_RES_0402LF-2.2,1%,1/16W,CHIP,CS-2202FB01    I13 @T6G_MB_LIB.T6G(SCH_1):PAGE171
PC152_C0P0_6    1      A Q_CAP_C0402-2.2UF,10V,10%,X6S,CH5222KEB01    I14 @T6G_MB_LIB.T6G(SCH_1):PAGE171
  PU48    4   PVCC ISL99390FRZTR5935-ISL99390FRZ-TR5935,SMLF,IC,AL099A    I18 @T6G_MB_LIB.T6G(SCH_1):PAGE171
 PR352    1      A Q_RES_0402LF-2.2,1%,1/16W,CHIP,CS-2202FB01    I40 @T6G_MB_LIB.T6G(SCH_1):PAGE171
PC568_C0P0_5    1      A Q_CAP_C0402-2.2UF,10V,10%,X6S,CH5222KEB01    I42 @T6G_MB_LIB.T6G(SCH_1):PAGE171
  PU10    4   PVCC ISL99390FRZTR5935-ISL99390FRZ-TR5935,SMLF,IC,AL099A    I73 @T6G_MB_LIB.T6G(SCH_1):PAGE171
 PR357    1      A Q_RES_0402LF-2.2,1%,1/16W,CHIP,CS-2202FB01    I12 @T6G_MB_LIB.T6G(SCH_1):PAGE173
PC582_SOP0_2    1      A Q_CAP_C0402-2.2UF,10V,10%,X6S,CH5222KEB01    I14 @T6G_MB_LIB.T6G(SCH_1):PAGE173
 PR356    1      A Q_RES_0402LF-2.2,1%,1/16W,CHIP,CS-2202FB01    I38 @T6G_MB_LIB.T6G(SCH_1):PAGE173
PC581_SOP0_1    1      A Q_CAP_C0402-2.2UF,10V,10%,X6S,CH5222KEB01    I40 @T6G_MB_LIB.T6G(SCH_1):PAGE173
  PU49    4   PVCC ISL99390FRZTR5935-ISL99390FRZ-TR5935,SMLF,IC,AL099A    I41 @T6G_MB_LIB.T6G(SCH_1):PAGE173
  PU50    4   PVCC ISL99390FRZTR5935-ISL99390FRZ-TR5935,SMLF,IC,AL099A    I86 @T6G_MB_LIB.T6G(SCH_1):PAGE173
 PR364    1      A Q_RES_0402LF-2.2,1%,1/16W,CHIP,CS-2202FB01    I15 @T6G_MB_LIB.T6G(SCH_1):PAGE174
PC607_SOP0_3    1      A Q_CAP_C0402-2.2UF,10V,10%,X6S,CH5222KEB01    I19 @T6G_MB_LIB.T6G(SCH_1):PAGE174

PVDDCR_CPU0_P0_PWM1 @T6G_MB_LIB.T6G(SCH_1):PVDDCR_CPU0_P0_PWM1
   PU6   34    PWM ISL99390FRZTR5935-ISL99390FRZ-TR5935,SMLF,IC,AL099A    I26 @T6G_MB_LIB.T6G(SCH_1):PAGE169
  PU42   12  PWM11 RAA229620GNPHA0-RAA229620GNP#HA0,SMLF,IC,ARF0TGP40A   I135 @T6G_MB_LIB.T6G(SCH_1):PAGE168

PVDDCR_CPU0_P0_PWM2 @T6G_MB_LIB.T6G(SCH_1):PVDDCR_CPU0_P0_PWM2
  PU43   34    PWM ISL99390FRZTR5935-ISL99390FRZ-TR5935,SMLF,IC,AL099A    I16 @T6G_MB_LIB.T6G(SCH_1):PAGE169
  PU42   11  PWM10 RAA229620GNPHA0-RAA229620GNP#HA0,SMLF,IC,ARF0TGP40A   I135 @T6G_MB_LIB.T6G(SCH_1):PAGE168

PVDDCR_CPU0_P0_PWM3 @T6G_MB_LIB.T6G(SCH_1):PVDDCR_CPU0_P0_PWM3
  PU42   10   PWM9 RAA229620GNPHA0-RAA229620GNP#HA0,SMLF,IC,ARF0TGP40A   I135 @T6G_MB_LIB.T6G(SCH_1):PAGE168
  PU46   34    PWM ISL99390FRZTR5935-ISL99390FRZ-TR5935,SMLF,IC,AL099A    I38 @T6G_MB_LIB.T6G(SCH_1):PAGE170

PVDDCR_CPU0_P0_PWM4 @T6G_MB_LIB.T6G(SCH_1):PVDDCR_CPU0_P0_PWM4
  PU42    9   PWM8 RAA229620GNPHA0-RAA229620GNP#HA0,SMLF,IC,ARF0TGP40A   I135 @T6G_MB_LIB.T6G(SCH_1):PAGE168
  PU47   34    PWM ISL99390FRZTR5935-ISL99390FRZ-TR5935,SMLF,IC,AL099A     I9 @T6G_MB_LIB.T6G(SCH_1):PAGE170

PVDDCR_CPU0_P0_PWM5 @T6G_MB_LIB.T6G(SCH_1):PVDDCR_CPU0_P0_PWM5
  PU42    8   PWM7 RAA229620GNPHA0-RAA229620GNP#HA0,SMLF,IC,ARF0TGP40A   I135 @T6G_MB_LIB.T6G(SCH_1):PAGE168
  PU48   34    PWM ISL99390FRZTR5935-ISL99390FRZ-TR5935,SMLF,IC,AL099A    I18 @T6G_MB_LIB.T6G(SCH_1):PAGE171

PVDDCR_CPU0_P0_PWM6 @T6G_MB_LIB.T6G(SCH_1):PVDDCR_CPU0_P0_PWM6
  PU42    7   PWM6 RAA229620GNPHA0-RAA229620GNP#HA0,SMLF,IC,ARF0TGP40A   I135 @T6G_MB_LIB.T6G(SCH_1):PAGE168
  PU10   34    PWM ISL99390FRZTR5935-ISL99390FRZ-TR5935,SMLF,IC,AL099A    I73 @T6G_MB_LIB.T6G(SCH_1):PAGE171

PVDDCR_CPU0_P0_RESET_N @T6G_MB_LIB.T6G(SCH_1):PVDDCR_CPU0_P0_RESET_N
   U29    6     1Y SN74LVC2G07DCKR_SMLF-SN74LVC2G07DCKR,IC,AL002G07006    I15 @T6G_MB_LIB.T6G(SCH_1):PAGE77
  R315    1      A Q_RES_0402LF-49.9,1%,1/16W,CHIP,CS04992FB07    I57 @T6G_MB_LIB.T6G(SCH_1):PAGE168

PVDDCR_CPU0_P0_RESET_N_R @T6G_MB_LIB.T6G(SCH_1):PVDDCR_CPU0_P0_RESET_N_R
 R8317    2      B Q_RES_0402LF-1K,1%,1/16W,CHIP,CS21002FB06    I42 @T6G_MB_LIB.T6G(SCH_1):PAGE168
  R315    2      B Q_RES_0402LF-49.9,1%,1/16W,CHIP,CS04992FB07    I57 @T6G_MB_LIB.T6G(SCH_1):PAGE168
  PU42   18 RESET_L RAA229620GNPHA0-RAA229620GNP#HA0,SMLF,IC,ARF0TGP40A   I135 @T6G_MB_LIB.T6G(SCH_1):PAGE168

PVDDCR_CPU0_P0_TEMP0 @T6G_MB_LIB.T6G(SCH_1):PVDDCR_CPU0_P0_TEMP0
  PU43   36 TOUT_FLT ISL99390FRZTR5935-ISL99390FRZ-TR5935,SMLF,IC,AL099A    I16 @T6G_MB_LIB.T6G(SCH_1):PAGE169
   PU6   36 TOUT_FLT ISL99390FRZTR5935-ISL99390FRZ-TR5935,SMLF,IC,AL099A    I26 @T6G_MB_LIB.T6G(SCH_1):PAGE169
 PC469    1      A Q_CAP_0402-470PF,50V,10%,X7R,TMP_QCH14706KB18    I95 @T6G_MB_LIB.T6G(SCH_1):PAGE168
  PU42   44  TEMP0 RAA229620GNPHA0-RAA229620GNP#HA0,SMLF,IC,ARF0TGP40A   I135 @T6G_MB_LIB.T6G(SCH_1):PAGE168
  PU47   36 TOUT_FLT ISL99390FRZTR5935-ISL99390FRZ-TR5935,SMLF,IC,AL099A     I9 @T6G_MB_LIB.T6G(SCH_1):PAGE170
  PU46   36 TOUT_FLT ISL99390FRZTR5935-ISL99390FRZ-TR5935,SMLF,IC,AL099A    I38 @T6G_MB_LIB.T6G(SCH_1):PAGE170
  PU48   36 TOUT_FLT ISL99390FRZTR5935-ISL99390FRZ-TR5935,SMLF,IC,AL099A    I18 @T6G_MB_LIB.T6G(SCH_1):PAGE171
  PU10   36 TOUT_FLT ISL99390FRZTR5935-ISL99390FRZ-TR5935,SMLF,IC,AL099A    I73 @T6G_MB_LIB.T6G(SCH_1):PAGE171

PVDDCR_CPU0_P0_VCC @T6G_MB_LIB.T6G(SCH_1):PVDDCR_CPU0_P0_VCC
  PC12    1      A Q_CAP_0402-0.1UF,25V,10%,X7R,CH4104K1B00   I120 @T6G_MB_LIB.T6G(SCH_1):PAGE168
 PC471    1      A Q_CAP_C0402-1UF,16V,10%,X6S,CH5103KEB01   I131 @T6G_MB_LIB.T6G(SCH_1):PAGE168
 PR316    1      A Q_RES_0402LF-1,1%,1/16W,CHIP,CS-1002FB04   I133 @T6G_MB_LIB.T6G(SCH_1):PAGE168
  PU42   47    VCC RAA229620GNPHA0-RAA229620GNP#HA0,SMLF,IC,ARF0TGP40A   I135 @T6G_MB_LIB.T6G(SCH_1):PAGE168

PVDDCR_CPU0_P0_VCC1 @T6G_MB_LIB.T6G(SCH_1):PVDDCR_CPU0_P0_VCC1
   PU6   35     EN ISL99390FRZTR5935-ISL99390FRZ-TR5935,SMLF,IC,AL099A    I26 @T6G_MB_LIB.T6G(SCH_1):PAGE169
   PU6    3    VCC ISL99390FRZTR5935-ISL99390FRZ-TR5935,SMLF,IC,AL099A    I26 @T6G_MB_LIB.T6G(SCH_1):PAGE169
 PC475    1      A Q_CAP_C0402-2.2UF,10V,10%,X6S,CH5222KEB01    I45 @T6G_MB_LIB.T6G(SCH_1):PAGE169
 PR318    2      B Q_RES_0402LF-2.2,1%,1/16W,CHIP,CS-2202FB01    I49 @T6G_MB_LIB.T6G(SCH_1):PAGE169

PVDDCR_CPU0_P0_VCC2 @T6G_MB_LIB.T6G(SCH_1):PVDDCR_CPU0_P0_VCC2
  PU43   35     EN ISL99390FRZTR5935-ISL99390FRZ-TR5935,SMLF,IC,AL099A    I16 @T6G_MB_LIB.T6G(SCH_1):PAGE169
  PU43    3    VCC ISL99390FRZTR5935-ISL99390FRZ-TR5935,SMLF,IC,AL099A    I16 @T6G_MB_LIB.T6G(SCH_1):PAGE169
 PR319    2      B Q_RES_0402LF-2.2,1%,1/16W,CHIP,CS-2202FB01    I17 @T6G_MB_LIB.T6G(SCH_1):PAGE169
 PC476    1      A Q_CAP_C0402-2.2UF,10V,10%,X6S,CH5222KEB01    I14 @T6G_MB_LIB.T6G(SCH_1):PAGE169

PVDDCR_CPU0_P0_VCC3 @T6G_MB_LIB.T6G(SCH_1):PVDDCR_CPU0_P0_VCC3
 PC546    1      A Q_CAP_C0402-2.2UF,10V,10%,X6S,CH5222KEB01    I36 @T6G_MB_LIB.T6G(SCH_1):PAGE170
 PR344    2      B Q_RES_0402LF-2.2,1%,1/16W,CHIP,CS-2202FB01    I37 @T6G_MB_LIB.T6G(SCH_1):PAGE170
  PU46   35     EN ISL99390FRZTR5935-ISL99390FRZ-TR5935,SMLF,IC,AL099A    I38 @T6G_MB_LIB.T6G(SCH_1):PAGE170
  PU46    3    VCC ISL99390FRZTR5935-ISL99390FRZ-TR5935,SMLF,IC,AL099A    I38 @T6G_MB_LIB.T6G(SCH_1):PAGE170

PVDDCR_CPU0_P0_VCC4 @T6G_MB_LIB.T6G(SCH_1):PVDDCR_CPU0_P0_VCC4
 PC547    1      A Q_CAP_C0402-2.2UF,10V,10%,X6S,CH5222KEB01     I6 @T6G_MB_LIB.T6G(SCH_1):PAGE170
  PU47   35     EN ISL99390FRZTR5935-ISL99390FRZ-TR5935,SMLF,IC,AL099A     I9 @T6G_MB_LIB.T6G(SCH_1):PAGE170
  PU47    3    VCC ISL99390FRZTR5935-ISL99390FRZ-TR5935,SMLF,IC,AL099A     I9 @T6G_MB_LIB.T6G(SCH_1):PAGE170
 PR345    2      B Q_RES_0402LF-2.2,1%,1/16W,CHIP,CS-2202FB01    I12 @T6G_MB_LIB.T6G(SCH_1):PAGE170

PVDDCR_CPU0_P0_VCC5 @T6G_MB_LIB.T6G(SCH_1):PVDDCR_CPU0_P0_VCC5
  PU48   35     EN ISL99390FRZTR5935-ISL99390FRZ-TR5935,SMLF,IC,AL099A    I18 @T6G_MB_LIB.T6G(SCH_1):PAGE171
  PU48    3    VCC ISL99390FRZTR5935-ISL99390FRZ-TR5935,SMLF,IC,AL099A    I18 @T6G_MB_LIB.T6G(SCH_1):PAGE171
 PC567    1      A Q_CAP_C0402-2.2UF,10V,10%,X6S,CH5222KEB01    I38 @T6G_MB_LIB.T6G(SCH_1):PAGE171
 PR352    2      B Q_RES_0402LF-2.2,1%,1/16W,CHIP,CS-2202FB01    I40 @T6G_MB_LIB.T6G(SCH_1):PAGE171

PVDDCR_CPU0_P0_VCC6 @T6G_MB_LIB.T6G(SCH_1):PVDDCR_CPU0_P0_VCC6
 PC151    1      A Q_CAP_C0402-2.2UF,10V,10%,X6S,CH5222KEB01    I11 @T6G_MB_LIB.T6G(SCH_1):PAGE171
 PR430    2      B Q_RES_0402LF-2.2,1%,1/16W,CHIP,CS-2202FB01    I13 @T6G_MB_LIB.T6G(SCH_1):PAGE171
  PU10   35     EN ISL99390FRZTR5935-ISL99390FRZ-TR5935,SMLF,IC,AL099A    I73 @T6G_MB_LIB.T6G(SCH_1):PAGE171
  PU10    3    VCC ISL99390FRZTR5935-ISL99390FRZ-TR5935,SMLF,IC,AL099A    I73 @T6G_MB_LIB.T6G(SCH_1):PAGE171

PVDDCR_CPU0_P0_VCCS @T6G_MB_LIB.T6G(SCH_1):PVDDCR_CPU0_P0_VCCS
  PC13    1      A Q_CAP_0402-0.1UF,25V,10%,X7R,CH4104K1B00   I118 @T6G_MB_LIB.T6G(SCH_1):PAGE168
  PU43   39  REFIN ISL99390FRZTR5935-ISL99390FRZ-TR5935,SMLF,IC,AL099A    I16 @T6G_MB_LIB.T6G(SCH_1):PAGE169
   PU6   39  REFIN ISL99390FRZTR5935-ISL99390FRZ-TR5935,SMLF,IC,AL099A    I26 @T6G_MB_LIB.T6G(SCH_1):PAGE169
PC578_8    1      A Q_CAP_0402-0.1UF,25V,10%,X7R,CH4104K1B00     I4 @T6G_MB_LIB.T6G(SCH_1):PAGE173
PC577_7    1      A Q_CAP_0402-0.1UF,25V,10%,X7R,CH4104K1B00    I29 @T6G_MB_LIB.T6G(SCH_1):PAGE173
  PU51   39  REFIN ISL99390FRZTR5935-ISL99390FRZ-TR5935,SMLF,IC,AL099A    I38 @T6G_MB_LIB.T6G(SCH_1):PAGE174
 PC470    1      A Q_CAP_C0402-10UF,6.3V,20%,X6S,CH6101MEB03   I129 @T6G_MB_LIB.T6G(SCH_1):PAGE168
  PU42   48   VCCS RAA229620GNPHA0-RAA229620GNP#HA0,SMLF,IC,ARF0TGP40A   I135 @T6G_MB_LIB.T6G(SCH_1):PAGE168
PC474_2    1      A Q_CAP_0402-0.1UF,25V,10%,X7R,CH4104K1B00     I8 @T6G_MB_LIB.T6G(SCH_1):PAGE169
PC473_1    1      A Q_CAP_0402-0.1UF,25V,10%,X7R,CH4104K1B00    I22 @T6G_MB_LIB.T6G(SCH_1):PAGE169
PC545_4    1      A Q_CAP_0402-0.1UF,25V,10%,X7R,CH4104K1B00     I2 @T6G_MB_LIB.T6G(SCH_1):PAGE170
  PU47   39  REFIN ISL99390FRZTR5935-ISL99390FRZ-TR5935,SMLF,IC,AL099A     I9 @T6G_MB_LIB.T6G(SCH_1):PAGE170
PC544_3    1      A Q_CAP_0402-0.1UF,25V,10%,X7R,CH4104K1B00    I27 @T6G_MB_LIB.T6G(SCH_1):PAGE170
  PU46   39  REFIN ISL99390FRZTR5935-ISL99390FRZ-TR5935,SMLF,IC,AL099A    I38 @T6G_MB_LIB.T6G(SCH_1):PAGE170
PC150_6    1      A Q_CAP_0402-0.1UF,25V,10%,X7R,CH4104K1B00     I4 @T6G_MB_LIB.T6G(SCH_1):PAGE171
  PU48   39  REFIN ISL99390FRZTR5935-ISL99390FRZ-TR5935,SMLF,IC,AL099A    I18 @T6G_MB_LIB.T6G(SCH_1):PAGE171
PC566_5    1      A Q_CAP_0402-0.1UF,25V,10%,X7R,CH4104K1B00    I33 @T6G_MB_LIB.T6G(SCH_1):PAGE171
  PU10   39  REFIN ISL99390FRZTR5935-ISL99390FRZ-TR5935,SMLF,IC,AL099A    I73 @T6G_MB_LIB.T6G(SCH_1):PAGE171
  PU49   39  REFIN ISL99390FRZTR5935-ISL99390FRZ-TR5935,SMLF,IC,AL099A    I41 @T6G_MB_LIB.T6G(SCH_1):PAGE173
  PU50   39  REFIN ISL99390FRZTR5935-ISL99390FRZ-TR5935,SMLF,IC,AL099A    I86 @T6G_MB_LIB.T6G(SCH_1):PAGE173
PC605_9    1      A Q_CAP_0402-0.1UF,25V,10%,X7R,CH4104K1B00     I2 @T6G_MB_LIB.T6G(SCH_1):PAGE174

PVDDCR_CPU0_P0_VINSEN @T6G_MB_LIB.T6G(SCH_1):PVDDCR_CPU0_P0_VINSEN
 PR599    1      A Q_RES_0402LF-4.99K,1%,1/16W,EMPTY,CS24992FB07    I47 @T6G_MB_LIB.T6G(SCH_1):PAGE168
 PR314    2      B Q_RES_0402LF-0,5%,1/16W,CHIP,CS00002JB13    I48 @T6G_MB_LIB.T6G(SCH_1):PAGE168
   PC7    1      A Q_CAP_0402-0.1UF,25V,10%,X7R,CH4104K1B00    I50 @T6G_MB_LIB.T6G(SCH_1):PAGE168
  PU42   46 VINSEN RAA229620GNPHA0-RAA229620GNP#HA0,SMLF,IC,ARF0TGP40A   I135 @T6G_MB_LIB.T6G(SCH_1):PAGE168

PVDDCR_CPU0_P0_VMON @T6G_MB_LIB.T6G(SCH_1):PVDDCR_CPU0_P0_VMON
 PR290    2      B Q_RES_0402LF-40.2K,1%,1/16W,CHIP,CS34022FB04    I15 @T6G_MB_LIB.T6G(SCH_1):PAGE168
   PR5    1      A Q_RES_0402LF-10K,1%,1/16W,CHIP,CS31002FB08    I21 @T6G_MB_LIB.T6G(SCH_1):PAGE168
 PC462    1      A Q_CAP_0402-0.1UF,25V,10%,X7R,CH4104K1B00    I23 @T6G_MB_LIB.T6G(SCH_1):PAGE168
  PU42   45 VMON||IINSEN RAA229620GNPHA0-RAA229620GNP#HA0,SMLF,IC,ARF0TGP40A   I135 @T6G_MB_LIB.T6G(SCH_1):PAGE168

PVDDCR_CPU0_P0_VOS1 @T6G_MB_LIB.T6G(SCH_1):PVDDCR_CPU0_P0_VOS1
   PU6    1    VOS ISL99390FRZTR5935-ISL99390FRZ-TR5935,SMLF,IC,AL099A    I26 @T6G_MB_LIB.T6G(SCH_1):PAGE169
 PR324    1      A Q_RES_0402LF-0,5%,1/16W,CHIP,CS00002JB13    I43 @T6G_MB_LIB.T6G(SCH_1):PAGE169

PVDDCR_CPU0_P0_VOS2 @T6G_MB_LIB.T6G(SCH_1):PVDDCR_CPU0_P0_VOS2
  PU43    1    VOS ISL99390FRZTR5935-ISL99390FRZ-TR5935,SMLF,IC,AL099A    I16 @T6G_MB_LIB.T6G(SCH_1):PAGE169
 PR325    1      A Q_RES_0402LF-0,5%,1/16W,CHIP,CS00002JB13    I30 @T6G_MB_LIB.T6G(SCH_1):PAGE169

PVDDCR_CPU0_P0_VOS3 @T6G_MB_LIB.T6G(SCH_1):PVDDCR_CPU0_P0_VOS3
 PR350    1      A Q_RES_0402LF-0,5%,1/16W,CHIP,CS00002JB13    I26 @T6G_MB_LIB.T6G(SCH_1):PAGE170
  PU46    1    VOS ISL99390FRZTR5935-ISL99390FRZ-TR5935,SMLF,IC,AL099A    I38 @T6G_MB_LIB.T6G(SCH_1):PAGE170

PVDDCR_CPU0_P0_VOS4 @T6G_MB_LIB.T6G(SCH_1):PVDDCR_CPU0_P0_VOS4
  PU47    1    VOS ISL99390FRZTR5935-ISL99390FRZ-TR5935,SMLF,IC,AL099A     I9 @T6G_MB_LIB.T6G(SCH_1):PAGE170
 PR351    1      A Q_RES_0402LF-0,5%,1/16W,CHIP,CS00002JB13    I50 @T6G_MB_LIB.T6G(SCH_1):PAGE170

PVDDCR_CPU0_P0_VOS5 @T6G_MB_LIB.T6G(SCH_1):PVDDCR_CPU0_P0_VOS5
  PU48    1    VOS ISL99390FRZTR5935-ISL99390FRZ-TR5935,SMLF,IC,AL099A    I18 @T6G_MB_LIB.T6G(SCH_1):PAGE171
 PR355    1      A Q_RES_0402LF-0,5%,1/16W,CHIP,CS00002JB13    I32 @T6G_MB_LIB.T6G(SCH_1):PAGE171

PVDDCR_CPU0_P0_VOS6 @T6G_MB_LIB.T6G(SCH_1):PVDDCR_CPU0_P0_VOS6
 PR433    1      A Q_RES_0402LF-0,5%,1/16W,CHIP,CS00002JB13    I21 @T6G_MB_LIB.T6G(SCH_1):PAGE171
  PU10    1    VOS ISL99390FRZTR5935-ISL99390FRZ-TR5935,SMLF,IC,AL099A    I73 @T6G_MB_LIB.T6G(SCH_1):PAGE171

PVDDCR_CPU0_P1 @T6G_MB_LIB.T6G(SCH_1):PVDDCR_CPU0_P1
   U26 AB23 VDDCR_CPU0_AB23 GENOA_SP5-SOCKET6096_13568-001,SMLF,IO,DGA^6000030    I29 @T6G_MB_LIB.T6G(SCH_1):PAGE57
   U26 AB24 VDDCR_CPU0_AB24 GENOA_SP5-SOCKET6096_13568-001,SMLF,IO,DGA^6000030    I29 @T6G_MB_LIB.T6G(SCH_1):PAGE57
   U26 AB26 VDDCR_CPU0_AB26 GENOA_SP5-SOCKET6096_13568-001,SMLF,IO,DGA^6000030    I29 @T6G_MB_LIB.T6G(SCH_1):PAGE57
   U26 AB27 VDDCR_CPU0_AB27 GENOA_SP5-SOCKET6096_13568-001,SMLF,IO,DGA^6000030    I29 @T6G_MB_LIB.T6G(SCH_1):PAGE57
   U26 AB29 VDDCR_CPU0_AB29 GENOA_SP5-SOCKET6096_13568-001,SMLF,IO,DGA^6000030    I29 @T6G_MB_LIB.T6G(SCH_1):PAGE57
   U26 AB30 VDDCR_CPU0_AB30 GENOA_SP5-SOCKET6096_13568-001,SMLF,IO,DGA^6000030    I29 @T6G_MB_LIB.T6G(SCH_1):PAGE57
   U26 AB32 VDDCR_CPU0_AB32 GENOA_SP5-SOCKET6096_13568-001,SMLF,IO,DGA^6000030    I29 @T6G_MB_LIB.T6G(SCH_1):PAGE57
   U26 AB33 VDDCR_CPU0_AB33 GENOA_SP5-SOCKET6096_13568-001,SMLF,IO,DGA^6000030    I29 @T6G_MB_LIB.T6G(SCH_1):PAGE57
   U26 AB43 VDDCR_CPU0_AB43 GENOA_SP5-SOCKET6096_13568-001,SMLF,IO,DGA^6000030    I29 @T6G_MB_LIB.T6G(SCH_1):PAGE57
   U26 AB44 VDDCR_CPU0_AB44 GENOA_SP5-SOCKET6096_13568-001,SMLF,IO,DGA^6000030    I29 @T6G_MB_LIB.T6G(SCH_1):PAGE57
   U26 AB46 VDDCR_CPU0_AB46 GENOA_SP5-SOCKET6096_13568-001,SMLF,IO,DGA^6000030    I29 @T6G_MB_LIB.T6G(SCH_1):PAGE57
   U26 AB47 VDDCR_CPU0_AB47 GENOA_SP5-SOCKET6096_13568-001,SMLF,IO,DGA^6000030    I29 @T6G_MB_LIB.T6G(SCH_1):PAGE57
   U26 AB49 VDDCR_CPU0_AB49 GENOA_SP5-SOCKET6096_13568-001,SMLF,IO,DGA^6000030    I29 @T6G_MB_LIB.T6G(SCH_1):PAGE57
   U26 AB50 VDDCR_CPU0_AB50 GENOA_SP5-SOCKET6096_13568-001,SMLF,IO,DGA^6000030    I29 @T6G_MB_LIB.T6G(SCH_1):PAGE57
   U26 AB52 VDDCR_CPU0_AB52 GENOA_SP5-SOCKET6096_13568-001,SMLF,IO,DGA^6000030    I29 @T6G_MB_LIB.T6G(SCH_1):PAGE57
   U26 AB53 VDDCR_CPU0_AB53 GENOA_SP5-SOCKET6096_13568-001,SMLF,IO,DGA^6000030    I29 @T6G_MB_LIB.T6G(SCH_1):PAGE57
   U26 AC35 VDDCR_CPU0_AC35 GENOA_SP5-SOCKET6096_13568-001,SMLF,IO,DGA^6000030    I29 @T6G_MB_LIB.T6G(SCH_1):PAGE57
   U26 AC36 VDDCR_CPU0_AC36 GENOA_SP5-SOCKET6096_13568-001,SMLF,IO,DGA^6000030    I29 @T6G_MB_LIB.T6G(SCH_1):PAGE57
   U26 AC40 VDDCR_CPU0_AC40 GENOA_SP5-SOCKET6096_13568-001,SMLF,IO,DGA^6000030    I29 @T6G_MB_LIB.T6G(SCH_1):PAGE57
   U26 AC41 VDDCR_CPU0_AC41 GENOA_SP5-SOCKET6096_13568-001,SMLF,IO,DGA^6000030    I29 @T6G_MB_LIB.T6G(SCH_1):PAGE57
   U26 AF23 VDDCR_CPU0_AF23 GENOA_SP5-SOCKET6096_13568-001,SMLF,IO,DGA^6000030    I29 @T6G_MB_LIB.T6G(SCH_1):PAGE57
   U26 AF24 VDDCR_CPU0_AF24 GENOA_SP5-SOCKET6096_13568-001,SMLF,IO,DGA^6000030    I29 @T6G_MB_LIB.T6G(SCH_1):PAGE57
   U26 AF26 VDDCR_CPU0_AF26 GENOA_SP5-SOCKET6096_13568-001,SMLF,IO,DGA^6000030    I29 @T6G_MB_LIB.T6G(SCH_1):PAGE57
   U26 AF27 VDDCR_CPU0_AF27 GENOA_SP5-SOCKET6096_13568-001,SMLF,IO,DGA^6000030    I29 @T6G_MB_LIB.T6G(SCH_1):PAGE57
   U26 AF29 VDDCR_CPU0_AF29 GENOA_SP5-SOCKET6096_13568-001,SMLF,IO,DGA^6000030    I29 @T6G_MB_LIB.T6G(SCH_1):PAGE57
   U26 AF30 VDDCR_CPU0_AF30 GENOA_SP5-SOCKET6096_13568-001,SMLF,IO,DGA^6000030    I29 @T6G_MB_LIB.T6G(SCH_1):PAGE57
   U26 AF32 VDDCR_CPU0_AF32 GENOA_SP5-SOCKET6096_13568-001,SMLF,IO,DGA^6000030    I29 @T6G_MB_LIB.T6G(SCH_1):PAGE57
   U26 AF33 VDDCR_CPU0_AF33 GENOA_SP5-SOCKET6096_13568-001,SMLF,IO,DGA^6000030    I29 @T6G_MB_LIB.T6G(SCH_1):PAGE57
   U26 AF43 VDDCR_CPU0_AF43 GENOA_SP5-SOCKET6096_13568-001,SMLF,IO,DGA^6000030    I29 @T6G_MB_LIB.T6G(SCH_1):PAGE57
   U26 AF44 VDDCR_CPU0_AF44 GENOA_SP5-SOCKET6096_13568-001,SMLF,IO,DGA^6000030    I29 @T6G_MB_LIB.T6G(SCH_1):PAGE57
   U26 AF46 VDDCR_CPU0_AF46 GENOA_SP5-SOCKET6096_13568-001,SMLF,IO,DGA^6000030    I29 @T6G_MB_LIB.T6G(SCH_1):PAGE57
   U26 AF47 VDDCR_CPU0_AF47 GENOA_SP5-SOCKET6096_13568-001,SMLF,IO,DGA^6000030    I29 @T6G_MB_LIB.T6G(SCH_1):PAGE57
   U26 AF49 VDDCR_CPU0_AF49 GENOA_SP5-SOCKET6096_13568-001,SMLF,IO,DGA^6000030    I29 @T6G_MB_LIB.T6G(SCH_1):PAGE57
   U26 AF50 VDDCR_CPU0_AF50 GENOA_SP5-SOCKET6096_13568-001,SMLF,IO,DGA^6000030    I29 @T6G_MB_LIB.T6G(SCH_1):PAGE57
   U26 AF52 VDDCR_CPU0_AF52 GENOA_SP5-SOCKET6096_13568-001,SMLF,IO,DGA^6000030    I29 @T6G_MB_LIB.T6G(SCH_1):PAGE57
   U26 AF53 VDDCR_CPU0_AF53 GENOA_SP5-SOCKET6096_13568-001,SMLF,IO,DGA^6000030    I29 @T6G_MB_LIB.T6G(SCH_1):PAGE57
   U26 AG35 VDDCR_CPU0_AG35 GENOA_SP5-SOCKET6096_13568-001,SMLF,IO,DGA^6000030    I29 @T6G_MB_LIB.T6G(SCH_1):PAGE57
   U26 AG36 VDDCR_CPU0_AG36 GENOA_SP5-SOCKET6096_13568-001,SMLF,IO,DGA^6000030    I29 @T6G_MB_LIB.T6G(SCH_1):PAGE57
   U26 AG40 VDDCR_CPU0_AG40 GENOA_SP5-SOCKET6096_13568-001,SMLF,IO,DGA^6000030    I29 @T6G_MB_LIB.T6G(SCH_1):PAGE57
   U26 AG41 VDDCR_CPU0_AG41 GENOA_SP5-SOCKET6096_13568-001,SMLF,IO,DGA^6000030    I29 @T6G_MB_LIB.T6G(SCH_1):PAGE57
   U26 AK23 VDDCR_CPU0_AK23 GENOA_SP5-SOCKET6096_13568-001,SMLF,IO,DGA^6000030    I29 @T6G_MB_LIB.T6G(SCH_1):PAGE57
   U26 AK24 VDDCR_CPU0_AK24 GENOA_SP5-SOCKET6096_13568-001,SMLF,IO,DGA^6000030    I29 @T6G_MB_LIB.T6G(SCH_1):PAGE57
   U26 AK26 VDDCR_CPU0_AK26 GENOA_SP5-SOCKET6096_13568-001,SMLF,IO,DGA^6000030    I29 @T6G_MB_LIB.T6G(SCH_1):PAGE57
   U26 AK27 VDDCR_CPU0_AK27 GENOA_SP5-SOCKET6096_13568-001,SMLF,IO,DGA^6000030    I29 @T6G_MB_LIB.T6G(SCH_1):PAGE57
   U26 AK29 VDDCR_CPU0_AK29 GENOA_SP5-SOCKET6096_13568-001,SMLF,IO,DGA^6000030    I29 @T6G_MB_LIB.T6G(SCH_1):PAGE57
   U26 AK30 VDDCR_CPU0_AK30 GENOA_SP5-SOCKET6096_13568-001,SMLF,IO,DGA^6000030    I29 @T6G_MB_LIB.T6G(SCH_1):PAGE57
   U26 AK32 VDDCR_CPU0_AK32 GENOA_SP5-SOCKET6096_13568-001,SMLF,IO,DGA^6000030    I29 @T6G_MB_LIB.T6G(SCH_1):PAGE57
   U26 AK33 VDDCR_CPU0_AK33 GENOA_SP5-SOCKET6096_13568-001,SMLF,IO,DGA^6000030    I29 @T6G_MB_LIB.T6G(SCH_1):PAGE57
   U26 AK43 VDDCR_CPU0_AK43 GENOA_SP5-SOCKET6096_13568-001,SMLF,IO,DGA^6000030    I29 @T6G_MB_LIB.T6G(SCH_1):PAGE57
   U26 AK44 VDDCR_CPU0_AK44 GENOA_SP5-SOCKET6096_13568-001,SMLF,IO,DGA^6000030    I29 @T6G_MB_LIB.T6G(SCH_1):PAGE57
   U26 AK46 VDDCR_CPU0_AK46 GENOA_SP5-SOCKET6096_13568-001,SMLF,IO,DGA^6000030    I29 @T6G_MB_LIB.T6G(SCH_1):PAGE57
   U26 AK47 VDDCR_CPU0_AK47 GENOA_SP5-SOCKET6096_13568-001,SMLF,IO,DGA^6000030    I29 @T6G_MB_LIB.T6G(SCH_1):PAGE57
   U26 AK49 VDDCR_CPU0_AK49 GENOA_SP5-SOCKET6096_13568-001,SMLF,IO,DGA^6000030    I29 @T6G_MB_LIB.T6G(SCH_1):PAGE57
   U26 AK50 VDDCR_CPU0_AK50 GENOA_SP5-SOCKET6096_13568-001,SMLF,IO,DGA^6000030    I29 @T6G_MB_LIB.T6G(SCH_1):PAGE57
   U26 AK52 VDDCR_CPU0_AK52 GENOA_SP5-SOCKET6096_13568-001,SMLF,IO,DGA^6000030    I29 @T6G_MB_LIB.T6G(SCH_1):PAGE57
   U26 AK53 VDDCR_CPU0_AK53 GENOA_SP5-SOCKET6096_13568-001,SMLF,IO,DGA^6000030    I29 @T6G_MB_LIB.T6G(SCH_1):PAGE57
   U26 AL35 VDDCR_CPU0_AL35 GENOA_SP5-SOCKET6096_13568-001,SMLF,IO,DGA^6000030    I29 @T6G_MB_LIB.T6G(SCH_1):PAGE57
   U26 AL36 VDDCR_CPU0_AL36 GENOA_SP5-SOCKET6096_13568-001,SMLF,IO,DGA^6000030    I29 @T6G_MB_LIB.T6G(SCH_1):PAGE57
   U26 AL40 VDDCR_CPU0_AL40 GENOA_SP5-SOCKET6096_13568-001,SMLF,IO,DGA^6000030    I29 @T6G_MB_LIB.T6G(SCH_1):PAGE57
   U26 AL41 VDDCR_CPU0_AL41 GENOA_SP5-SOCKET6096_13568-001,SMLF,IO,DGA^6000030    I29 @T6G_MB_LIB.T6G(SCH_1):PAGE57
   U26 AP23 VDDCR_CPU0_AP23 GENOA_SP5-SOCKET6096_13568-001,SMLF,IO,DGA^6000030    I29 @T6G_MB_LIB.T6G(SCH_1):PAGE57
   U26 AP24 VDDCR_CPU0_AP24 GENOA_SP5-SOCKET6096_13568-001,SMLF,IO,DGA^6000030    I29 @T6G_MB_LIB.T6G(SCH_1):PAGE57
   U26 AP26 VDDCR_CPU0_AP26 GENOA_SP5-SOCKET6096_13568-001,SMLF,IO,DGA^6000030    I29 @T6G_MB_LIB.T6G(SCH_1):PAGE57
   U26 AP27 VDDCR_CPU0_AP27 GENOA_SP5-SOCKET6096_13568-001,SMLF,IO,DGA^6000030    I29 @T6G_MB_LIB.T6G(SCH_1):PAGE57
   U26 AP29 VDDCR_CPU0_AP29 GENOA_SP5-SOCKET6096_13568-001,SMLF,IO,DGA^6000030    I29 @T6G_MB_LIB.T6G(SCH_1):PAGE57
   U26 AP30 VDDCR_CPU0_AP30 GENOA_SP5-SOCKET6096_13568-001,SMLF,IO,DGA^6000030    I29 @T6G_MB_LIB.T6G(SCH_1):PAGE57
   U26 AP32 VDDCR_CPU0_AP32 GENOA_SP5-SOCKET6096_13568-001,SMLF,IO,DGA^6000030    I29 @T6G_MB_LIB.T6G(SCH_1):PAGE57
   U26 AP33 VDDCR_CPU0_AP33 GENOA_SP5-SOCKET6096_13568-001,SMLF,IO,DGA^6000030    I29 @T6G_MB_LIB.T6G(SCH_1):PAGE57
   U26 AP43 VDDCR_CPU0_AP43 GENOA_SP5-SOCKET6096_13568-001,SMLF,IO,DGA^6000030    I29 @T6G_MB_LIB.T6G(SCH_1):PAGE57
   U26 AP44 VDDCR_CPU0_AP44 GENOA_SP5-SOCKET6096_13568-001,SMLF,IO,DGA^6000030    I29 @T6G_MB_LIB.T6G(SCH_1):PAGE57
   U26 AP46 VDDCR_CPU0_AP46 GENOA_SP5-SOCKET6096_13568-001,SMLF,IO,DGA^6000030    I29 @T6G_MB_LIB.T6G(SCH_1):PAGE57
   U26 AP47 VDDCR_CPU0_AP47 GENOA_SP5-SOCKET6096_13568-001,SMLF,IO,DGA^6000030    I29 @T6G_MB_LIB.T6G(SCH_1):PAGE57
   U26 AP49 VDDCR_CPU0_AP49 GENOA_SP5-SOCKET6096_13568-001,SMLF,IO,DGA^6000030    I29 @T6G_MB_LIB.T6G(SCH_1):PAGE57
   U26 AP50 VDDCR_CPU0_AP50 GENOA_SP5-SOCKET6096_13568-001,SMLF,IO,DGA^6000030    I29 @T6G_MB_LIB.T6G(SCH_1):PAGE57
   U26 AP52 VDDCR_CPU0_AP52 GENOA_SP5-SOCKET6096_13568-001,SMLF,IO,DGA^6000030    I29 @T6G_MB_LIB.T6G(SCH_1):PAGE57
   U26 AP53 VDDCR_CPU0_AP53 GENOA_SP5-SOCKET6096_13568-001,SMLF,IO,DGA^6000030    I29 @T6G_MB_LIB.T6G(SCH_1):PAGE57
   U26 AR23 VDDCR_CPU0_AR23 GENOA_SP5-SOCKET6096_13568-001,SMLF,IO,DGA^6000030    I29 @T6G_MB_LIB.T6G(SCH_1):PAGE57
   U26 AR25 VDDCR_CPU0_AR25 GENOA_SP5-SOCKET6096_13568-001,SMLF,IO,DGA^6000030    I29 @T6G_MB_LIB.T6G(SCH_1):PAGE57
   U26 AR27 VDDCR_CPU0_AR27 GENOA_SP5-SOCKET6096_13568-001,SMLF,IO,DGA^6000030    I29 @T6G_MB_LIB.T6G(SCH_1):PAGE57
   U26 AR29 VDDCR_CPU0_AR29 GENOA_SP5-SOCKET6096_13568-001,SMLF,IO,DGA^6000030    I29 @T6G_MB_LIB.T6G(SCH_1):PAGE57
   U26 AR31 VDDCR_CPU0_AR31 GENOA_SP5-SOCKET6096_13568-001,SMLF,IO,DGA^6000030    I29 @T6G_MB_LIB.T6G(SCH_1):PAGE57
   U26 AR33 VDDCR_CPU0_AR33 GENOA_SP5-SOCKET6096_13568-001,SMLF,IO,DGA^6000030    I29 @T6G_MB_LIB.T6G(SCH_1):PAGE57
   U26 AR35 VDDCR_CPU0_AR35 GENOA_SP5-SOCKET6096_13568-001,SMLF,IO,DGA^6000030    I29 @T6G_MB_LIB.T6G(SCH_1):PAGE57
   U26 AR40 VDDCR_CPU0_AR40 GENOA_SP5-SOCKET6096_13568-001,SMLF,IO,DGA^6000030    I29 @T6G_MB_LIB.T6G(SCH_1):PAGE57
   U26 AR42 VDDCR_CPU0_AR42 GENOA_SP5-SOCKET6096_13568-001,SMLF,IO,DGA^6000030    I29 @T6G_MB_LIB.T6G(SCH_1):PAGE57
   U26 AR44 VDDCR_CPU0_AR44 GENOA_SP5-SOCKET6096_13568-001,SMLF,IO,DGA^6000030    I29 @T6G_MB_LIB.T6G(SCH_1):PAGE57
   U26 AR46 VDDCR_CPU0_AR46 GENOA_SP5-SOCKET6096_13568-001,SMLF,IO,DGA^6000030    I29 @T6G_MB_LIB.T6G(SCH_1):PAGE57
   U26 AR48 VDDCR_CPU0_AR48 GENOA_SP5-SOCKET6096_13568-001,SMLF,IO,DGA^6000030    I29 @T6G_MB_LIB.T6G(SCH_1):PAGE57
   U26 AR50 VDDCR_CPU0_AR50 GENOA_SP5-SOCKET6096_13568-001,SMLF,IO,DGA^6000030    I29 @T6G_MB_LIB.T6G(SCH_1):PAGE57
   U26 AT24 VDDCR_CPU0_AT24 GENOA_SP5-SOCKET6096_13568-001,SMLF,IO,DGA^6000030    I29 @T6G_MB_LIB.T6G(SCH_1):PAGE57
   U26 AT26 VDDCR_CPU0_AT26 GENOA_SP5-SOCKET6096_13568-001,SMLF,IO,DGA^6000030    I29 @T6G_MB_LIB.T6G(SCH_1):PAGE57
   U26 AT28 VDDCR_CPU0_AT28 GENOA_SP5-SOCKET6096_13568-001,SMLF,IO,DGA^6000030    I29 @T6G_MB_LIB.T6G(SCH_1):PAGE57
   U26 AT30 VDDCR_CPU0_AT30 GENOA_SP5-SOCKET6096_13568-001,SMLF,IO,DGA^6000030    I29 @T6G_MB_LIB.T6G(SCH_1):PAGE57
   U26 AT32 VDDCR_CPU0_AT32 GENOA_SP5-SOCKET6096_13568-001,SMLF,IO,DGA^6000030    I29 @T6G_MB_LIB.T6G(SCH_1):PAGE57
   U26 AT34 VDDCR_CPU0_AT34 GENOA_SP5-SOCKET6096_13568-001,SMLF,IO,DGA^6000030    I29 @T6G_MB_LIB.T6G(SCH_1):PAGE57
   U26 AT36 VDDCR_CPU0_AT36 GENOA_SP5-SOCKET6096_13568-001,SMLF,IO,DGA^6000030    I29 @T6G_MB_LIB.T6G(SCH_1):PAGE57
   U26 AT39 VDDCR_CPU0_AT39 GENOA_SP5-SOCKET6096_13568-001,SMLF,IO,DGA^6000030    I29 @T6G_MB_LIB.T6G(SCH_1):PAGE57
   U26 AT41 VDDCR_CPU0_AT41 GENOA_SP5-SOCKET6096_13568-001,SMLF,IO,DGA^6000030    I29 @T6G_MB_LIB.T6G(SCH_1):PAGE57
   U26 AT43 VDDCR_CPU0_AT43 GENOA_SP5-SOCKET6096_13568-001,SMLF,IO,DGA^6000030    I29 @T6G_MB_LIB.T6G(SCH_1):PAGE57
   U26 AT45 VDDCR_CPU0_AT45 GENOA_SP5-SOCKET6096_13568-001,SMLF,IO,DGA^6000030    I29 @T6G_MB_LIB.T6G(SCH_1):PAGE57
   U26 AT47 VDDCR_CPU0_AT47 GENOA_SP5-SOCKET6096_13568-001,SMLF,IO,DGA^6000030    I29 @T6G_MB_LIB.T6G(SCH_1):PAGE57
   U26 AT49 VDDCR_CPU0_AT49 GENOA_SP5-SOCKET6096_13568-001,SMLF,IO,DGA^6000030    I29 @T6G_MB_LIB.T6G(SCH_1):PAGE57
   U26 AU25 VDDCR_CPU0_AU25 GENOA_SP5-SOCKET6096_13568-001,SMLF,IO,DGA^6000030    I29 @T6G_MB_LIB.T6G(SCH_1):PAGE57
   U26 AU29 VDDCR_CPU0_AU29 GENOA_SP5-SOCKET6096_13568-001,SMLF,IO,DGA^6000030    I29 @T6G_MB_LIB.T6G(SCH_1):PAGE57
   U26 AU33 VDDCR_CPU0_AU33 GENOA_SP5-SOCKET6096_13568-001,SMLF,IO,DGA^6000030    I29 @T6G_MB_LIB.T6G(SCH_1):PAGE57
   U26 AU42 VDDCR_CPU0_AU42 GENOA_SP5-SOCKET6096_13568-001,SMLF,IO,DGA^6000030    I29 @T6G_MB_LIB.T6G(SCH_1):PAGE57
   U26 AU44 VDDCR_CPU0_AU44 GENOA_SP5-SOCKET6096_13568-001,SMLF,IO,DGA^6000030    I29 @T6G_MB_LIB.T6G(SCH_1):PAGE57
   U26 AU46 VDDCR_CPU0_AU46 GENOA_SP5-SOCKET6096_13568-001,SMLF,IO,DGA^6000030    I29 @T6G_MB_LIB.T6G(SCH_1):PAGE57
   U26 AU48 VDDCR_CPU0_AU48 GENOA_SP5-SOCKET6096_13568-001,SMLF,IO,DGA^6000030    I29 @T6G_MB_LIB.T6G(SCH_1):PAGE57
   U26  B19 VDDCR_CPU0_B19 GENOA_SP5-SOCKET6096_13568-001,SMLF,IO,DGA^6000030    I29 @T6G_MB_LIB.T6G(SCH_1):PAGE57
   U26  B20 VDDCR_CPU0_B20 GENOA_SP5-SOCKET6096_13568-001,SMLF,IO,DGA^6000030    I29 @T6G_MB_LIB.T6G(SCH_1):PAGE57
   U26  B22 VDDCR_CPU0_B22 GENOA_SP5-SOCKET6096_13568-001,SMLF,IO,DGA^6000030    I29 @T6G_MB_LIB.T6G(SCH_1):PAGE57
   U26  B23 VDDCR_CPU0_B23 GENOA_SP5-SOCKET6096_13568-001,SMLF,IO,DGA^6000030    I29 @T6G_MB_LIB.T6G(SCH_1):PAGE57
   U26  B25 VDDCR_CPU0_B25 GENOA_SP5-SOCKET6096_13568-001,SMLF,IO,DGA^6000030    I29 @T6G_MB_LIB.T6G(SCH_1):PAGE57
   U26  B26 VDDCR_CPU0_B26 GENOA_SP5-SOCKET6096_13568-001,SMLF,IO,DGA^6000030    I29 @T6G_MB_LIB.T6G(SCH_1):PAGE57
   U26  B28 VDDCR_CPU0_B28 GENOA_SP5-SOCKET6096_13568-001,SMLF,IO,DGA^6000030    I29 @T6G_MB_LIB.T6G(SCH_1):PAGE57
   U26  B29 VDDCR_CPU0_B29 GENOA_SP5-SOCKET6096_13568-001,SMLF,IO,DGA^6000030    I29 @T6G_MB_LIB.T6G(SCH_1):PAGE57
   U26  B31 VDDCR_CPU0_B31 GENOA_SP5-SOCKET6096_13568-001,SMLF,IO,DGA^6000030    I29 @T6G_MB_LIB.T6G(SCH_1):PAGE57
   U26  B32 VDDCR_CPU0_B32 GENOA_SP5-SOCKET6096_13568-001,SMLF,IO,DGA^6000030    I29 @T6G_MB_LIB.T6G(SCH_1):PAGE57
   U26  B34 VDDCR_CPU0_B34 GENOA_SP5-SOCKET6096_13568-001,SMLF,IO,DGA^6000030    I29 @T6G_MB_LIB.T6G(SCH_1):PAGE57
   U26  B35 VDDCR_CPU0_B35 GENOA_SP5-SOCKET6096_13568-001,SMLF,IO,DGA^6000030    I29 @T6G_MB_LIB.T6G(SCH_1):PAGE57
   U26  B41 VDDCR_CPU0_B41 GENOA_SP5-SOCKET6096_13568-001,SMLF,IO,DGA^6000030    I29 @T6G_MB_LIB.T6G(SCH_1):PAGE57
   U26  B42 VDDCR_CPU0_B42 GENOA_SP5-SOCKET6096_13568-001,SMLF,IO,DGA^6000030    I29 @T6G_MB_LIB.T6G(SCH_1):PAGE57
   U26  B44 VDDCR_CPU0_B44 GENOA_SP5-SOCKET6096_13568-001,SMLF,IO,DGA^6000030    I29 @T6G_MB_LIB.T6G(SCH_1):PAGE57
   U26  B45 VDDCR_CPU0_B45 GENOA_SP5-SOCKET6096_13568-001,SMLF,IO,DGA^6000030    I29 @T6G_MB_LIB.T6G(SCH_1):PAGE57
   U26  B47 VDDCR_CPU0_B47 GENOA_SP5-SOCKET6096_13568-001,SMLF,IO,DGA^6000030    I29 @T6G_MB_LIB.T6G(SCH_1):PAGE57
   U26  B48 VDDCR_CPU0_B48 GENOA_SP5-SOCKET6096_13568-001,SMLF,IO,DGA^6000030    I29 @T6G_MB_LIB.T6G(SCH_1):PAGE57
   U26  B50 VDDCR_CPU0_B50 GENOA_SP5-SOCKET6096_13568-001,SMLF,IO,DGA^6000030    I29 @T6G_MB_LIB.T6G(SCH_1):PAGE57
   U26  B51 VDDCR_CPU0_B51 GENOA_SP5-SOCKET6096_13568-001,SMLF,IO,DGA^6000030    I29 @T6G_MB_LIB.T6G(SCH_1):PAGE57
   U26  B53 VDDCR_CPU0_B53 GENOA_SP5-SOCKET6096_13568-001,SMLF,IO,DGA^6000030    I29 @T6G_MB_LIB.T6G(SCH_1):PAGE57
   U26  B54 VDDCR_CPU0_B54 GENOA_SP5-SOCKET6096_13568-001,SMLF,IO,DGA^6000030    I29 @T6G_MB_LIB.T6G(SCH_1):PAGE57
   U26  B56 VDDCR_CPU0_B56 GENOA_SP5-SOCKET6096_13568-001,SMLF,IO,DGA^6000030    I29 @T6G_MB_LIB.T6G(SCH_1):PAGE57
   U26  B57 VDDCR_CPU0_B57 GENOA_SP5-SOCKET6096_13568-001,SMLF,IO,DGA^6000030    I29 @T6G_MB_LIB.T6G(SCH_1):PAGE57
   U26  C20 VDDCR_CPU0_C20 GENOA_SP5-SOCKET6096_13568-001,SMLF,IO,DGA^6000030    I29 @T6G_MB_LIB.T6G(SCH_1):PAGE57
   U26  D55 VDDCR_CPU0_D55 GENOA_SP5-SOCKET6096_13568-001,SMLF,IO,DGA^6000030    I29 @T6G_MB_LIB.T6G(SCH_1):PAGE57
   U26  D56 VDDCR_CPU0_D56 GENOA_SP5-SOCKET6096_13568-001,SMLF,IO,DGA^6000030    I29 @T6G_MB_LIB.T6G(SCH_1):PAGE57
   U26  E22 VDDCR_CPU0_E22 GENOA_SP5-SOCKET6096_13568-001,SMLF,IO,DGA^6000030    I29 @T6G_MB_LIB.T6G(SCH_1):PAGE57
   U26  E25 VDDCR_CPU0_E25 GENOA_SP5-SOCKET6096_13568-001,SMLF,IO,DGA^6000030    I29 @T6G_MB_LIB.T6G(SCH_1):PAGE57
   U26  E28 VDDCR_CPU0_E28 GENOA_SP5-SOCKET6096_13568-001,SMLF,IO,DGA^6000030    I29 @T6G_MB_LIB.T6G(SCH_1):PAGE57
   U26  E31 VDDCR_CPU0_E31 GENOA_SP5-SOCKET6096_13568-001,SMLF,IO,DGA^6000030    I29 @T6G_MB_LIB.T6G(SCH_1):PAGE57
   U26  E34 VDDCR_CPU0_E34 GENOA_SP5-SOCKET6096_13568-001,SMLF,IO,DGA^6000030    I29 @T6G_MB_LIB.T6G(SCH_1):PAGE57
   U26  E35 VDDCR_CPU0_E35 GENOA_SP5-SOCKET6096_13568-001,SMLF,IO,DGA^6000030    I29 @T6G_MB_LIB.T6G(SCH_1):PAGE57
   U26  E42 VDDCR_CPU0_E42 GENOA_SP5-SOCKET6096_13568-001,SMLF,IO,DGA^6000030    I29 @T6G_MB_LIB.T6G(SCH_1):PAGE57
   U26  E45 VDDCR_CPU0_E45 GENOA_SP5-SOCKET6096_13568-001,SMLF,IO,DGA^6000030    I29 @T6G_MB_LIB.T6G(SCH_1):PAGE57
   U26  E48 VDDCR_CPU0_E48 GENOA_SP5-SOCKET6096_13568-001,SMLF,IO,DGA^6000030    I29 @T6G_MB_LIB.T6G(SCH_1):PAGE57
   U26  E51 VDDCR_CPU0_E51 GENOA_SP5-SOCKET6096_13568-001,SMLF,IO,DGA^6000030    I29 @T6G_MB_LIB.T6G(SCH_1):PAGE57
   U26  E54 VDDCR_CPU0_E54 GENOA_SP5-SOCKET6096_13568-001,SMLF,IO,DGA^6000030    I29 @T6G_MB_LIB.T6G(SCH_1):PAGE57
   U26  F22 VDDCR_CPU0_F22 GENOA_SP5-SOCKET6096_13568-001,SMLF,IO,DGA^6000030    I29 @T6G_MB_LIB.T6G(SCH_1):PAGE57
   U26  F25 VDDCR_CPU0_F25 GENOA_SP5-SOCKET6096_13568-001,SMLF,IO,DGA^6000030    I29 @T6G_MB_LIB.T6G(SCH_1):PAGE57
   U26  F28 VDDCR_CPU0_F28 GENOA_SP5-SOCKET6096_13568-001,SMLF,IO,DGA^6000030    I29 @T6G_MB_LIB.T6G(SCH_1):PAGE57
   U26  F31 VDDCR_CPU0_F31 GENOA_SP5-SOCKET6096_13568-001,SMLF,IO,DGA^6000030    I29 @T6G_MB_LIB.T6G(SCH_1):PAGE57
   U26  F34 VDDCR_CPU0_F34 GENOA_SP5-SOCKET6096_13568-001,SMLF,IO,DGA^6000030    I29 @T6G_MB_LIB.T6G(SCH_1):PAGE57
   U26  F42 VDDCR_CPU0_F42 GENOA_SP5-SOCKET6096_13568-001,SMLF,IO,DGA^6000030    I29 @T6G_MB_LIB.T6G(SCH_1):PAGE57
   U26  F45 VDDCR_CPU0_F45 GENOA_SP5-SOCKET6096_13568-001,SMLF,IO,DGA^6000030    I29 @T6G_MB_LIB.T6G(SCH_1):PAGE57
   U26  F48 VDDCR_CPU0_F48 GENOA_SP5-SOCKET6096_13568-001,SMLF,IO,DGA^6000030    I29 @T6G_MB_LIB.T6G(SCH_1):PAGE57
   U26  F51 VDDCR_CPU0_F51 GENOA_SP5-SOCKET6096_13568-001,SMLF,IO,DGA^6000030    I29 @T6G_MB_LIB.T6G(SCH_1):PAGE57
   U26  F54 VDDCR_CPU0_F54 GENOA_SP5-SOCKET6096_13568-001,SMLF,IO,DGA^6000030    I29 @T6G_MB_LIB.T6G(SCH_1):PAGE57
   U26  G35 VDDCR_CPU0_G35 GENOA_SP5-SOCKET6096_13568-001,SMLF,IO,DGA^6000030    I29 @T6G_MB_LIB.T6G(SCH_1):PAGE57
   U26  G36 VDDCR_CPU0_G36 GENOA_SP5-SOCKET6096_13568-001,SMLF,IO,DGA^6000030    I29 @T6G_MB_LIB.T6G(SCH_1):PAGE57
   U26  G40 VDDCR_CPU0_G40 GENOA_SP5-SOCKET6096_13568-001,SMLF,IO,DGA^6000030    I29 @T6G_MB_LIB.T6G(SCH_1):PAGE57
   U26  G41 VDDCR_CPU0_G41 GENOA_SP5-SOCKET6096_13568-001,SMLF,IO,DGA^6000030    I29 @T6G_MB_LIB.T6G(SCH_1):PAGE57
   U26  H23 VDDCR_CPU0_H23 GENOA_SP5-SOCKET6096_13568-001,SMLF,IO,DGA^6000030    I29 @T6G_MB_LIB.T6G(SCH_1):PAGE57
   U26  H24 VDDCR_CPU0_H24 GENOA_SP5-SOCKET6096_13568-001,SMLF,IO,DGA^6000030    I29 @T6G_MB_LIB.T6G(SCH_1):PAGE57
   U26  H26 VDDCR_CPU0_H26 GENOA_SP5-SOCKET6096_13568-001,SMLF,IO,DGA^6000030    I29 @T6G_MB_LIB.T6G(SCH_1):PAGE57
   U26  H27 VDDCR_CPU0_H27 GENOA_SP5-SOCKET6096_13568-001,SMLF,IO,DGA^6000030    I29 @T6G_MB_LIB.T6G(SCH_1):PAGE57
   U26  H29 VDDCR_CPU0_H29 GENOA_SP5-SOCKET6096_13568-001,SMLF,IO,DGA^6000030    I29 @T6G_MB_LIB.T6G(SCH_1):PAGE57
   U26  H30 VDDCR_CPU0_H30 GENOA_SP5-SOCKET6096_13568-001,SMLF,IO,DGA^6000030    I29 @T6G_MB_LIB.T6G(SCH_1):PAGE57
   U26  H32 VDDCR_CPU0_H32 GENOA_SP5-SOCKET6096_13568-001,SMLF,IO,DGA^6000030    I29 @T6G_MB_LIB.T6G(SCH_1):PAGE57
   U26  H33 VDDCR_CPU0_H33 GENOA_SP5-SOCKET6096_13568-001,SMLF,IO,DGA^6000030    I29 @T6G_MB_LIB.T6G(SCH_1):PAGE57
   U26  H43 VDDCR_CPU0_H43 GENOA_SP5-SOCKET6096_13568-001,SMLF,IO,DGA^6000030    I29 @T6G_MB_LIB.T6G(SCH_1):PAGE57
   U26  H44 VDDCR_CPU0_H44 GENOA_SP5-SOCKET6096_13568-001,SMLF,IO,DGA^6000030    I29 @T6G_MB_LIB.T6G(SCH_1):PAGE57
   U26  H46 VDDCR_CPU0_H46 GENOA_SP5-SOCKET6096_13568-001,SMLF,IO,DGA^6000030    I29 @T6G_MB_LIB.T6G(SCH_1):PAGE57
   U26  H47 VDDCR_CPU0_H47 GENOA_SP5-SOCKET6096_13568-001,SMLF,IO,DGA^6000030    I29 @T6G_MB_LIB.T6G(SCH_1):PAGE57
   U26  H49 VDDCR_CPU0_H49 GENOA_SP5-SOCKET6096_13568-001,SMLF,IO,DGA^6000030    I29 @T6G_MB_LIB.T6G(SCH_1):PAGE57
   U26  H50 VDDCR_CPU0_H50 GENOA_SP5-SOCKET6096_13568-001,SMLF,IO,DGA^6000030    I29 @T6G_MB_LIB.T6G(SCH_1):PAGE57
   U26  H52 VDDCR_CPU0_H52 GENOA_SP5-SOCKET6096_13568-001,SMLF,IO,DGA^6000030    I29 @T6G_MB_LIB.T6G(SCH_1):PAGE57
   U26  H53 VDDCR_CPU0_H53 GENOA_SP5-SOCKET6096_13568-001,SMLF,IO,DGA^6000030    I29 @T6G_MB_LIB.T6G(SCH_1):PAGE57
   U26  J35 VDDCR_CPU0_J35 GENOA_SP5-SOCKET6096_13568-001,SMLF,IO,DGA^6000030    I29 @T6G_MB_LIB.T6G(SCH_1):PAGE57
   U26  J36 VDDCR_CPU0_J36 GENOA_SP5-SOCKET6096_13568-001,SMLF,IO,DGA^6000030    I29 @T6G_MB_LIB.T6G(SCH_1):PAGE57
   U26  J40 VDDCR_CPU0_J40 GENOA_SP5-SOCKET6096_13568-001,SMLF,IO,DGA^6000030    I29 @T6G_MB_LIB.T6G(SCH_1):PAGE57
   U26  J41 VDDCR_CPU0_J41 GENOA_SP5-SOCKET6096_13568-001,SMLF,IO,DGA^6000030    I29 @T6G_MB_LIB.T6G(SCH_1):PAGE57
   U26  M23 VDDCR_CPU0_M23 GENOA_SP5-SOCKET6096_13568-001,SMLF,IO,DGA^6000030    I29 @T6G_MB_LIB.T6G(SCH_1):PAGE57
   U26  M24 VDDCR_CPU0_M24 GENOA_SP5-SOCKET6096_13568-001,SMLF,IO,DGA^6000030    I29 @T6G_MB_LIB.T6G(SCH_1):PAGE57
   U26  M26 VDDCR_CPU0_M26 GENOA_SP5-SOCKET6096_13568-001,SMLF,IO,DGA^6000030    I29 @T6G_MB_LIB.T6G(SCH_1):PAGE57
   U26  M27 VDDCR_CPU0_M27 GENOA_SP5-SOCKET6096_13568-001,SMLF,IO,DGA^6000030    I29 @T6G_MB_LIB.T6G(SCH_1):PAGE57
   U26  M29 VDDCR_CPU0_M29 GENOA_SP5-SOCKET6096_13568-001,SMLF,IO,DGA^6000030    I29 @T6G_MB_LIB.T6G(SCH_1):PAGE57
   U26  M30 VDDCR_CPU0_M30 GENOA_SP5-SOCKET6096_13568-001,SMLF,IO,DGA^6000030    I29 @T6G_MB_LIB.T6G(SCH_1):PAGE57
   U26  M32 VDDCR_CPU0_M32 GENOA_SP5-SOCKET6096_13568-001,SMLF,IO,DGA^6000030    I29 @T6G_MB_LIB.T6G(SCH_1):PAGE57
   U26  M33 VDDCR_CPU0_M33 GENOA_SP5-SOCKET6096_13568-001,SMLF,IO,DGA^6000030    I29 @T6G_MB_LIB.T6G(SCH_1):PAGE57
   U26  M43 VDDCR_CPU0_M43 GENOA_SP5-SOCKET6096_13568-001,SMLF,IO,DGA^6000030    I29 @T6G_MB_LIB.T6G(SCH_1):PAGE57
   U26  M44 VDDCR_CPU0_M44 GENOA_SP5-SOCKET6096_13568-001,SMLF,IO,DGA^6000030    I29 @T6G_MB_LIB.T6G(SCH_1):PAGE57
   U26  M46 VDDCR_CPU0_M46 GENOA_SP5-SOCKET6096_13568-001,SMLF,IO,DGA^6000030    I29 @T6G_MB_LIB.T6G(SCH_1):PAGE57
   U26  M47 VDDCR_CPU0_M47 GENOA_SP5-SOCKET6096_13568-001,SMLF,IO,DGA^6000030    I29 @T6G_MB_LIB.T6G(SCH_1):PAGE57
   U26  M49 VDDCR_CPU0_M49 GENOA_SP5-SOCKET6096_13568-001,SMLF,IO,DGA^6000030    I29 @T6G_MB_LIB.T6G(SCH_1):PAGE57
   U26  M50 VDDCR_CPU0_M50 GENOA_SP5-SOCKET6096_13568-001,SMLF,IO,DGA^6000030    I29 @T6G_MB_LIB.T6G(SCH_1):PAGE57
   U26  M52 VDDCR_CPU0_M52 GENOA_SP5-SOCKET6096_13568-001,SMLF,IO,DGA^6000030    I29 @T6G_MB_LIB.T6G(SCH_1):PAGE57
   U26  M53 VDDCR_CPU0_M53 GENOA_SP5-SOCKET6096_13568-001,SMLF,IO,DGA^6000030    I29 @T6G_MB_LIB.T6G(SCH_1):PAGE57
   U26  N35 VDDCR_CPU0_N35 GENOA_SP5-SOCKET6096_13568-001,SMLF,IO,DGA^6000030    I29 @T6G_MB_LIB.T6G(SCH_1):PAGE57
   U26  N36 VDDCR_CPU0_N36 GENOA_SP5-SOCKET6096_13568-001,SMLF,IO,DGA^6000030    I29 @T6G_MB_LIB.T6G(SCH_1):PAGE57
   U26  N40 VDDCR_CPU0_N40 GENOA_SP5-SOCKET6096_13568-001,SMLF,IO,DGA^6000030    I29 @T6G_MB_LIB.T6G(SCH_1):PAGE57
   U26  N41 VDDCR_CPU0_N41 GENOA_SP5-SOCKET6096_13568-001,SMLF,IO,DGA^6000030    I29 @T6G_MB_LIB.T6G(SCH_1):PAGE57
   U26  T23 VDDCR_CPU0_T23 GENOA_SP5-SOCKET6096_13568-001,SMLF,IO,DGA^6000030    I29 @T6G_MB_LIB.T6G(SCH_1):PAGE57
   U26  T24 VDDCR_CPU0_T24 GENOA_SP5-SOCKET6096_13568-001,SMLF,IO,DGA^6000030    I29 @T6G_MB_LIB.T6G(SCH_1):PAGE57
   U26  T26 VDDCR_CPU0_T26 GENOA_SP5-SOCKET6096_13568-001,SMLF,IO,DGA^6000030    I29 @T6G_MB_LIB.T6G(SCH_1):PAGE57
   U26  T27 VDDCR_CPU0_T27 GENOA_SP5-SOCKET6096_13568-001,SMLF,IO,DGA^6000030    I29 @T6G_MB_LIB.T6G(SCH_1):PAGE57
   U26  T29 VDDCR_CPU0_T29 GENOA_SP5-SOCKET6096_13568-001,SMLF,IO,DGA^6000030    I29 @T6G_MB_LIB.T6G(SCH_1):PAGE57
   U26  T30 VDDCR_CPU0_T30 GENOA_SP5-SOCKET6096_13568-001,SMLF,IO,DGA^6000030    I29 @T6G_MB_LIB.T6G(SCH_1):PAGE57
   U26  T32 VDDCR_CPU0_T32 GENOA_SP5-SOCKET6096_13568-001,SMLF,IO,DGA^6000030    I29 @T6G_MB_LIB.T6G(SCH_1):PAGE57
   U26  T33 VDDCR_CPU0_T33 GENOA_SP5-SOCKET6096_13568-001,SMLF,IO,DGA^6000030    I29 @T6G_MB_LIB.T6G(SCH_1):PAGE57
   U26  T43 VDDCR_CPU0_T43 GENOA_SP5-SOCKET6096_13568-001,SMLF,IO,DGA^6000030    I29 @T6G_MB_LIB.T6G(SCH_1):PAGE57
   U26  T44 VDDCR_CPU0_T44 GENOA_SP5-SOCKET6096_13568-001,SMLF,IO,DGA^6000030    I29 @T6G_MB_LIB.T6G(SCH_1):PAGE57
   U26  T46 VDDCR_CPU0_T46 GENOA_SP5-SOCKET6096_13568-001,SMLF,IO,DGA^6000030    I29 @T6G_MB_LIB.T6G(SCH_1):PAGE57
   U26  T47 VDDCR_CPU0_T47 GENOA_SP5-SOCKET6096_13568-001,SMLF,IO,DGA^6000030    I29 @T6G_MB_LIB.T6G(SCH_1):PAGE57
   U26  T49 VDDCR_CPU0_T49 GENOA_SP5-SOCKET6096_13568-001,SMLF,IO,DGA^6000030    I29 @T6G_MB_LIB.T6G(SCH_1):PAGE57
   U26  T50 VDDCR_CPU0_T50 GENOA_SP5-SOCKET6096_13568-001,SMLF,IO,DGA^6000030    I29 @T6G_MB_LIB.T6G(SCH_1):PAGE57
   U26  T52 VDDCR_CPU0_T52 GENOA_SP5-SOCKET6096_13568-001,SMLF,IO,DGA^6000030    I29 @T6G_MB_LIB.T6G(SCH_1):PAGE57
   U26  T53 VDDCR_CPU0_T53 GENOA_SP5-SOCKET6096_13568-001,SMLF,IO,DGA^6000030    I29 @T6G_MB_LIB.T6G(SCH_1):PAGE57
   U26  U35 VDDCR_CPU0_U35 GENOA_SP5-SOCKET6096_13568-001,SMLF,IO,DGA^6000030    I29 @T6G_MB_LIB.T6G(SCH_1):PAGE57
   U26  U36 VDDCR_CPU0_U36 GENOA_SP5-SOCKET6096_13568-001,SMLF,IO,DGA^6000030    I29 @T6G_MB_LIB.T6G(SCH_1):PAGE57
   U26  U40 VDDCR_CPU0_U40 GENOA_SP5-SOCKET6096_13568-001,SMLF,IO,DGA^6000030    I29 @T6G_MB_LIB.T6G(SCH_1):PAGE57
   U26  U41 VDDCR_CPU0_U41 GENOA_SP5-SOCKET6096_13568-001,SMLF,IO,DGA^6000030    I29 @T6G_MB_LIB.T6G(SCH_1):PAGE57
   U26  W29 VDDCR_CPU0_W29 GENOA_SP5-SOCKET6096_13568-001,SMLF,IO,DGA^6000030    I29 @T6G_MB_LIB.T6G(SCH_1):PAGE57
   U26  W30 VDDCR_CPU0_W30 GENOA_SP5-SOCKET6096_13568-001,SMLF,IO,DGA^6000030    I29 @T6G_MB_LIB.T6G(SCH_1):PAGE57
   U26  W32 VDDCR_CPU0_W32 GENOA_SP5-SOCKET6096_13568-001,SMLF,IO,DGA^6000030    I29 @T6G_MB_LIB.T6G(SCH_1):PAGE57
   U26  W33 VDDCR_CPU0_W33 GENOA_SP5-SOCKET6096_13568-001,SMLF,IO,DGA^6000030    I29 @T6G_MB_LIB.T6G(SCH_1):PAGE57
   U26  W43 VDDCR_CPU0_W43 GENOA_SP5-SOCKET6096_13568-001,SMLF,IO,DGA^6000030    I29 @T6G_MB_LIB.T6G(SCH_1):PAGE57
   U26  W44 VDDCR_CPU0_W44 GENOA_SP5-SOCKET6096_13568-001,SMLF,IO,DGA^6000030    I29 @T6G_MB_LIB.T6G(SCH_1):PAGE57
   U26  W46 VDDCR_CPU0_W46 GENOA_SP5-SOCKET6096_13568-001,SMLF,IO,DGA^6000030    I29 @T6G_MB_LIB.T6G(SCH_1):PAGE57
   U26  W47 VDDCR_CPU0_W47 GENOA_SP5-SOCKET6096_13568-001,SMLF,IO,DGA^6000030    I29 @T6G_MB_LIB.T6G(SCH_1):PAGE57
   U26  Y35 VDDCR_CPU0_Y35 GENOA_SP5-SOCKET6096_13568-001,SMLF,IO,DGA^6000030    I29 @T6G_MB_LIB.T6G(SCH_1):PAGE57
   U26  Y36 VDDCR_CPU0_Y36 GENOA_SP5-SOCKET6096_13568-001,SMLF,IO,DGA^6000030    I29 @T6G_MB_LIB.T6G(SCH_1):PAGE57
   U26  Y40 VDDCR_CPU0_Y40 GENOA_SP5-SOCKET6096_13568-001,SMLF,IO,DGA^6000030    I29 @T6G_MB_LIB.T6G(SCH_1):PAGE57
   U26  Y41 VDDCR_CPU0_Y41 GENOA_SP5-SOCKET6096_13568-001,SMLF,IO,DGA^6000030    I29 @T6G_MB_LIB.T6G(SCH_1):PAGE57
 C2298    1      A Q_CAP_C0402-22UF,4V,20%,X6S,CH622KMEB02     I1 @T6G_MB_LIB.T6G(SCH_1):PAGE72
 C2304    1      A Q_CAP_C0402-22UF,4V,20%,X6S,CH622KMEB02     I3 @T6G_MB_LIB.T6G(SCH_1):PAGE72
 C2310    1      A Q_CAP_C0402-22UF,4V,20%,X6S,CH622KMEB02     I4 @T6G_MB_LIB.T6G(SCH_1):PAGE72
 C2297    1      A Q_CAP_C0402-22UF,4V,20%,X6S,CH622KMEB02     I5 @T6G_MB_LIB.T6G(SCH_1):PAGE72
 C2296    1      A Q_CAP_C0402-22UF,4V,20%,X6S,CH622KMEB02     I7 @T6G_MB_LIB.T6G(SCH_1):PAGE72
 C2295    1      A Q_CAP_C0402-22UF,4V,20%,X6S,CH622KMEB02     I9 @T6G_MB_LIB.T6G(SCH_1):PAGE72
 C2303    1      A Q_CAP_C0402-22UF,4V,20%,X6S,CH622KMEB02    I10 @T6G_MB_LIB.T6G(SCH_1):PAGE72
 C2309    1      A Q_CAP_C0402-22UF,4V,20%,X6S,CH622KMEB02    I11 @T6G_MB_LIB.T6G(SCH_1):PAGE72
 C2302    1      A Q_CAP_C0402-22UF,4V,20%,X6S,CH622KMEB02    I12 @T6G_MB_LIB.T6G(SCH_1):PAGE72
 C2301    1      A Q_CAP_C0402-22UF,4V,20%,X6S,CH622KMEB02    I13 @T6G_MB_LIB.T6G(SCH_1):PAGE72
 C2308    1      A Q_CAP_C0402-22UF,4V,20%,X6S,CH622KMEB02    I14 @T6G_MB_LIB.T6G(SCH_1):PAGE72
 C2307    1      A Q_CAP_C0402-22UF,4V,20%,X6S,CH622KMEB02    I15 @T6G_MB_LIB.T6G(SCH_1):PAGE72
 C2294    1      A Q_CAP_C0402-22UF,4V,20%,X6S,CH622KMEB02    I17 @T6G_MB_LIB.T6G(SCH_1):PAGE72
 C2300    1      A Q_CAP_C0402-22UF,4V,20%,X6S,CH622KMEB02    I19 @T6G_MB_LIB.T6G(SCH_1):PAGE72
 C2306    1      A Q_CAP_C0402-22UF,4V,20%,X6S,CH622KMEB02    I20 @T6G_MB_LIB.T6G(SCH_1):PAGE72
 C2316    1      A Q_CAP_C0402-22UF,4V,20%,X6S,CH622KMEB02    I21 @T6G_MB_LIB.T6G(SCH_1):PAGE72
 C2322    1      A Q_CAP_C0402-22UF,4V,20%,X6S,CH622KMEB02    I23 @T6G_MB_LIB.T6G(SCH_1):PAGE72
 C2315    1      A Q_CAP_C0402-22UF,4V,20%,X6S,CH622KMEB02    I24 @T6G_MB_LIB.T6G(SCH_1):PAGE72
 C2321    1      A Q_CAP_C0402-22UF,4V,20%,X6S,CH622KMEB02    I25 @T6G_MB_LIB.T6G(SCH_1):PAGE72
 C2327    1      A Q_CAP_C0402-22UF,4V,20%,X6S,CH622KMEB02    I26 @T6G_MB_LIB.T6G(SCH_1):PAGE72
 C2314    1      A Q_CAP_C0402-22UF,4V,20%,X6S,CH622KMEB02    I27 @T6G_MB_LIB.T6G(SCH_1):PAGE72
 C2313    1      A Q_CAP_C0402-22UF,4V,20%,X6S,CH622KMEB02    I28 @T6G_MB_LIB.T6G(SCH_1):PAGE72
 C2320    1      A Q_CAP_C0402-22UF,4V,20%,X6S,CH622KMEB02    I29 @T6G_MB_LIB.T6G(SCH_1):PAGE72
 C2326    1      A Q_CAP_C0402-22UF,4V,20%,X6S,CH622KMEB02    I30 @T6G_MB_LIB.T6G(SCH_1):PAGE72
 C2319    1      A Q_CAP_C0402-22UF,4V,20%,X6S,CH622KMEB02    I31 @T6G_MB_LIB.T6G(SCH_1):PAGE72
 C2325    1      A Q_CAP_C0402-22UF,4V,20%,X6S,CH622KMEB02    I32 @T6G_MB_LIB.T6G(SCH_1):PAGE72
 C2333    1      A Q_CAP_C0402-22UF,4V,20%,X6S,CH622KMEB02    I33 @T6G_MB_LIB.T6G(SCH_1):PAGE72
 C2338    1      A Q_CAP_C0402-22UF,4V,20%,X6S,CH622KMEB02    I34 @T6G_MB_LIB.T6G(SCH_1):PAGE72
 C2332    1      A Q_CAP_C0402-22UF,4V,20%,X6S,CH622KMEB02    I35 @T6G_MB_LIB.T6G(SCH_1):PAGE72
 C2331    1      A Q_CAP_C0402-22UF,4V,20%,X6S,CH622KMEB02    I36 @T6G_MB_LIB.T6G(SCH_1):PAGE72
 C2337    1      A Q_CAP_C0402-22UF,4V,20%,X6S,CH622KMEB02    I37 @T6G_MB_LIB.T6G(SCH_1):PAGE72
 C2336    1      A Q_CAP_C0402-22UF,4V,20%,X6S,CH622KMEB02    I38 @T6G_MB_LIB.T6G(SCH_1):PAGE72
 C2343    1      A Q_CAP_C0402-22UF,4V,20%,X6S,CH622KMEB02    I42 @T6G_MB_LIB.T6G(SCH_1):PAGE72
 C2348    1      A Q_CAP_C0402-22UF,4V,20%,X6S,CH622KMEB02    I44 @T6G_MB_LIB.T6G(SCH_1):PAGE72
 C2342    1      A Q_CAP_C0402-22UF,4V,20%,X6S,CH622KMEB02    I46 @T6G_MB_LIB.T6G(SCH_1):PAGE72
 C2341    1      A Q_CAP_C0402-22UF,4V,20%,X6S,CH622KMEB02    I47 @T6G_MB_LIB.T6G(SCH_1):PAGE72
 C2347    1      A Q_CAP_C0402-22UF,4V,20%,X6S,CH622KMEB02    I48 @T6G_MB_LIB.T6G(SCH_1):PAGE72
 C2346    1      A Q_CAP_C0402-22UF,4V,20%,X6S,CH622KMEB02    I50 @T6G_MB_LIB.T6G(SCH_1):PAGE72
 C2312    1      A Q_CAP_C0402-22UF,4V,20%,X6S,CH622KMEB02    I59 @T6G_MB_LIB.T6G(SCH_1):PAGE72
 C2318    1      A Q_CAP_C0402-22UF,4V,20%,X6S,CH622KMEB02    I60 @T6G_MB_LIB.T6G(SCH_1):PAGE72
 C2324    1      A Q_CAP_C0402-22UF,4V,20%,X6S,CH622KMEB02    I61 @T6G_MB_LIB.T6G(SCH_1):PAGE72
 C2330    1      A Q_CAP_C0402-22UF,4V,20%,X6S,CH622KMEB02    I62 @T6G_MB_LIB.T6G(SCH_1):PAGE72
 C2335    1      A Q_CAP_C0402-22UF,4V,20%,X6S,CH622KMEB02    I63 @T6G_MB_LIB.T6G(SCH_1):PAGE72
 C2340    1      A Q_CAP_C0402-22UF,4V,20%,X6S,CH622KMEB02    I64 @T6G_MB_LIB.T6G(SCH_1):PAGE72
 C2345    1      A Q_CAP_C0402-22UF,4V,20%,X6S,CH622KMEB02    I66 @T6G_MB_LIB.T6G(SCH_1):PAGE72
 PR191    2      B Q_RES_0402LF-0,5%,1/16W,CHIP,CS00002JB13    I35 @T6G_MB_LIB.T6G(SCH_1):PAGE186
PC282_2    1      A Q_CAP_C0805-22UF,4V,20%,X6S,CH622KMEA03    I63 @T6G_MB_LIB.T6G(SCH_1):PAGE186
 PC279    1      A Q_CAPP_SMLF-220UF,4V,20%,SPCAP,CH122KM8801    I66 @T6G_MB_LIB.T6G(SCH_1):PAGE186
 PR161    1      A Q_RES_0402LF-49.9,1%,1/16W,CHIP,CS04992FB07    I70 @T6G_MB_LIB.T6G(SCH_1):PAGE185
 PR192    2      B Q_RES_0402LF-0,5%,1/16W,CHIP,CS00002JB13    I23 @T6G_MB_LIB.T6G(SCH_1):PAGE186
  PL29    4      4 Q_INDUCTOR4P_14-150NH,SMLF,IND,CV+15^0TZ04    I56 @T6G_MB_LIB.T6G(SCH_1):PAGE186
 PC275    1      A Q_CAPP_SMLF-220UF,4V,20%,SPCAP,CH122KM8801    I58 @T6G_MB_LIB.T6G(SCH_1):PAGE186
 PC276    1      A Q_CAPP_SMLF-220UF,4V,20%,SPCAP,CH122KM8801    I59 @T6G_MB_LIB.T6G(SCH_1):PAGE186
 PC277    1      A Q_CAPP_SMLF-220UF,4V,20%,SPCAP,CH122KM8801    I60 @T6G_MB_LIB.T6G(SCH_1):PAGE186
PC280_2    1      A Q_CAP_C0805-22UF,4V,20%,X6S,CH622KMEA03    I61 @T6G_MB_LIB.T6G(SCH_1):PAGE186
PC281_1    1      A Q_CAP_C0805-22UF,4V,20%,X6S,CH622KMEA03    I76 @T6G_MB_LIB.T6G(SCH_1):PAGE186
PC283_1    1      A Q_CAP_C0805-22UF,4V,20%,X6S,CH622KMEA03    I77 @T6G_MB_LIB.T6G(SCH_1):PAGE186
 PR337    1      A Q_RES_0402LF-1K,1%,1/16W,CHIP,CS21002FB06    I78 @T6G_MB_LIB.T6G(SCH_1):PAGE186
 PC105    1      A Q_CAPP_SMLF-220UF,4V,20%,SPCAP,CH122KM8801    I84 @T6G_MB_LIB.T6G(SCH_1):PAGE186
 PC278    1      A Q_CAP_0402-0.1UF,25V,10%,X7R,CH4104K1B00    I85 @T6G_MB_LIB.T6G(SCH_1):PAGE186
  PL28    4      4 Q_INDUCTOR4P_14-150NH,SMLF,IND,CV+15^0TZ04    I90 @T6G_MB_LIB.T6G(SCH_1):PAGE186
 PR200    2      B Q_RES_0402LF-0,5%,1/16W,CHIP,CS00002JB13    I17 @T6G_MB_LIB.T6G(SCH_1):PAGE187
 PR199    2      B Q_RES_0402LF-0,5%,1/16W,CHIP,CS00002JB13    I27 @T6G_MB_LIB.T6G(SCH_1):PAGE187
  PL32    4      4 Q_INDUCTOR4P_14-150NH,SMLF,IND,CV+15^0TZ04    I53 @T6G_MB_LIB.T6G(SCH_1):PAGE187
PC303_4    1      A Q_CAP_C0805-22UF,4V,20%,X6S,CH622KMEA03    I58 @T6G_MB_LIB.T6G(SCH_1):PAGE187
PC305_4    1      A Q_CAP_C0805-22UF,4V,20%,X6S,CH622KMEA03    I60 @T6G_MB_LIB.T6G(SCH_1):PAGE187
  PL31    4      4 Q_INDUCTOR4P_14-150NH,SMLF,IND,CV+15^0TZ04    I67 @T6G_MB_LIB.T6G(SCH_1):PAGE187
PC302_3    1      A Q_CAP_C0805-22UF,4V,20%,X6S,CH622KMEA03    I69 @T6G_MB_LIB.T6G(SCH_1):PAGE187
PC304_3    1      A Q_CAP_C0805-22UF,4V,20%,X6S,CH622KMEA03    I71 @T6G_MB_LIB.T6G(SCH_1):PAGE187
 PR425    2      B Q_RES_0402LF-0,5%,1/16W,CHIP,CS00002JB13    I22 @T6G_MB_LIB.T6G(SCH_1):PAGE188
 PR204    2      B Q_RES_0402LF-0,5%,1/16W,CHIP,CS00002JB13    I33 @T6G_MB_LIB.T6G(SCH_1):PAGE188
   PL8    4      4 Q_INDUCTOR4P_14-150NH,SMLF,IND,CV+15^0TZ04    I53 @T6G_MB_LIB.T6G(SCH_1):PAGE188
PC134_6    1      A Q_CAP_C0805-22UF,4V,20%,X6S,CH622KMEA03    I58 @T6G_MB_LIB.T6G(SCH_1):PAGE188
PC135_6    1      A Q_CAP_C0805-22UF,4V,20%,X6S,CH622KMEA03    I60 @T6G_MB_LIB.T6G(SCH_1):PAGE188
  PL33    4      4 Q_INDUCTOR4P_14-150NH,SMLF,IND,CV+15^0TZ04    I64 @T6G_MB_LIB.T6G(SCH_1):PAGE188
PC315_5    1      A Q_CAP_C0805-22UF,4V,20%,X6S,CH622KMEA03    I69 @T6G_MB_LIB.T6G(SCH_1):PAGE188
PC316_5    1      A Q_CAP_C0805-22UF,4V,20%,X6S,CH622KMEA03    I71 @T6G_MB_LIB.T6G(SCH_1):PAGE188

PVDDCR_CPU0_P1_EN @T6G_MB_LIB.T6G(SCH_1):PVDDCR_CPU0_P1_EN
  R208    1      A Q_RES_0402LF-33,5%,1/16W,CHIP,CS03302JB10    I65 @T6G_MB_LIB.T6G(SCH_1):PAGE80
 R8179    1      A Q_RES_0402LF-0,5%,1/16W,CHIP,CS00002JB13    I84 @T6G_MB_LIB.T6G(SCH_1):PAGE185

PVDDCR_CPU0_P1_EN_R @T6G_MB_LIB.T6G(SCH_1):PVDDCR_CPU0_P1_EN_R
  C249    1      A Q_CAP_0402-1000PF,50V,5%,X7R,TMP_QCH21006JB10    I86 @T6G_MB_LIB.T6G(SCH_1):PAGE185
 R8179    2      B Q_RES_0402LF-0,5%,1/16W,CHIP,CS00002JB13    I84 @T6G_MB_LIB.T6G(SCH_1):PAGE185
  PU25   17    EN0 RAA229620GNPHA0-RAA229620GNP#HA0,SMLF,IC,ARF0TGP40A   I133 @T6G_MB_LIB.T6G(SCH_1):PAGE185

PVDDCR_CPU0_P1_IMON1 @T6G_MB_LIB.T6G(SCH_1):PVDDCR_CPU0_P1_IMON1
  PU25   27   CS11 RAA229620GNPHA0-RAA229620GNP#HA0,SMLF,IC,ARF0TGP40A   I133 @T6G_MB_LIB.T6G(SCH_1):PAGE185
   PU4   38   IOUT ISL99390FRZTR5935-ISL99390FRZ-TR5935,SMLF,IC,AL099A    I88 @T6G_MB_LIB.T6G(SCH_1):PAGE186

PVDDCR_CPU0_P1_IMON2 @T6G_MB_LIB.T6G(SCH_1):PVDDCR_CPU0_P1_IMON2
  PU25   28   CS10 RAA229620GNPHA0-RAA229620GNP#HA0,SMLF,IC,ARF0TGP40A   I133 @T6G_MB_LIB.T6G(SCH_1):PAGE185
  PU26   38   IOUT ISL99390FRZTR5935-ISL99390FRZ-TR5935,SMLF,IC,AL099A    I91 @T6G_MB_LIB.T6G(SCH_1):PAGE186

PVDDCR_CPU0_P1_IMON3 @T6G_MB_LIB.T6G(SCH_1):PVDDCR_CPU0_P1_IMON3
  PU25   29    CS9 RAA229620GNPHA0-RAA229620GNP#HA0,SMLF,IC,ARF0TGP40A   I133 @T6G_MB_LIB.T6G(SCH_1):PAGE185
  PU27   38   IOUT ISL99390FRZTR5935-ISL99390FRZ-TR5935,SMLF,IC,AL099A    I39 @T6G_MB_LIB.T6G(SCH_1):PAGE187

PVDDCR_CPU0_P1_IMON4 @T6G_MB_LIB.T6G(SCH_1):PVDDCR_CPU0_P1_IMON4
  PU25   30    CS8 RAA229620GNPHA0-RAA229620GNP#HA0,SMLF,IC,ARF0TGP40A   I133 @T6G_MB_LIB.T6G(SCH_1):PAGE185
  PU28   38   IOUT ISL99390FRZTR5935-ISL99390FRZ-TR5935,SMLF,IC,AL099A     I9 @T6G_MB_LIB.T6G(SCH_1):PAGE187

PVDDCR_CPU0_P1_IMON5 @T6G_MB_LIB.T6G(SCH_1):PVDDCR_CPU0_P1_IMON5
  PU25   31    CS7 RAA229620GNPHA0-RAA229620GNP#HA0,SMLF,IC,ARF0TGP40A   I133 @T6G_MB_LIB.T6G(SCH_1):PAGE185
  PU29   38   IOUT ISL99390FRZTR5935-ISL99390FRZ-TR5935,SMLF,IC,AL099A    I18 @T6G_MB_LIB.T6G(SCH_1):PAGE188

PVDDCR_CPU0_P1_IMON6 @T6G_MB_LIB.T6G(SCH_1):PVDDCR_CPU0_P1_IMON6
  PU25   32    CS6 RAA229620GNPHA0-RAA229620GNP#HA0,SMLF,IC,ARF0TGP40A   I133 @T6G_MB_LIB.T6G(SCH_1):PAGE185
  PU24   38   IOUT ISL99390FRZTR5935-ISL99390FRZ-TR5935,SMLF,IC,AL099A    I73 @T6G_MB_LIB.T6G(SCH_1):PAGE188

PVDDCR_CPU0_P1_LSET1 @T6G_MB_LIB.T6G(SCH_1):PVDDCR_CPU0_P1_LSET1
 PR187    2      B Q_RES_0402LF-8.87K,1%,1/16W,EMPTY,CS28872FB01    I37 @T6G_MB_LIB.T6G(SCH_1):PAGE186
   PU4   37   LSET ISL99390FRZTR5935-ISL99390FRZ-TR5935,SMLF,IC,AL099A    I88 @T6G_MB_LIB.T6G(SCH_1):PAGE186

PVDDCR_CPU0_P1_LSET2 @T6G_MB_LIB.T6G(SCH_1):PVDDCR_CPU0_P1_LSET2
 PR188    2      B Q_RES_0402LF-8.87K,1%,1/16W,EMPTY,CS28872FB01    I80 @T6G_MB_LIB.T6G(SCH_1):PAGE186
  PU26   37   LSET ISL99390FRZTR5935-ISL99390FRZ-TR5935,SMLF,IC,AL099A    I91 @T6G_MB_LIB.T6G(SCH_1):PAGE186

PVDDCR_CPU0_P1_LSET3 @T6G_MB_LIB.T6G(SCH_1):PVDDCR_CPU0_P1_LSET3
 PR195    2      B Q_RES_0402LF-8.87K,1%,1/16W,EMPTY,CS28872FB01    I34 @T6G_MB_LIB.T6G(SCH_1):PAGE187
  PU27   37   LSET ISL99390FRZTR5935-ISL99390FRZ-TR5935,SMLF,IC,AL099A    I39 @T6G_MB_LIB.T6G(SCH_1):PAGE187

PVDDCR_CPU0_P1_LSET4 @T6G_MB_LIB.T6G(SCH_1):PVDDCR_CPU0_P1_LSET4
  PU28   37   LSET ISL99390FRZTR5935-ISL99390FRZ-TR5935,SMLF,IC,AL099A     I9 @T6G_MB_LIB.T6G(SCH_1):PAGE187
 PR196    2      B Q_RES_0402LF-8.87K,1%,1/16W,EMPTY,CS28872FB01    I11 @T6G_MB_LIB.T6G(SCH_1):PAGE187

PVDDCR_CPU0_P1_LSET5 @T6G_MB_LIB.T6G(SCH_1):PVDDCR_CPU0_P1_LSET5
  PU29   37   LSET ISL99390FRZTR5935-ISL99390FRZ-TR5935,SMLF,IC,AL099A    I18 @T6G_MB_LIB.T6G(SCH_1):PAGE188
 PR202    2      B Q_RES_0402LF-8.87K,1%,1/16W,EMPTY,CS28872FB01    I37 @T6G_MB_LIB.T6G(SCH_1):PAGE188

PVDDCR_CPU0_P1_LSET6 @T6G_MB_LIB.T6G(SCH_1):PVDDCR_CPU0_P1_LSET6
 PR423    2      B Q_RES_0402LF-8.87K,1%,1/16W,EMPTY,CS28872FB01     I8 @T6G_MB_LIB.T6G(SCH_1):PAGE188
  PU24   37   LSET ISL99390FRZTR5935-ISL99390FRZ-TR5935,SMLF,IC,AL099A    I73 @T6G_MB_LIB.T6G(SCH_1):PAGE188

PVDDCR_CPU0_P1_OCP_N @T6G_MB_LIB.T6G(SCH_1):PVDDCR_CPU0_P1_OCP_N
 R8168    1      A Q_RES_0402LF-0,5%,1/16W,CHIP,CS00002JB13    I43 @T6G_MB_LIB.T6G(SCH_1):PAGE185
  R284    2      B Q_RES_0402LF-0,5%,1/16W,CHIP,CS00002JB13   I140 @T6G_MB_LIB.T6G(SCH_1):PAGE81

PVDDCR_CPU0_P1_OCP_N_R @T6G_MB_LIB.T6G(SCH_1):PVDDCR_CPU0_P1_OCP_N_R
 R8168    2      B Q_RES_0402LF-0,5%,1/16W,CHIP,CS00002JB13    I43 @T6G_MB_LIB.T6G(SCH_1):PAGE185
 R8180    2      B Q_RES_0402LF-1K,1%,1/16W,CHIP,CS21002FB06    I54 @T6G_MB_LIB.T6G(SCH_1):PAGE185
  PU25   41  OCP_L RAA229620GNPHA0-RAA229620GNP#HA0,SMLF,IC,ARF0TGP40A   I133 @T6G_MB_LIB.T6G(SCH_1):PAGE185

PVDDCR_CPU0_P1_PMALERT @T6G_MB_LIB.T6G(SCH_1):PVDDCR_CPU0_P1_PMALERT
 R1187    1      A Q_RES_0402LF-1K,1%,1/16W,CHIP,CS21002FB06    I59 @T6G_MB_LIB.T6G(SCH_1):PAGE82
   U18   M5  PL17D LCMXO3LF9400C5BG484C-LCMXO3LF-9400C-5BG484C,SMLF,IA   I143 @T6G_MB_LIB.T6G(SCH_1):PAGE81
 R8177    1      A Q_RES_0402LF-33,5%,1/16W,CHIP,CS03302JB10    I79 @T6G_MB_LIB.T6G(SCH_1):PAGE185
 C5012    1      A Q_CAP_0402-1000PF,50V,5%,X7R,TMP_QCH21006JB10   I139 @T6G_MB_LIB.T6G(SCH_1):PAGE185

PVDDCR_CPU0_P1_PMALERT_R @T6G_MB_LIB.T6G(SCH_1):PVDDCR_CPU0_P1_PMALERT_R
 R8177    2      B Q_RES_0402LF-33,5%,1/16W,CHIP,CS03302JB10    I79 @T6G_MB_LIB.T6G(SCH_1):PAGE185
  PU25   15 NPMALERT RAA229620GNPHA0-RAA229620GNP#HA0,SMLF,IC,ARF0TGP40A   I133 @T6G_MB_LIB.T6G(SCH_1):PAGE185

PVDDCR_CPU0_P1_PMSCL_R @T6G_MB_LIB.T6G(SCH_1):PVDDCR_CPU0_P1_PMSCL_R
  R175    2      B Q_RES_0402LF-0,5%,1/16W,CHIP,CS00002JB13    I81 @T6G_MB_LIB.T6G(SCH_1):PAGE185
  PU25   14  PMSCL RAA229620GNPHA0-RAA229620GNP#HA0,SMLF,IC,ARF0TGP40A   I133 @T6G_MB_LIB.T6G(SCH_1):PAGE185

PVDDCR_CPU0_P1_PMSDA_R @T6G_MB_LIB.T6G(SCH_1):PVDDCR_CPU0_P1_PMSDA_R
 R8176    2      B Q_RES_0402LF-0,5%,1/16W,CHIP,CS00002JB13    I80 @T6G_MB_LIB.T6G(SCH_1):PAGE185
  PU25   13  PMSDA RAA229620GNPHA0-RAA229620GNP#HA0,SMLF,IC,ARF0TGP40A   I133 @T6G_MB_LIB.T6G(SCH_1):PAGE185

PVDDCR_CPU0_P1_PVCC @T6G_MB_LIB.T6G(SCH_1):PVDDCR_CPU0_P1_PVCC
 PR335    1      A Q_RES_0402LF-0,5%,1/16W,CHIP,CS00002JB13     I3 @T6G_MB_LIB.T6G(SCH_1):PAGE186
 PR186    1      A Q_RES_0402LF-2.2,1%,1/16W,CHIP,CS-2202FB01    I11 @T6G_MB_LIB.T6G(SCH_1):PAGE186
PC259_C0P1_2    1      A Q_CAP_C0402-2.2UF,10V,10%,X6S,CH5222KEB01    I13 @T6G_MB_LIB.T6G(SCH_1):PAGE186
 PR205    1      A Q_RES_0402LF-2.2,1%,1/16W,CHIP,CS-2202FB01    I39 @T6G_MB_LIB.T6G(SCH_1):PAGE190
PC347_SOP1_3    1      A Q_CAP_C0402-2.2UF,10V,10%,X6S,CH5222KEB01    I18 @T6G_MB_LIB.T6G(SCH_1):PAGE191
  PU32    4   PVCC ISL99390FRZTR5935-ISL99390FRZ-TR5935,SMLF,IC,AL099A    I38 @T6G_MB_LIB.T6G(SCH_1):PAGE191
 PR336    1      A Q_RES_0402LF-0,5%,1/16W,EMPTY,CS00002JB13    I41 @T6G_MB_LIB.T6G(SCH_1):PAGE186
 PR185    1      A Q_RES_0402LF-2.2,1%,1/16W,CHIP,CS-2202FB01    I43 @T6G_MB_LIB.T6G(SCH_1):PAGE186
PC258_C0P1_1    1      A Q_CAP_C0402-2.2UF,10V,10%,X6S,CH5222KEB01    I44 @T6G_MB_LIB.T6G(SCH_1):PAGE186
   PU4    4   PVCC ISL99390FRZTR5935-ISL99390FRZ-TR5935,SMLF,IC,AL099A    I88 @T6G_MB_LIB.T6G(SCH_1):PAGE186
  PU26    4   PVCC ISL99390FRZTR5935-ISL99390FRZ-TR5935,SMLF,IC,AL099A    I91 @T6G_MB_LIB.T6G(SCH_1):PAGE186
  PU28    4   PVCC ISL99390FRZTR5935-ISL99390FRZ-TR5935,SMLF,IC,AL099A     I9 @T6G_MB_LIB.T6G(SCH_1):PAGE187
 PR194    1      A Q_RES_0402LF-2.2,1%,1/16W,CHIP,CS-2202FB01    I12 @T6G_MB_LIB.T6G(SCH_1):PAGE187
PC289_C0P1_4    1      A Q_CAP_C0402-2.2UF,10V,10%,X6S,CH5222KEB01    I15 @T6G_MB_LIB.T6G(SCH_1):PAGE187
 PR193    1      A Q_RES_0402LF-2.2,1%,1/16W,CHIP,CS-2202FB01    I38 @T6G_MB_LIB.T6G(SCH_1):PAGE187
  PU27    4   PVCC ISL99390FRZTR5935-ISL99390FRZ-TR5935,SMLF,IC,AL099A    I39 @T6G_MB_LIB.T6G(SCH_1):PAGE187
PC288_C0P1_3    1      A Q_CAP_C0402-2.2UF,10V,10%,X6S,CH5222KEB01    I41 @T6G_MB_LIB.T6G(SCH_1):PAGE187
 PR422    1      A Q_RES_0402LF-2.2,1%,1/16W,CHIP,CS-2202FB01    I12 @T6G_MB_LIB.T6G(SCH_1):PAGE188
PC126_C0P1_6    1      A Q_CAP_C0402-2.2UF,10V,10%,X6S,CH5222KEB01    I15 @T6G_MB_LIB.T6G(SCH_1):PAGE188
  PU29    4   PVCC ISL99390FRZTR5935-ISL99390FRZ-TR5935,SMLF,IC,AL099A    I18 @T6G_MB_LIB.T6G(SCH_1):PAGE188
 PR201    1      A Q_RES_0402LF-2.2,1%,1/16W,CHIP,CS-2202FB01    I41 @T6G_MB_LIB.T6G(SCH_1):PAGE188
PC308_C0P1_5    1      A Q_CAP_C0402-2.2UF,10V,10%,X6S,CH5222KEB01    I43 @T6G_MB_LIB.T6G(SCH_1):PAGE188
  PU24    4   PVCC ISL99390FRZTR5935-ISL99390FRZ-TR5935,SMLF,IC,AL099A    I73 @T6G_MB_LIB.T6G(SCH_1):PAGE188
 PR213    1      A Q_RES_0402LF-2.2,1%,1/16W,CHIP,CS-2202FB01    I14 @T6G_MB_LIB.T6G(SCH_1):PAGE191
 PR206    1      A Q_RES_0402LF-2.2,1%,1/16W,CHIP,CS-2202FB01    I12 @T6G_MB_LIB.T6G(SCH_1):PAGE190
PC322_SOP1_2    1      A Q_CAP_C0402-2.2UF,10V,10%,X6S,CH5222KEB01    I14 @T6G_MB_LIB.T6G(SCH_1):PAGE190
  PU30    4   PVCC ISL99390FRZTR5935-ISL99390FRZ-TR5935,SMLF,IC,AL099A    I17 @T6G_MB_LIB.T6G(SCH_1):PAGE190
PC321_SOP1_1    1      A Q_CAP_C0402-2.2UF,10V,10%,X6S,CH5222KEB01    I41 @T6G_MB_LIB.T6G(SCH_1):PAGE190
  PU31    4   PVCC ISL99390FRZTR5935-ISL99390FRZ-TR5935,SMLF,IC,AL099A    I86 @T6G_MB_LIB.T6G(SCH_1):PAGE190

PVDDCR_CPU0_P1_PWM1 @T6G_MB_LIB.T6G(SCH_1):PVDDCR_CPU0_P1_PWM1
  PU25   12  PWM11 RAA229620GNPHA0-RAA229620GNP#HA0,SMLF,IC,ARF0TGP40A   I133 @T6G_MB_LIB.T6G(SCH_1):PAGE185
   PU4   34    PWM ISL99390FRZTR5935-ISL99390FRZ-TR5935,SMLF,IC,AL099A    I88 @T6G_MB_LIB.T6G(SCH_1):PAGE186

PVDDCR_CPU0_P1_PWM2 @T6G_MB_LIB.T6G(SCH_1):PVDDCR_CPU0_P1_PWM2
  PU25   11  PWM10 RAA229620GNPHA0-RAA229620GNP#HA0,SMLF,IC,ARF0TGP40A   I133 @T6G_MB_LIB.T6G(SCH_1):PAGE185
  PU26   34    PWM ISL99390FRZTR5935-ISL99390FRZ-TR5935,SMLF,IC,AL099A    I91 @T6G_MB_LIB.T6G(SCH_1):PAGE186

PVDDCR_CPU0_P1_PWM3 @T6G_MB_LIB.T6G(SCH_1):PVDDCR_CPU0_P1_PWM3
  PU25   10   PWM9 RAA229620GNPHA0-RAA229620GNP#HA0,SMLF,IC,ARF0TGP40A   I133 @T6G_MB_LIB.T6G(SCH_1):PAGE185
  PU27   34    PWM ISL99390FRZTR5935-ISL99390FRZ-TR5935,SMLF,IC,AL099A    I39 @T6G_MB_LIB.T6G(SCH_1):PAGE187

PVDDCR_CPU0_P1_PWM4 @T6G_MB_LIB.T6G(SCH_1):PVDDCR_CPU0_P1_PWM4
  PU25    9   PWM8 RAA229620GNPHA0-RAA229620GNP#HA0,SMLF,IC,ARF0TGP40A   I133 @T6G_MB_LIB.T6G(SCH_1):PAGE185
  PU28   34    PWM ISL99390FRZTR5935-ISL99390FRZ-TR5935,SMLF,IC,AL099A     I9 @T6G_MB_LIB.T6G(SCH_1):PAGE187

PVDDCR_CPU0_P1_PWM5 @T6G_MB_LIB.T6G(SCH_1):PVDDCR_CPU0_P1_PWM5
  PU25    8   PWM7 RAA229620GNPHA0-RAA229620GNP#HA0,SMLF,IC,ARF0TGP40A   I133 @T6G_MB_LIB.T6G(SCH_1):PAGE185
  PU29   34    PWM ISL99390FRZTR5935-ISL99390FRZ-TR5935,SMLF,IC,AL099A    I18 @T6G_MB_LIB.T6G(SCH_1):PAGE188

PVDDCR_CPU0_P1_PWM6 @T6G_MB_LIB.T6G(SCH_1):PVDDCR_CPU0_P1_PWM6
  PU25    7   PWM6 RAA229620GNPHA0-RAA229620GNP#HA0,SMLF,IC,ARF0TGP40A   I133 @T6G_MB_LIB.T6G(SCH_1):PAGE185
  PU24   34    PWM ISL99390FRZTR5935-ISL99390FRZ-TR5935,SMLF,IC,AL099A    I73 @T6G_MB_LIB.T6G(SCH_1):PAGE188

PVDDCR_CPU0_P1_RESET_N @T6G_MB_LIB.T6G(SCH_1):PVDDCR_CPU0_P1_RESET_N
   U40    6     1Y SN74LVC2G07DCKR_SMLF-SN74LVC2G07DCKR,IC,AL002G07006    I21 @T6G_MB_LIB.T6G(SCH_1):PAGE77
 R8182    1      A Q_RES_0402LF-49.9,1%,1/16W,CHIP,CS04992FB07    I42 @T6G_MB_LIB.T6G(SCH_1):PAGE185

PVDDCR_CPU0_P1_RESET_N_R @T6G_MB_LIB.T6G(SCH_1):PVDDCR_CPU0_P1_RESET_N_R
 R8182    2      B Q_RES_0402LF-49.9,1%,1/16W,CHIP,CS04992FB07    I42 @T6G_MB_LIB.T6G(SCH_1):PAGE185
 R8184    2      B Q_RES_0402LF-1K,1%,1/16W,CHIP,CS21002FB06    I41 @T6G_MB_LIB.T6G(SCH_1):PAGE185
  PU25   18 RESET_L RAA229620GNPHA0-RAA229620GNP#HA0,SMLF,IC,ARF0TGP40A   I133 @T6G_MB_LIB.T6G(SCH_1):PAGE185

PVDDCR_CPU0_P1_TEMP0 @T6G_MB_LIB.T6G(SCH_1):PVDDCR_CPU0_P1_TEMP0
 PC250    1      A Q_CAP_0402-470PF,50V,10%,X7R,TMP_QCH14706KB18    I91 @T6G_MB_LIB.T6G(SCH_1):PAGE185
  PU25   44  TEMP0 RAA229620GNPHA0-RAA229620GNP#HA0,SMLF,IC,ARF0TGP40A   I133 @T6G_MB_LIB.T6G(SCH_1):PAGE185
   PU4   36 TOUT_FLT ISL99390FRZTR5935-ISL99390FRZ-TR5935,SMLF,IC,AL099A    I88 @T6G_MB_LIB.T6G(SCH_1):PAGE186
  PU26   36 TOUT_FLT ISL99390FRZTR5935-ISL99390FRZ-TR5935,SMLF,IC,AL099A    I91 @T6G_MB_LIB.T6G(SCH_1):PAGE186
  PU28   36 TOUT_FLT ISL99390FRZTR5935-ISL99390FRZ-TR5935,SMLF,IC,AL099A     I9 @T6G_MB_LIB.T6G(SCH_1):PAGE187
  PU27   36 TOUT_FLT ISL99390FRZTR5935-ISL99390FRZ-TR5935,SMLF,IC,AL099A    I39 @T6G_MB_LIB.T6G(SCH_1):PAGE187
  PU29   36 TOUT_FLT ISL99390FRZTR5935-ISL99390FRZ-TR5935,SMLF,IC,AL099A    I18 @T6G_MB_LIB.T6G(SCH_1):PAGE188
  PU24   36 TOUT_FLT ISL99390FRZTR5935-ISL99390FRZ-TR5935,SMLF,IC,AL099A    I73 @T6G_MB_LIB.T6G(SCH_1):PAGE188

PVDDCR_CPU0_P1_VCC @T6G_MB_LIB.T6G(SCH_1):PVDDCR_CPU0_P1_VCC
  PC10    1      A Q_CAP_0402-0.1UF,25V,10%,X7R,CH4104K1B00   I116 @T6G_MB_LIB.T6G(SCH_1):PAGE185
 PC252    1      A Q_CAP_C0402-1UF,16V,10%,X6S,CH5103KEB01   I127 @T6G_MB_LIB.T6G(SCH_1):PAGE185
 PR183    1      A Q_RES_0402LF-1,1%,1/16W,CHIP,CS-1002FB04   I129 @T6G_MB_LIB.T6G(SCH_1):PAGE185
  PU25   47    VCC RAA229620GNPHA0-RAA229620GNP#HA0,SMLF,IC,ARF0TGP40A   I133 @T6G_MB_LIB.T6G(SCH_1):PAGE185

PVDDCR_CPU0_P1_VCC1 @T6G_MB_LIB.T6G(SCH_1):PVDDCR_CPU0_P1_VCC1
 PC256    1      A Q_CAP_C0402-2.2UF,10V,10%,X6S,CH5222KEB01    I36 @T6G_MB_LIB.T6G(SCH_1):PAGE186
 PR185    2      B Q_RES_0402LF-2.2,1%,1/16W,CHIP,CS-2202FB01    I43 @T6G_MB_LIB.T6G(SCH_1):PAGE186
   PU4   35     EN ISL99390FRZTR5935-ISL99390FRZ-TR5935,SMLF,IC,AL099A    I88 @T6G_MB_LIB.T6G(SCH_1):PAGE186
   PU4    3    VCC ISL99390FRZTR5935-ISL99390FRZ-TR5935,SMLF,IC,AL099A    I88 @T6G_MB_LIB.T6G(SCH_1):PAGE186

PVDDCR_CPU0_P1_VCC2 @T6G_MB_LIB.T6G(SCH_1):PVDDCR_CPU0_P1_VCC2
 PR186    2      B Q_RES_0402LF-2.2,1%,1/16W,CHIP,CS-2202FB01    I11 @T6G_MB_LIB.T6G(SCH_1):PAGE186
 PC257    1      A Q_CAP_C0402-2.2UF,10V,10%,X6S,CH5222KEB01     I9 @T6G_MB_LIB.T6G(SCH_1):PAGE186
  PU26   35     EN ISL99390FRZTR5935-ISL99390FRZ-TR5935,SMLF,IC,AL099A    I91 @T6G_MB_LIB.T6G(SCH_1):PAGE186
  PU26    3    VCC ISL99390FRZTR5935-ISL99390FRZ-TR5935,SMLF,IC,AL099A    I91 @T6G_MB_LIB.T6G(SCH_1):PAGE186

PVDDCR_CPU0_P1_VCC3 @T6G_MB_LIB.T6G(SCH_1):PVDDCR_CPU0_P1_VCC3
 PC286    1      A Q_CAP_C0402-2.2UF,10V,10%,X6S,CH5222KEB01    I37 @T6G_MB_LIB.T6G(SCH_1):PAGE187
 PR193    2      B Q_RES_0402LF-2.2,1%,1/16W,CHIP,CS-2202FB01    I38 @T6G_MB_LIB.T6G(SCH_1):PAGE187
  PU27   35     EN ISL99390FRZTR5935-ISL99390FRZ-TR5935,SMLF,IC,AL099A    I39 @T6G_MB_LIB.T6G(SCH_1):PAGE187
  PU27    3    VCC ISL99390FRZTR5935-ISL99390FRZ-TR5935,SMLF,IC,AL099A    I39 @T6G_MB_LIB.T6G(SCH_1):PAGE187

PVDDCR_CPU0_P1_VCC4 @T6G_MB_LIB.T6G(SCH_1):PVDDCR_CPU0_P1_VCC4
 PC287    1      A Q_CAP_C0402-2.2UF,10V,10%,X6S,CH5222KEB01     I6 @T6G_MB_LIB.T6G(SCH_1):PAGE187
  PU28   35     EN ISL99390FRZTR5935-ISL99390FRZ-TR5935,SMLF,IC,AL099A     I9 @T6G_MB_LIB.T6G(SCH_1):PAGE187
  PU28    3    VCC ISL99390FRZTR5935-ISL99390FRZ-TR5935,SMLF,IC,AL099A     I9 @T6G_MB_LIB.T6G(SCH_1):PAGE187
 PR194    2      B Q_RES_0402LF-2.2,1%,1/16W,CHIP,CS-2202FB01    I12 @T6G_MB_LIB.T6G(SCH_1):PAGE187

PVDDCR_CPU0_P1_VCC5 @T6G_MB_LIB.T6G(SCH_1):PVDDCR_CPU0_P1_VCC5
  PU29   35     EN ISL99390FRZTR5935-ISL99390FRZ-TR5935,SMLF,IC,AL099A    I18 @T6G_MB_LIB.T6G(SCH_1):PAGE188
  PU29    3    VCC ISL99390FRZTR5935-ISL99390FRZ-TR5935,SMLF,IC,AL099A    I18 @T6G_MB_LIB.T6G(SCH_1):PAGE188
 PC307    1      A Q_CAP_C0402-2.2UF,10V,10%,X6S,CH5222KEB01    I39 @T6G_MB_LIB.T6G(SCH_1):PAGE188
 PR201    2      B Q_RES_0402LF-2.2,1%,1/16W,CHIP,CS-2202FB01    I41 @T6G_MB_LIB.T6G(SCH_1):PAGE188

PVDDCR_CPU0_P1_VCC6 @T6G_MB_LIB.T6G(SCH_1):PVDDCR_CPU0_P1_VCC6
 PC125    1      A Q_CAP_C0402-2.2UF,10V,10%,X6S,CH5222KEB01    I10 @T6G_MB_LIB.T6G(SCH_1):PAGE188
 PR422    2      B Q_RES_0402LF-2.2,1%,1/16W,CHIP,CS-2202FB01    I12 @T6G_MB_LIB.T6G(SCH_1):PAGE188
  PU24   35     EN ISL99390FRZTR5935-ISL99390FRZ-TR5935,SMLF,IC,AL099A    I73 @T6G_MB_LIB.T6G(SCH_1):PAGE188
  PU24    3    VCC ISL99390FRZTR5935-ISL99390FRZ-TR5935,SMLF,IC,AL099A    I73 @T6G_MB_LIB.T6G(SCH_1):PAGE188

PVDDCR_CPU0_P1_VCCS @T6G_MB_LIB.T6G(SCH_1):PVDDCR_CPU0_P1_VCCS
  PC11    1      A Q_CAP_0402-0.1UF,25V,10%,X7R,CH4104K1B00   I114 @T6G_MB_LIB.T6G(SCH_1):PAGE185
PC254_1    1      A Q_CAP_0402-0.1UF,25V,10%,X7R,CH4104K1B00    I16 @T6G_MB_LIB.T6G(SCH_1):PAGE186
PC318_8    1      A Q_CAP_0402-0.1UF,25V,10%,X7R,CH4104K1B00     I4 @T6G_MB_LIB.T6G(SCH_1):PAGE190
  PU32   39  REFIN ISL99390FRZTR5935-ISL99390FRZ-TR5935,SMLF,IC,AL099A    I38 @T6G_MB_LIB.T6G(SCH_1):PAGE191
 PC251    1      A Q_CAP_C0402-10UF,6.3V,20%,X6S,CH6101MEB03   I125 @T6G_MB_LIB.T6G(SCH_1):PAGE185
  PU25   48   VCCS RAA229620GNPHA0-RAA229620GNP#HA0,SMLF,IC,ARF0TGP40A   I133 @T6G_MB_LIB.T6G(SCH_1):PAGE185
PC255_2    1      A Q_CAP_0402-0.1UF,25V,10%,X7R,CH4104K1B00     I5 @T6G_MB_LIB.T6G(SCH_1):PAGE186
   PU4   39  REFIN ISL99390FRZTR5935-ISL99390FRZ-TR5935,SMLF,IC,AL099A    I88 @T6G_MB_LIB.T6G(SCH_1):PAGE186
  PU26   39  REFIN ISL99390FRZTR5935-ISL99390FRZ-TR5935,SMLF,IC,AL099A    I91 @T6G_MB_LIB.T6G(SCH_1):PAGE186
PC285_4    1      A Q_CAP_0402-0.1UF,25V,10%,X7R,CH4104K1B00     I2 @T6G_MB_LIB.T6G(SCH_1):PAGE187
  PU28   39  REFIN ISL99390FRZTR5935-ISL99390FRZ-TR5935,SMLF,IC,AL099A     I9 @T6G_MB_LIB.T6G(SCH_1):PAGE187
PC284_3    1      A Q_CAP_0402-0.1UF,25V,10%,X7R,CH4104K1B00    I28 @T6G_MB_LIB.T6G(SCH_1):PAGE187
  PU27   39  REFIN ISL99390FRZTR5935-ISL99390FRZ-TR5935,SMLF,IC,AL099A    I39 @T6G_MB_LIB.T6G(SCH_1):PAGE187
PC124_6    1      A Q_CAP_0402-0.1UF,25V,10%,X7R,CH4104K1B00     I4 @T6G_MB_LIB.T6G(SCH_1):PAGE188
  PU29   39  REFIN ISL99390FRZTR5935-ISL99390FRZ-TR5935,SMLF,IC,AL099A    I18 @T6G_MB_LIB.T6G(SCH_1):PAGE188
PC306_5    1      A Q_CAP_0402-0.1UF,25V,10%,X7R,CH4104K1B00    I34 @T6G_MB_LIB.T6G(SCH_1):PAGE188
  PU24   39  REFIN ISL99390FRZTR5935-ISL99390FRZ-TR5935,SMLF,IC,AL099A    I73 @T6G_MB_LIB.T6G(SCH_1):PAGE188
PC345_9    1      A Q_CAP_0402-0.1UF,25V,10%,X7R,CH4104K1B00     I2 @T6G_MB_LIB.T6G(SCH_1):PAGE191
  PU30   39  REFIN ISL99390FRZTR5935-ISL99390FRZ-TR5935,SMLF,IC,AL099A    I17 @T6G_MB_LIB.T6G(SCH_1):PAGE190
PC317_7    1      A Q_CAP_0402-0.1UF,25V,10%,X7R,CH4104K1B00    I32 @T6G_MB_LIB.T6G(SCH_1):PAGE190
  PU31   39  REFIN ISL99390FRZTR5935-ISL99390FRZ-TR5935,SMLF,IC,AL099A    I86 @T6G_MB_LIB.T6G(SCH_1):PAGE190

PVDDCR_CPU0_P1_VINSEN @T6G_MB_LIB.T6G(SCH_1):PVDDCR_CPU0_P1_VINSEN
 PR181    2      B Q_RES_0402LF-0,5%,1/16W,CHIP,CS00002JB13    I47 @T6G_MB_LIB.T6G(SCH_1):PAGE185
 PR602    1      A Q_RES_0402LF-4.99K,1%,1/16W,EMPTY,CS24992FB07    I48 @T6G_MB_LIB.T6G(SCH_1):PAGE185
   PC6    1      A Q_CAP_0402-0.1UF,25V,10%,X7R,CH4104K1B00    I51 @T6G_MB_LIB.T6G(SCH_1):PAGE185
  PU25   46 VINSEN RAA229620GNPHA0-RAA229620GNP#HA0,SMLF,IC,ARF0TGP40A   I133 @T6G_MB_LIB.T6G(SCH_1):PAGE185

PVDDCR_CPU0_P1_VMON @T6G_MB_LIB.T6G(SCH_1):PVDDCR_CPU0_P1_VMON
 PR157    2      B Q_RES_0402LF-40.2K,1%,1/16W,CHIP,CS34022FB04    I14 @T6G_MB_LIB.T6G(SCH_1):PAGE185
   PR4    1      A Q_RES_0402LF-10K,1%,1/16W,CHIP,CS31002FB08    I20 @T6G_MB_LIB.T6G(SCH_1):PAGE185
 PC243    1      A Q_CAP_0402-0.1UF,25V,10%,X7R,CH4104K1B00    I22 @T6G_MB_LIB.T6G(SCH_1):PAGE185
  PU25   45 VMON||IINSEN RAA229620GNPHA0-RAA229620GNP#HA0,SMLF,IC,ARF0TGP40A   I133 @T6G_MB_LIB.T6G(SCH_1):PAGE185

PVDDCR_CPU0_P1_VOS1 @T6G_MB_LIB.T6G(SCH_1):PVDDCR_CPU0_P1_VOS1
 PR191    1      A Q_RES_0402LF-0,5%,1/16W,CHIP,CS00002JB13    I35 @T6G_MB_LIB.T6G(SCH_1):PAGE186
   PU4    1    VOS ISL99390FRZTR5935-ISL99390FRZ-TR5935,SMLF,IC,AL099A    I88 @T6G_MB_LIB.T6G(SCH_1):PAGE186

PVDDCR_CPU0_P1_VOS2 @T6G_MB_LIB.T6G(SCH_1):PVDDCR_CPU0_P1_VOS2
 PR192    1      A Q_RES_0402LF-0,5%,1/16W,CHIP,CS00002JB13    I23 @T6G_MB_LIB.T6G(SCH_1):PAGE186
  PU26    1    VOS ISL99390FRZTR5935-ISL99390FRZ-TR5935,SMLF,IC,AL099A    I91 @T6G_MB_LIB.T6G(SCH_1):PAGE186

PVDDCR_CPU0_P1_VOS3 @T6G_MB_LIB.T6G(SCH_1):PVDDCR_CPU0_P1_VOS3
 PR199    1      A Q_RES_0402LF-0,5%,1/16W,CHIP,CS00002JB13    I27 @T6G_MB_LIB.T6G(SCH_1):PAGE187
  PU27    1    VOS ISL99390FRZTR5935-ISL99390FRZ-TR5935,SMLF,IC,AL099A    I39 @T6G_MB_LIB.T6G(SCH_1):PAGE187

PVDDCR_CPU0_P1_VOS4 @T6G_MB_LIB.T6G(SCH_1):PVDDCR_CPU0_P1_VOS4
  PU28    1    VOS ISL99390FRZTR5935-ISL99390FRZ-TR5935,SMLF,IC,AL099A     I9 @T6G_MB_LIB.T6G(SCH_1):PAGE187
 PR200    1      A Q_RES_0402LF-0,5%,1/16W,CHIP,CS00002JB13    I17 @T6G_MB_LIB.T6G(SCH_1):PAGE187

PVDDCR_CPU0_P1_VOS5 @T6G_MB_LIB.T6G(SCH_1):PVDDCR_CPU0_P1_VOS5
  PU29    1    VOS ISL99390FRZTR5935-ISL99390FRZ-TR5935,SMLF,IC,AL099A    I18 @T6G_MB_LIB.T6G(SCH_1):PAGE188
 PR204    1      A Q_RES_0402LF-0,5%,1/16W,CHIP,CS00002JB13    I33 @T6G_MB_LIB.T6G(SCH_1):PAGE188

PVDDCR_CPU0_P1_VOS6 @T6G_MB_LIB.T6G(SCH_1):PVDDCR_CPU0_P1_VOS6
 PR425    1      A Q_RES_0402LF-0,5%,1/16W,CHIP,CS00002JB13    I22 @T6G_MB_LIB.T6G(SCH_1):PAGE188
  PU24    1    VOS ISL99390FRZTR5935-ISL99390FRZ-TR5935,SMLF,IC,AL099A    I73 @T6G_MB_LIB.T6G(SCH_1):PAGE188

PVDDCR_CPU1_P0 @T6G_MB_LIB.T6G(SCH_1):PVDDCR_CPU1_P0
   U25 BN27 VDDCR_CPU1_BN27 GENOA_SP5-SOCKET6096_13568-001,SMLF,IO,DGA^6000030    I45 @T6G_MB_LIB.T6G(SCH_1):PAGE30
   U25 BN31 VDDCR_CPU1_BN31 GENOA_SP5-SOCKET6096_13568-001,SMLF,IO,DGA^6000030    I45 @T6G_MB_LIB.T6G(SCH_1):PAGE30
   U25 BN35 VDDCR_CPU1_BN35 GENOA_SP5-SOCKET6096_13568-001,SMLF,IO,DGA^6000030    I45 @T6G_MB_LIB.T6G(SCH_1):PAGE30
   U25 BN42 VDDCR_CPU1_BN42 GENOA_SP5-SOCKET6096_13568-001,SMLF,IO,DGA^6000030    I45 @T6G_MB_LIB.T6G(SCH_1):PAGE30
   U25 BN46 VDDCR_CPU1_BN46 GENOA_SP5-SOCKET6096_13568-001,SMLF,IO,DGA^6000030    I45 @T6G_MB_LIB.T6G(SCH_1):PAGE30
   U25 BN50 VDDCR_CPU1_BN50 GENOA_SP5-SOCKET6096_13568-001,SMLF,IO,DGA^6000030    I45 @T6G_MB_LIB.T6G(SCH_1):PAGE30
   U25 BP24 VDDCR_CPU1_BP24 GENOA_SP5-SOCKET6096_13568-001,SMLF,IO,DGA^6000030    I45 @T6G_MB_LIB.T6G(SCH_1):PAGE30
   U25 BP26 VDDCR_CPU1_BP26 GENOA_SP5-SOCKET6096_13568-001,SMLF,IO,DGA^6000030    I45 @T6G_MB_LIB.T6G(SCH_1):PAGE30
   U25 BP28 VDDCR_CPU1_BP28 GENOA_SP5-SOCKET6096_13568-001,SMLF,IO,DGA^6000030    I45 @T6G_MB_LIB.T6G(SCH_1):PAGE30
   U25 BP30 VDDCR_CPU1_BP30 GENOA_SP5-SOCKET6096_13568-001,SMLF,IO,DGA^6000030    I45 @T6G_MB_LIB.T6G(SCH_1):PAGE30
   U25 BP32 VDDCR_CPU1_BP32 GENOA_SP5-SOCKET6096_13568-001,SMLF,IO,DGA^6000030    I45 @T6G_MB_LIB.T6G(SCH_1):PAGE30
   U25 BP34 VDDCR_CPU1_BP34 GENOA_SP5-SOCKET6096_13568-001,SMLF,IO,DGA^6000030    I45 @T6G_MB_LIB.T6G(SCH_1):PAGE30
   U25 BP36 VDDCR_CPU1_BP36 GENOA_SP5-SOCKET6096_13568-001,SMLF,IO,DGA^6000030    I45 @T6G_MB_LIB.T6G(SCH_1):PAGE30
   U25 BP39 VDDCR_CPU1_BP39 GENOA_SP5-SOCKET6096_13568-001,SMLF,IO,DGA^6000030    I45 @T6G_MB_LIB.T6G(SCH_1):PAGE30
   U25 BP41 VDDCR_CPU1_BP41 GENOA_SP5-SOCKET6096_13568-001,SMLF,IO,DGA^6000030    I45 @T6G_MB_LIB.T6G(SCH_1):PAGE30
   U25 BP43 VDDCR_CPU1_BP43 GENOA_SP5-SOCKET6096_13568-001,SMLF,IO,DGA^6000030    I45 @T6G_MB_LIB.T6G(SCH_1):PAGE30
   U25 BP45 VDDCR_CPU1_BP45 GENOA_SP5-SOCKET6096_13568-001,SMLF,IO,DGA^6000030    I45 @T6G_MB_LIB.T6G(SCH_1):PAGE30
   U25 BP47 VDDCR_CPU1_BP47 GENOA_SP5-SOCKET6096_13568-001,SMLF,IO,DGA^6000030    I45 @T6G_MB_LIB.T6G(SCH_1):PAGE30
   U25 BP49 VDDCR_CPU1_BP49 GENOA_SP5-SOCKET6096_13568-001,SMLF,IO,DGA^6000030    I45 @T6G_MB_LIB.T6G(SCH_1):PAGE30
   U25 BR23 VDDCR_CPU1_BR23 GENOA_SP5-SOCKET6096_13568-001,SMLF,IO,DGA^6000030    I45 @T6G_MB_LIB.T6G(SCH_1):PAGE30
   U25 BR25 VDDCR_CPU1_BR25 GENOA_SP5-SOCKET6096_13568-001,SMLF,IO,DGA^6000030    I45 @T6G_MB_LIB.T6G(SCH_1):PAGE30
   U25 BR27 VDDCR_CPU1_BR27 GENOA_SP5-SOCKET6096_13568-001,SMLF,IO,DGA^6000030    I45 @T6G_MB_LIB.T6G(SCH_1):PAGE30
   U25 BR29 VDDCR_CPU1_BR29 GENOA_SP5-SOCKET6096_13568-001,SMLF,IO,DGA^6000030    I45 @T6G_MB_LIB.T6G(SCH_1):PAGE30
   U25 BR31 VDDCR_CPU1_BR31 GENOA_SP5-SOCKET6096_13568-001,SMLF,IO,DGA^6000030    I45 @T6G_MB_LIB.T6G(SCH_1):PAGE30
   U25 BR33 VDDCR_CPU1_BR33 GENOA_SP5-SOCKET6096_13568-001,SMLF,IO,DGA^6000030    I45 @T6G_MB_LIB.T6G(SCH_1):PAGE30
   U25 BR35 VDDCR_CPU1_BR35 GENOA_SP5-SOCKET6096_13568-001,SMLF,IO,DGA^6000030    I45 @T6G_MB_LIB.T6G(SCH_1):PAGE30
   U25 BR40 VDDCR_CPU1_BR40 GENOA_SP5-SOCKET6096_13568-001,SMLF,IO,DGA^6000030    I45 @T6G_MB_LIB.T6G(SCH_1):PAGE30
   U25 BR42 VDDCR_CPU1_BR42 GENOA_SP5-SOCKET6096_13568-001,SMLF,IO,DGA^6000030    I45 @T6G_MB_LIB.T6G(SCH_1):PAGE30
   U25 BR44 VDDCR_CPU1_BR44 GENOA_SP5-SOCKET6096_13568-001,SMLF,IO,DGA^6000030    I45 @T6G_MB_LIB.T6G(SCH_1):PAGE30
   U25 BR46 VDDCR_CPU1_BR46 GENOA_SP5-SOCKET6096_13568-001,SMLF,IO,DGA^6000030    I45 @T6G_MB_LIB.T6G(SCH_1):PAGE30
   U25 BR48 VDDCR_CPU1_BR48 GENOA_SP5-SOCKET6096_13568-001,SMLF,IO,DGA^6000030    I45 @T6G_MB_LIB.T6G(SCH_1):PAGE30
   U25 BR50 VDDCR_CPU1_BR50 GENOA_SP5-SOCKET6096_13568-001,SMLF,IO,DGA^6000030    I45 @T6G_MB_LIB.T6G(SCH_1):PAGE30
   U25 BR52 VDDCR_CPU1_BR52 GENOA_SP5-SOCKET6096_13568-001,SMLF,IO,DGA^6000030    I45 @T6G_MB_LIB.T6G(SCH_1):PAGE30
   U25 BT23 VDDCR_CPU1_BT23 GENOA_SP5-SOCKET6096_13568-001,SMLF,IO,DGA^6000030    I45 @T6G_MB_LIB.T6G(SCH_1):PAGE30
   U25 BT24 VDDCR_CPU1_BT24 GENOA_SP5-SOCKET6096_13568-001,SMLF,IO,DGA^6000030    I45 @T6G_MB_LIB.T6G(SCH_1):PAGE30
   U25 BT26 VDDCR_CPU1_BT26 GENOA_SP5-SOCKET6096_13568-001,SMLF,IO,DGA^6000030    I45 @T6G_MB_LIB.T6G(SCH_1):PAGE30
   U25 BT27 VDDCR_CPU1_BT27 GENOA_SP5-SOCKET6096_13568-001,SMLF,IO,DGA^6000030    I45 @T6G_MB_LIB.T6G(SCH_1):PAGE30
   U25 BT29 VDDCR_CPU1_BT29 GENOA_SP5-SOCKET6096_13568-001,SMLF,IO,DGA^6000030    I45 @T6G_MB_LIB.T6G(SCH_1):PAGE30
   U25 BT30 VDDCR_CPU1_BT30 GENOA_SP5-SOCKET6096_13568-001,SMLF,IO,DGA^6000030    I45 @T6G_MB_LIB.T6G(SCH_1):PAGE30
   U25 BT32 VDDCR_CPU1_BT32 GENOA_SP5-SOCKET6096_13568-001,SMLF,IO,DGA^6000030    I45 @T6G_MB_LIB.T6G(SCH_1):PAGE30
   U25 BT33 VDDCR_CPU1_BT33 GENOA_SP5-SOCKET6096_13568-001,SMLF,IO,DGA^6000030    I45 @T6G_MB_LIB.T6G(SCH_1):PAGE30
   U25 BT43 VDDCR_CPU1_BT43 GENOA_SP5-SOCKET6096_13568-001,SMLF,IO,DGA^6000030    I45 @T6G_MB_LIB.T6G(SCH_1):PAGE30
   U25 BT44 VDDCR_CPU1_BT44 GENOA_SP5-SOCKET6096_13568-001,SMLF,IO,DGA^6000030    I45 @T6G_MB_LIB.T6G(SCH_1):PAGE30
   U25 BT46 VDDCR_CPU1_BT46 GENOA_SP5-SOCKET6096_13568-001,SMLF,IO,DGA^6000030    I45 @T6G_MB_LIB.T6G(SCH_1):PAGE30
   U25 BT47 VDDCR_CPU1_BT47 GENOA_SP5-SOCKET6096_13568-001,SMLF,IO,DGA^6000030    I45 @T6G_MB_LIB.T6G(SCH_1):PAGE30
   U25 BT49 VDDCR_CPU1_BT49 GENOA_SP5-SOCKET6096_13568-001,SMLF,IO,DGA^6000030    I45 @T6G_MB_LIB.T6G(SCH_1):PAGE30
   U25 BT50 VDDCR_CPU1_BT50 GENOA_SP5-SOCKET6096_13568-001,SMLF,IO,DGA^6000030    I45 @T6G_MB_LIB.T6G(SCH_1):PAGE30
   U25 BT52 VDDCR_CPU1_BT52 GENOA_SP5-SOCKET6096_13568-001,SMLF,IO,DGA^6000030    I45 @T6G_MB_LIB.T6G(SCH_1):PAGE30
   U25 BT53 VDDCR_CPU1_BT53 GENOA_SP5-SOCKET6096_13568-001,SMLF,IO,DGA^6000030    I45 @T6G_MB_LIB.T6G(SCH_1):PAGE30
   U25 BW35 VDDCR_CPU1_BW35 GENOA_SP5-SOCKET6096_13568-001,SMLF,IO,DGA^6000030    I45 @T6G_MB_LIB.T6G(SCH_1):PAGE30
   U25 BW36 VDDCR_CPU1_BW36 GENOA_SP5-SOCKET6096_13568-001,SMLF,IO,DGA^6000030    I45 @T6G_MB_LIB.T6G(SCH_1):PAGE30
   U25 BW40 VDDCR_CPU1_BW40 GENOA_SP5-SOCKET6096_13568-001,SMLF,IO,DGA^6000030    I45 @T6G_MB_LIB.T6G(SCH_1):PAGE30
   U25 BW41 VDDCR_CPU1_BW41 GENOA_SP5-SOCKET6096_13568-001,SMLF,IO,DGA^6000030    I45 @T6G_MB_LIB.T6G(SCH_1):PAGE30
   U25 BY23 VDDCR_CPU1_BY23 GENOA_SP5-SOCKET6096_13568-001,SMLF,IO,DGA^6000030    I45 @T6G_MB_LIB.T6G(SCH_1):PAGE30
   U25 BY24 VDDCR_CPU1_BY24 GENOA_SP5-SOCKET6096_13568-001,SMLF,IO,DGA^6000030    I45 @T6G_MB_LIB.T6G(SCH_1):PAGE30
   U25 BY26 VDDCR_CPU1_BY26 GENOA_SP5-SOCKET6096_13568-001,SMLF,IO,DGA^6000030    I45 @T6G_MB_LIB.T6G(SCH_1):PAGE30
   U25 BY27 VDDCR_CPU1_BY27 GENOA_SP5-SOCKET6096_13568-001,SMLF,IO,DGA^6000030    I45 @T6G_MB_LIB.T6G(SCH_1):PAGE30
   U25 BY29 VDDCR_CPU1_BY29 GENOA_SP5-SOCKET6096_13568-001,SMLF,IO,DGA^6000030    I45 @T6G_MB_LIB.T6G(SCH_1):PAGE30
   U25 BY30 VDDCR_CPU1_BY30 GENOA_SP5-SOCKET6096_13568-001,SMLF,IO,DGA^6000030    I45 @T6G_MB_LIB.T6G(SCH_1):PAGE30
   U25 BY32 VDDCR_CPU1_BY32 GENOA_SP5-SOCKET6096_13568-001,SMLF,IO,DGA^6000030    I45 @T6G_MB_LIB.T6G(SCH_1):PAGE30
   U25 BY33 VDDCR_CPU1_BY33 GENOA_SP5-SOCKET6096_13568-001,SMLF,IO,DGA^6000030    I45 @T6G_MB_LIB.T6G(SCH_1):PAGE30
   U25 BY43 VDDCR_CPU1_BY43 GENOA_SP5-SOCKET6096_13568-001,SMLF,IO,DGA^6000030    I45 @T6G_MB_LIB.T6G(SCH_1):PAGE30
   U25 BY44 VDDCR_CPU1_BY44 GENOA_SP5-SOCKET6096_13568-001,SMLF,IO,DGA^6000030    I45 @T6G_MB_LIB.T6G(SCH_1):PAGE30
   U25 BY46 VDDCR_CPU1_BY46 GENOA_SP5-SOCKET6096_13568-001,SMLF,IO,DGA^6000030    I45 @T6G_MB_LIB.T6G(SCH_1):PAGE30
   U25 BY47 VDDCR_CPU1_BY47 GENOA_SP5-SOCKET6096_13568-001,SMLF,IO,DGA^6000030    I45 @T6G_MB_LIB.T6G(SCH_1):PAGE30
   U25 BY49 VDDCR_CPU1_BY49 GENOA_SP5-SOCKET6096_13568-001,SMLF,IO,DGA^6000030    I45 @T6G_MB_LIB.T6G(SCH_1):PAGE30
   U25 BY50 VDDCR_CPU1_BY50 GENOA_SP5-SOCKET6096_13568-001,SMLF,IO,DGA^6000030    I45 @T6G_MB_LIB.T6G(SCH_1):PAGE30
   U25 BY52 VDDCR_CPU1_BY52 GENOA_SP5-SOCKET6096_13568-001,SMLF,IO,DGA^6000030    I45 @T6G_MB_LIB.T6G(SCH_1):PAGE30
   U25 BY53 VDDCR_CPU1_BY53 GENOA_SP5-SOCKET6096_13568-001,SMLF,IO,DGA^6000030    I45 @T6G_MB_LIB.T6G(SCH_1):PAGE30
   U25 CC35 VDDCR_CPU1_CC35 GENOA_SP5-SOCKET6096_13568-001,SMLF,IO,DGA^6000030    I45 @T6G_MB_LIB.T6G(SCH_1):PAGE30
   U25 CC36 VDDCR_CPU1_CC36 GENOA_SP5-SOCKET6096_13568-001,SMLF,IO,DGA^6000030    I45 @T6G_MB_LIB.T6G(SCH_1):PAGE30
   U25 CC40 VDDCR_CPU1_CC40 GENOA_SP5-SOCKET6096_13568-001,SMLF,IO,DGA^6000030    I45 @T6G_MB_LIB.T6G(SCH_1):PAGE30
   U25 CC41 VDDCR_CPU1_CC41 GENOA_SP5-SOCKET6096_13568-001,SMLF,IO,DGA^6000030    I45 @T6G_MB_LIB.T6G(SCH_1):PAGE30
   U25 CD23 VDDCR_CPU1_CD23 GENOA_SP5-SOCKET6096_13568-001,SMLF,IO,DGA^6000030    I45 @T6G_MB_LIB.T6G(SCH_1):PAGE30
   U25 CD24 VDDCR_CPU1_CD24 GENOA_SP5-SOCKET6096_13568-001,SMLF,IO,DGA^6000030    I45 @T6G_MB_LIB.T6G(SCH_1):PAGE30
   U25 CD26 VDDCR_CPU1_CD26 GENOA_SP5-SOCKET6096_13568-001,SMLF,IO,DGA^6000030    I45 @T6G_MB_LIB.T6G(SCH_1):PAGE30
   U25 CD27 VDDCR_CPU1_CD27 GENOA_SP5-SOCKET6096_13568-001,SMLF,IO,DGA^6000030    I45 @T6G_MB_LIB.T6G(SCH_1):PAGE30
   U25 CD29 VDDCR_CPU1_CD29 GENOA_SP5-SOCKET6096_13568-001,SMLF,IO,DGA^6000030    I45 @T6G_MB_LIB.T6G(SCH_1):PAGE30
   U25 CD30 VDDCR_CPU1_CD30 GENOA_SP5-SOCKET6096_13568-001,SMLF,IO,DGA^6000030    I45 @T6G_MB_LIB.T6G(SCH_1):PAGE30
   U25 CD32 VDDCR_CPU1_CD32 GENOA_SP5-SOCKET6096_13568-001,SMLF,IO,DGA^6000030    I45 @T6G_MB_LIB.T6G(SCH_1):PAGE30
   U25 CD33 VDDCR_CPU1_CD33 GENOA_SP5-SOCKET6096_13568-001,SMLF,IO,DGA^6000030    I45 @T6G_MB_LIB.T6G(SCH_1):PAGE30
   U25 CD43 VDDCR_CPU1_CD43 GENOA_SP5-SOCKET6096_13568-001,SMLF,IO,DGA^6000030    I45 @T6G_MB_LIB.T6G(SCH_1):PAGE30
   U25 CD44 VDDCR_CPU1_CD44 GENOA_SP5-SOCKET6096_13568-001,SMLF,IO,DGA^6000030    I45 @T6G_MB_LIB.T6G(SCH_1):PAGE30
   U25 CD46 VDDCR_CPU1_CD46 GENOA_SP5-SOCKET6096_13568-001,SMLF,IO,DGA^6000030    I45 @T6G_MB_LIB.T6G(SCH_1):PAGE30
   U25 CD47 VDDCR_CPU1_CD47 GENOA_SP5-SOCKET6096_13568-001,SMLF,IO,DGA^6000030    I45 @T6G_MB_LIB.T6G(SCH_1):PAGE30
   U25 CD49 VDDCR_CPU1_CD49 GENOA_SP5-SOCKET6096_13568-001,SMLF,IO,DGA^6000030    I45 @T6G_MB_LIB.T6G(SCH_1):PAGE30
   U25 CD50 VDDCR_CPU1_CD50 GENOA_SP5-SOCKET6096_13568-001,SMLF,IO,DGA^6000030    I45 @T6G_MB_LIB.T6G(SCH_1):PAGE30
   U25 CD52 VDDCR_CPU1_CD52 GENOA_SP5-SOCKET6096_13568-001,SMLF,IO,DGA^6000030    I45 @T6G_MB_LIB.T6G(SCH_1):PAGE30
   U25 CD53 VDDCR_CPU1_CD53 GENOA_SP5-SOCKET6096_13568-001,SMLF,IO,DGA^6000030    I45 @T6G_MB_LIB.T6G(SCH_1):PAGE30
   U25 CG35 VDDCR_CPU1_CG35 GENOA_SP5-SOCKET6096_13568-001,SMLF,IO,DGA^6000030    I45 @T6G_MB_LIB.T6G(SCH_1):PAGE30
   U25 CG36 VDDCR_CPU1_CG36 GENOA_SP5-SOCKET6096_13568-001,SMLF,IO,DGA^6000030    I45 @T6G_MB_LIB.T6G(SCH_1):PAGE30
   U25 CG40 VDDCR_CPU1_CG40 GENOA_SP5-SOCKET6096_13568-001,SMLF,IO,DGA^6000030    I45 @T6G_MB_LIB.T6G(SCH_1):PAGE30
   U25 CG41 VDDCR_CPU1_CG41 GENOA_SP5-SOCKET6096_13568-001,SMLF,IO,DGA^6000030    I45 @T6G_MB_LIB.T6G(SCH_1):PAGE30
   U25 CH23 VDDCR_CPU1_CH23 GENOA_SP5-SOCKET6096_13568-001,SMLF,IO,DGA^6000030    I45 @T6G_MB_LIB.T6G(SCH_1):PAGE30
   U25 CH24 VDDCR_CPU1_CH24 GENOA_SP5-SOCKET6096_13568-001,SMLF,IO,DGA^6000030    I45 @T6G_MB_LIB.T6G(SCH_1):PAGE30
   U25 CH26 VDDCR_CPU1_CH26 GENOA_SP5-SOCKET6096_13568-001,SMLF,IO,DGA^6000030    I45 @T6G_MB_LIB.T6G(SCH_1):PAGE30
   U25 CH27 VDDCR_CPU1_CH27 GENOA_SP5-SOCKET6096_13568-001,SMLF,IO,DGA^6000030    I45 @T6G_MB_LIB.T6G(SCH_1):PAGE30
   U25 CH29 VDDCR_CPU1_CH29 GENOA_SP5-SOCKET6096_13568-001,SMLF,IO,DGA^6000030    I45 @T6G_MB_LIB.T6G(SCH_1):PAGE30
   U25 CH30 VDDCR_CPU1_CH30 GENOA_SP5-SOCKET6096_13568-001,SMLF,IO,DGA^6000030    I45 @T6G_MB_LIB.T6G(SCH_1):PAGE30
   U25 CH32 VDDCR_CPU1_CH32 GENOA_SP5-SOCKET6096_13568-001,SMLF,IO,DGA^6000030    I45 @T6G_MB_LIB.T6G(SCH_1):PAGE30
   U25 CH33 VDDCR_CPU1_CH33 GENOA_SP5-SOCKET6096_13568-001,SMLF,IO,DGA^6000030    I45 @T6G_MB_LIB.T6G(SCH_1):PAGE30
   U25 CH43 VDDCR_CPU1_CH43 GENOA_SP5-SOCKET6096_13568-001,SMLF,IO,DGA^6000030    I45 @T6G_MB_LIB.T6G(SCH_1):PAGE30
   U25 CH44 VDDCR_CPU1_CH44 GENOA_SP5-SOCKET6096_13568-001,SMLF,IO,DGA^6000030    I45 @T6G_MB_LIB.T6G(SCH_1):PAGE30
   U25 CH46 VDDCR_CPU1_CH46 GENOA_SP5-SOCKET6096_13568-001,SMLF,IO,DGA^6000030    I45 @T6G_MB_LIB.T6G(SCH_1):PAGE30
   U25 CH47 VDDCR_CPU1_CH47 GENOA_SP5-SOCKET6096_13568-001,SMLF,IO,DGA^6000030    I45 @T6G_MB_LIB.T6G(SCH_1):PAGE30
   U25 CH49 VDDCR_CPU1_CH49 GENOA_SP5-SOCKET6096_13568-001,SMLF,IO,DGA^6000030    I45 @T6G_MB_LIB.T6G(SCH_1):PAGE30
   U25 CH50 VDDCR_CPU1_CH50 GENOA_SP5-SOCKET6096_13568-001,SMLF,IO,DGA^6000030    I45 @T6G_MB_LIB.T6G(SCH_1):PAGE30
   U25 CH52 VDDCR_CPU1_CH52 GENOA_SP5-SOCKET6096_13568-001,SMLF,IO,DGA^6000030    I45 @T6G_MB_LIB.T6G(SCH_1):PAGE30
   U25 CH53 VDDCR_CPU1_CH53 GENOA_SP5-SOCKET6096_13568-001,SMLF,IO,DGA^6000030    I45 @T6G_MB_LIB.T6G(SCH_1):PAGE30
   U25 CK35 VDDCR_CPU1_CK35 GENOA_SP5-SOCKET6096_13568-001,SMLF,IO,DGA^6000030    I45 @T6G_MB_LIB.T6G(SCH_1):PAGE30
   U25 CK36 VDDCR_CPU1_CK36 GENOA_SP5-SOCKET6096_13568-001,SMLF,IO,DGA^6000030    I45 @T6G_MB_LIB.T6G(SCH_1):PAGE30
   U25 CK40 VDDCR_CPU1_CK40 GENOA_SP5-SOCKET6096_13568-001,SMLF,IO,DGA^6000030    I45 @T6G_MB_LIB.T6G(SCH_1):PAGE30
   U25 CK41 VDDCR_CPU1_CK41 GENOA_SP5-SOCKET6096_13568-001,SMLF,IO,DGA^6000030    I45 @T6G_MB_LIB.T6G(SCH_1):PAGE30
   U25 CL29 VDDCR_CPU1_CL29 GENOA_SP5-SOCKET6096_13568-001,SMLF,IO,DGA^6000030    I45 @T6G_MB_LIB.T6G(SCH_1):PAGE30
   U25 CL30 VDDCR_CPU1_CL30 GENOA_SP5-SOCKET6096_13568-001,SMLF,IO,DGA^6000030    I45 @T6G_MB_LIB.T6G(SCH_1):PAGE30
   U25 CL32 VDDCR_CPU1_CL32 GENOA_SP5-SOCKET6096_13568-001,SMLF,IO,DGA^6000030    I45 @T6G_MB_LIB.T6G(SCH_1):PAGE30
   U25 CL33 VDDCR_CPU1_CL33 GENOA_SP5-SOCKET6096_13568-001,SMLF,IO,DGA^6000030    I45 @T6G_MB_LIB.T6G(SCH_1):PAGE30
   U25 CL43 VDDCR_CPU1_CL43 GENOA_SP5-SOCKET6096_13568-001,SMLF,IO,DGA^6000030    I45 @T6G_MB_LIB.T6G(SCH_1):PAGE30
   U25 CL44 VDDCR_CPU1_CL44 GENOA_SP5-SOCKET6096_13568-001,SMLF,IO,DGA^6000030    I45 @T6G_MB_LIB.T6G(SCH_1):PAGE30
   U25 CL46 VDDCR_CPU1_CL46 GENOA_SP5-SOCKET6096_13568-001,SMLF,IO,DGA^6000030    I45 @T6G_MB_LIB.T6G(SCH_1):PAGE30
   U25 CL47 VDDCR_CPU1_CL47 GENOA_SP5-SOCKET6096_13568-001,SMLF,IO,DGA^6000030    I45 @T6G_MB_LIB.T6G(SCH_1):PAGE30
   U25 CN35 VDDCR_CPU1_CN35 GENOA_SP5-SOCKET6096_13568-001,SMLF,IO,DGA^6000030    I45 @T6G_MB_LIB.T6G(SCH_1):PAGE30
   U25 CN36 VDDCR_CPU1_CN36 GENOA_SP5-SOCKET6096_13568-001,SMLF,IO,DGA^6000030    I45 @T6G_MB_LIB.T6G(SCH_1):PAGE30
   U25 CN40 VDDCR_CPU1_CN40 GENOA_SP5-SOCKET6096_13568-001,SMLF,IO,DGA^6000030    I45 @T6G_MB_LIB.T6G(SCH_1):PAGE30
   U25 CN41 VDDCR_CPU1_CN41 GENOA_SP5-SOCKET6096_13568-001,SMLF,IO,DGA^6000030    I45 @T6G_MB_LIB.T6G(SCH_1):PAGE30
   U25 CP23 VDDCR_CPU1_CP23 GENOA_SP5-SOCKET6096_13568-001,SMLF,IO,DGA^6000030    I45 @T6G_MB_LIB.T6G(SCH_1):PAGE30
   U25 CP24 VDDCR_CPU1_CP24 GENOA_SP5-SOCKET6096_13568-001,SMLF,IO,DGA^6000030    I45 @T6G_MB_LIB.T6G(SCH_1):PAGE30
   U25 CP26 VDDCR_CPU1_CP26 GENOA_SP5-SOCKET6096_13568-001,SMLF,IO,DGA^6000030    I45 @T6G_MB_LIB.T6G(SCH_1):PAGE30
   U25 CP27 VDDCR_CPU1_CP27 GENOA_SP5-SOCKET6096_13568-001,SMLF,IO,DGA^6000030    I45 @T6G_MB_LIB.T6G(SCH_1):PAGE30
   U25 CP29 VDDCR_CPU1_CP29 GENOA_SP5-SOCKET6096_13568-001,SMLF,IO,DGA^6000030    I45 @T6G_MB_LIB.T6G(SCH_1):PAGE30
   U25 CP30 VDDCR_CPU1_CP30 GENOA_SP5-SOCKET6096_13568-001,SMLF,IO,DGA^6000030    I45 @T6G_MB_LIB.T6G(SCH_1):PAGE30
   U25 CP32 VDDCR_CPU1_CP32 GENOA_SP5-SOCKET6096_13568-001,SMLF,IO,DGA^6000030    I45 @T6G_MB_LIB.T6G(SCH_1):PAGE30
   U25 CP33 VDDCR_CPU1_CP33 GENOA_SP5-SOCKET6096_13568-001,SMLF,IO,DGA^6000030    I45 @T6G_MB_LIB.T6G(SCH_1):PAGE30
   U25 CP43 VDDCR_CPU1_CP43 GENOA_SP5-SOCKET6096_13568-001,SMLF,IO,DGA^6000030    I45 @T6G_MB_LIB.T6G(SCH_1):PAGE30
   U25 CP44 VDDCR_CPU1_CP44 GENOA_SP5-SOCKET6096_13568-001,SMLF,IO,DGA^6000030    I45 @T6G_MB_LIB.T6G(SCH_1):PAGE30
   U25 CP46 VDDCR_CPU1_CP46 GENOA_SP5-SOCKET6096_13568-001,SMLF,IO,DGA^6000030    I45 @T6G_MB_LIB.T6G(SCH_1):PAGE30
   U25 CP47 VDDCR_CPU1_CP47 GENOA_SP5-SOCKET6096_13568-001,SMLF,IO,DGA^6000030    I45 @T6G_MB_LIB.T6G(SCH_1):PAGE30
   U25 CP49 VDDCR_CPU1_CP49 GENOA_SP5-SOCKET6096_13568-001,SMLF,IO,DGA^6000030    I45 @T6G_MB_LIB.T6G(SCH_1):PAGE30
   U25 CP50 VDDCR_CPU1_CP50 GENOA_SP5-SOCKET6096_13568-001,SMLF,IO,DGA^6000030    I45 @T6G_MB_LIB.T6G(SCH_1):PAGE30
   U25 CP52 VDDCR_CPU1_CP52 GENOA_SP5-SOCKET6096_13568-001,SMLF,IO,DGA^6000030    I45 @T6G_MB_LIB.T6G(SCH_1):PAGE30
   U25 CP53 VDDCR_CPU1_CP53 GENOA_SP5-SOCKET6096_13568-001,SMLF,IO,DGA^6000030    I45 @T6G_MB_LIB.T6G(SCH_1):PAGE30
   U25 CU35 VDDCR_CPU1_CU35 GENOA_SP5-SOCKET6096_13568-001,SMLF,IO,DGA^6000030    I45 @T6G_MB_LIB.T6G(SCH_1):PAGE30
   U25 CU36 VDDCR_CPU1_CU36 GENOA_SP5-SOCKET6096_13568-001,SMLF,IO,DGA^6000030    I45 @T6G_MB_LIB.T6G(SCH_1):PAGE30
   U25 CU40 VDDCR_CPU1_CU40 GENOA_SP5-SOCKET6096_13568-001,SMLF,IO,DGA^6000030    I45 @T6G_MB_LIB.T6G(SCH_1):PAGE30
   U25 CU41 VDDCR_CPU1_CU41 GENOA_SP5-SOCKET6096_13568-001,SMLF,IO,DGA^6000030    I45 @T6G_MB_LIB.T6G(SCH_1):PAGE30
   U25 CV23 VDDCR_CPU1_CV23 GENOA_SP5-SOCKET6096_13568-001,SMLF,IO,DGA^6000030    I45 @T6G_MB_LIB.T6G(SCH_1):PAGE30
   U25 CV24 VDDCR_CPU1_CV24 GENOA_SP5-SOCKET6096_13568-001,SMLF,IO,DGA^6000030    I45 @T6G_MB_LIB.T6G(SCH_1):PAGE30
   U25 CV26 VDDCR_CPU1_CV26 GENOA_SP5-SOCKET6096_13568-001,SMLF,IO,DGA^6000030    I45 @T6G_MB_LIB.T6G(SCH_1):PAGE30
   U25 CV27 VDDCR_CPU1_CV27 GENOA_SP5-SOCKET6096_13568-001,SMLF,IO,DGA^6000030    I45 @T6G_MB_LIB.T6G(SCH_1):PAGE30
   U25 CV29 VDDCR_CPU1_CV29 GENOA_SP5-SOCKET6096_13568-001,SMLF,IO,DGA^6000030    I45 @T6G_MB_LIB.T6G(SCH_1):PAGE30
   U25 CV30 VDDCR_CPU1_CV30 GENOA_SP5-SOCKET6096_13568-001,SMLF,IO,DGA^6000030    I45 @T6G_MB_LIB.T6G(SCH_1):PAGE30
   U25 CV32 VDDCR_CPU1_CV32 GENOA_SP5-SOCKET6096_13568-001,SMLF,IO,DGA^6000030    I45 @T6G_MB_LIB.T6G(SCH_1):PAGE30
   U25 CV33 VDDCR_CPU1_CV33 GENOA_SP5-SOCKET6096_13568-001,SMLF,IO,DGA^6000030    I45 @T6G_MB_LIB.T6G(SCH_1):PAGE30
   U25 CV43 VDDCR_CPU1_CV43 GENOA_SP5-SOCKET6096_13568-001,SMLF,IO,DGA^6000030    I45 @T6G_MB_LIB.T6G(SCH_1):PAGE30
   U25 CV44 VDDCR_CPU1_CV44 GENOA_SP5-SOCKET6096_13568-001,SMLF,IO,DGA^6000030    I45 @T6G_MB_LIB.T6G(SCH_1):PAGE30
   U25 CV46 VDDCR_CPU1_CV46 GENOA_SP5-SOCKET6096_13568-001,SMLF,IO,DGA^6000030    I45 @T6G_MB_LIB.T6G(SCH_1):PAGE30
   U25 CV47 VDDCR_CPU1_CV47 GENOA_SP5-SOCKET6096_13568-001,SMLF,IO,DGA^6000030    I45 @T6G_MB_LIB.T6G(SCH_1):PAGE30
   U25 CV49 VDDCR_CPU1_CV49 GENOA_SP5-SOCKET6096_13568-001,SMLF,IO,DGA^6000030    I45 @T6G_MB_LIB.T6G(SCH_1):PAGE30
   U25 CV50 VDDCR_CPU1_CV50 GENOA_SP5-SOCKET6096_13568-001,SMLF,IO,DGA^6000030    I45 @T6G_MB_LIB.T6G(SCH_1):PAGE30
   U25 CV52 VDDCR_CPU1_CV52 GENOA_SP5-SOCKET6096_13568-001,SMLF,IO,DGA^6000030    I45 @T6G_MB_LIB.T6G(SCH_1):PAGE30
   U25 CV53 VDDCR_CPU1_CV53 GENOA_SP5-SOCKET6096_13568-001,SMLF,IO,DGA^6000030    I45 @T6G_MB_LIB.T6G(SCH_1):PAGE30
   U25 DA35 VDDCR_CPU1_DA35 GENOA_SP5-SOCKET6096_13568-001,SMLF,IO,DGA^6000030    I45 @T6G_MB_LIB.T6G(SCH_1):PAGE30
   U25 DA36 VDDCR_CPU1_DA36 GENOA_SP5-SOCKET6096_13568-001,SMLF,IO,DGA^6000030    I45 @T6G_MB_LIB.T6G(SCH_1):PAGE30
   U25 DA40 VDDCR_CPU1_DA40 GENOA_SP5-SOCKET6096_13568-001,SMLF,IO,DGA^6000030    I45 @T6G_MB_LIB.T6G(SCH_1):PAGE30
   U25 DA41 VDDCR_CPU1_DA41 GENOA_SP5-SOCKET6096_13568-001,SMLF,IO,DGA^6000030    I45 @T6G_MB_LIB.T6G(SCH_1):PAGE30
   U25 DB23 VDDCR_CPU1_DB23 GENOA_SP5-SOCKET6096_13568-001,SMLF,IO,DGA^6000030    I45 @T6G_MB_LIB.T6G(SCH_1):PAGE30
   U25 DB24 VDDCR_CPU1_DB24 GENOA_SP5-SOCKET6096_13568-001,SMLF,IO,DGA^6000030    I45 @T6G_MB_LIB.T6G(SCH_1):PAGE30
   U25 DB26 VDDCR_CPU1_DB26 GENOA_SP5-SOCKET6096_13568-001,SMLF,IO,DGA^6000030    I45 @T6G_MB_LIB.T6G(SCH_1):PAGE30
   U25 DB27 VDDCR_CPU1_DB27 GENOA_SP5-SOCKET6096_13568-001,SMLF,IO,DGA^6000030    I45 @T6G_MB_LIB.T6G(SCH_1):PAGE30
   U25 DB29 VDDCR_CPU1_DB29 GENOA_SP5-SOCKET6096_13568-001,SMLF,IO,DGA^6000030    I45 @T6G_MB_LIB.T6G(SCH_1):PAGE30
   U25 DB30 VDDCR_CPU1_DB30 GENOA_SP5-SOCKET6096_13568-001,SMLF,IO,DGA^6000030    I45 @T6G_MB_LIB.T6G(SCH_1):PAGE30
   U25 DB32 VDDCR_CPU1_DB32 GENOA_SP5-SOCKET6096_13568-001,SMLF,IO,DGA^6000030    I45 @T6G_MB_LIB.T6G(SCH_1):PAGE30
   U25 DB33 VDDCR_CPU1_DB33 GENOA_SP5-SOCKET6096_13568-001,SMLF,IO,DGA^6000030    I45 @T6G_MB_LIB.T6G(SCH_1):PAGE30
   U25 DB43 VDDCR_CPU1_DB43 GENOA_SP5-SOCKET6096_13568-001,SMLF,IO,DGA^6000030    I45 @T6G_MB_LIB.T6G(SCH_1):PAGE30
   U25 DB44 VDDCR_CPU1_DB44 GENOA_SP5-SOCKET6096_13568-001,SMLF,IO,DGA^6000030    I45 @T6G_MB_LIB.T6G(SCH_1):PAGE30
   U25 DB46 VDDCR_CPU1_DB46 GENOA_SP5-SOCKET6096_13568-001,SMLF,IO,DGA^6000030    I45 @T6G_MB_LIB.T6G(SCH_1):PAGE30
   U25 DB47 VDDCR_CPU1_DB47 GENOA_SP5-SOCKET6096_13568-001,SMLF,IO,DGA^6000030    I45 @T6G_MB_LIB.T6G(SCH_1):PAGE30
   U25 DB49 VDDCR_CPU1_DB49 GENOA_SP5-SOCKET6096_13568-001,SMLF,IO,DGA^6000030    I45 @T6G_MB_LIB.T6G(SCH_1):PAGE30
   U25 DB50 VDDCR_CPU1_DB50 GENOA_SP5-SOCKET6096_13568-001,SMLF,IO,DGA^6000030    I45 @T6G_MB_LIB.T6G(SCH_1):PAGE30
   U25 DB52 VDDCR_CPU1_DB52 GENOA_SP5-SOCKET6096_13568-001,SMLF,IO,DGA^6000030    I45 @T6G_MB_LIB.T6G(SCH_1):PAGE30
   U25 DB53 VDDCR_CPU1_DB53 GENOA_SP5-SOCKET6096_13568-001,SMLF,IO,DGA^6000030    I45 @T6G_MB_LIB.T6G(SCH_1):PAGE30
   U25 DC35 VDDCR_CPU1_DC35 GENOA_SP5-SOCKET6096_13568-001,SMLF,IO,DGA^6000030    I45 @T6G_MB_LIB.T6G(SCH_1):PAGE30
   U25 DC36 VDDCR_CPU1_DC36 GENOA_SP5-SOCKET6096_13568-001,SMLF,IO,DGA^6000030    I45 @T6G_MB_LIB.T6G(SCH_1):PAGE30
   U25 DC40 VDDCR_CPU1_DC40 GENOA_SP5-SOCKET6096_13568-001,SMLF,IO,DGA^6000030    I45 @T6G_MB_LIB.T6G(SCH_1):PAGE30
   U25 DC41 VDDCR_CPU1_DC41 GENOA_SP5-SOCKET6096_13568-001,SMLF,IO,DGA^6000030    I45 @T6G_MB_LIB.T6G(SCH_1):PAGE30
   U25 DD22 VDDCR_CPU1_DD22 GENOA_SP5-SOCKET6096_13568-001,SMLF,IO,DGA^6000030    I45 @T6G_MB_LIB.T6G(SCH_1):PAGE30
   U25 DD25 VDDCR_CPU1_DD25 GENOA_SP5-SOCKET6096_13568-001,SMLF,IO,DGA^6000030    I45 @T6G_MB_LIB.T6G(SCH_1):PAGE30
   U25 DD28 VDDCR_CPU1_DD28 GENOA_SP5-SOCKET6096_13568-001,SMLF,IO,DGA^6000030    I45 @T6G_MB_LIB.T6G(SCH_1):PAGE30
   U25 DD31 VDDCR_CPU1_DD31 GENOA_SP5-SOCKET6096_13568-001,SMLF,IO,DGA^6000030    I45 @T6G_MB_LIB.T6G(SCH_1):PAGE30
   U25 DD34 VDDCR_CPU1_DD34 GENOA_SP5-SOCKET6096_13568-001,SMLF,IO,DGA^6000030    I45 @T6G_MB_LIB.T6G(SCH_1):PAGE30
   U25 DD42 VDDCR_CPU1_DD42 GENOA_SP5-SOCKET6096_13568-001,SMLF,IO,DGA^6000030    I45 @T6G_MB_LIB.T6G(SCH_1):PAGE30
   U25 DD45 VDDCR_CPU1_DD45 GENOA_SP5-SOCKET6096_13568-001,SMLF,IO,DGA^6000030    I45 @T6G_MB_LIB.T6G(SCH_1):PAGE30
   U25 DD48 VDDCR_CPU1_DD48 GENOA_SP5-SOCKET6096_13568-001,SMLF,IO,DGA^6000030    I45 @T6G_MB_LIB.T6G(SCH_1):PAGE30
   U25 DD51 VDDCR_CPU1_DD51 GENOA_SP5-SOCKET6096_13568-001,SMLF,IO,DGA^6000030    I45 @T6G_MB_LIB.T6G(SCH_1):PAGE30
   U25 DD54 VDDCR_CPU1_DD54 GENOA_SP5-SOCKET6096_13568-001,SMLF,IO,DGA^6000030    I45 @T6G_MB_LIB.T6G(SCH_1):PAGE30
   U25 DE22 VDDCR_CPU1_DE22 GENOA_SP5-SOCKET6096_13568-001,SMLF,IO,DGA^6000030    I45 @T6G_MB_LIB.T6G(SCH_1):PAGE30
   U25 DE25 VDDCR_CPU1_DE25 GENOA_SP5-SOCKET6096_13568-001,SMLF,IO,DGA^6000030    I45 @T6G_MB_LIB.T6G(SCH_1):PAGE30
   U25 DE28 VDDCR_CPU1_DE28 GENOA_SP5-SOCKET6096_13568-001,SMLF,IO,DGA^6000030    I45 @T6G_MB_LIB.T6G(SCH_1):PAGE30
   U25 DE31 VDDCR_CPU1_DE31 GENOA_SP5-SOCKET6096_13568-001,SMLF,IO,DGA^6000030    I45 @T6G_MB_LIB.T6G(SCH_1):PAGE30
   U25 DE34 VDDCR_CPU1_DE34 GENOA_SP5-SOCKET6096_13568-001,SMLF,IO,DGA^6000030    I45 @T6G_MB_LIB.T6G(SCH_1):PAGE30
   U25 DE35 VDDCR_CPU1_DE35 GENOA_SP5-SOCKET6096_13568-001,SMLF,IO,DGA^6000030    I45 @T6G_MB_LIB.T6G(SCH_1):PAGE30
   U25 DE41 VDDCR_CPU1_DE41 GENOA_SP5-SOCKET6096_13568-001,SMLF,IO,DGA^6000030    I45 @T6G_MB_LIB.T6G(SCH_1):PAGE30
   U25 DE42 VDDCR_CPU1_DE42 GENOA_SP5-SOCKET6096_13568-001,SMLF,IO,DGA^6000030    I45 @T6G_MB_LIB.T6G(SCH_1):PAGE30
   U25 DE45 VDDCR_CPU1_DE45 GENOA_SP5-SOCKET6096_13568-001,SMLF,IO,DGA^6000030    I45 @T6G_MB_LIB.T6G(SCH_1):PAGE30
   U25 DE48 VDDCR_CPU1_DE48 GENOA_SP5-SOCKET6096_13568-001,SMLF,IO,DGA^6000030    I45 @T6G_MB_LIB.T6G(SCH_1):PAGE30
   U25 DE51 VDDCR_CPU1_DE51 GENOA_SP5-SOCKET6096_13568-001,SMLF,IO,DGA^6000030    I45 @T6G_MB_LIB.T6G(SCH_1):PAGE30
   U25 DE54 VDDCR_CPU1_DE54 GENOA_SP5-SOCKET6096_13568-001,SMLF,IO,DGA^6000030    I45 @T6G_MB_LIB.T6G(SCH_1):PAGE30
   U25 DG19 VDDCR_CPU1_DG19 GENOA_SP5-SOCKET6096_13568-001,SMLF,IO,DGA^6000030    I45 @T6G_MB_LIB.T6G(SCH_1):PAGE30
   U25 DG57 VDDCR_CPU1_DG57 GENOA_SP5-SOCKET6096_13568-001,SMLF,IO,DGA^6000030    I45 @T6G_MB_LIB.T6G(SCH_1):PAGE30
   U25 DH19 VDDCR_CPU1_DH19 GENOA_SP5-SOCKET6096_13568-001,SMLF,IO,DGA^6000030    I45 @T6G_MB_LIB.T6G(SCH_1):PAGE30
   U25 DH20 VDDCR_CPU1_DH20 GENOA_SP5-SOCKET6096_13568-001,SMLF,IO,DGA^6000030    I45 @T6G_MB_LIB.T6G(SCH_1):PAGE30
   U25 DH22 VDDCR_CPU1_DH22 GENOA_SP5-SOCKET6096_13568-001,SMLF,IO,DGA^6000030    I45 @T6G_MB_LIB.T6G(SCH_1):PAGE30
   U25 DH23 VDDCR_CPU1_DH23 GENOA_SP5-SOCKET6096_13568-001,SMLF,IO,DGA^6000030    I45 @T6G_MB_LIB.T6G(SCH_1):PAGE30
   U25 DH25 VDDCR_CPU1_DH25 GENOA_SP5-SOCKET6096_13568-001,SMLF,IO,DGA^6000030    I45 @T6G_MB_LIB.T6G(SCH_1):PAGE30
   U25 DH26 VDDCR_CPU1_DH26 GENOA_SP5-SOCKET6096_13568-001,SMLF,IO,DGA^6000030    I45 @T6G_MB_LIB.T6G(SCH_1):PAGE30
   U25 DH28 VDDCR_CPU1_DH28 GENOA_SP5-SOCKET6096_13568-001,SMLF,IO,DGA^6000030    I45 @T6G_MB_LIB.T6G(SCH_1):PAGE30
   U25 DH29 VDDCR_CPU1_DH29 GENOA_SP5-SOCKET6096_13568-001,SMLF,IO,DGA^6000030    I45 @T6G_MB_LIB.T6G(SCH_1):PAGE30
   U25 DH31 VDDCR_CPU1_DH31 GENOA_SP5-SOCKET6096_13568-001,SMLF,IO,DGA^6000030    I45 @T6G_MB_LIB.T6G(SCH_1):PAGE30
   U25 DH32 VDDCR_CPU1_DH32 GENOA_SP5-SOCKET6096_13568-001,SMLF,IO,DGA^6000030    I45 @T6G_MB_LIB.T6G(SCH_1):PAGE30
   U25 DH34 VDDCR_CPU1_DH34 GENOA_SP5-SOCKET6096_13568-001,SMLF,IO,DGA^6000030    I45 @T6G_MB_LIB.T6G(SCH_1):PAGE30
   U25 DH35 VDDCR_CPU1_DH35 GENOA_SP5-SOCKET6096_13568-001,SMLF,IO,DGA^6000030    I45 @T6G_MB_LIB.T6G(SCH_1):PAGE30
   U25 DH41 VDDCR_CPU1_DH41 GENOA_SP5-SOCKET6096_13568-001,SMLF,IO,DGA^6000030    I45 @T6G_MB_LIB.T6G(SCH_1):PAGE30
   U25 DH42 VDDCR_CPU1_DH42 GENOA_SP5-SOCKET6096_13568-001,SMLF,IO,DGA^6000030    I45 @T6G_MB_LIB.T6G(SCH_1):PAGE30
   U25 DH44 VDDCR_CPU1_DH44 GENOA_SP5-SOCKET6096_13568-001,SMLF,IO,DGA^6000030    I45 @T6G_MB_LIB.T6G(SCH_1):PAGE30
   U25 DH45 VDDCR_CPU1_DH45 GENOA_SP5-SOCKET6096_13568-001,SMLF,IO,DGA^6000030    I45 @T6G_MB_LIB.T6G(SCH_1):PAGE30
   U25 DH47 VDDCR_CPU1_DH47 GENOA_SP5-SOCKET6096_13568-001,SMLF,IO,DGA^6000030    I45 @T6G_MB_LIB.T6G(SCH_1):PAGE30
   U25 DH48 VDDCR_CPU1_DH48 GENOA_SP5-SOCKET6096_13568-001,SMLF,IO,DGA^6000030    I45 @T6G_MB_LIB.T6G(SCH_1):PAGE30
   U25 DH50 VDDCR_CPU1_DH50 GENOA_SP5-SOCKET6096_13568-001,SMLF,IO,DGA^6000030    I45 @T6G_MB_LIB.T6G(SCH_1):PAGE30
   U25 DH51 VDDCR_CPU1_DH51 GENOA_SP5-SOCKET6096_13568-001,SMLF,IO,DGA^6000030    I45 @T6G_MB_LIB.T6G(SCH_1):PAGE30
   U25 DH53 VDDCR_CPU1_DH53 GENOA_SP5-SOCKET6096_13568-001,SMLF,IO,DGA^6000030    I45 @T6G_MB_LIB.T6G(SCH_1):PAGE30
   U25 DH54 VDDCR_CPU1_DH54 GENOA_SP5-SOCKET6096_13568-001,SMLF,IO,DGA^6000030    I45 @T6G_MB_LIB.T6G(SCH_1):PAGE30
   U25 DH56 VDDCR_CPU1_DH56 GENOA_SP5-SOCKET6096_13568-001,SMLF,IO,DGA^6000030    I45 @T6G_MB_LIB.T6G(SCH_1):PAGE30
   U25 DH57 VDDCR_CPU1_DH57 GENOA_SP5-SOCKET6096_13568-001,SMLF,IO,DGA^6000030    I45 @T6G_MB_LIB.T6G(SCH_1):PAGE30
 C2205    1      A Q_CAP_C0402-22UF,4V,20%,X6S,CH622KMEB02    I30 @T6G_MB_LIB.T6G(SCH_1):PAGE68
 C2204    1      A Q_CAP_C0402-22UF,4V,20%,X6S,CH622KMEB02    I38 @T6G_MB_LIB.T6G(SCH_1):PAGE68
 C2203    1      A Q_CAP_C0402-22UF,4V,20%,X6S,CH622KMEB02    I43 @T6G_MB_LIB.T6G(SCH_1):PAGE68
 C2202    1      A Q_CAP_C0402-22UF,4V,20%,X6S,CH622KMEB02    I60 @T6G_MB_LIB.T6G(SCH_1):PAGE68
 C2201    1      A Q_CAP_C0402-22UF,4V,20%,X6S,CH622KMEB02    I63 @T6G_MB_LIB.T6G(SCH_1):PAGE68
 C2211    1      A Q_CAP_C0402-22UF,4V,20%,X6S,CH622KMEB02    I65 @T6G_MB_LIB.T6G(SCH_1):PAGE68
 C2217    1      A Q_CAP_C0402-22UF,4V,20%,X6S,CH622KMEB02    I66 @T6G_MB_LIB.T6G(SCH_1):PAGE68
 C2223    1      A Q_CAP_C0402-22UF,4V,20%,X6S,CH622KMEB02    I67 @T6G_MB_LIB.T6G(SCH_1):PAGE68
 C2229    1      A Q_CAP_C0402-22UF,4V,20%,X6S,CH622KMEB02    I69 @T6G_MB_LIB.T6G(SCH_1):PAGE68
 C2210    1      A Q_CAP_C0402-22UF,4V,20%,X6S,CH622KMEB02    I70 @T6G_MB_LIB.T6G(SCH_1):PAGE68
 C2216    1      A Q_CAP_C0402-22UF,4V,20%,X6S,CH622KMEB02    I71 @T6G_MB_LIB.T6G(SCH_1):PAGE68
 C2209    1      A Q_CAP_C0402-22UF,4V,20%,X6S,CH622KMEB02    I72 @T6G_MB_LIB.T6G(SCH_1):PAGE68
 C2215    1      A Q_CAP_C0402-22UF,4V,20%,X6S,CH622KMEB02    I73 @T6G_MB_LIB.T6G(SCH_1):PAGE68
 C2222    1      A Q_CAP_C0402-22UF,4V,20%,X6S,CH622KMEB02    I74 @T6G_MB_LIB.T6G(SCH_1):PAGE68
 C2228    1      A Q_CAP_C0402-22UF,4V,20%,X6S,CH622KMEB02    I75 @T6G_MB_LIB.T6G(SCH_1):PAGE68
 C2234    1      A Q_CAP_C0402-22UF,4V,20%,X6S,CH622KMEB02    I76 @T6G_MB_LIB.T6G(SCH_1):PAGE68
 C2221    1      A Q_CAP_C0402-22UF,4V,20%,X6S,CH622KMEB02    I77 @T6G_MB_LIB.T6G(SCH_1):PAGE68
 C2227    1      A Q_CAP_C0402-22UF,4V,20%,X6S,CH622KMEB02    I78 @T6G_MB_LIB.T6G(SCH_1):PAGE68
 C2233    1      A Q_CAP_C0402-22UF,4V,20%,X6S,CH622KMEB02    I79 @T6G_MB_LIB.T6G(SCH_1):PAGE68
 C2240    1      A Q_CAP_C0402-22UF,4V,20%,X6S,CH622KMEB02    I80 @T6G_MB_LIB.T6G(SCH_1):PAGE68
 C2246    1      A Q_CAP_C0402-22UF,4V,20%,X6S,CH622KMEB02    I81 @T6G_MB_LIB.T6G(SCH_1):PAGE68
 C2239    1      A Q_CAP_C0402-22UF,4V,20%,X6S,CH622KMEB02    I82 @T6G_MB_LIB.T6G(SCH_1):PAGE68
 C2245    1      A Q_CAP_C0402-22UF,4V,20%,X6S,CH622KMEB02    I83 @T6G_MB_LIB.T6G(SCH_1):PAGE68
 C2251    1      A Q_CAP_C0402-22UF,4V,20%,X6S,CH622KMEB02    I84 @T6G_MB_LIB.T6G(SCH_1):PAGE68
 C2256    1      A Q_CAP_C0402-22UF,4V,20%,X6S,CH622KMEB02    I86 @T6G_MB_LIB.T6G(SCH_1):PAGE68
 C2250    1      A Q_CAP_C0402-22UF,4V,20%,X6S,CH622KMEB02    I87 @T6G_MB_LIB.T6G(SCH_1):PAGE68
 C2255    1      A Q_CAP_C0402-22UF,4V,20%,X6S,CH622KMEB02    I89 @T6G_MB_LIB.T6G(SCH_1):PAGE68
 C2208    1      A Q_CAP_C0402-22UF,4V,20%,X6S,CH622KMEB02    I91 @T6G_MB_LIB.T6G(SCH_1):PAGE68
 C2214    1      A Q_CAP_C0402-22UF,4V,20%,X6S,CH622KMEB02    I92 @T6G_MB_LIB.T6G(SCH_1):PAGE68
 C2207    1      A Q_CAP_C0402-22UF,4V,20%,X6S,CH622KMEB02    I93 @T6G_MB_LIB.T6G(SCH_1):PAGE68
 C2213    1      A Q_CAP_C0402-22UF,4V,20%,X6S,CH622KMEB02    I94 @T6G_MB_LIB.T6G(SCH_1):PAGE68
 C2220    1      A Q_CAP_C0402-22UF,4V,20%,X6S,CH622KMEB02    I95 @T6G_MB_LIB.T6G(SCH_1):PAGE68
 C2226    1      A Q_CAP_C0402-22UF,4V,20%,X6S,CH622KMEB02    I96 @T6G_MB_LIB.T6G(SCH_1):PAGE68
 C2232    1      A Q_CAP_C0402-22UF,4V,20%,X6S,CH622KMEB02    I97 @T6G_MB_LIB.T6G(SCH_1):PAGE68
 C2219    1      A Q_CAP_C0402-22UF,4V,20%,X6S,CH622KMEB02    I98 @T6G_MB_LIB.T6G(SCH_1):PAGE68
 C2225    1      A Q_CAP_C0402-22UF,4V,20%,X6S,CH622KMEB02    I99 @T6G_MB_LIB.T6G(SCH_1):PAGE68
 C2231    1      A Q_CAP_C0402-22UF,4V,20%,X6S,CH622KMEB02   I100 @T6G_MB_LIB.T6G(SCH_1):PAGE68
 C2238    1      A Q_CAP_C0402-22UF,4V,20%,X6S,CH622KMEB02   I101 @T6G_MB_LIB.T6G(SCH_1):PAGE68
 C2244    1      A Q_CAP_C0402-22UF,4V,20%,X6S,CH622KMEB02   I102 @T6G_MB_LIB.T6G(SCH_1):PAGE68
 C2237    1      A Q_CAP_C0402-22UF,4V,20%,X6S,CH622KMEB02   I103 @T6G_MB_LIB.T6G(SCH_1):PAGE68
 C2243    1      A Q_CAP_C0402-22UF,4V,20%,X6S,CH622KMEB02   I104 @T6G_MB_LIB.T6G(SCH_1):PAGE68
 C2249    1      A Q_CAP_C0402-22UF,4V,20%,X6S,CH622KMEB02   I105 @T6G_MB_LIB.T6G(SCH_1):PAGE68
 C2254    1      A Q_CAP_C0402-22UF,4V,20%,X6S,CH622KMEB02   I106 @T6G_MB_LIB.T6G(SCH_1):PAGE68
 C2248    1      A Q_CAP_C0402-22UF,4V,20%,X6S,CH622KMEB02   I108 @T6G_MB_LIB.T6G(SCH_1):PAGE68
 C2253    1      A Q_CAP_C0402-22UF,4V,20%,X6S,CH622KMEB02   I109 @T6G_MB_LIB.T6G(SCH_1):PAGE68
  PL11    4      4 Q_INDUCTOR4P_14-150NH,SMLF,IND,CV+15^0TZ04    I46 @T6G_MB_LIB.T6G(SCH_1):PAGE176
 PC103    1      A Q_CAPP_SMLF-220UF,4V,20%,SPCAP,CH122KM8801    I75 @T6G_MB_LIB.T6G(SCH_1):PAGE176
  PR91    2      B Q_RES_0402LF-0,5%,1/16W,CHIP,CS00002JB13    I40 @T6G_MB_LIB.T6G(SCH_1):PAGE177
  PL13    4      4 Q_INDUCTOR4P_14-150NH,SMLF,IND,CV+15^0TZ04    I42 @T6G_MB_LIB.T6G(SCH_1):PAGE177
  PR92    2      B Q_RES_0402LF-0,5%,1/16W,CHIP,CS00002JB13    I51 @T6G_MB_LIB.T6G(SCH_1):PAGE177
PC128_4    1      A Q_CAP_C0805-22UF,4V,20%,X6S,CH622KMEA03    I55 @T6G_MB_LIB.T6G(SCH_1):PAGE177
  PR51    2      B Q_RES_0402LF-49.9,1%,1/16W,CHIP,CS04992FB07    I36 @T6G_MB_LIB.T6G(SCH_1):PAGE175
  PR83    2      B Q_RES_0402LF-0,5%,1/16W,CHIP,CS00002JB13    I42 @T6G_MB_LIB.T6G(SCH_1):PAGE176
  PR84    2      B Q_RES_0402LF-0,5%,1/16W,CHIP,CS00002JB13    I54 @T6G_MB_LIB.T6G(SCH_1):PAGE176
  PL10    4      4 Q_INDUCTOR4P_14-150NH,SMLF,IND,CV+15^0TZ04    I62 @T6G_MB_LIB.T6G(SCH_1):PAGE176
PC106_2    1      A Q_CAP_C0805-22UF,4V,20%,X6S,CH622KMEA03    I69 @T6G_MB_LIB.T6G(SCH_1):PAGE176
 PC102    1      A Q_CAPP_SMLF-220UF,4V,20%,SPCAP,CH122KM8801    I70 @T6G_MB_LIB.T6G(SCH_1):PAGE176
  PC97    1      A Q_CAPP_SMLF-220UF,4V,20%,SPCAP,CH122KM8801    I71 @T6G_MB_LIB.T6G(SCH_1):PAGE176
  PC98    1      A Q_CAPP_SMLF-220UF,4V,20%,SPCAP,CH122KM8801    I72 @T6G_MB_LIB.T6G(SCH_1):PAGE176
 PC100    1      A Q_CAPP_SMLF-220UF,4V,20%,SPCAP,CH122KM8801    I73 @T6G_MB_LIB.T6G(SCH_1):PAGE176
PC108_2    1      A Q_CAP_C0805-22UF,4V,20%,X6S,CH622KMEA03    I77 @T6G_MB_LIB.T6G(SCH_1):PAGE176
  PC99    1      A Q_CAP_0402-0.1UF,25V,10%,X7R,CH4104K1B00    I84 @T6G_MB_LIB.T6G(SCH_1):PAGE176
PC102_1    1      A Q_CAP_C0805-22UF,4V,20%,X6S,CH622KMEA03    I86 @T6G_MB_LIB.T6G(SCH_1):PAGE176
PC105_1    1      A Q_CAP_C0805-22UF,4V,20%,X6S,CH622KMEA03    I89 @T6G_MB_LIB.T6G(SCH_1):PAGE176
 PR444    1      A Q_RES_0402LF-1K,1%,1/16W,CHIP,CS21002FB06    I90 @T6G_MB_LIB.T6G(SCH_1):PAGE176
PC127_4    1      A Q_CAP_C0805-22UF,4V,20%,X6S,CH622KMEA03    I54 @T6G_MB_LIB.T6G(SCH_1):PAGE177
  PL14    4      4 Q_INDUCTOR4P_14-150NH,SMLF,IND,CV+15^0TZ04    I64 @T6G_MB_LIB.T6G(SCH_1):PAGE177
PC129_3    1      A Q_CAP_C0805-22UF,4V,20%,X6S,CH622KMEA03    I69 @T6G_MB_LIB.T6G(SCH_1):PAGE177
PC130_3    1      A Q_CAP_C0805-22UF,4V,20%,X6S,CH622KMEA03    I71 @T6G_MB_LIB.T6G(SCH_1):PAGE177
 PR421    2      B Q_RES_0402LF-0,5%,1/16W,CHIP,CS00002JB13    I35 @T6G_MB_LIB.T6G(SCH_1):PAGE178
   PL7    4      4 Q_INDUCTOR4P_14-150NH,SMLF,IND,CV+15^0TZ04    I38 @T6G_MB_LIB.T6G(SCH_1):PAGE178
  PR96    2      B Q_RES_0402LF-0,5%,1/16W,CHIP,CS00002JB13    I49 @T6G_MB_LIB.T6G(SCH_1):PAGE178
PC120_6    1      A Q_CAP_C0805-22UF,4V,20%,X6S,CH622KMEA03    I51 @T6G_MB_LIB.T6G(SCH_1):PAGE178
PC123_6    1      A Q_CAP_C0805-22UF,4V,20%,X6S,CH622KMEA03    I53 @T6G_MB_LIB.T6G(SCH_1):PAGE178
  PL15    4      4 Q_INDUCTOR4P_14-150NH,SMLF,IND,CV+15^0TZ04    I63 @T6G_MB_LIB.T6G(SCH_1):PAGE178
PC140_5    1      A Q_CAP_C0805-22UF,4V,20%,X6S,CH622KMEA03    I69 @T6G_MB_LIB.T6G(SCH_1):PAGE178
PC141_5    1      A Q_CAP_C0805-22UF,4V,20%,X6S,CH622KMEA03    I70 @T6G_MB_LIB.T6G(SCH_1):PAGE178

PVDDCR_CPU1_P0_EN1_ADDR_CFG @T6G_MB_LIB.T6G(SCH_1):PVDDCR_CPU1_P0_EN1_ADDR_CFG
  PR67    1      A Q_RES_0402LF-1.96K,1%,1/16W,CHIP,CS21962FB05    I12 @T6G_MB_LIB.T6G(SCH_1):PAGE175
  PQ10    D      D MOSFET_PCH_GDS_ESD_PROTECTED-PJA3415AE,SMLF,IC,BAMA    I13 @T6G_MB_LIB.T6G(SCH_1):PAGE175
  PU12   42 EN1||ADDR_CFG RAA229620GNPHA0-RAA229620GNP#HA0,SMLF,IC,ARF0TGP40A   I128 @T6G_MB_LIB.T6G(SCH_1):PAGE175

PVDDCR_CPU1_P0_EN_R @T6G_MB_LIB.T6G(SCH_1):PVDDCR_CPU1_P0_EN_R
 C8069    1      A Q_CAP_0402-1000PF,50V,5%,X7R,TMP_QCH21006JB10    I86 @T6G_MB_LIB.T6G(SCH_1):PAGE175
 R8058    2      B Q_RES_0402LF-0,5%,1/16W,CHIP,CS00002JB13    I88 @T6G_MB_LIB.T6G(SCH_1):PAGE175
  PU12   17    EN0 RAA229620GNPHA0-RAA229620GNP#HA0,SMLF,IC,ARF0TGP40A   I128 @T6G_MB_LIB.T6G(SCH_1):PAGE175

PVDDCR_CPU1_P0_IMON1 @T6G_MB_LIB.T6G(SCH_1):PVDDCR_CPU1_P0_IMON1
  PU12   27   CS11 RAA229620GNPHA0-RAA229620GNP#HA0,SMLF,IC,ARF0TGP40A   I128 @T6G_MB_LIB.T6G(SCH_1):PAGE175
  PU13   38   IOUT ISL99390FRZTR5935-ISL99390FRZ-TR5935,SMLF,IC,AL099A    I35 @T6G_MB_LIB.T6G(SCH_1):PAGE176

PVDDCR_CPU1_P0_IMON2 @T6G_MB_LIB.T6G(SCH_1):PVDDCR_CPU1_P0_IMON2
  PU12   28   CS10 RAA229620GNPHA0-RAA229620GNP#HA0,SMLF,IC,ARF0TGP40A   I128 @T6G_MB_LIB.T6G(SCH_1):PAGE175
   PU2   38   IOUT ISL99390FRZTR5935-ISL99390FRZ-TR5935,SMLF,IC,AL099A    I33 @T6G_MB_LIB.T6G(SCH_1):PAGE176

PVDDCR_CPU1_P0_IMON3 @T6G_MB_LIB.T6G(SCH_1):PVDDCR_CPU1_P0_IMON3
  PU12   29    CS9 RAA229620GNPHA0-RAA229620GNP#HA0,SMLF,IC,ARF0TGP40A   I128 @T6G_MB_LIB.T6G(SCH_1):PAGE175
  PU15   38   IOUT ISL99390FRZTR5935-ISL99390FRZ-TR5935,SMLF,IC,AL099A    I23 @T6G_MB_LIB.T6G(SCH_1):PAGE177

PVDDCR_CPU1_P0_IMON4 @T6G_MB_LIB.T6G(SCH_1):PVDDCR_CPU1_P0_IMON4
  PU12   30    CS8 RAA229620GNPHA0-RAA229620GNP#HA0,SMLF,IC,ARF0TGP40A   I128 @T6G_MB_LIB.T6G(SCH_1):PAGE175
  PU14   38   IOUT ISL99390FRZTR5935-ISL99390FRZ-TR5935,SMLF,IC,AL099A    I21 @T6G_MB_LIB.T6G(SCH_1):PAGE177

PVDDCR_CPU1_P0_IMON5 @T6G_MB_LIB.T6G(SCH_1):PVDDCR_CPU1_P0_IMON5
  PU12   31    CS7 RAA229620GNPHA0-RAA229620GNP#HA0,SMLF,IC,ARF0TGP40A   I128 @T6G_MB_LIB.T6G(SCH_1):PAGE175
  PU16   38   IOUT ISL99390FRZTR5935-ISL99390FRZ-TR5935,SMLF,IC,AL099A    I22 @T6G_MB_LIB.T6G(SCH_1):PAGE178

PVDDCR_CPU1_P0_IMON6 @T6G_MB_LIB.T6G(SCH_1):PVDDCR_CPU1_P0_IMON6
  PU12   32    CS6 RAA229620GNPHA0-RAA229620GNP#HA0,SMLF,IC,ARF0TGP40A   I128 @T6G_MB_LIB.T6G(SCH_1):PAGE175
  PU11   38   IOUT ISL99390FRZTR5935-ISL99390FRZ-TR5935,SMLF,IC,AL099A    I73 @T6G_MB_LIB.T6G(SCH_1):PAGE178

PVDDCR_CPU1_P0_LSET1 @T6G_MB_LIB.T6G(SCH_1):PVDDCR_CPU1_P0_LSET1
  PR78    1      A Q_RES_0402LF-8.87K,1%,1/16W,EMPTY,CS28872FB01    I18 @T6G_MB_LIB.T6G(SCH_1):PAGE176
  PU13   37   LSET ISL99390FRZTR5935-ISL99390FRZ-TR5935,SMLF,IC,AL099A    I35 @T6G_MB_LIB.T6G(SCH_1):PAGE176

PVDDCR_CPU1_P0_LSET2 @T6G_MB_LIB.T6G(SCH_1):PVDDCR_CPU1_P0_LSET2
  PR77    1      A Q_RES_0402LF-8.87K,1%,1/16W,EMPTY,CS28872FB01     I4 @T6G_MB_LIB.T6G(SCH_1):PAGE176
   PU2   37   LSET ISL99390FRZTR5935-ISL99390FRZ-TR5935,SMLF,IC,AL099A    I33 @T6G_MB_LIB.T6G(SCH_1):PAGE176

PVDDCR_CPU1_P0_LSET3 @T6G_MB_LIB.T6G(SCH_1):PVDDCR_CPU1_P0_LSET3
  PR86    1      A Q_RES_0402LF-8.87K,1%,1/16W,EMPTY,CS28872FB01    I18 @T6G_MB_LIB.T6G(SCH_1):PAGE177
  PU15   37   LSET ISL99390FRZTR5935-ISL99390FRZ-TR5935,SMLF,IC,AL099A    I23 @T6G_MB_LIB.T6G(SCH_1):PAGE177

PVDDCR_CPU1_P0_LSET4 @T6G_MB_LIB.T6G(SCH_1):PVDDCR_CPU1_P0_LSET4
  PR85    1      A Q_RES_0402LF-8.87K,1%,1/16W,EMPTY,CS28872FB01     I4 @T6G_MB_LIB.T6G(SCH_1):PAGE177
  PU14   37   LSET ISL99390FRZTR5935-ISL99390FRZ-TR5935,SMLF,IC,AL099A    I21 @T6G_MB_LIB.T6G(SCH_1):PAGE177

PVDDCR_CPU1_P0_LSET5 @T6G_MB_LIB.T6G(SCH_1):PVDDCR_CPU1_P0_LSET5
  PR93    1      A Q_RES_0402LF-8.87K,1%,1/16W,EMPTY,CS28872FB01    I15 @T6G_MB_LIB.T6G(SCH_1):PAGE178
  PU16   37   LSET ISL99390FRZTR5935-ISL99390FRZ-TR5935,SMLF,IC,AL099A    I22 @T6G_MB_LIB.T6G(SCH_1):PAGE178

PVDDCR_CPU1_P0_LSET6 @T6G_MB_LIB.T6G(SCH_1):PVDDCR_CPU1_P0_LSET6
   PR7    1      A Q_RES_0402LF-8.87K,1%,1/16W,EMPTY,CS28872FB01     I4 @T6G_MB_LIB.T6G(SCH_1):PAGE178
  PU11   37   LSET ISL99390FRZTR5935-ISL99390FRZ-TR5935,SMLF,IC,AL099A    I73 @T6G_MB_LIB.T6G(SCH_1):PAGE178

PVDDCR_CPU1_P0_OCP_N @T6G_MB_LIB.T6G(SCH_1):PVDDCR_CPU1_P0_OCP_N
  R137    1      A Q_RES_0402LF-0,5%,1/16W,CHIP,CS00002JB13    I59 @T6G_MB_LIB.T6G(SCH_1):PAGE81
 R8064    1      A Q_RES_0402LF-0,5%,1/16W,CHIP,CS00002JB13    I66 @T6G_MB_LIB.T6G(SCH_1):PAGE175

PVDDCR_CPU1_P0_OCP_N_R @T6G_MB_LIB.T6G(SCH_1):PVDDCR_CPU1_P0_OCP_N_R
 R8064    2      B Q_RES_0402LF-0,5%,1/16W,CHIP,CS00002JB13    I66 @T6G_MB_LIB.T6G(SCH_1):PAGE175
 R8075    2      B Q_RES_0402LF-1K,1%,1/16W,CHIP,CS21002FB06    I71 @T6G_MB_LIB.T6G(SCH_1):PAGE175
  PU12   41  OCP_L RAA229620GNPHA0-RAA229620GNP#HA0,SMLF,IC,ARF0TGP40A   I128 @T6G_MB_LIB.T6G(SCH_1):PAGE175

PVDDCR_CPU1_P0_PVCC @T6G_MB_LIB.T6G(SCH_1):PVDDCR_CPU1_P0_PVCC
 PR442    1      A Q_RES_0402LF-0,5%,1/16W,CHIP,CS00002JB13    I21 @T6G_MB_LIB.T6G(SCH_1):PAGE176
  PR88    1      A Q_RES_0402LF-2.2,1%,1/16W,CHIP,CS-2202FB01    I30 @T6G_MB_LIB.T6G(SCH_1):PAGE177
PC133_C1P0_5    1      A Q_CAP_C0402-2.2UF,10V,10%,X6S,CH5222KEB01    I31 @T6G_MB_LIB.T6G(SCH_1):PAGE178
 PR108    1      A Q_RES_0402LF-2.2,1%,1/16W,CHIP,CS-2202FB01    I28 @T6G_MB_LIB.T6G(SCH_1):PAGE181
  PR80    1      A Q_RES_0402LF-2.2,1%,1/16W,CHIP,CS-2202FB01    I13 @T6G_MB_LIB.T6G(SCH_1):PAGE176
PC82_C1P0_2    1      A Q_CAP_C0402-2.2UF,10V,10%,X6S,CH5222KEB01    I15 @T6G_MB_LIB.T6G(SCH_1):PAGE176
 PR443    1      A Q_RES_0402LF-0,5%,1/16W,EMPTY,CS00002JB13    I27 @T6G_MB_LIB.T6G(SCH_1):PAGE176
  PR79    1      A Q_RES_0402LF-2.2,1%,1/16W,CHIP,CS-2202FB01    I29 @T6G_MB_LIB.T6G(SCH_1):PAGE176
PC81_C1P0_1    1      A Q_CAP_C0402-2.2UF,10V,10%,X6S,CH5222KEB01    I30 @T6G_MB_LIB.T6G(SCH_1):PAGE176
   PU2    4   PVCC ISL99390FRZTR5935-ISL99390FRZ-TR5935,SMLF,IC,AL099A    I33 @T6G_MB_LIB.T6G(SCH_1):PAGE176
  PU13    4   PVCC ISL99390FRZTR5935-ISL99390FRZ-TR5935,SMLF,IC,AL099A    I35 @T6G_MB_LIB.T6G(SCH_1):PAGE176
  PR87    1      A Q_RES_0402LF-2.2,1%,1/16W,CHIP,CS-2202FB01    I13 @T6G_MB_LIB.T6G(SCH_1):PAGE177
PC111_C1P0_4    1      A Q_CAP_C0402-2.2UF,10V,10%,X6S,CH5222KEB01    I16 @T6G_MB_LIB.T6G(SCH_1):PAGE177
  PU14    4   PVCC ISL99390FRZTR5935-ISL99390FRZ-TR5935,SMLF,IC,AL099A    I21 @T6G_MB_LIB.T6G(SCH_1):PAGE177
  PU15    4   PVCC ISL99390FRZTR5935-ISL99390FRZ-TR5935,SMLF,IC,AL099A    I23 @T6G_MB_LIB.T6G(SCH_1):PAGE177
PC112_C1P0_3    1      A Q_CAP_C0402-2.2UF,10V,10%,X6S,CH5222KEB01    I32 @T6G_MB_LIB.T6G(SCH_1):PAGE177
 PR416    1      A Q_RES_0402LF-2.2,1%,1/16W,CHIP,CS-2202FB01    I13 @T6G_MB_LIB.T6G(SCH_1):PAGE178
PC113_C1P0_6    1      A Q_CAP_C0402-2.2UF,10V,10%,X6S,CH5222KEB01    I20 @T6G_MB_LIB.T6G(SCH_1):PAGE178
  PU16    4   PVCC ISL99390FRZTR5935-ISL99390FRZ-TR5935,SMLF,IC,AL099A    I22 @T6G_MB_LIB.T6G(SCH_1):PAGE178
  PR94    1      A Q_RES_0402LF-2.2,1%,1/16W,CHIP,CS-2202FB01    I28 @T6G_MB_LIB.T6G(SCH_1):PAGE178
  PU11    4   PVCC ISL99390FRZTR5935-ISL99390FRZ-TR5935,SMLF,IC,AL099A    I73 @T6G_MB_LIB.T6G(SCH_1):PAGE178
  PR99    1      A Q_RES_0402LF-2.2,1%,1/16W,CHIP,CS-2202FB01    I12 @T6G_MB_LIB.T6G(SCH_1):PAGE180
PC144_IOP0_2    1      A Q_CAP_C0402-2.2UF,10V,10%,X6S,CH5222KEB01    I13 @T6G_MB_LIB.T6G(SCH_1):PAGE180
  PU18    4   PVCC ISL99390FRZTR5935-ISL99390FRZ-TR5935,SMLF,IC,AL099A    I15 @T6G_MB_LIB.T6G(SCH_1):PAGE180
 PR100    1      A Q_RES_0402LF-2.2,1%,1/16W,CHIP,CS-2202FB01    I29 @T6G_MB_LIB.T6G(SCH_1):PAGE180
PC147_IOP0_1    1      A Q_CAP_C0402-2.2UF,10V,10%,X6S,CH5222KEB01    I31 @T6G_MB_LIB.T6G(SCH_1):PAGE180
  PU17    4   PVCC ISL99390FRZTR5935-ISL99390FRZ-TR5935,SMLF,IC,AL099A    I84 @T6G_MB_LIB.T6G(SCH_1):PAGE180
 PR107    1      A Q_RES_0402LF-2.2,1%,1/16W,CHIP,CS-2202FB01    I12 @T6G_MB_LIB.T6G(SCH_1):PAGE181
PC173_IOP0_4    1      A Q_CAP_C0402-2.2UF,10V,10%,X6S,CH5222KEB01    I13 @T6G_MB_LIB.T6G(SCH_1):PAGE181
PC174_IOP0_3    1      A Q_CAP_C0402-2.2UF,10V,10%,X6S,CH5222KEB01    I30 @T6G_MB_LIB.T6G(SCH_1):PAGE181
  PU19    4   PVCC ISL99390FRZTR5935-ISL99390FRZ-TR5935,SMLF,IC,AL099A    I32 @T6G_MB_LIB.T6G(SCH_1):PAGE181
  PU20    4   PVCC ISL99390FRZTR5935-ISL99390FRZ-TR5935,SMLF,IC,AL099A    I73 @T6G_MB_LIB.T6G(SCH_1):PAGE181

PVDDCR_CPU1_P0_PWM1 @T6G_MB_LIB.T6G(SCH_1):PVDDCR_CPU1_P0_PWM1
  PU12   12  PWM11 RAA229620GNPHA0-RAA229620GNP#HA0,SMLF,IC,ARF0TGP40A   I128 @T6G_MB_LIB.T6G(SCH_1):PAGE175
  PU13   34    PWM ISL99390FRZTR5935-ISL99390FRZ-TR5935,SMLF,IC,AL099A    I35 @T6G_MB_LIB.T6G(SCH_1):PAGE176

PVDDCR_CPU1_P0_PWM2 @T6G_MB_LIB.T6G(SCH_1):PVDDCR_CPU1_P0_PWM2
  PU12   11  PWM10 RAA229620GNPHA0-RAA229620GNP#HA0,SMLF,IC,ARF0TGP40A   I128 @T6G_MB_LIB.T6G(SCH_1):PAGE175
   PU2   34    PWM ISL99390FRZTR5935-ISL99390FRZ-TR5935,SMLF,IC,AL099A    I33 @T6G_MB_LIB.T6G(SCH_1):PAGE176

PVDDCR_CPU1_P0_PWM3 @T6G_MB_LIB.T6G(SCH_1):PVDDCR_CPU1_P0_PWM3
  PU12   10   PWM9 RAA229620GNPHA0-RAA229620GNP#HA0,SMLF,IC,ARF0TGP40A   I128 @T6G_MB_LIB.T6G(SCH_1):PAGE175
  PU15   34    PWM ISL99390FRZTR5935-ISL99390FRZ-TR5935,SMLF,IC,AL099A    I23 @T6G_MB_LIB.T6G(SCH_1):PAGE177

PVDDCR_CPU1_P0_PWM4 @T6G_MB_LIB.T6G(SCH_1):PVDDCR_CPU1_P0_PWM4
  PU12    9   PWM8 RAA229620GNPHA0-RAA229620GNP#HA0,SMLF,IC,ARF0TGP40A   I128 @T6G_MB_LIB.T6G(SCH_1):PAGE175
  PU14   34    PWM ISL99390FRZTR5935-ISL99390FRZ-TR5935,SMLF,IC,AL099A    I21 @T6G_MB_LIB.T6G(SCH_1):PAGE177

PVDDCR_CPU1_P0_PWM5 @T6G_MB_LIB.T6G(SCH_1):PVDDCR_CPU1_P0_PWM5
  PU12    8   PWM7 RAA229620GNPHA0-RAA229620GNP#HA0,SMLF,IC,ARF0TGP40A   I128 @T6G_MB_LIB.T6G(SCH_1):PAGE175
  PU16   34    PWM ISL99390FRZTR5935-ISL99390FRZ-TR5935,SMLF,IC,AL099A    I22 @T6G_MB_LIB.T6G(SCH_1):PAGE178

PVDDCR_CPU1_P0_PWM6 @T6G_MB_LIB.T6G(SCH_1):PVDDCR_CPU1_P0_PWM6
  PU12    7   PWM6 RAA229620GNPHA0-RAA229620GNP#HA0,SMLF,IC,ARF0TGP40A   I128 @T6G_MB_LIB.T6G(SCH_1):PAGE175
  PU11   34    PWM ISL99390FRZTR5935-ISL99390FRZ-TR5935,SMLF,IC,AL099A    I73 @T6G_MB_LIB.T6G(SCH_1):PAGE178

PVDDCR_CPU1_P0_RESET_N @T6G_MB_LIB.T6G(SCH_1):PVDDCR_CPU1_P0_RESET_N
   U29    4     2Y SN74LVC2G07DCKR_SMLF-SN74LVC2G07DCKR,IC,AL002G07006    I15 @T6G_MB_LIB.T6G(SCH_1):PAGE77
 R8063    1      A Q_RES_0402LF-100,1%,1/16W,CHIP,CS11002FB07    I67 @T6G_MB_LIB.T6G(SCH_1):PAGE175

PVDDCR_CPU1_P0_RESET_N_R @T6G_MB_LIB.T6G(SCH_1):PVDDCR_CPU1_P0_RESET_N_R
 R8063    2      B Q_RES_0402LF-100,1%,1/16W,CHIP,CS11002FB07    I67 @T6G_MB_LIB.T6G(SCH_1):PAGE175
 R8070    2      B Q_RES_0402LF-1K,1%,1/16W,CHIP,CS21002FB06    I68 @T6G_MB_LIB.T6G(SCH_1):PAGE175
  PU12   18 RESET_L RAA229620GNPHA0-RAA229620GNP#HA0,SMLF,IC,ARF0TGP40A   I128 @T6G_MB_LIB.T6G(SCH_1):PAGE175

PVDDCR_CPU1_P0_SMB_ALERT @T6G_MB_LIB.T6G(SCH_1):PVDDCR_CPU1_P0_SMB_ALERT
 R1186    1      A Q_RES_0402LF-1K,1%,1/16W,CHIP,CS21002FB06    I60 @T6G_MB_LIB.T6G(SCH_1):PAGE82
   U18   L5  PL14D LCMXO3LF9400C5BG484C-LCMXO3LF-9400C-5BG484C,SMLF,IA   I143 @T6G_MB_LIB.T6G(SCH_1):PAGE81
 R8073    1      A Q_RES_0402LF-33,5%,1/16W,CHIP,CS03302JB10    I81 @T6G_MB_LIB.T6G(SCH_1):PAGE175
 C5013    1      A Q_CAP_0402-1000PF,50V,5%,X7R,TMP_QCH21006JB10   I130 @T6G_MB_LIB.T6G(SCH_1):PAGE175

PVDDCR_CPU1_P0_SMB_ALERT_R @T6G_MB_LIB.T6G(SCH_1):PVDDCR_CPU1_P0_SMB_ALERT_R
 R8073    2      B Q_RES_0402LF-33,5%,1/16W,CHIP,CS03302JB10    I81 @T6G_MB_LIB.T6G(SCH_1):PAGE175
  PU12   15 NPMALERT RAA229620GNPHA0-RAA229620GNP#HA0,SMLF,IC,ARF0TGP40A   I128 @T6G_MB_LIB.T6G(SCH_1):PAGE175

PVDDCR_CPU1_P0_TEMP0 @T6G_MB_LIB.T6G(SCH_1):PVDDCR_CPU1_P0_TEMP0
  PC78    1      A Q_CAP_0402-470PF,50V,10%,X7R,TMP_QCH14706KB18    I73 @T6G_MB_LIB.T6G(SCH_1):PAGE175
  PU12   44  TEMP0 RAA229620GNPHA0-RAA229620GNP#HA0,SMLF,IC,ARF0TGP40A   I128 @T6G_MB_LIB.T6G(SCH_1):PAGE175
   PU2   36 TOUT_FLT ISL99390FRZTR5935-ISL99390FRZ-TR5935,SMLF,IC,AL099A    I33 @T6G_MB_LIB.T6G(SCH_1):PAGE176
  PU13   36 TOUT_FLT ISL99390FRZTR5935-ISL99390FRZ-TR5935,SMLF,IC,AL099A    I35 @T6G_MB_LIB.T6G(SCH_1):PAGE176
  PU14   36 TOUT_FLT ISL99390FRZTR5935-ISL99390FRZ-TR5935,SMLF,IC,AL099A    I21 @T6G_MB_LIB.T6G(SCH_1):PAGE177
  PU15   36 TOUT_FLT ISL99390FRZTR5935-ISL99390FRZ-TR5935,SMLF,IC,AL099A    I23 @T6G_MB_LIB.T6G(SCH_1):PAGE177
  PU16   36 TOUT_FLT ISL99390FRZTR5935-ISL99390FRZ-TR5935,SMLF,IC,AL099A    I22 @T6G_MB_LIB.T6G(SCH_1):PAGE178
  PU11   36 TOUT_FLT ISL99390FRZTR5935-ISL99390FRZ-TR5935,SMLF,IC,AL099A    I73 @T6G_MB_LIB.T6G(SCH_1):PAGE178

PVDDCR_CPU1_P0_VCC @T6G_MB_LIB.T6G(SCH_1):PVDDCR_CPU1_P0_VCC
  PC14    1      A Q_CAP_0402-0.1UF,25V,10%,X7R,CH4104K1B00    I96 @T6G_MB_LIB.T6G(SCH_1):PAGE175
  PC75    1      A Q_CAP_C0402-1UF,16V,10%,X6S,CH5103KEB01   I100 @T6G_MB_LIB.T6G(SCH_1):PAGE175
  PR76    1      A Q_RES_0402LF-1,1%,1/16W,CHIP,CS-1002FB04   I126 @T6G_MB_LIB.T6G(SCH_1):PAGE175
  PU12   47    VCC RAA229620GNPHA0-RAA229620GNP#HA0,SMLF,IC,ARF0TGP40A   I128 @T6G_MB_LIB.T6G(SCH_1):PAGE175

PVDDCR_CPU1_P0_VCC1 @T6G_MB_LIB.T6G(SCH_1):PVDDCR_CPU1_P0_VCC1
  PC79    1      A Q_CAP_C0402-2.2UF,10V,10%,X6S,CH5222KEB01    I24 @T6G_MB_LIB.T6G(SCH_1):PAGE176
  PR79    2      B Q_RES_0402LF-2.2,1%,1/16W,CHIP,CS-2202FB01    I29 @T6G_MB_LIB.T6G(SCH_1):PAGE176
  PU13   35     EN ISL99390FRZTR5935-ISL99390FRZ-TR5935,SMLF,IC,AL099A    I35 @T6G_MB_LIB.T6G(SCH_1):PAGE176
  PU13    3    VCC ISL99390FRZTR5935-ISL99390FRZ-TR5935,SMLF,IC,AL099A    I35 @T6G_MB_LIB.T6G(SCH_1):PAGE176

PVDDCR_CPU1_P0_VCC2 @T6G_MB_LIB.T6G(SCH_1):PVDDCR_CPU1_P0_VCC2
  PC80    1      A Q_CAP_C0402-2.2UF,10V,10%,X6S,CH5222KEB01    I10 @T6G_MB_LIB.T6G(SCH_1):PAGE176
  PR80    2      B Q_RES_0402LF-2.2,1%,1/16W,CHIP,CS-2202FB01    I13 @T6G_MB_LIB.T6G(SCH_1):PAGE176
   PU2   35     EN ISL99390FRZTR5935-ISL99390FRZ-TR5935,SMLF,IC,AL099A    I33 @T6G_MB_LIB.T6G(SCH_1):PAGE176
   PU2    3    VCC ISL99390FRZTR5935-ISL99390FRZ-TR5935,SMLF,IC,AL099A    I33 @T6G_MB_LIB.T6G(SCH_1):PAGE176

PVDDCR_CPU1_P0_VCC3 @T6G_MB_LIB.T6G(SCH_1):PVDDCR_CPU1_P0_VCC3
  PR88    2      B Q_RES_0402LF-2.2,1%,1/16W,CHIP,CS-2202FB01    I30 @T6G_MB_LIB.T6G(SCH_1):PAGE177
  PU15   35     EN ISL99390FRZTR5935-ISL99390FRZ-TR5935,SMLF,IC,AL099A    I23 @T6G_MB_LIB.T6G(SCH_1):PAGE177
  PU15    3    VCC ISL99390FRZTR5935-ISL99390FRZ-TR5935,SMLF,IC,AL099A    I23 @T6G_MB_LIB.T6G(SCH_1):PAGE177
 PC110    1      A Q_CAP_C0402-2.2UF,10V,10%,X6S,CH5222KEB01    I28 @T6G_MB_LIB.T6G(SCH_1):PAGE177

PVDDCR_CPU1_P0_VCC4 @T6G_MB_LIB.T6G(SCH_1):PVDDCR_CPU1_P0_VCC4
 PC109    1      A Q_CAP_C0402-2.2UF,10V,10%,X6S,CH5222KEB01     I7 @T6G_MB_LIB.T6G(SCH_1):PAGE177
  PR87    2      B Q_RES_0402LF-2.2,1%,1/16W,CHIP,CS-2202FB01    I13 @T6G_MB_LIB.T6G(SCH_1):PAGE177
  PU14   35     EN ISL99390FRZTR5935-ISL99390FRZ-TR5935,SMLF,IC,AL099A    I21 @T6G_MB_LIB.T6G(SCH_1):PAGE177
  PU14    3    VCC ISL99390FRZTR5935-ISL99390FRZ-TR5935,SMLF,IC,AL099A    I21 @T6G_MB_LIB.T6G(SCH_1):PAGE177

PVDDCR_CPU1_P0_VCC5 @T6G_MB_LIB.T6G(SCH_1):PVDDCR_CPU1_P0_VCC5
  PU16   35     EN ISL99390FRZTR5935-ISL99390FRZ-TR5935,SMLF,IC,AL099A    I22 @T6G_MB_LIB.T6G(SCH_1):PAGE178
  PU16    3    VCC ISL99390FRZTR5935-ISL99390FRZ-TR5935,SMLF,IC,AL099A    I22 @T6G_MB_LIB.T6G(SCH_1):PAGE178
 PC131    1      A Q_CAP_C0402-2.2UF,10V,10%,X6S,CH5222KEB01    I27 @T6G_MB_LIB.T6G(SCH_1):PAGE178
  PR94    2      B Q_RES_0402LF-2.2,1%,1/16W,CHIP,CS-2202FB01    I28 @T6G_MB_LIB.T6G(SCH_1):PAGE178

PVDDCR_CPU1_P0_VCC6 @T6G_MB_LIB.T6G(SCH_1):PVDDCR_CPU1_P0_VCC6
 PC112    1      A Q_CAP_C0402-2.2UF,10V,10%,X6S,CH5222KEB01    I11 @T6G_MB_LIB.T6G(SCH_1):PAGE178
 PR416    2      B Q_RES_0402LF-2.2,1%,1/16W,CHIP,CS-2202FB01    I13 @T6G_MB_LIB.T6G(SCH_1):PAGE178
  PU11   35     EN ISL99390FRZTR5935-ISL99390FRZ-TR5935,SMLF,IC,AL099A    I73 @T6G_MB_LIB.T6G(SCH_1):PAGE178
  PU11    3    VCC ISL99390FRZTR5935-ISL99390FRZ-TR5935,SMLF,IC,AL099A    I73 @T6G_MB_LIB.T6G(SCH_1):PAGE178

PVDDCR_CPU1_P0_VCCS @T6G_MB_LIB.T6G(SCH_1):PVDDCR_CPU1_P0_VCCS
PC83_2    1      A Q_CAP_0402-0.1UF,25V,10%,X7R,CH4104K1B00     I2 @T6G_MB_LIB.T6G(SCH_1):PAGE176
PC113_4    1      A Q_CAP_0402-0.1UF,25V,10%,X7R,CH4104K1B00     I2 @T6G_MB_LIB.T6G(SCH_1):PAGE177
  PC15    1      A Q_CAP_0402-0.1UF,25V,10%,X7R,CH4104K1B00    I94 @T6G_MB_LIB.T6G(SCH_1):PAGE175
  PC76    1      A Q_CAP_C0402-10UF,6.3V,20%,X6S,CH6101MEB03    I98 @T6G_MB_LIB.T6G(SCH_1):PAGE175
  PU12   48   VCCS RAA229620GNPHA0-RAA229620GNP#HA0,SMLF,IC,ARF0TGP40A   I128 @T6G_MB_LIB.T6G(SCH_1):PAGE175
PC84_1    1      A Q_CAP_0402-0.1UF,25V,10%,X7R,CH4104K1B00    I12 @T6G_MB_LIB.T6G(SCH_1):PAGE176
   PU2   39  REFIN ISL99390FRZTR5935-ISL99390FRZ-TR5935,SMLF,IC,AL099A    I33 @T6G_MB_LIB.T6G(SCH_1):PAGE176
  PU13   39  REFIN ISL99390FRZTR5935-ISL99390FRZ-TR5935,SMLF,IC,AL099A    I35 @T6G_MB_LIB.T6G(SCH_1):PAGE176
PC114_3    1      A Q_CAP_0402-0.1UF,25V,10%,X7R,CH4104K1B00    I12 @T6G_MB_LIB.T6G(SCH_1):PAGE177
  PU14   39  REFIN ISL99390FRZTR5935-ISL99390FRZ-TR5935,SMLF,IC,AL099A    I21 @T6G_MB_LIB.T6G(SCH_1):PAGE177
  PU15   39  REFIN ISL99390FRZTR5935-ISL99390FRZ-TR5935,SMLF,IC,AL099A    I23 @T6G_MB_LIB.T6G(SCH_1):PAGE177
PC111_6    1      A Q_CAP_0402-0.1UF,25V,10%,X7R,CH4104K1B00     I2 @T6G_MB_LIB.T6G(SCH_1):PAGE178
PC132_5    1      A Q_CAP_0402-0.1UF,25V,10%,X7R,CH4104K1B00    I10 @T6G_MB_LIB.T6G(SCH_1):PAGE178
  PU16   39  REFIN ISL99390FRZTR5935-ISL99390FRZ-TR5935,SMLF,IC,AL099A    I22 @T6G_MB_LIB.T6G(SCH_1):PAGE178
  PU11   39  REFIN ISL99390FRZTR5935-ISL99390FRZ-TR5935,SMLF,IC,AL099A    I73 @T6G_MB_LIB.T6G(SCH_1):PAGE178
PC146_8    1      A Q_CAP_0402-0.1UF,25V,10%,X7R,CH4104K1B00     I2 @T6G_MB_LIB.T6G(SCH_1):PAGE180
  PU18   39  REFIN ISL99390FRZTR5935-ISL99390FRZ-TR5935,SMLF,IC,AL099A    I15 @T6G_MB_LIB.T6G(SCH_1):PAGE180
PC145_7    1      A Q_CAP_0402-0.1UF,25V,10%,X7R,CH4104K1B00    I20 @T6G_MB_LIB.T6G(SCH_1):PAGE180
  PU17   39  REFIN ISL99390FRZTR5935-ISL99390FRZ-TR5935,SMLF,IC,AL099A    I84 @T6G_MB_LIB.T6G(SCH_1):PAGE180
PC176_10    1      A Q_CAP_0402-0.1UF,25V,10%,X7R,CH4104K1B00     I1 @T6G_MB_LIB.T6G(SCH_1):PAGE181
PC175_9    1      A Q_CAP_0402-0.1UF,25V,10%,X7R,CH4104K1B00    I19 @T6G_MB_LIB.T6G(SCH_1):PAGE181
  PU19   39  REFIN ISL99390FRZTR5935-ISL99390FRZ-TR5935,SMLF,IC,AL099A    I32 @T6G_MB_LIB.T6G(SCH_1):PAGE181
  PU20   39  REFIN ISL99390FRZTR5935-ISL99390FRZ-TR5935,SMLF,IC,AL099A    I73 @T6G_MB_LIB.T6G(SCH_1):PAGE181

PVDDCR_CPU1_P0_VINSEN @T6G_MB_LIB.T6G(SCH_1):PVDDCR_CPU1_P0_VINSEN
  PR74    2      B Q_RES_0402LF-0,5%,1/16W,CHIP,CS00002JB13    I51 @T6G_MB_LIB.T6G(SCH_1):PAGE175
 PR600    1      A Q_RES_0402LF-4.99K,1%,1/16W,EMPTY,CS24992FB07    I59 @T6G_MB_LIB.T6G(SCH_1):PAGE175
  PC74    1      A Q_CAP_0402-0.1UF,25V,10%,X7R,CH4104K1B00    I60 @T6G_MB_LIB.T6G(SCH_1):PAGE175
  PU12   46 VINSEN RAA229620GNPHA0-RAA229620GNP#HA0,SMLF,IC,ARF0TGP40A   I128 @T6G_MB_LIB.T6G(SCH_1):PAGE175

PVDDCR_CPU1_P0_VMON @T6G_MB_LIB.T6G(SCH_1):PVDDCR_CPU1_P0_VMON
  PR54    1      A Q_RES_0402LF-10K,1%,1/16W,CHIP,CS31002FB08     I8 @T6G_MB_LIB.T6G(SCH_1):PAGE175
  PR53    2      B Q_RES_0402LF-40.2K,1%,1/16W,CHIP,CS34022FB04     I9 @T6G_MB_LIB.T6G(SCH_1):PAGE175
  PC67    1      A Q_CAP_0402-0.1UF,25V,10%,X7R,CH4104K1B00    I50 @T6G_MB_LIB.T6G(SCH_1):PAGE175
  PU12   45 VMON||IINSEN RAA229620GNPHA0-RAA229620GNP#HA0,SMLF,IC,ARF0TGP40A   I128 @T6G_MB_LIB.T6G(SCH_1):PAGE175

PVDDCR_CPU1_P0_VOS1 @T6G_MB_LIB.T6G(SCH_1):PVDDCR_CPU1_P0_VOS1
  PU13    1    VOS ISL99390FRZTR5935-ISL99390FRZ-TR5935,SMLF,IC,AL099A    I35 @T6G_MB_LIB.T6G(SCH_1):PAGE176
  PR84    1      A Q_RES_0402LF-0,5%,1/16W,CHIP,CS00002JB13    I54 @T6G_MB_LIB.T6G(SCH_1):PAGE176

PVDDCR_CPU1_P0_VOS2 @T6G_MB_LIB.T6G(SCH_1):PVDDCR_CPU1_P0_VOS2
   PU2    1    VOS ISL99390FRZTR5935-ISL99390FRZ-TR5935,SMLF,IC,AL099A    I33 @T6G_MB_LIB.T6G(SCH_1):PAGE176
  PR83    1      A Q_RES_0402LF-0,5%,1/16W,CHIP,CS00002JB13    I42 @T6G_MB_LIB.T6G(SCH_1):PAGE176

PVDDCR_CPU1_P0_VOS3 @T6G_MB_LIB.T6G(SCH_1):PVDDCR_CPU1_P0_VOS3
  PR92    1      A Q_RES_0402LF-0,5%,1/16W,CHIP,CS00002JB13    I51 @T6G_MB_LIB.T6G(SCH_1):PAGE177
  PU15    1    VOS ISL99390FRZTR5935-ISL99390FRZ-TR5935,SMLF,IC,AL099A    I23 @T6G_MB_LIB.T6G(SCH_1):PAGE177

PVDDCR_CPU1_P0_VOS4 @T6G_MB_LIB.T6G(SCH_1):PVDDCR_CPU1_P0_VOS4
  PR91    1      A Q_RES_0402LF-0,5%,1/16W,CHIP,CS00002JB13    I40 @T6G_MB_LIB.T6G(SCH_1):PAGE177
  PU14    1    VOS ISL99390FRZTR5935-ISL99390FRZ-TR5935,SMLF,IC,AL099A    I21 @T6G_MB_LIB.T6G(SCH_1):PAGE177

PVDDCR_CPU1_P0_VOS5 @T6G_MB_LIB.T6G(SCH_1):PVDDCR_CPU1_P0_VOS5
  PU16    1    VOS ISL99390FRZTR5935-ISL99390FRZ-TR5935,SMLF,IC,AL099A    I22 @T6G_MB_LIB.T6G(SCH_1):PAGE178
  PR96    1      A Q_RES_0402LF-0,5%,1/16W,CHIP,CS00002JB13    I49 @T6G_MB_LIB.T6G(SCH_1):PAGE178

PVDDCR_CPU1_P0_VOS6 @T6G_MB_LIB.T6G(SCH_1):PVDDCR_CPU1_P0_VOS6
 PR421    1      A Q_RES_0402LF-0,5%,1/16W,CHIP,CS00002JB13    I35 @T6G_MB_LIB.T6G(SCH_1):PAGE178
  PU11    1    VOS ISL99390FRZTR5935-ISL99390FRZ-TR5935,SMLF,IC,AL099A    I73 @T6G_MB_LIB.T6G(SCH_1):PAGE178

PVDDCR_CPU1_P1 @T6G_MB_LIB.T6G(SCH_1):PVDDCR_CPU1_P1
   U26 BN27 VDDCR_CPU1_BN27 GENOA_SP5-SOCKET6096_13568-001,SMLF,IO,DGA^6000030    I32 @T6G_MB_LIB.T6G(SCH_1):PAGE57
   U26 BN31 VDDCR_CPU1_BN31 GENOA_SP5-SOCKET6096_13568-001,SMLF,IO,DGA^6000030    I32 @T6G_MB_LIB.T6G(SCH_1):PAGE57
   U26 BN35 VDDCR_CPU1_BN35 GENOA_SP5-SOCKET6096_13568-001,SMLF,IO,DGA^6000030    I32 @T6G_MB_LIB.T6G(SCH_1):PAGE57
   U26 BN42 VDDCR_CPU1_BN42 GENOA_SP5-SOCKET6096_13568-001,SMLF,IO,DGA^6000030    I32 @T6G_MB_LIB.T6G(SCH_1):PAGE57
   U26 BN46 VDDCR_CPU1_BN46 GENOA_SP5-SOCKET6096_13568-001,SMLF,IO,DGA^6000030    I32 @T6G_MB_LIB.T6G(SCH_1):PAGE57
   U26 BN50 VDDCR_CPU1_BN50 GENOA_SP5-SOCKET6096_13568-001,SMLF,IO,DGA^6000030    I32 @T6G_MB_LIB.T6G(SCH_1):PAGE57
   U26 BP24 VDDCR_CPU1_BP24 GENOA_SP5-SOCKET6096_13568-001,SMLF,IO,DGA^6000030    I32 @T6G_MB_LIB.T6G(SCH_1):PAGE57
   U26 BP26 VDDCR_CPU1_BP26 GENOA_SP5-SOCKET6096_13568-001,SMLF,IO,DGA^6000030    I32 @T6G_MB_LIB.T6G(SCH_1):PAGE57
   U26 BP28 VDDCR_CPU1_BP28 GENOA_SP5-SOCKET6096_13568-001,SMLF,IO,DGA^6000030    I32 @T6G_MB_LIB.T6G(SCH_1):PAGE57
   U26 BP30 VDDCR_CPU1_BP30 GENOA_SP5-SOCKET6096_13568-001,SMLF,IO,DGA^6000030    I32 @T6G_MB_LIB.T6G(SCH_1):PAGE57
   U26 BP32 VDDCR_CPU1_BP32 GENOA_SP5-SOCKET6096_13568-001,SMLF,IO,DGA^6000030    I32 @T6G_MB_LIB.T6G(SCH_1):PAGE57
   U26 BP34 VDDCR_CPU1_BP34 GENOA_SP5-SOCKET6096_13568-001,SMLF,IO,DGA^6000030    I32 @T6G_MB_LIB.T6G(SCH_1):PAGE57
   U26 BP36 VDDCR_CPU1_BP36 GENOA_SP5-SOCKET6096_13568-001,SMLF,IO,DGA^6000030    I32 @T6G_MB_LIB.T6G(SCH_1):PAGE57
   U26 BP39 VDDCR_CPU1_BP39 GENOA_SP5-SOCKET6096_13568-001,SMLF,IO,DGA^6000030    I32 @T6G_MB_LIB.T6G(SCH_1):PAGE57
   U26 BP41 VDDCR_CPU1_BP41 GENOA_SP5-SOCKET6096_13568-001,SMLF,IO,DGA^6000030    I32 @T6G_MB_LIB.T6G(SCH_1):PAGE57
   U26 BP43 VDDCR_CPU1_BP43 GENOA_SP5-SOCKET6096_13568-001,SMLF,IO,DGA^6000030    I32 @T6G_MB_LIB.T6G(SCH_1):PAGE57
   U26 BP45 VDDCR_CPU1_BP45 GENOA_SP5-SOCKET6096_13568-001,SMLF,IO,DGA^6000030    I32 @T6G_MB_LIB.T6G(SCH_1):PAGE57
   U26 BP47 VDDCR_CPU1_BP47 GENOA_SP5-SOCKET6096_13568-001,SMLF,IO,DGA^6000030    I32 @T6G_MB_LIB.T6G(SCH_1):PAGE57
   U26 BP49 VDDCR_CPU1_BP49 GENOA_SP5-SOCKET6096_13568-001,SMLF,IO,DGA^6000030    I32 @T6G_MB_LIB.T6G(SCH_1):PAGE57
   U26 BR23 VDDCR_CPU1_BR23 GENOA_SP5-SOCKET6096_13568-001,SMLF,IO,DGA^6000030    I32 @T6G_MB_LIB.T6G(SCH_1):PAGE57
   U26 BR25 VDDCR_CPU1_BR25 GENOA_SP5-SOCKET6096_13568-001,SMLF,IO,DGA^6000030    I32 @T6G_MB_LIB.T6G(SCH_1):PAGE57
   U26 BR27 VDDCR_CPU1_BR27 GENOA_SP5-SOCKET6096_13568-001,SMLF,IO,DGA^6000030    I32 @T6G_MB_LIB.T6G(SCH_1):PAGE57
   U26 BR29 VDDCR_CPU1_BR29 GENOA_SP5-SOCKET6096_13568-001,SMLF,IO,DGA^6000030    I32 @T6G_MB_LIB.T6G(SCH_1):PAGE57
   U26 BR31 VDDCR_CPU1_BR31 GENOA_SP5-SOCKET6096_13568-001,SMLF,IO,DGA^6000030    I32 @T6G_MB_LIB.T6G(SCH_1):PAGE57
   U26 BR33 VDDCR_CPU1_BR33 GENOA_SP5-SOCKET6096_13568-001,SMLF,IO,DGA^6000030    I32 @T6G_MB_LIB.T6G(SCH_1):PAGE57
   U26 BR35 VDDCR_CPU1_BR35 GENOA_SP5-SOCKET6096_13568-001,SMLF,IO,DGA^6000030    I32 @T6G_MB_LIB.T6G(SCH_1):PAGE57
   U26 BR40 VDDCR_CPU1_BR40 GENOA_SP5-SOCKET6096_13568-001,SMLF,IO,DGA^6000030    I32 @T6G_MB_LIB.T6G(SCH_1):PAGE57
   U26 BR42 VDDCR_CPU1_BR42 GENOA_SP5-SOCKET6096_13568-001,SMLF,IO,DGA^6000030    I32 @T6G_MB_LIB.T6G(SCH_1):PAGE57
   U26 BR44 VDDCR_CPU1_BR44 GENOA_SP5-SOCKET6096_13568-001,SMLF,IO,DGA^6000030    I32 @T6G_MB_LIB.T6G(SCH_1):PAGE57
   U26 BR46 VDDCR_CPU1_BR46 GENOA_SP5-SOCKET6096_13568-001,SMLF,IO,DGA^6000030    I32 @T6G_MB_LIB.T6G(SCH_1):PAGE57
   U26 BR48 VDDCR_CPU1_BR48 GENOA_SP5-SOCKET6096_13568-001,SMLF,IO,DGA^6000030    I32 @T6G_MB_LIB.T6G(SCH_1):PAGE57
   U26 BR50 VDDCR_CPU1_BR50 GENOA_SP5-SOCKET6096_13568-001,SMLF,IO,DGA^6000030    I32 @T6G_MB_LIB.T6G(SCH_1):PAGE57
   U26 BR52 VDDCR_CPU1_BR52 GENOA_SP5-SOCKET6096_13568-001,SMLF,IO,DGA^6000030    I32 @T6G_MB_LIB.T6G(SCH_1):PAGE57
   U26 BT23 VDDCR_CPU1_BT23 GENOA_SP5-SOCKET6096_13568-001,SMLF,IO,DGA^6000030    I32 @T6G_MB_LIB.T6G(SCH_1):PAGE57
   U26 BT24 VDDCR_CPU1_BT24 GENOA_SP5-SOCKET6096_13568-001,SMLF,IO,DGA^6000030    I32 @T6G_MB_LIB.T6G(SCH_1):PAGE57
   U26 BT26 VDDCR_CPU1_BT26 GENOA_SP5-SOCKET6096_13568-001,SMLF,IO,DGA^6000030    I32 @T6G_MB_LIB.T6G(SCH_1):PAGE57
   U26 BT27 VDDCR_CPU1_BT27 GENOA_SP5-SOCKET6096_13568-001,SMLF,IO,DGA^6000030    I32 @T6G_MB_LIB.T6G(SCH_1):PAGE57
   U26 BT29 VDDCR_CPU1_BT29 GENOA_SP5-SOCKET6096_13568-001,SMLF,IO,DGA^6000030    I32 @T6G_MB_LIB.T6G(SCH_1):PAGE57
   U26 BT30 VDDCR_CPU1_BT30 GENOA_SP5-SOCKET6096_13568-001,SMLF,IO,DGA^6000030    I32 @T6G_MB_LIB.T6G(SCH_1):PAGE57
   U26 BT32 VDDCR_CPU1_BT32 GENOA_SP5-SOCKET6096_13568-001,SMLF,IO,DGA^6000030    I32 @T6G_MB_LIB.T6G(SCH_1):PAGE57
   U26 BT33 VDDCR_CPU1_BT33 GENOA_SP5-SOCKET6096_13568-001,SMLF,IO,DGA^6000030    I32 @T6G_MB_LIB.T6G(SCH_1):PAGE57
   U26 BT43 VDDCR_CPU1_BT43 GENOA_SP5-SOCKET6096_13568-001,SMLF,IO,DGA^6000030    I32 @T6G_MB_LIB.T6G(SCH_1):PAGE57
   U26 BT44 VDDCR_CPU1_BT44 GENOA_SP5-SOCKET6096_13568-001,SMLF,IO,DGA^6000030    I32 @T6G_MB_LIB.T6G(SCH_1):PAGE57
   U26 BT46 VDDCR_CPU1_BT46 GENOA_SP5-SOCKET6096_13568-001,SMLF,IO,DGA^6000030    I32 @T6G_MB_LIB.T6G(SCH_1):PAGE57
   U26 BT47 VDDCR_CPU1_BT47 GENOA_SP5-SOCKET6096_13568-001,SMLF,IO,DGA^6000030    I32 @T6G_MB_LIB.T6G(SCH_1):PAGE57
   U26 BT49 VDDCR_CPU1_BT49 GENOA_SP5-SOCKET6096_13568-001,SMLF,IO,DGA^6000030    I32 @T6G_MB_LIB.T6G(SCH_1):PAGE57
   U26 BT50 VDDCR_CPU1_BT50 GENOA_SP5-SOCKET6096_13568-001,SMLF,IO,DGA^6000030    I32 @T6G_MB_LIB.T6G(SCH_1):PAGE57
   U26 BT52 VDDCR_CPU1_BT52 GENOA_SP5-SOCKET6096_13568-001,SMLF,IO,DGA^6000030    I32 @T6G_MB_LIB.T6G(SCH_1):PAGE57
   U26 BT53 VDDCR_CPU1_BT53 GENOA_SP5-SOCKET6096_13568-001,SMLF,IO,DGA^6000030    I32 @T6G_MB_LIB.T6G(SCH_1):PAGE57
   U26 BW35 VDDCR_CPU1_BW35 GENOA_SP5-SOCKET6096_13568-001,SMLF,IO,DGA^6000030    I32 @T6G_MB_LIB.T6G(SCH_1):PAGE57
   U26 BW36 VDDCR_CPU1_BW36 GENOA_SP5-SOCKET6096_13568-001,SMLF,IO,DGA^6000030    I32 @T6G_MB_LIB.T6G(SCH_1):PAGE57
   U26 BW40 VDDCR_CPU1_BW40 GENOA_SP5-SOCKET6096_13568-001,SMLF,IO,DGA^6000030    I32 @T6G_MB_LIB.T6G(SCH_1):PAGE57
   U26 BW41 VDDCR_CPU1_BW41 GENOA_SP5-SOCKET6096_13568-001,SMLF,IO,DGA^6000030    I32 @T6G_MB_LIB.T6G(SCH_1):PAGE57
   U26 BY23 VDDCR_CPU1_BY23 GENOA_SP5-SOCKET6096_13568-001,SMLF,IO,DGA^6000030    I32 @T6G_MB_LIB.T6G(SCH_1):PAGE57
   U26 BY24 VDDCR_CPU1_BY24 GENOA_SP5-SOCKET6096_13568-001,SMLF,IO,DGA^6000030    I32 @T6G_MB_LIB.T6G(SCH_1):PAGE57
   U26 BY26 VDDCR_CPU1_BY26 GENOA_SP5-SOCKET6096_13568-001,SMLF,IO,DGA^6000030    I32 @T6G_MB_LIB.T6G(SCH_1):PAGE57
   U26 BY27 VDDCR_CPU1_BY27 GENOA_SP5-SOCKET6096_13568-001,SMLF,IO,DGA^6000030    I32 @T6G_MB_LIB.T6G(SCH_1):PAGE57
   U26 BY29 VDDCR_CPU1_BY29 GENOA_SP5-SOCKET6096_13568-001,SMLF,IO,DGA^6000030    I32 @T6G_MB_LIB.T6G(SCH_1):PAGE57
   U26 BY30 VDDCR_CPU1_BY30 GENOA_SP5-SOCKET6096_13568-001,SMLF,IO,DGA^6000030    I32 @T6G_MB_LIB.T6G(SCH_1):PAGE57
   U26 BY32 VDDCR_CPU1_BY32 GENOA_SP5-SOCKET6096_13568-001,SMLF,IO,DGA^6000030    I32 @T6G_MB_LIB.T6G(SCH_1):PAGE57
   U26 BY33 VDDCR_CPU1_BY33 GENOA_SP5-SOCKET6096_13568-001,SMLF,IO,DGA^6000030    I32 @T6G_MB_LIB.T6G(SCH_1):PAGE57
   U26 BY43 VDDCR_CPU1_BY43 GENOA_SP5-SOCKET6096_13568-001,SMLF,IO,DGA^6000030    I32 @T6G_MB_LIB.T6G(SCH_1):PAGE57
   U26 BY44 VDDCR_CPU1_BY44 GENOA_SP5-SOCKET6096_13568-001,SMLF,IO,DGA^6000030    I32 @T6G_MB_LIB.T6G(SCH_1):PAGE57
   U26 BY46 VDDCR_CPU1_BY46 GENOA_SP5-SOCKET6096_13568-001,SMLF,IO,DGA^6000030    I32 @T6G_MB_LIB.T6G(SCH_1):PAGE57
   U26 BY47 VDDCR_CPU1_BY47 GENOA_SP5-SOCKET6096_13568-001,SMLF,IO,DGA^6000030    I32 @T6G_MB_LIB.T6G(SCH_1):PAGE57
   U26 BY49 VDDCR_CPU1_BY49 GENOA_SP5-SOCKET6096_13568-001,SMLF,IO,DGA^6000030    I32 @T6G_MB_LIB.T6G(SCH_1):PAGE57
   U26 BY50 VDDCR_CPU1_BY50 GENOA_SP5-SOCKET6096_13568-001,SMLF,IO,DGA^6000030    I32 @T6G_MB_LIB.T6G(SCH_1):PAGE57
   U26 BY52 VDDCR_CPU1_BY52 GENOA_SP5-SOCKET6096_13568-001,SMLF,IO,DGA^6000030    I32 @T6G_MB_LIB.T6G(SCH_1):PAGE57
   U26 BY53 VDDCR_CPU1_BY53 GENOA_SP5-SOCKET6096_13568-001,SMLF,IO,DGA^6000030    I32 @T6G_MB_LIB.T6G(SCH_1):PAGE57
   U26 CC35 VDDCR_CPU1_CC35 GENOA_SP5-SOCKET6096_13568-001,SMLF,IO,DGA^6000030    I32 @T6G_MB_LIB.T6G(SCH_1):PAGE57
   U26 CC36 VDDCR_CPU1_CC36 GENOA_SP5-SOCKET6096_13568-001,SMLF,IO,DGA^6000030    I32 @T6G_MB_LIB.T6G(SCH_1):PAGE57
   U26 CC40 VDDCR_CPU1_CC40 GENOA_SP5-SOCKET6096_13568-001,SMLF,IO,DGA^6000030    I32 @T6G_MB_LIB.T6G(SCH_1):PAGE57
   U26 CC41 VDDCR_CPU1_CC41 GENOA_SP5-SOCKET6096_13568-001,SMLF,IO,DGA^6000030    I32 @T6G_MB_LIB.T6G(SCH_1):PAGE57
   U26 CD23 VDDCR_CPU1_CD23 GENOA_SP5-SOCKET6096_13568-001,SMLF,IO,DGA^6000030    I32 @T6G_MB_LIB.T6G(SCH_1):PAGE57
   U26 CD24 VDDCR_CPU1_CD24 GENOA_SP5-SOCKET6096_13568-001,SMLF,IO,DGA^6000030    I32 @T6G_MB_LIB.T6G(SCH_1):PAGE57
   U26 CD26 VDDCR_CPU1_CD26 GENOA_SP5-SOCKET6096_13568-001,SMLF,IO,DGA^6000030    I32 @T6G_MB_LIB.T6G(SCH_1):PAGE57
   U26 CD27 VDDCR_CPU1_CD27 GENOA_SP5-SOCKET6096_13568-001,SMLF,IO,DGA^6000030    I32 @T6G_MB_LIB.T6G(SCH_1):PAGE57
   U26 CD29 VDDCR_CPU1_CD29 GENOA_SP5-SOCKET6096_13568-001,SMLF,IO,DGA^6000030    I32 @T6G_MB_LIB.T6G(SCH_1):PAGE57
   U26 CD30 VDDCR_CPU1_CD30 GENOA_SP5-SOCKET6096_13568-001,SMLF,IO,DGA^6000030    I32 @T6G_MB_LIB.T6G(SCH_1):PAGE57
   U26 CD32 VDDCR_CPU1_CD32 GENOA_SP5-SOCKET6096_13568-001,SMLF,IO,DGA^6000030    I32 @T6G_MB_LIB.T6G(SCH_1):PAGE57
   U26 CD33 VDDCR_CPU1_CD33 GENOA_SP5-SOCKET6096_13568-001,SMLF,IO,DGA^6000030    I32 @T6G_MB_LIB.T6G(SCH_1):PAGE57
   U26 CD43 VDDCR_CPU1_CD43 GENOA_SP5-SOCKET6096_13568-001,SMLF,IO,DGA^6000030    I32 @T6G_MB_LIB.T6G(SCH_1):PAGE57
   U26 CD44 VDDCR_CPU1_CD44 GENOA_SP5-SOCKET6096_13568-001,SMLF,IO,DGA^6000030    I32 @T6G_MB_LIB.T6G(SCH_1):PAGE57
   U26 CD46 VDDCR_CPU1_CD46 GENOA_SP5-SOCKET6096_13568-001,SMLF,IO,DGA^6000030    I32 @T6G_MB_LIB.T6G(SCH_1):PAGE57
   U26 CD47 VDDCR_CPU1_CD47 GENOA_SP5-SOCKET6096_13568-001,SMLF,IO,DGA^6000030    I32 @T6G_MB_LIB.T6G(SCH_1):PAGE57
   U26 CD49 VDDCR_CPU1_CD49 GENOA_SP5-SOCKET6096_13568-001,SMLF,IO,DGA^6000030    I32 @T6G_MB_LIB.T6G(SCH_1):PAGE57
   U26 CD50 VDDCR_CPU1_CD50 GENOA_SP5-SOCKET6096_13568-001,SMLF,IO,DGA^6000030    I32 @T6G_MB_LIB.T6G(SCH_1):PAGE57
   U26 CD52 VDDCR_CPU1_CD52 GENOA_SP5-SOCKET6096_13568-001,SMLF,IO,DGA^6000030    I32 @T6G_MB_LIB.T6G(SCH_1):PAGE57
   U26 CD53 VDDCR_CPU1_CD53 GENOA_SP5-SOCKET6096_13568-001,SMLF,IO,DGA^6000030    I32 @T6G_MB_LIB.T6G(SCH_1):PAGE57
   U26 CG35 VDDCR_CPU1_CG35 GENOA_SP5-SOCKET6096_13568-001,SMLF,IO,DGA^6000030    I32 @T6G_MB_LIB.T6G(SCH_1):PAGE57
   U26 CG36 VDDCR_CPU1_CG36 GENOA_SP5-SOCKET6096_13568-001,SMLF,IO,DGA^6000030    I32 @T6G_MB_LIB.T6G(SCH_1):PAGE57
   U26 CG40 VDDCR_CPU1_CG40 GENOA_SP5-SOCKET6096_13568-001,SMLF,IO,DGA^6000030    I32 @T6G_MB_LIB.T6G(SCH_1):PAGE57
   U26 CG41 VDDCR_CPU1_CG41 GENOA_SP5-SOCKET6096_13568-001,SMLF,IO,DGA^6000030    I32 @T6G_MB_LIB.T6G(SCH_1):PAGE57
   U26 CH23 VDDCR_CPU1_CH23 GENOA_SP5-SOCKET6096_13568-001,SMLF,IO,DGA^6000030    I32 @T6G_MB_LIB.T6G(SCH_1):PAGE57
   U26 CH24 VDDCR_CPU1_CH24 GENOA_SP5-SOCKET6096_13568-001,SMLF,IO,DGA^6000030    I32 @T6G_MB_LIB.T6G(SCH_1):PAGE57
   U26 CH26 VDDCR_CPU1_CH26 GENOA_SP5-SOCKET6096_13568-001,SMLF,IO,DGA^6000030    I32 @T6G_MB_LIB.T6G(SCH_1):PAGE57
   U26 CH27 VDDCR_CPU1_CH27 GENOA_SP5-SOCKET6096_13568-001,SMLF,IO,DGA^6000030    I32 @T6G_MB_LIB.T6G(SCH_1):PAGE57
   U26 CH29 VDDCR_CPU1_CH29 GENOA_SP5-SOCKET6096_13568-001,SMLF,IO,DGA^6000030    I32 @T6G_MB_LIB.T6G(SCH_1):PAGE57
   U26 CH30 VDDCR_CPU1_CH30 GENOA_SP5-SOCKET6096_13568-001,SMLF,IO,DGA^6000030    I32 @T6G_MB_LIB.T6G(SCH_1):PAGE57
   U26 CH32 VDDCR_CPU1_CH32 GENOA_SP5-SOCKET6096_13568-001,SMLF,IO,DGA^6000030    I32 @T6G_MB_LIB.T6G(SCH_1):PAGE57
   U26 CH33 VDDCR_CPU1_CH33 GENOA_SP5-SOCKET6096_13568-001,SMLF,IO,DGA^6000030    I32 @T6G_MB_LIB.T6G(SCH_1):PAGE57
   U26 CH43 VDDCR_CPU1_CH43 GENOA_SP5-SOCKET6096_13568-001,SMLF,IO,DGA^6000030    I32 @T6G_MB_LIB.T6G(SCH_1):PAGE57
   U26 CH44 VDDCR_CPU1_CH44 GENOA_SP5-SOCKET6096_13568-001,SMLF,IO,DGA^6000030    I32 @T6G_MB_LIB.T6G(SCH_1):PAGE57
   U26 CH46 VDDCR_CPU1_CH46 GENOA_SP5-SOCKET6096_13568-001,SMLF,IO,DGA^6000030    I32 @T6G_MB_LIB.T6G(SCH_1):PAGE57
   U26 CH47 VDDCR_CPU1_CH47 GENOA_SP5-SOCKET6096_13568-001,SMLF,IO,DGA^6000030    I32 @T6G_MB_LIB.T6G(SCH_1):PAGE57
   U26 CH49 VDDCR_CPU1_CH49 GENOA_SP5-SOCKET6096_13568-001,SMLF,IO,DGA^6000030    I32 @T6G_MB_LIB.T6G(SCH_1):PAGE57
   U26 CH50 VDDCR_CPU1_CH50 GENOA_SP5-SOCKET6096_13568-001,SMLF,IO,DGA^6000030    I32 @T6G_MB_LIB.T6G(SCH_1):PAGE57
   U26 CH52 VDDCR_CPU1_CH52 GENOA_SP5-SOCKET6096_13568-001,SMLF,IO,DGA^6000030    I32 @T6G_MB_LIB.T6G(SCH_1):PAGE57
   U26 CH53 VDDCR_CPU1_CH53 GENOA_SP5-SOCKET6096_13568-001,SMLF,IO,DGA^6000030    I32 @T6G_MB_LIB.T6G(SCH_1):PAGE57
   U26 CK35 VDDCR_CPU1_CK35 GENOA_SP5-SOCKET6096_13568-001,SMLF,IO,DGA^6000030    I32 @T6G_MB_LIB.T6G(SCH_1):PAGE57
   U26 CK36 VDDCR_CPU1_CK36 GENOA_SP5-SOCKET6096_13568-001,SMLF,IO,DGA^6000030    I32 @T6G_MB_LIB.T6G(SCH_1):PAGE57
   U26 CK40 VDDCR_CPU1_CK40 GENOA_SP5-SOCKET6096_13568-001,SMLF,IO,DGA^6000030    I32 @T6G_MB_LIB.T6G(SCH_1):PAGE57
   U26 CK41 VDDCR_CPU1_CK41 GENOA_SP5-SOCKET6096_13568-001,SMLF,IO,DGA^6000030    I32 @T6G_MB_LIB.T6G(SCH_1):PAGE57
   U26 CL29 VDDCR_CPU1_CL29 GENOA_SP5-SOCKET6096_13568-001,SMLF,IO,DGA^6000030    I32 @T6G_MB_LIB.T6G(SCH_1):PAGE57
   U26 CL30 VDDCR_CPU1_CL30 GENOA_SP5-SOCKET6096_13568-001,SMLF,IO,DGA^6000030    I32 @T6G_MB_LIB.T6G(SCH_1):PAGE57
   U26 CL32 VDDCR_CPU1_CL32 GENOA_SP5-SOCKET6096_13568-001,SMLF,IO,DGA^6000030    I32 @T6G_MB_LIB.T6G(SCH_1):PAGE57
   U26 CL33 VDDCR_CPU1_CL33 GENOA_SP5-SOCKET6096_13568-001,SMLF,IO,DGA^6000030    I32 @T6G_MB_LIB.T6G(SCH_1):PAGE57
   U26 CL43 VDDCR_CPU1_CL43 GENOA_SP5-SOCKET6096_13568-001,SMLF,IO,DGA^6000030    I32 @T6G_MB_LIB.T6G(SCH_1):PAGE57
   U26 CL44 VDDCR_CPU1_CL44 GENOA_SP5-SOCKET6096_13568-001,SMLF,IO,DGA^6000030    I32 @T6G_MB_LIB.T6G(SCH_1):PAGE57
   U26 CL46 VDDCR_CPU1_CL46 GENOA_SP5-SOCKET6096_13568-001,SMLF,IO,DGA^6000030    I32 @T6G_MB_LIB.T6G(SCH_1):PAGE57
   U26 CL47 VDDCR_CPU1_CL47 GENOA_SP5-SOCKET6096_13568-001,SMLF,IO,DGA^6000030    I32 @T6G_MB_LIB.T6G(SCH_1):PAGE57
   U26 CN35 VDDCR_CPU1_CN35 GENOA_SP5-SOCKET6096_13568-001,SMLF,IO,DGA^6000030    I32 @T6G_MB_LIB.T6G(SCH_1):PAGE57
   U26 CN36 VDDCR_CPU1_CN36 GENOA_SP5-SOCKET6096_13568-001,SMLF,IO,DGA^6000030    I32 @T6G_MB_LIB.T6G(SCH_1):PAGE57
   U26 CN40 VDDCR_CPU1_CN40 GENOA_SP5-SOCKET6096_13568-001,SMLF,IO,DGA^6000030    I32 @T6G_MB_LIB.T6G(SCH_1):PAGE57
   U26 CN41 VDDCR_CPU1_CN41 GENOA_SP5-SOCKET6096_13568-001,SMLF,IO,DGA^6000030    I32 @T6G_MB_LIB.T6G(SCH_1):PAGE57
   U26 CP23 VDDCR_CPU1_CP23 GENOA_SP5-SOCKET6096_13568-001,SMLF,IO,DGA^6000030    I32 @T6G_MB_LIB.T6G(SCH_1):PAGE57
   U26 CP24 VDDCR_CPU1_CP24 GENOA_SP5-SOCKET6096_13568-001,SMLF,IO,DGA^6000030    I32 @T6G_MB_LIB.T6G(SCH_1):PAGE57
   U26 CP26 VDDCR_CPU1_CP26 GENOA_SP5-SOCKET6096_13568-001,SMLF,IO,DGA^6000030    I32 @T6G_MB_LIB.T6G(SCH_1):PAGE57
   U26 CP27 VDDCR_CPU1_CP27 GENOA_SP5-SOCKET6096_13568-001,SMLF,IO,DGA^6000030    I32 @T6G_MB_LIB.T6G(SCH_1):PAGE57
   U26 CP29 VDDCR_CPU1_CP29 GENOA_SP5-SOCKET6096_13568-001,SMLF,IO,DGA^6000030    I32 @T6G_MB_LIB.T6G(SCH_1):PAGE57
   U26 CP30 VDDCR_CPU1_CP30 GENOA_SP5-SOCKET6096_13568-001,SMLF,IO,DGA^6000030    I32 @T6G_MB_LIB.T6G(SCH_1):PAGE57
   U26 CP32 VDDCR_CPU1_CP32 GENOA_SP5-SOCKET6096_13568-001,SMLF,IO,DGA^6000030    I32 @T6G_MB_LIB.T6G(SCH_1):PAGE57
   U26 CP33 VDDCR_CPU1_CP33 GENOA_SP5-SOCKET6096_13568-001,SMLF,IO,DGA^6000030    I32 @T6G_MB_LIB.T6G(SCH_1):PAGE57
   U26 CP43 VDDCR_CPU1_CP43 GENOA_SP5-SOCKET6096_13568-001,SMLF,IO,DGA^6000030    I32 @T6G_MB_LIB.T6G(SCH_1):PAGE57
   U26 CP44 VDDCR_CPU1_CP44 GENOA_SP5-SOCKET6096_13568-001,SMLF,IO,DGA^6000030    I32 @T6G_MB_LIB.T6G(SCH_1):PAGE57
   U26 CP46 VDDCR_CPU1_CP46 GENOA_SP5-SOCKET6096_13568-001,SMLF,IO,DGA^6000030    I32 @T6G_MB_LIB.T6G(SCH_1):PAGE57
   U26 CP47 VDDCR_CPU1_CP47 GENOA_SP5-SOCKET6096_13568-001,SMLF,IO,DGA^6000030    I32 @T6G_MB_LIB.T6G(SCH_1):PAGE57
   U26 CP49 VDDCR_CPU1_CP49 GENOA_SP5-SOCKET6096_13568-001,SMLF,IO,DGA^6000030    I32 @T6G_MB_LIB.T6G(SCH_1):PAGE57
   U26 CP50 VDDCR_CPU1_CP50 GENOA_SP5-SOCKET6096_13568-001,SMLF,IO,DGA^6000030    I32 @T6G_MB_LIB.T6G(SCH_1):PAGE57
   U26 CP52 VDDCR_CPU1_CP52 GENOA_SP5-SOCKET6096_13568-001,SMLF,IO,DGA^6000030    I32 @T6G_MB_LIB.T6G(SCH_1):PAGE57
   U26 CP53 VDDCR_CPU1_CP53 GENOA_SP5-SOCKET6096_13568-001,SMLF,IO,DGA^6000030    I32 @T6G_MB_LIB.T6G(SCH_1):PAGE57
   U26 CU35 VDDCR_CPU1_CU35 GENOA_SP5-SOCKET6096_13568-001,SMLF,IO,DGA^6000030    I32 @T6G_MB_LIB.T6G(SCH_1):PAGE57
   U26 CU36 VDDCR_CPU1_CU36 GENOA_SP5-SOCKET6096_13568-001,SMLF,IO,DGA^6000030    I32 @T6G_MB_LIB.T6G(SCH_1):PAGE57
   U26 CU40 VDDCR_CPU1_CU40 GENOA_SP5-SOCKET6096_13568-001,SMLF,IO,DGA^6000030    I32 @T6G_MB_LIB.T6G(SCH_1):PAGE57
   U26 CU41 VDDCR_CPU1_CU41 GENOA_SP5-SOCKET6096_13568-001,SMLF,IO,DGA^6000030    I32 @T6G_MB_LIB.T6G(SCH_1):PAGE57
   U26 CV23 VDDCR_CPU1_CV23 GENOA_SP5-SOCKET6096_13568-001,SMLF,IO,DGA^6000030    I32 @T6G_MB_LIB.T6G(SCH_1):PAGE57
   U26 CV24 VDDCR_CPU1_CV24 GENOA_SP5-SOCKET6096_13568-001,SMLF,IO,DGA^6000030    I32 @T6G_MB_LIB.T6G(SCH_1):PAGE57
   U26 CV26 VDDCR_CPU1_CV26 GENOA_SP5-SOCKET6096_13568-001,SMLF,IO,DGA^6000030    I32 @T6G_MB_LIB.T6G(SCH_1):PAGE57
   U26 CV27 VDDCR_CPU1_CV27 GENOA_SP5-SOCKET6096_13568-001,SMLF,IO,DGA^6000030    I32 @T6G_MB_LIB.T6G(SCH_1):PAGE57
   U26 CV29 VDDCR_CPU1_CV29 GENOA_SP5-SOCKET6096_13568-001,SMLF,IO,DGA^6000030    I32 @T6G_MB_LIB.T6G(SCH_1):PAGE57
   U26 CV30 VDDCR_CPU1_CV30 GENOA_SP5-SOCKET6096_13568-001,SMLF,IO,DGA^6000030    I32 @T6G_MB_LIB.T6G(SCH_1):PAGE57
   U26 CV32 VDDCR_CPU1_CV32 GENOA_SP5-SOCKET6096_13568-001,SMLF,IO,DGA^6000030    I32 @T6G_MB_LIB.T6G(SCH_1):PAGE57
   U26 CV33 VDDCR_CPU1_CV33 GENOA_SP5-SOCKET6096_13568-001,SMLF,IO,DGA^6000030    I32 @T6G_MB_LIB.T6G(SCH_1):PAGE57
   U26 CV43 VDDCR_CPU1_CV43 GENOA_SP5-SOCKET6096_13568-001,SMLF,IO,DGA^6000030    I32 @T6G_MB_LIB.T6G(SCH_1):PAGE57
   U26 CV44 VDDCR_CPU1_CV44 GENOA_SP5-SOCKET6096_13568-001,SMLF,IO,DGA^6000030    I32 @T6G_MB_LIB.T6G(SCH_1):PAGE57
   U26 CV46 VDDCR_CPU1_CV46 GENOA_SP5-SOCKET6096_13568-001,SMLF,IO,DGA^6000030    I32 @T6G_MB_LIB.T6G(SCH_1):PAGE57
   U26 CV47 VDDCR_CPU1_CV47 GENOA_SP5-SOCKET6096_13568-001,SMLF,IO,DGA^6000030    I32 @T6G_MB_LIB.T6G(SCH_1):PAGE57
   U26 CV49 VDDCR_CPU1_CV49 GENOA_SP5-SOCKET6096_13568-001,SMLF,IO,DGA^6000030    I32 @T6G_MB_LIB.T6G(SCH_1):PAGE57
   U26 CV50 VDDCR_CPU1_CV50 GENOA_SP5-SOCKET6096_13568-001,SMLF,IO,DGA^6000030    I32 @T6G_MB_LIB.T6G(SCH_1):PAGE57
   U26 CV52 VDDCR_CPU1_CV52 GENOA_SP5-SOCKET6096_13568-001,SMLF,IO,DGA^6000030    I32 @T6G_MB_LIB.T6G(SCH_1):PAGE57
   U26 CV53 VDDCR_CPU1_CV53 GENOA_SP5-SOCKET6096_13568-001,SMLF,IO,DGA^6000030    I32 @T6G_MB_LIB.T6G(SCH_1):PAGE57
   U26 DA35 VDDCR_CPU1_DA35 GENOA_SP5-SOCKET6096_13568-001,SMLF,IO,DGA^6000030    I32 @T6G_MB_LIB.T6G(SCH_1):PAGE57
   U26 DA36 VDDCR_CPU1_DA36 GENOA_SP5-SOCKET6096_13568-001,SMLF,IO,DGA^6000030    I32 @T6G_MB_LIB.T6G(SCH_1):PAGE57
   U26 DA40 VDDCR_CPU1_DA40 GENOA_SP5-SOCKET6096_13568-001,SMLF,IO,DGA^6000030    I32 @T6G_MB_LIB.T6G(SCH_1):PAGE57
   U26 DA41 VDDCR_CPU1_DA41 GENOA_SP5-SOCKET6096_13568-001,SMLF,IO,DGA^6000030    I32 @T6G_MB_LIB.T6G(SCH_1):PAGE57
   U26 DB23 VDDCR_CPU1_DB23 GENOA_SP5-SOCKET6096_13568-001,SMLF,IO,DGA^6000030    I32 @T6G_MB_LIB.T6G(SCH_1):PAGE57
   U26 DB24 VDDCR_CPU1_DB24 GENOA_SP5-SOCKET6096_13568-001,SMLF,IO,DGA^6000030    I32 @T6G_MB_LIB.T6G(SCH_1):PAGE57
   U26 DB26 VDDCR_CPU1_DB26 GENOA_SP5-SOCKET6096_13568-001,SMLF,IO,DGA^6000030    I32 @T6G_MB_LIB.T6G(SCH_1):PAGE57
   U26 DB27 VDDCR_CPU1_DB27 GENOA_SP5-SOCKET6096_13568-001,SMLF,IO,DGA^6000030    I32 @T6G_MB_LIB.T6G(SCH_1):PAGE57
   U26 DB29 VDDCR_CPU1_DB29 GENOA_SP5-SOCKET6096_13568-001,SMLF,IO,DGA^6000030    I32 @T6G_MB_LIB.T6G(SCH_1):PAGE57
   U26 DB30 VDDCR_CPU1_DB30 GENOA_SP5-SOCKET6096_13568-001,SMLF,IO,DGA^6000030    I32 @T6G_MB_LIB.T6G(SCH_1):PAGE57
   U26 DB32 VDDCR_CPU1_DB32 GENOA_SP5-SOCKET6096_13568-001,SMLF,IO,DGA^6000030    I32 @T6G_MB_LIB.T6G(SCH_1):PAGE57
   U26 DB33 VDDCR_CPU1_DB33 GENOA_SP5-SOCKET6096_13568-001,SMLF,IO,DGA^6000030    I32 @T6G_MB_LIB.T6G(SCH_1):PAGE57
   U26 DB43 VDDCR_CPU1_DB43 GENOA_SP5-SOCKET6096_13568-001,SMLF,IO,DGA^6000030    I32 @T6G_MB_LIB.T6G(SCH_1):PAGE57
   U26 DB44 VDDCR_CPU1_DB44 GENOA_SP5-SOCKET6096_13568-001,SMLF,IO,DGA^6000030    I32 @T6G_MB_LIB.T6G(SCH_1):PAGE57
   U26 DB46 VDDCR_CPU1_DB46 GENOA_SP5-SOCKET6096_13568-001,SMLF,IO,DGA^6000030    I32 @T6G_MB_LIB.T6G(SCH_1):PAGE57
   U26 DB47 VDDCR_CPU1_DB47 GENOA_SP5-SOCKET6096_13568-001,SMLF,IO,DGA^6000030    I32 @T6G_MB_LIB.T6G(SCH_1):PAGE57
   U26 DB49 VDDCR_CPU1_DB49 GENOA_SP5-SOCKET6096_13568-001,SMLF,IO,DGA^6000030    I32 @T6G_MB_LIB.T6G(SCH_1):PAGE57
   U26 DB50 VDDCR_CPU1_DB50 GENOA_SP5-SOCKET6096_13568-001,SMLF,IO,DGA^6000030    I32 @T6G_MB_LIB.T6G(SCH_1):PAGE57
   U26 DB52 VDDCR_CPU1_DB52 GENOA_SP5-SOCKET6096_13568-001,SMLF,IO,DGA^6000030    I32 @T6G_MB_LIB.T6G(SCH_1):PAGE57
   U26 DB53 VDDCR_CPU1_DB53 GENOA_SP5-SOCKET6096_13568-001,SMLF,IO,DGA^6000030    I32 @T6G_MB_LIB.T6G(SCH_1):PAGE57
   U26 DC35 VDDCR_CPU1_DC35 GENOA_SP5-SOCKET6096_13568-001,SMLF,IO,DGA^6000030    I32 @T6G_MB_LIB.T6G(SCH_1):PAGE57
   U26 DC36 VDDCR_CPU1_DC36 GENOA_SP5-SOCKET6096_13568-001,SMLF,IO,DGA^6000030    I32 @T6G_MB_LIB.T6G(SCH_1):PAGE57
   U26 DC40 VDDCR_CPU1_DC40 GENOA_SP5-SOCKET6096_13568-001,SMLF,IO,DGA^6000030    I32 @T6G_MB_LIB.T6G(SCH_1):PAGE57
   U26 DC41 VDDCR_CPU1_DC41 GENOA_SP5-SOCKET6096_13568-001,SMLF,IO,DGA^6000030    I32 @T6G_MB_LIB.T6G(SCH_1):PAGE57
   U26 DD22 VDDCR_CPU1_DD22 GENOA_SP5-SOCKET6096_13568-001,SMLF,IO,DGA^6000030    I32 @T6G_MB_LIB.T6G(SCH_1):PAGE57
   U26 DD25 VDDCR_CPU1_DD25 GENOA_SP5-SOCKET6096_13568-001,SMLF,IO,DGA^6000030    I32 @T6G_MB_LIB.T6G(SCH_1):PAGE57
   U26 DD28 VDDCR_CPU1_DD28 GENOA_SP5-SOCKET6096_13568-001,SMLF,IO,DGA^6000030    I32 @T6G_MB_LIB.T6G(SCH_1):PAGE57
   U26 DD31 VDDCR_CPU1_DD31 GENOA_SP5-SOCKET6096_13568-001,SMLF,IO,DGA^6000030    I32 @T6G_MB_LIB.T6G(SCH_1):PAGE57
   U26 DD34 VDDCR_CPU1_DD34 GENOA_SP5-SOCKET6096_13568-001,SMLF,IO,DGA^6000030    I32 @T6G_MB_LIB.T6G(SCH_1):PAGE57
   U26 DD42 VDDCR_CPU1_DD42 GENOA_SP5-SOCKET6096_13568-001,SMLF,IO,DGA^6000030    I32 @T6G_MB_LIB.T6G(SCH_1):PAGE57
   U26 DD45 VDDCR_CPU1_DD45 GENOA_SP5-SOCKET6096_13568-001,SMLF,IO,DGA^6000030    I32 @T6G_MB_LIB.T6G(SCH_1):PAGE57
   U26 DD48 VDDCR_CPU1_DD48 GENOA_SP5-SOCKET6096_13568-001,SMLF,IO,DGA^6000030    I32 @T6G_MB_LIB.T6G(SCH_1):PAGE57
   U26 DD51 VDDCR_CPU1_DD51 GENOA_SP5-SOCKET6096_13568-001,SMLF,IO,DGA^6000030    I32 @T6G_MB_LIB.T6G(SCH_1):PAGE57
   U26 DD54 VDDCR_CPU1_DD54 GENOA_SP5-SOCKET6096_13568-001,SMLF,IO,DGA^6000030    I32 @T6G_MB_LIB.T6G(SCH_1):PAGE57
   U26 DE22 VDDCR_CPU1_DE22 GENOA_SP5-SOCKET6096_13568-001,SMLF,IO,DGA^6000030    I32 @T6G_MB_LIB.T6G(SCH_1):PAGE57
   U26 DE25 VDDCR_CPU1_DE25 GENOA_SP5-SOCKET6096_13568-001,SMLF,IO,DGA^6000030    I32 @T6G_MB_LIB.T6G(SCH_1):PAGE57
   U26 DE28 VDDCR_CPU1_DE28 GENOA_SP5-SOCKET6096_13568-001,SMLF,IO,DGA^6000030    I32 @T6G_MB_LIB.T6G(SCH_1):PAGE57
   U26 DE31 VDDCR_CPU1_DE31 GENOA_SP5-SOCKET6096_13568-001,SMLF,IO,DGA^6000030    I32 @T6G_MB_LIB.T6G(SCH_1):PAGE57
   U26 DE34 VDDCR_CPU1_DE34 GENOA_SP5-SOCKET6096_13568-001,SMLF,IO,DGA^6000030    I32 @T6G_MB_LIB.T6G(SCH_1):PAGE57
   U26 DE35 VDDCR_CPU1_DE35 GENOA_SP5-SOCKET6096_13568-001,SMLF,IO,DGA^6000030    I32 @T6G_MB_LIB.T6G(SCH_1):PAGE57
   U26 DE41 VDDCR_CPU1_DE41 GENOA_SP5-SOCKET6096_13568-001,SMLF,IO,DGA^6000030    I32 @T6G_MB_LIB.T6G(SCH_1):PAGE57
   U26 DE42 VDDCR_CPU1_DE42 GENOA_SP5-SOCKET6096_13568-001,SMLF,IO,DGA^6000030    I32 @T6G_MB_LIB.T6G(SCH_1):PAGE57
   U26 DE45 VDDCR_CPU1_DE45 GENOA_SP5-SOCKET6096_13568-001,SMLF,IO,DGA^6000030    I32 @T6G_MB_LIB.T6G(SCH_1):PAGE57
   U26 DE48 VDDCR_CPU1_DE48 GENOA_SP5-SOCKET6096_13568-001,SMLF,IO,DGA^6000030    I32 @T6G_MB_LIB.T6G(SCH_1):PAGE57
   U26 DE51 VDDCR_CPU1_DE51 GENOA_SP5-SOCKET6096_13568-001,SMLF,IO,DGA^6000030    I32 @T6G_MB_LIB.T6G(SCH_1):PAGE57
   U26 DE54 VDDCR_CPU1_DE54 GENOA_SP5-SOCKET6096_13568-001,SMLF,IO,DGA^6000030    I32 @T6G_MB_LIB.T6G(SCH_1):PAGE57
   U26 DG19 VDDCR_CPU1_DG19 GENOA_SP5-SOCKET6096_13568-001,SMLF,IO,DGA^6000030    I32 @T6G_MB_LIB.T6G(SCH_1):PAGE57
   U26 DG57 VDDCR_CPU1_DG57 GENOA_SP5-SOCKET6096_13568-001,SMLF,IO,DGA^6000030    I32 @T6G_MB_LIB.T6G(SCH_1):PAGE57
   U26 DH19 VDDCR_CPU1_DH19 GENOA_SP5-SOCKET6096_13568-001,SMLF,IO,DGA^6000030    I32 @T6G_MB_LIB.T6G(SCH_1):PAGE57
   U26 DH20 VDDCR_CPU1_DH20 GENOA_SP5-SOCKET6096_13568-001,SMLF,IO,DGA^6000030    I32 @T6G_MB_LIB.T6G(SCH_1):PAGE57
   U26 DH22 VDDCR_CPU1_DH22 GENOA_SP5-SOCKET6096_13568-001,SMLF,IO,DGA^6000030    I32 @T6G_MB_LIB.T6G(SCH_1):PAGE57
   U26 DH23 VDDCR_CPU1_DH23 GENOA_SP5-SOCKET6096_13568-001,SMLF,IO,DGA^6000030    I32 @T6G_MB_LIB.T6G(SCH_1):PAGE57
   U26 DH25 VDDCR_CPU1_DH25 GENOA_SP5-SOCKET6096_13568-001,SMLF,IO,DGA^6000030    I32 @T6G_MB_LIB.T6G(SCH_1):PAGE57
   U26 DH26 VDDCR_CPU1_DH26 GENOA_SP5-SOCKET6096_13568-001,SMLF,IO,DGA^6000030    I32 @T6G_MB_LIB.T6G(SCH_1):PAGE57
   U26 DH28 VDDCR_CPU1_DH28 GENOA_SP5-SOCKET6096_13568-001,SMLF,IO,DGA^6000030    I32 @T6G_MB_LIB.T6G(SCH_1):PAGE57
   U26 DH29 VDDCR_CPU1_DH29 GENOA_SP5-SOCKET6096_13568-001,SMLF,IO,DGA^6000030    I32 @T6G_MB_LIB.T6G(SCH_1):PAGE57
   U26 DH31 VDDCR_CPU1_DH31 GENOA_SP5-SOCKET6096_13568-001,SMLF,IO,DGA^6000030    I32 @T6G_MB_LIB.T6G(SCH_1):PAGE57
   U26 DH32 VDDCR_CPU1_DH32 GENOA_SP5-SOCKET6096_13568-001,SMLF,IO,DGA^6000030    I32 @T6G_MB_LIB.T6G(SCH_1):PAGE57
   U26 DH34 VDDCR_CPU1_DH34 GENOA_SP5-SOCKET6096_13568-001,SMLF,IO,DGA^6000030    I32 @T6G_MB_LIB.T6G(SCH_1):PAGE57
   U26 DH35 VDDCR_CPU1_DH35 GENOA_SP5-SOCKET6096_13568-001,SMLF,IO,DGA^6000030    I32 @T6G_MB_LIB.T6G(SCH_1):PAGE57
   U26 DH41 VDDCR_CPU1_DH41 GENOA_SP5-SOCKET6096_13568-001,SMLF,IO,DGA^6000030    I32 @T6G_MB_LIB.T6G(SCH_1):PAGE57
   U26 DH42 VDDCR_CPU1_DH42 GENOA_SP5-SOCKET6096_13568-001,SMLF,IO,DGA^6000030    I32 @T6G_MB_LIB.T6G(SCH_1):PAGE57
   U26 DH44 VDDCR_CPU1_DH44 GENOA_SP5-SOCKET6096_13568-001,SMLF,IO,DGA^6000030    I32 @T6G_MB_LIB.T6G(SCH_1):PAGE57
   U26 DH45 VDDCR_CPU1_DH45 GENOA_SP5-SOCKET6096_13568-001,SMLF,IO,DGA^6000030    I32 @T6G_MB_LIB.T6G(SCH_1):PAGE57
   U26 DH47 VDDCR_CPU1_DH47 GENOA_SP5-SOCKET6096_13568-001,SMLF,IO,DGA^6000030    I32 @T6G_MB_LIB.T6G(SCH_1):PAGE57
   U26 DH48 VDDCR_CPU1_DH48 GENOA_SP5-SOCKET6096_13568-001,SMLF,IO,DGA^6000030    I32 @T6G_MB_LIB.T6G(SCH_1):PAGE57
   U26 DH50 VDDCR_CPU1_DH50 GENOA_SP5-SOCKET6096_13568-001,SMLF,IO,DGA^6000030    I32 @T6G_MB_LIB.T6G(SCH_1):PAGE57
   U26 DH51 VDDCR_CPU1_DH51 GENOA_SP5-SOCKET6096_13568-001,SMLF,IO,DGA^6000030    I32 @T6G_MB_LIB.T6G(SCH_1):PAGE57
   U26 DH53 VDDCR_CPU1_DH53 GENOA_SP5-SOCKET6096_13568-001,SMLF,IO,DGA^6000030    I32 @T6G_MB_LIB.T6G(SCH_1):PAGE57
   U26 DH54 VDDCR_CPU1_DH54 GENOA_SP5-SOCKET6096_13568-001,SMLF,IO,DGA^6000030    I32 @T6G_MB_LIB.T6G(SCH_1):PAGE57
   U26 DH56 VDDCR_CPU1_DH56 GENOA_SP5-SOCKET6096_13568-001,SMLF,IO,DGA^6000030    I32 @T6G_MB_LIB.T6G(SCH_1):PAGE57
   U26 DH57 VDDCR_CPU1_DH57 GENOA_SP5-SOCKET6096_13568-001,SMLF,IO,DGA^6000030    I32 @T6G_MB_LIB.T6G(SCH_1):PAGE57
 C2354    1      A Q_CAP_C0402-22UF,4V,20%,X6S,CH622KMEB02    I40 @T6G_MB_LIB.T6G(SCH_1):PAGE72
 C2360    1      A Q_CAP_C0402-22UF,4V,20%,X6S,CH622KMEB02    I41 @T6G_MB_LIB.T6G(SCH_1):PAGE72
 C2353    1      A Q_CAP_C0402-22UF,4V,20%,X6S,CH622KMEB02    I51 @T6G_MB_LIB.T6G(SCH_1):PAGE72
 C2359    1      A Q_CAP_C0402-22UF,4V,20%,X6S,CH622KMEB02    I53 @T6G_MB_LIB.T6G(SCH_1):PAGE72
 C2352    1      A Q_CAP_C0402-22UF,4V,20%,X6S,CH622KMEB02    I55 @T6G_MB_LIB.T6G(SCH_1):PAGE72
 C2351    1      A Q_CAP_C0402-22UF,4V,20%,X6S,CH622KMEB02    I56 @T6G_MB_LIB.T6G(SCH_1):PAGE72
 C2358    1      A Q_CAP_C0402-22UF,4V,20%,X6S,CH622KMEB02    I57 @T6G_MB_LIB.T6G(SCH_1):PAGE72
 C2357    1      A Q_CAP_C0402-22UF,4V,20%,X6S,CH622KMEB02    I58 @T6G_MB_LIB.T6G(SCH_1):PAGE72
 C2356    1      A Q_CAP_C0402-22UF,4V,20%,X6S,CH622KMEB02    I68 @T6G_MB_LIB.T6G(SCH_1):PAGE72
 C2366    1      A Q_CAP_C0402-22UF,4V,20%,X6S,CH622KMEB02    I70 @T6G_MB_LIB.T6G(SCH_1):PAGE72
 C2372    1      A Q_CAP_C0402-22UF,4V,20%,X6S,CH622KMEB02    I71 @T6G_MB_LIB.T6G(SCH_1):PAGE72
 C2378    1      A Q_CAP_C0402-22UF,4V,20%,X6S,CH622KMEB02    I72 @T6G_MB_LIB.T6G(SCH_1):PAGE72
 C2365    1      A Q_CAP_C0402-22UF,4V,20%,X6S,CH622KMEB02    I74 @T6G_MB_LIB.T6G(SCH_1):PAGE72
 C2371    1      A Q_CAP_C0402-22UF,4V,20%,X6S,CH622KMEB02    I75 @T6G_MB_LIB.T6G(SCH_1):PAGE72
 C2364    1      A Q_CAP_C0402-22UF,4V,20%,X6S,CH622KMEB02    I76 @T6G_MB_LIB.T6G(SCH_1):PAGE72
 C2363    1      A Q_CAP_C0402-22UF,4V,20%,X6S,CH622KMEB02    I77 @T6G_MB_LIB.T6G(SCH_1):PAGE72
 C2370    1      A Q_CAP_C0402-22UF,4V,20%,X6S,CH622KMEB02    I78 @T6G_MB_LIB.T6G(SCH_1):PAGE72
 C2369    1      A Q_CAP_C0402-22UF,4V,20%,X6S,CH622KMEB02    I79 @T6G_MB_LIB.T6G(SCH_1):PAGE72
 C2376    1      A Q_CAP_C0402-22UF,4V,20%,X6S,CH622KMEB02    I80 @T6G_MB_LIB.T6G(SCH_1):PAGE72
 C2377    1      A Q_CAP_C0402-22UF,4V,20%,X6S,CH622KMEB02    I81 @T6G_MB_LIB.T6G(SCH_1):PAGE72
 C2383    1      A Q_CAP_C0402-22UF,4V,20%,X6S,CH622KMEB02    I82 @T6G_MB_LIB.T6G(SCH_1):PAGE72
 C2389    1      A Q_CAP_C0402-22UF,4V,20%,X6S,CH622KMEB02    I83 @T6G_MB_LIB.T6G(SCH_1):PAGE72
 C2382    1      A Q_CAP_C0402-22UF,4V,20%,X6S,CH622KMEB02    I84 @T6G_MB_LIB.T6G(SCH_1):PAGE72
 C2375    1      A Q_CAP_C0402-22UF,4V,20%,X6S,CH622KMEB02    I85 @T6G_MB_LIB.T6G(SCH_1):PAGE72
 C2381    1      A Q_CAP_C0402-22UF,4V,20%,X6S,CH622KMEB02    I86 @T6G_MB_LIB.T6G(SCH_1):PAGE72
 C2388    1      A Q_CAP_C0402-22UF,4V,20%,X6S,CH622KMEB02    I87 @T6G_MB_LIB.T6G(SCH_1):PAGE72
 C2387    1      A Q_CAP_C0402-22UF,4V,20%,X6S,CH622KMEB02    I88 @T6G_MB_LIB.T6G(SCH_1):PAGE72
 C2395    1      A Q_CAP_C0402-22UF,4V,20%,X6S,CH622KMEB02    I89 @T6G_MB_LIB.T6G(SCH_1):PAGE72
 C2400    1      A Q_CAP_C0402-22UF,4V,20%,X6S,CH622KMEB02    I90 @T6G_MB_LIB.T6G(SCH_1):PAGE72
 C2394    1      A Q_CAP_C0402-22UF,4V,20%,X6S,CH622KMEB02    I91 @T6G_MB_LIB.T6G(SCH_1):PAGE72
 C2393    1      A Q_CAP_C0402-22UF,4V,20%,X6S,CH622KMEB02    I92 @T6G_MB_LIB.T6G(SCH_1):PAGE72
 C2399    1      A Q_CAP_C0402-22UF,4V,20%,X6S,CH622KMEB02    I93 @T6G_MB_LIB.T6G(SCH_1):PAGE72
 C2398    1      A Q_CAP_C0402-22UF,4V,20%,X6S,CH622KMEB02    I94 @T6G_MB_LIB.T6G(SCH_1):PAGE72
 C2405    1      A Q_CAP_C0402-22UF,4V,20%,X6S,CH622KMEB02    I96 @T6G_MB_LIB.T6G(SCH_1):PAGE72
 C2404    1      A Q_CAP_C0402-22UF,4V,20%,X6S,CH622KMEB02    I98 @T6G_MB_LIB.T6G(SCH_1):PAGE72
 C2403    1      A Q_CAP_C0402-22UF,4V,20%,X6S,CH622KMEB02   I100 @T6G_MB_LIB.T6G(SCH_1):PAGE72
 C2362    1      A Q_CAP_C0402-22UF,4V,20%,X6S,CH622KMEB02   I101 @T6G_MB_LIB.T6G(SCH_1):PAGE72
 C2368    1      A Q_CAP_C0402-22UF,4V,20%,X6S,CH622KMEB02   I102 @T6G_MB_LIB.T6G(SCH_1):PAGE72
 C2374    1      A Q_CAP_C0402-22UF,4V,20%,X6S,CH622KMEB02   I103 @T6G_MB_LIB.T6G(SCH_1):PAGE72
 C2380    1      A Q_CAP_C0402-22UF,4V,20%,X6S,CH622KMEB02   I104 @T6G_MB_LIB.T6G(SCH_1):PAGE72
 C2386    1      A Q_CAP_C0402-22UF,4V,20%,X6S,CH622KMEB02   I105 @T6G_MB_LIB.T6G(SCH_1):PAGE72
 C2392    1      A Q_CAP_C0402-22UF,4V,20%,X6S,CH622KMEB02   I106 @T6G_MB_LIB.T6G(SCH_1):PAGE72
 C2397    1      A Q_CAP_C0402-22UF,4V,20%,X6S,CH622KMEB02   I107 @T6G_MB_LIB.T6G(SCH_1):PAGE72
 C2402    1      A Q_CAP_C0402-22UF,4V,20%,X6S,CH622KMEB02   I109 @T6G_MB_LIB.T6G(SCH_1):PAGE72
 C2350    1      A Q_CAP_C0402-22UF,4V,20%,X6S,CH622KMEB02   I110 @T6G_MB_LIB.T6G(SCH_1):PAGE72
 PC106    1      A Q_CAPP_SMLF-220UF,4V,20%,SPCAP,CH122KM8801    I65 @T6G_MB_LIB.T6G(SCH_1):PAGE193
 PC387    1      A Q_CAPP_SMLF-220UF,4V,20%,SPCAP,CH122KM8801    I66 @T6G_MB_LIB.T6G(SCH_1):PAGE193
 PC388    1      A Q_CAPP_SMLF-220UF,4V,20%,SPCAP,CH122KM8801    I67 @T6G_MB_LIB.T6G(SCH_1):PAGE193
 PC391    1      A Q_CAPP_SMLF-220UF,4V,20%,SPCAP,CH122KM8801    I74 @T6G_MB_LIB.T6G(SCH_1):PAGE193
 PR342    1      A Q_RES_0402LF-1K,1%,1/16W,CHIP,CS21002FB06    I87 @T6G_MB_LIB.T6G(SCH_1):PAGE193
 PR268    2      B Q_RES_0402LF-0,5%,1/16W,CHIP,CS00002JB13    I38 @T6G_MB_LIB.T6G(SCH_1):PAGE194
  PL43    4      4 Q_INDUCTOR4P_14-150NH,SMLF,IND,CV+15^0TZ04    I50 @T6G_MB_LIB.T6G(SCH_1):PAGE194
 PR228    2      B Q_RES_0402LF-49.9,1%,1/16W,CHIP,CS04992FB07    I34 @T6G_MB_LIB.T6G(SCH_1):PAGE192
 PR260    2      B Q_RES_0402LF-0,5%,1/16W,CHIP,CS00002JB13    I38 @T6G_MB_LIB.T6G(SCH_1):PAGE193
  PL41    4      4 Q_INDUCTOR4P_14-150NH,SMLF,IND,CV+15^0TZ04    I62 @T6G_MB_LIB.T6G(SCH_1):PAGE193
 PR261    2      B Q_RES_0402LF-0,5%,1/16W,CHIP,CS00002JB13    I64 @T6G_MB_LIB.T6G(SCH_1):PAGE193
PC394_2    1      A Q_CAP_C0805-22UF,4V,20%,X6S,CH622KMEA03    I68 @T6G_MB_LIB.T6G(SCH_1):PAGE193
PC397_2    1      A Q_CAP_C0805-22UF,4V,20%,X6S,CH622KMEA03    I70 @T6G_MB_LIB.T6G(SCH_1):PAGE193
 PC389    1      A Q_CAPP_SMLF-220UF,4V,20%,SPCAP,CH122KM8801    I73 @T6G_MB_LIB.T6G(SCH_1):PAGE193
  PL40    4      4 Q_INDUCTOR4P_14-150NH,SMLF,IND,CV+15^0TZ04    I77 @T6G_MB_LIB.T6G(SCH_1):PAGE193
 PC392    1      A Q_CAP_0402-0.1UF,25V,10%,X7R,CH4104K1B00    I82 @T6G_MB_LIB.T6G(SCH_1):PAGE193
PC395_1    1      A Q_CAP_C0805-22UF,4V,20%,X6S,CH622KMEA03    I85 @T6G_MB_LIB.T6G(SCH_1):PAGE193
PC398_1    1      A Q_CAP_C0805-22UF,4V,20%,X6S,CH622KMEA03    I86 @T6G_MB_LIB.T6G(SCH_1):PAGE193
 PR269    2      B Q_RES_0402LF-0,5%,1/16W,CHIP,CS00002JB13    I49 @T6G_MB_LIB.T6G(SCH_1):PAGE194
  PL44    4      4 Q_INDUCTOR4P_14-150NH,SMLF,IND,CV+15^0TZ04    I62 @T6G_MB_LIB.T6G(SCH_1):PAGE194
PC417_3    1      A Q_CAP_C0805-22UF,4V,20%,X6S,CH622KMEA03    I64 @T6G_MB_LIB.T6G(SCH_1):PAGE194
PC418_4    1      A Q_CAP_C0805-22UF,4V,20%,X6S,CH622KMEA03    I65 @T6G_MB_LIB.T6G(SCH_1):PAGE194
PC420_4    1      A Q_CAP_C0805-22UF,4V,20%,X6S,CH622KMEA03    I67 @T6G_MB_LIB.T6G(SCH_1):PAGE194
PC419_3    1      A Q_CAP_C0805-22UF,4V,20%,X6S,CH622KMEA03    I70 @T6G_MB_LIB.T6G(SCH_1):PAGE194
 PR429    2      B Q_RES_0402LF-0,5%,1/16W,CHIP,CS00002JB13    I35 @T6G_MB_LIB.T6G(SCH_1):PAGE195
 PR273    2      B Q_RES_0402LF-0,5%,1/16W,CHIP,CS00002JB13    I49 @T6G_MB_LIB.T6G(SCH_1):PAGE195
  PL69    4      4 Q_INDUCTOR4P_14-150NH,SMLF,IND,CV+15^0TZ04    I50 @T6G_MB_LIB.T6G(SCH_1):PAGE195
  PL45    4      4 Q_INDUCTOR4P_14-150NH,SMLF,IND,CV+15^0TZ04    I63 @T6G_MB_LIB.T6G(SCH_1):PAGE195
PC148_6    1      A Q_CAP_C0805-22UF,4V,20%,X6S,CH622KMEA03    I65 @T6G_MB_LIB.T6G(SCH_1):PAGE195
PC149_6    1      A Q_CAP_C0805-22UF,4V,20%,X6S,CH622KMEA03    I67 @T6G_MB_LIB.T6G(SCH_1):PAGE195
PC430_5    1      A Q_CAP_C0805-22UF,4V,20%,X6S,CH622KMEA03    I70 @T6G_MB_LIB.T6G(SCH_1):PAGE195
PC431_5    1      A Q_CAP_C0805-22UF,4V,20%,X6S,CH622KMEA03    I71 @T6G_MB_LIB.T6G(SCH_1):PAGE195

PVDDCR_CPU1_P1_EN1_ADDR_CFG @T6G_MB_LIB.T6G(SCH_1):PVDDCR_CPU1_P1_EN1_ADDR_CFG
 PR244    1      A Q_RES_0402LF-9.53K,1%,1/16W,CHIP,CS29532FB06    I12 @T6G_MB_LIB.T6G(SCH_1):PAGE192
  PQ12    D      D MOSFET_PCH_GDS_ESD_PROTECTED-PJA3415AE,SMLF,IC,BAMA    I13 @T6G_MB_LIB.T6G(SCH_1):PAGE192
  PU34   42 EN1||ADDR_CFG RAA229620GNPHA0-RAA229620GNP#HA0,SMLF,IC,ARF0TGP40A   I128 @T6G_MB_LIB.T6G(SCH_1):PAGE192

PVDDCR_CPU1_P1_EN_R @T6G_MB_LIB.T6G(SCH_1):PVDDCR_CPU1_P1_EN_R
 C8359    1      A Q_CAP_0402-1000PF,50V,5%,X7R,TMP_QCH21006JB10    I85 @T6G_MB_LIB.T6G(SCH_1):PAGE192
 R8235    2      B Q_RES_0402LF-0,5%,1/16W,CHIP,CS00002JB13    I87 @T6G_MB_LIB.T6G(SCH_1):PAGE192
  PU34   17    EN0 RAA229620GNPHA0-RAA229620GNP#HA0,SMLF,IC,ARF0TGP40A   I128 @T6G_MB_LIB.T6G(SCH_1):PAGE192

PVDDCR_CPU1_P1_IMON1 @T6G_MB_LIB.T6G(SCH_1):PVDDCR_CPU1_P1_IMON1
  PU34   27   CS11 RAA229620GNPHA0-RAA229620GNP#HA0,SMLF,IC,ARF0TGP40A   I128 @T6G_MB_LIB.T6G(SCH_1):PAGE192
  PU35   38   IOUT ISL99390FRZTR5935-ISL99390FRZ-TR5935,SMLF,IC,AL099A    I91 @T6G_MB_LIB.T6G(SCH_1):PAGE193

PVDDCR_CPU1_P1_IMON2 @T6G_MB_LIB.T6G(SCH_1):PVDDCR_CPU1_P1_IMON2
  PU34   28   CS10 RAA229620GNPHA0-RAA229620GNP#HA0,SMLF,IC,ARF0TGP40A   I128 @T6G_MB_LIB.T6G(SCH_1):PAGE192
   PU5   38   IOUT ISL99390FRZTR5935-ISL99390FRZ-TR5935,SMLF,IC,AL099A    I31 @T6G_MB_LIB.T6G(SCH_1):PAGE193

PVDDCR_CPU1_P1_IMON3 @T6G_MB_LIB.T6G(SCH_1):PVDDCR_CPU1_P1_IMON3
  PU34   29    CS9 RAA229620GNPHA0-RAA229620GNP#HA0,SMLF,IC,ARF0TGP40A   I128 @T6G_MB_LIB.T6G(SCH_1):PAGE192
  PU37   38   IOUT ISL99390FRZTR5935-ISL99390FRZ-TR5935,SMLF,IC,AL099A    I72 @T6G_MB_LIB.T6G(SCH_1):PAGE194

PVDDCR_CPU1_P1_IMON4 @T6G_MB_LIB.T6G(SCH_1):PVDDCR_CPU1_P1_IMON4
  PU34   30    CS8 RAA229620GNPHA0-RAA229620GNP#HA0,SMLF,IC,ARF0TGP40A   I128 @T6G_MB_LIB.T6G(SCH_1):PAGE192
  PU36   38   IOUT ISL99390FRZTR5935-ISL99390FRZ-TR5935,SMLF,IC,AL099A    I21 @T6G_MB_LIB.T6G(SCH_1):PAGE194

PVDDCR_CPU1_P1_IMON5 @T6G_MB_LIB.T6G(SCH_1):PVDDCR_CPU1_P1_IMON5
  PU34   31    CS7 RAA229620GNPHA0-RAA229620GNP#HA0,SMLF,IC,ARF0TGP40A   I128 @T6G_MB_LIB.T6G(SCH_1):PAGE192
  PU38   38   IOUT ISL99390FRZTR5935-ISL99390FRZ-TR5935,SMLF,IC,AL099A    I73 @T6G_MB_LIB.T6G(SCH_1):PAGE195

PVDDCR_CPU1_P1_IMON6 @T6G_MB_LIB.T6G(SCH_1):PVDDCR_CPU1_P1_IMON6
  PU34   32    CS6 RAA229620GNPHA0-RAA229620GNP#HA0,SMLF,IC,ARF0TGP40A   I128 @T6G_MB_LIB.T6G(SCH_1):PAGE192
  PU33   38   IOUT ISL99390FRZTR5935-ISL99390FRZ-TR5935,SMLF,IC,AL099A    I19 @T6G_MB_LIB.T6G(SCH_1):PAGE195

PVDDCR_CPU1_P1_LSET1 @T6G_MB_LIB.T6G(SCH_1):PVDDCR_CPU1_P1_LSET1
 PR255    1      A Q_RES_0402LF-8.87K,1%,1/16W,EMPTY,CS28872FB01    I17 @T6G_MB_LIB.T6G(SCH_1):PAGE193
  PU35   37   LSET ISL99390FRZTR5935-ISL99390FRZ-TR5935,SMLF,IC,AL099A    I91 @T6G_MB_LIB.T6G(SCH_1):PAGE193

PVDDCR_CPU1_P1_LSET2 @T6G_MB_LIB.T6G(SCH_1):PVDDCR_CPU1_P1_LSET2
 PR254    1      A Q_RES_0402LF-8.87K,1%,1/16W,EMPTY,CS28872FB01     I4 @T6G_MB_LIB.T6G(SCH_1):PAGE193
   PU5   37   LSET ISL99390FRZTR5935-ISL99390FRZ-TR5935,SMLF,IC,AL099A    I31 @T6G_MB_LIB.T6G(SCH_1):PAGE193

PVDDCR_CPU1_P1_LSET3 @T6G_MB_LIB.T6G(SCH_1):PVDDCR_CPU1_P1_LSET3
 PR263    1      A Q_RES_0402LF-8.87K,1%,1/16W,EMPTY,CS28872FB01    I18 @T6G_MB_LIB.T6G(SCH_1):PAGE194
  PU37   37   LSET ISL99390FRZTR5935-ISL99390FRZ-TR5935,SMLF,IC,AL099A    I72 @T6G_MB_LIB.T6G(SCH_1):PAGE194

PVDDCR_CPU1_P1_LSET4 @T6G_MB_LIB.T6G(SCH_1):PVDDCR_CPU1_P1_LSET4
 PR262    1      A Q_RES_0402LF-8.87K,1%,1/16W,EMPTY,CS28872FB01     I4 @T6G_MB_LIB.T6G(SCH_1):PAGE194
  PU36   37   LSET ISL99390FRZTR5935-ISL99390FRZ-TR5935,SMLF,IC,AL099A    I21 @T6G_MB_LIB.T6G(SCH_1):PAGE194

PVDDCR_CPU1_P1_LSET5 @T6G_MB_LIB.T6G(SCH_1):PVDDCR_CPU1_P1_LSET5
 PR270    1      A Q_RES_0402LF-8.87K,1%,1/16W,EMPTY,CS28872FB01    I15 @T6G_MB_LIB.T6G(SCH_1):PAGE195
  PU38   37   LSET ISL99390FRZTR5935-ISL99390FRZ-TR5935,SMLF,IC,AL099A    I73 @T6G_MB_LIB.T6G(SCH_1):PAGE195

PVDDCR_CPU1_P1_LSET6 @T6G_MB_LIB.T6G(SCH_1):PVDDCR_CPU1_P1_LSET6
 PR426    1      A Q_RES_0402LF-8.87K,1%,1/16W,EMPTY,CS28872FB01     I4 @T6G_MB_LIB.T6G(SCH_1):PAGE195
  PU33   37   LSET ISL99390FRZTR5935-ISL99390FRZ-TR5935,SMLF,IC,AL099A    I19 @T6G_MB_LIB.T6G(SCH_1):PAGE195

PVDDCR_CPU1_P1_OCP_N @T6G_MB_LIB.T6G(SCH_1):PVDDCR_CPU1_P1_OCP_N
  R141    1      A Q_RES_0402LF-0,5%,1/16W,CHIP,CS00002JB13    I57 @T6G_MB_LIB.T6G(SCH_1):PAGE81
 R8241    1      A Q_RES_0402LF-0,5%,1/16W,CHIP,CS00002JB13    I64 @T6G_MB_LIB.T6G(SCH_1):PAGE192

PVDDCR_CPU1_P1_OCP_N_R @T6G_MB_LIB.T6G(SCH_1):PVDDCR_CPU1_P1_OCP_N_R
 R8241    2      B Q_RES_0402LF-0,5%,1/16W,CHIP,CS00002JB13    I64 @T6G_MB_LIB.T6G(SCH_1):PAGE192
 R8252    2      B Q_RES_0402LF-1K,1%,1/16W,CHIP,CS21002FB06    I71 @T6G_MB_LIB.T6G(SCH_1):PAGE192
  PU34   41  OCP_L RAA229620GNPHA0-RAA229620GNP#HA0,SMLF,IC,ARF0TGP40A   I128 @T6G_MB_LIB.T6G(SCH_1):PAGE192

PVDDCR_CPU1_P1_PVCC @T6G_MB_LIB.T6G(SCH_1):PVDDCR_CPU1_P1_PVCC
 PR257    1      A Q_RES_0402LF-2.2,1%,1/16W,CHIP,CS-2202FB01    I14 @T6G_MB_LIB.T6G(SCH_1):PAGE193
PC423_C1P1_5    1      A Q_CAP_C0402-2.2UF,10V,10%,X6S,CH5222KEB01    I31 @T6G_MB_LIB.T6G(SCH_1):PAGE195
  PU53    4   PVCC ISL99390FRZTR5935-ISL99390FRZ-TR5935,SMLF,IC,AL099A    I15 @T6G_MB_LIB.T6G(SCH_1):PAGE198
PC372_C1P1_2    1      A Q_CAP_C0402-2.2UF,10V,10%,X6S,CH5222KEB01    I15 @T6G_MB_LIB.T6G(SCH_1):PAGE193
 PR256    1      A Q_RES_0402LF-2.2,1%,1/16W,CHIP,CS-2202FB01    I27 @T6G_MB_LIB.T6G(SCH_1):PAGE193
PC371_C1P1_1    1      A Q_CAP_C0402-2.2UF,10V,10%,X6S,CH5222KEB01    I29 @T6G_MB_LIB.T6G(SCH_1):PAGE193
   PU5    4   PVCC ISL99390FRZTR5935-ISL99390FRZ-TR5935,SMLF,IC,AL099A    I31 @T6G_MB_LIB.T6G(SCH_1):PAGE193
 PR340    1      A Q_RES_0402LF-0,5%,1/16W,CHIP,CS00002JB13    I89 @T6G_MB_LIB.T6G(SCH_1):PAGE193
 PR341    1      A Q_RES_0402LF-0,5%,1/16W,EMPTY,CS00002JB13    I90 @T6G_MB_LIB.T6G(SCH_1):PAGE193
  PU35    4   PVCC ISL99390FRZTR5935-ISL99390FRZ-TR5935,SMLF,IC,AL099A    I91 @T6G_MB_LIB.T6G(SCH_1):PAGE193
 PR264    1      A Q_RES_0402LF-2.2,1%,1/16W,CHIP,CS-2202FB01    I13 @T6G_MB_LIB.T6G(SCH_1):PAGE194
PC401_C1P1_4    1      A Q_CAP_C0402-2.2UF,10V,10%,X6S,CH5222KEB01    I16 @T6G_MB_LIB.T6G(SCH_1):PAGE194
  PU36    4   PVCC ISL99390FRZTR5935-ISL99390FRZ-TR5935,SMLF,IC,AL099A    I21 @T6G_MB_LIB.T6G(SCH_1):PAGE194
 PR265    1      A Q_RES_0402LF-2.2,1%,1/16W,CHIP,CS-2202FB01    I29 @T6G_MB_LIB.T6G(SCH_1):PAGE194
PC402_C1P1_3    1      A Q_CAP_C0402-2.2UF,10V,10%,X6S,CH5222KEB01    I31 @T6G_MB_LIB.T6G(SCH_1):PAGE194
  PU37    4   PVCC ISL99390FRZTR5935-ISL99390FRZ-TR5935,SMLF,IC,AL099A    I72 @T6G_MB_LIB.T6G(SCH_1):PAGE194
 PR427    1      A Q_RES_0402LF-2.2,1%,1/16W,CHIP,CS-2202FB01    I13 @T6G_MB_LIB.T6G(SCH_1):PAGE195
  PU33    4   PVCC ISL99390FRZTR5935-ISL99390FRZ-TR5935,SMLF,IC,AL099A    I19 @T6G_MB_LIB.T6G(SCH_1):PAGE195
PC139_C1P1_6    1      A Q_CAP_C0402-2.2UF,10V,10%,X6S,CH5222KEB01    I22 @T6G_MB_LIB.T6G(SCH_1):PAGE195
 PR271    1      A Q_RES_0402LF-2.2,1%,1/16W,CHIP,CS-2202FB01    I28 @T6G_MB_LIB.T6G(SCH_1):PAGE195
  PU38    4   PVCC ISL99390FRZTR5935-ISL99390FRZ-TR5935,SMLF,IC,AL099A    I73 @T6G_MB_LIB.T6G(SCH_1):PAGE195
 PR276    1      A Q_RES_0402LF-2.2,1%,1/16W,CHIP,CS-2202FB01    I13 @T6G_MB_LIB.T6G(SCH_1):PAGE197
PC434_IOP1_2    1      A Q_CAP_C0402-2.2UF,10V,10%,X6S,CH5222KEB01    I16 @T6G_MB_LIB.T6G(SCH_1):PAGE197
 PR277    1      A Q_RES_0402LF-2.2,1%,1/16W,CHIP,CS-2202FB01    I35 @T6G_MB_LIB.T6G(SCH_1):PAGE197
PC437_IOP1_1    1      A Q_CAP_C0402-2.2UF,10V,10%,X6S,CH5222KEB01    I38 @T6G_MB_LIB.T6G(SCH_1):PAGE197
  PU39    4   PVCC ISL99390FRZTR5935-ISL99390FRZ-TR5935,SMLF,IC,AL099A    I39 @T6G_MB_LIB.T6G(SCH_1):PAGE197
  PU40    4   PVCC ISL99390FRZTR5935-ISL99390FRZ-TR5935,SMLF,IC,AL099A    I84 @T6G_MB_LIB.T6G(SCH_1):PAGE197
 PR370    1      A Q_RES_0402LF-2.2,1%,1/16W,CHIP,CS-2202FB01    I12 @T6G_MB_LIB.T6G(SCH_1):PAGE198
PC618_IOP1_4    1      A Q_CAP_C0402-2.2UF,10V,10%,X6S,CH5222KEB01    I13 @T6G_MB_LIB.T6G(SCH_1):PAGE198
 PR371    1      A Q_RES_0402LF-2.2,1%,1/16W,CHIP,CS-2202FB01    I29 @T6G_MB_LIB.T6G(SCH_1):PAGE198
PC619_IOP1_3    1      A Q_CAP_C0402-2.2UF,10V,10%,X6S,CH5222KEB01    I31 @T6G_MB_LIB.T6G(SCH_1):PAGE198
  PU52    4   PVCC ISL99390FRZTR5935-ISL99390FRZ-TR5935,SMLF,IC,AL099A    I73 @T6G_MB_LIB.T6G(SCH_1):PAGE198

PVDDCR_CPU1_P1_PWM1 @T6G_MB_LIB.T6G(SCH_1):PVDDCR_CPU1_P1_PWM1
  PU34   12  PWM11 RAA229620GNPHA0-RAA229620GNP#HA0,SMLF,IC,ARF0TGP40A   I128 @T6G_MB_LIB.T6G(SCH_1):PAGE192
  PU35   34    PWM ISL99390FRZTR5935-ISL99390FRZ-TR5935,SMLF,IC,AL099A    I91 @T6G_MB_LIB.T6G(SCH_1):PAGE193

PVDDCR_CPU1_P1_PWM2 @T6G_MB_LIB.T6G(SCH_1):PVDDCR_CPU1_P1_PWM2
  PU34   11  PWM10 RAA229620GNPHA0-RAA229620GNP#HA0,SMLF,IC,ARF0TGP40A   I128 @T6G_MB_LIB.T6G(SCH_1):PAGE192
   PU5   34    PWM ISL99390FRZTR5935-ISL99390FRZ-TR5935,SMLF,IC,AL099A    I31 @T6G_MB_LIB.T6G(SCH_1):PAGE193

PVDDCR_CPU1_P1_PWM3 @T6G_MB_LIB.T6G(SCH_1):PVDDCR_CPU1_P1_PWM3
  PU34   10   PWM9 RAA229620GNPHA0-RAA229620GNP#HA0,SMLF,IC,ARF0TGP40A   I128 @T6G_MB_LIB.T6G(SCH_1):PAGE192
  PU37   34    PWM ISL99390FRZTR5935-ISL99390FRZ-TR5935,SMLF,IC,AL099A    I72 @T6G_MB_LIB.T6G(SCH_1):PAGE194

PVDDCR_CPU1_P1_PWM4 @T6G_MB_LIB.T6G(SCH_1):PVDDCR_CPU1_P1_PWM4
  PU34    9   PWM8 RAA229620GNPHA0-RAA229620GNP#HA0,SMLF,IC,ARF0TGP40A   I128 @T6G_MB_LIB.T6G(SCH_1):PAGE192
  PU36   34    PWM ISL99390FRZTR5935-ISL99390FRZ-TR5935,SMLF,IC,AL099A    I21 @T6G_MB_LIB.T6G(SCH_1):PAGE194

PVDDCR_CPU1_P1_PWM5 @T6G_MB_LIB.T6G(SCH_1):PVDDCR_CPU1_P1_PWM5
  PU34    8   PWM7 RAA229620GNPHA0-RAA229620GNP#HA0,SMLF,IC,ARF0TGP40A   I128 @T6G_MB_LIB.T6G(SCH_1):PAGE192
  PU38   34    PWM ISL99390FRZTR5935-ISL99390FRZ-TR5935,SMLF,IC,AL099A    I73 @T6G_MB_LIB.T6G(SCH_1):PAGE195

PVDDCR_CPU1_P1_PWM6 @T6G_MB_LIB.T6G(SCH_1):PVDDCR_CPU1_P1_PWM6
  PU34    7   PWM6 RAA229620GNPHA0-RAA229620GNP#HA0,SMLF,IC,ARF0TGP40A   I128 @T6G_MB_LIB.T6G(SCH_1):PAGE192
  PU33   34    PWM ISL99390FRZTR5935-ISL99390FRZ-TR5935,SMLF,IC,AL099A    I19 @T6G_MB_LIB.T6G(SCH_1):PAGE195

PVDDCR_CPU1_P1_RESET_N @T6G_MB_LIB.T6G(SCH_1):PVDDCR_CPU1_P1_RESET_N
   U40    4     2Y SN74LVC2G07DCKR_SMLF-SN74LVC2G07DCKR,IC,AL002G07006    I21 @T6G_MB_LIB.T6G(SCH_1):PAGE77
  R240    1      A Q_RES_0402LF-100,1%,1/16W,CHIP,CS11002FB07    I65 @T6G_MB_LIB.T6G(SCH_1):PAGE192

PVDDCR_CPU1_P1_RESET_N_R @T6G_MB_LIB.T6G(SCH_1):PVDDCR_CPU1_P1_RESET_N_R
  R240    2      B Q_RES_0402LF-100,1%,1/16W,CHIP,CS11002FB07    I65 @T6G_MB_LIB.T6G(SCH_1):PAGE192
 R8247    2      B Q_RES_0402LF-1K,1%,1/16W,CHIP,CS21002FB06    I66 @T6G_MB_LIB.T6G(SCH_1):PAGE192
  PU34   18 RESET_L RAA229620GNPHA0-RAA229620GNP#HA0,SMLF,IC,ARF0TGP40A   I128 @T6G_MB_LIB.T6G(SCH_1):PAGE192

PVDDCR_CPU1_P1_SMB_ALERT @T6G_MB_LIB.T6G(SCH_1):PVDDCR_CPU1_P1_SMB_ALERT
 R1188    1      A Q_RES_0402LF-1K,1%,1/16W,CHIP,CS21002FB06    I61 @T6G_MB_LIB.T6G(SCH_1):PAGE82
   U18   L6  PL14C LCMXO3LF9400C5BG484C-LCMXO3LF-9400C-5BG484C,SMLF,IA   I143 @T6G_MB_LIB.T6G(SCH_1):PAGE81
 R8250    1      A Q_RES_0402LF-33,5%,1/16W,CHIP,CS03302JB10    I80 @T6G_MB_LIB.T6G(SCH_1):PAGE192
 C5020    2      B Q_CAP_0402-1000PF,50V,5%,X7R,TMP_QCH21006JB10   I133 @T6G_MB_LIB.T6G(SCH_1):PAGE192

PVDDCR_CPU1_P1_SMB_ALERT_R @T6G_MB_LIB.T6G(SCH_1):PVDDCR_CPU1_P1_SMB_ALERT_R
 R8250    2      B Q_RES_0402LF-33,5%,1/16W,CHIP,CS03302JB10    I80 @T6G_MB_LIB.T6G(SCH_1):PAGE192
  PU34   15 NPMALERT RAA229620GNPHA0-RAA229620GNP#HA0,SMLF,IC,ARF0TGP40A   I128 @T6G_MB_LIB.T6G(SCH_1):PAGE192

PVDDCR_CPU1_P1_TEMP0 @T6G_MB_LIB.T6G(SCH_1):PVDDCR_CPU1_P1_TEMP0
 PC368    1      A Q_CAP_0402-470PF,50V,10%,X7R,TMP_QCH14706KB18    I73 @T6G_MB_LIB.T6G(SCH_1):PAGE192
  PU34   44  TEMP0 RAA229620GNPHA0-RAA229620GNP#HA0,SMLF,IC,ARF0TGP40A   I128 @T6G_MB_LIB.T6G(SCH_1):PAGE192
   PU5   36 TOUT_FLT ISL99390FRZTR5935-ISL99390FRZ-TR5935,SMLF,IC,AL099A    I31 @T6G_MB_LIB.T6G(SCH_1):PAGE193
  PU35   36 TOUT_FLT ISL99390FRZTR5935-ISL99390FRZ-TR5935,SMLF,IC,AL099A    I91 @T6G_MB_LIB.T6G(SCH_1):PAGE193
  PU36   36 TOUT_FLT ISL99390FRZTR5935-ISL99390FRZ-TR5935,SMLF,IC,AL099A    I21 @T6G_MB_LIB.T6G(SCH_1):PAGE194
  PU37   36 TOUT_FLT ISL99390FRZTR5935-ISL99390FRZ-TR5935,SMLF,IC,AL099A    I72 @T6G_MB_LIB.T6G(SCH_1):PAGE194
  PU33   36 TOUT_FLT ISL99390FRZTR5935-ISL99390FRZ-TR5935,SMLF,IC,AL099A    I19 @T6G_MB_LIB.T6G(SCH_1):PAGE195
  PU38   36 TOUT_FLT ISL99390FRZTR5935-ISL99390FRZ-TR5935,SMLF,IC,AL099A    I73 @T6G_MB_LIB.T6G(SCH_1):PAGE195

PVDDCR_CPU1_P1_VCC @T6G_MB_LIB.T6G(SCH_1):PVDDCR_CPU1_P1_VCC
  PC29    1      A Q_CAP_0402-0.1UF,25V,10%,X7R,CH4104K1B00    I95 @T6G_MB_LIB.T6G(SCH_1):PAGE192
 PC365    1      A Q_CAP_C0402-1UF,16V,10%,X6S,CH5103KEB01    I99 @T6G_MB_LIB.T6G(SCH_1):PAGE192
 PR253    1      A Q_RES_0402LF-1,1%,1/16W,CHIP,CS-1002FB04   I124 @T6G_MB_LIB.T6G(SCH_1):PAGE192
  PU34   47    VCC RAA229620GNPHA0-RAA229620GNP#HA0,SMLF,IC,ARF0TGP40A   I128 @T6G_MB_LIB.T6G(SCH_1):PAGE192

PVDDCR_CPU1_P1_VCC1 @T6G_MB_LIB.T6G(SCH_1):PVDDCR_CPU1_P1_VCC1
 PC369    1      A Q_CAP_C0402-2.2UF,10V,10%,X6S,CH5222KEB01    I23 @T6G_MB_LIB.T6G(SCH_1):PAGE193
 PR256    2      B Q_RES_0402LF-2.2,1%,1/16W,CHIP,CS-2202FB01    I27 @T6G_MB_LIB.T6G(SCH_1):PAGE193
  PU35   35     EN ISL99390FRZTR5935-ISL99390FRZ-TR5935,SMLF,IC,AL099A    I91 @T6G_MB_LIB.T6G(SCH_1):PAGE193
  PU35    3    VCC ISL99390FRZTR5935-ISL99390FRZ-TR5935,SMLF,IC,AL099A    I91 @T6G_MB_LIB.T6G(SCH_1):PAGE193

PVDDCR_CPU1_P1_VCC2 @T6G_MB_LIB.T6G(SCH_1):PVDDCR_CPU1_P1_VCC2
 PR257    2      B Q_RES_0402LF-2.2,1%,1/16W,CHIP,CS-2202FB01    I14 @T6G_MB_LIB.T6G(SCH_1):PAGE193
 PC370    1      A Q_CAP_C0402-2.2UF,10V,10%,X6S,CH5222KEB01    I12 @T6G_MB_LIB.T6G(SCH_1):PAGE193
   PU5   35     EN ISL99390FRZTR5935-ISL99390FRZ-TR5935,SMLF,IC,AL099A    I31 @T6G_MB_LIB.T6G(SCH_1):PAGE193
   PU5    3    VCC ISL99390FRZTR5935-ISL99390FRZ-TR5935,SMLF,IC,AL099A    I31 @T6G_MB_LIB.T6G(SCH_1):PAGE193

PVDDCR_CPU1_P1_VCC3 @T6G_MB_LIB.T6G(SCH_1):PVDDCR_CPU1_P1_VCC3
 PC400    1      A Q_CAP_C0402-2.2UF,10V,10%,X6S,CH5222KEB01    I27 @T6G_MB_LIB.T6G(SCH_1):PAGE194
 PR265    2      B Q_RES_0402LF-2.2,1%,1/16W,CHIP,CS-2202FB01    I29 @T6G_MB_LIB.T6G(SCH_1):PAGE194
  PU37   35     EN ISL99390FRZTR5935-ISL99390FRZ-TR5935,SMLF,IC,AL099A    I72 @T6G_MB_LIB.T6G(SCH_1):PAGE194
  PU37    3    VCC ISL99390FRZTR5935-ISL99390FRZ-TR5935,SMLF,IC,AL099A    I72 @T6G_MB_LIB.T6G(SCH_1):PAGE194

PVDDCR_CPU1_P1_VCC4 @T6G_MB_LIB.T6G(SCH_1):PVDDCR_CPU1_P1_VCC4
 PC399    1      A Q_CAP_C0402-2.2UF,10V,10%,X6S,CH5222KEB01     I7 @T6G_MB_LIB.T6G(SCH_1):PAGE194
 PR264    2      B Q_RES_0402LF-2.2,1%,1/16W,CHIP,CS-2202FB01    I13 @T6G_MB_LIB.T6G(SCH_1):PAGE194
  PU36   35     EN ISL99390FRZTR5935-ISL99390FRZ-TR5935,SMLF,IC,AL099A    I21 @T6G_MB_LIB.T6G(SCH_1):PAGE194
  PU36    3    VCC ISL99390FRZTR5935-ISL99390FRZ-TR5935,SMLF,IC,AL099A    I21 @T6G_MB_LIB.T6G(SCH_1):PAGE194

PVDDCR_CPU1_P1_VCC5 @T6G_MB_LIB.T6G(SCH_1):PVDDCR_CPU1_P1_VCC5
 PC421    1      A Q_CAP_C0402-2.2UF,10V,10%,X6S,CH5222KEB01    I27 @T6G_MB_LIB.T6G(SCH_1):PAGE195
 PR271    2      B Q_RES_0402LF-2.2,1%,1/16W,CHIP,CS-2202FB01    I28 @T6G_MB_LIB.T6G(SCH_1):PAGE195
  PU38   35     EN ISL99390FRZTR5935-ISL99390FRZ-TR5935,SMLF,IC,AL099A    I73 @T6G_MB_LIB.T6G(SCH_1):PAGE195
  PU38    3    VCC ISL99390FRZTR5935-ISL99390FRZ-TR5935,SMLF,IC,AL099A    I73 @T6G_MB_LIB.T6G(SCH_1):PAGE195

PVDDCR_CPU1_P1_VCC6 @T6G_MB_LIB.T6G(SCH_1):PVDDCR_CPU1_P1_VCC6
 PC138    1      A Q_CAP_C0402-2.2UF,10V,10%,X6S,CH5222KEB01    I12 @T6G_MB_LIB.T6G(SCH_1):PAGE195
 PR427    2      B Q_RES_0402LF-2.2,1%,1/16W,CHIP,CS-2202FB01    I13 @T6G_MB_LIB.T6G(SCH_1):PAGE195
  PU33   35     EN ISL99390FRZTR5935-ISL99390FRZ-TR5935,SMLF,IC,AL099A    I19 @T6G_MB_LIB.T6G(SCH_1):PAGE195
  PU33    3    VCC ISL99390FRZTR5935-ISL99390FRZ-TR5935,SMLF,IC,AL099A    I19 @T6G_MB_LIB.T6G(SCH_1):PAGE195

PVDDCR_CPU1_P1_VCCS @T6G_MB_LIB.T6G(SCH_1):PVDDCR_CPU1_P1_VCCS
PC373_2    1      A Q_CAP_0402-0.1UF,25V,10%,X7R,CH4104K1B00     I2 @T6G_MB_LIB.T6G(SCH_1):PAGE193
PC403_4    1      A Q_CAP_0402-0.1UF,25V,10%,X7R,CH4104K1B00     I2 @T6G_MB_LIB.T6G(SCH_1):PAGE194
PC621_10    1      A Q_CAP_0402-0.1UF,25V,10%,X7R,CH4104K1B00     I2 @T6G_MB_LIB.T6G(SCH_1):PAGE198
  PU53   39  REFIN ISL99390FRZTR5935-ISL99390FRZ-TR5935,SMLF,IC,AL099A    I15 @T6G_MB_LIB.T6G(SCH_1):PAGE198
  PC93    1      A Q_CAP_0402-0.1UF,25V,10%,X7R,CH4104K1B00    I93 @T6G_MB_LIB.T6G(SCH_1):PAGE192
 PC366    1      A Q_CAP_C0402-10UF,6.3V,20%,X6S,CH6101MEB03    I97 @T6G_MB_LIB.T6G(SCH_1):PAGE192
  PU34   48   VCCS RAA229620GNPHA0-RAA229620GNP#HA0,SMLF,IC,ARF0TGP40A   I128 @T6G_MB_LIB.T6G(SCH_1):PAGE192
PC374_1    1      A Q_CAP_0402-0.1UF,25V,10%,X7R,CH4104K1B00    I11 @T6G_MB_LIB.T6G(SCH_1):PAGE193
   PU5   39  REFIN ISL99390FRZTR5935-ISL99390FRZ-TR5935,SMLF,IC,AL099A    I31 @T6G_MB_LIB.T6G(SCH_1):PAGE193
  PU35   39  REFIN ISL99390FRZTR5935-ISL99390FRZ-TR5935,SMLF,IC,AL099A    I91 @T6G_MB_LIB.T6G(SCH_1):PAGE193
PC404_3    1      A Q_CAP_0402-0.1UF,25V,10%,X7R,CH4104K1B00    I12 @T6G_MB_LIB.T6G(SCH_1):PAGE194
  PU36   39  REFIN ISL99390FRZTR5935-ISL99390FRZ-TR5935,SMLF,IC,AL099A    I21 @T6G_MB_LIB.T6G(SCH_1):PAGE194
  PU37   39  REFIN ISL99390FRZTR5935-ISL99390FRZ-TR5935,SMLF,IC,AL099A    I72 @T6G_MB_LIB.T6G(SCH_1):PAGE194
PC136_6    1      A Q_CAP_0402-0.1UF,25V,10%,X7R,CH4104K1B00     I1 @T6G_MB_LIB.T6G(SCH_1):PAGE195
PC422_5    1      A Q_CAP_0402-0.1UF,25V,10%,X7R,CH4104K1B00    I10 @T6G_MB_LIB.T6G(SCH_1):PAGE195
  PU33   39  REFIN ISL99390FRZTR5935-ISL99390FRZ-TR5935,SMLF,IC,AL099A    I19 @T6G_MB_LIB.T6G(SCH_1):PAGE195
  PU38   39  REFIN ISL99390FRZTR5935-ISL99390FRZ-TR5935,SMLF,IC,AL099A    I73 @T6G_MB_LIB.T6G(SCH_1):PAGE195
PC436_8    1      A Q_CAP_0402-0.1UF,25V,10%,X7R,CH4104K1B00     I3 @T6G_MB_LIB.T6G(SCH_1):PAGE197
PC435_7    1      A Q_CAP_0402-0.1UF,25V,10%,X7R,CH4104K1B00     I4 @T6G_MB_LIB.T6G(SCH_1):PAGE197
  PU39   39  REFIN ISL99390FRZTR5935-ISL99390FRZ-TR5935,SMLF,IC,AL099A    I39 @T6G_MB_LIB.T6G(SCH_1):PAGE197
  PU40   39  REFIN ISL99390FRZTR5935-ISL99390FRZ-TR5935,SMLF,IC,AL099A    I84 @T6G_MB_LIB.T6G(SCH_1):PAGE197
PC620_9    1      A Q_CAP_0402-0.1UF,25V,10%,X7R,CH4104K1B00    I20 @T6G_MB_LIB.T6G(SCH_1):PAGE198
  PU52   39  REFIN ISL99390FRZTR5935-ISL99390FRZ-TR5935,SMLF,IC,AL099A    I73 @T6G_MB_LIB.T6G(SCH_1):PAGE198

PVDDCR_CPU1_P1_VINSEN @T6G_MB_LIB.T6G(SCH_1):PVDDCR_CPU1_P1_VINSEN
 PR251    2      B Q_RES_0402LF-0,5%,1/16W,CHIP,CS00002JB13    I49 @T6G_MB_LIB.T6G(SCH_1):PAGE192
 PR603    1      A Q_RES_0402LF-4.99K,1%,1/16W,EMPTY,CS24992FB07    I55 @T6G_MB_LIB.T6G(SCH_1):PAGE192
 PC364    1      A Q_CAP_0402-0.1UF,25V,10%,X7R,CH4104K1B00    I56 @T6G_MB_LIB.T6G(SCH_1):PAGE192
  PU34   46 VINSEN RAA229620GNPHA0-RAA229620GNP#HA0,SMLF,IC,ARF0TGP40A   I128 @T6G_MB_LIB.T6G(SCH_1):PAGE192

PVDDCR_CPU1_P1_VMON @T6G_MB_LIB.T6G(SCH_1):PVDDCR_CPU1_P1_VMON
 PR231    1      A Q_RES_0402LF-10K,1%,1/16W,CHIP,CS31002FB08     I8 @T6G_MB_LIB.T6G(SCH_1):PAGE192
 PR230    2      B Q_RES_0402LF-40.2K,1%,1/16W,CHIP,CS34022FB04     I9 @T6G_MB_LIB.T6G(SCH_1):PAGE192
 PC357    1      A Q_CAP_0402-0.1UF,25V,10%,X7R,CH4104K1B00    I47 @T6G_MB_LIB.T6G(SCH_1):PAGE192
  PU34   45 VMON||IINSEN RAA229620GNPHA0-RAA229620GNP#HA0,SMLF,IC,ARF0TGP40A   I128 @T6G_MB_LIB.T6G(SCH_1):PAGE192

PVDDCR_CPU1_P1_VOS1 @T6G_MB_LIB.T6G(SCH_1):PVDDCR_CPU1_P1_VOS1
 PR261    1      A Q_RES_0402LF-0,5%,1/16W,CHIP,CS00002JB13    I64 @T6G_MB_LIB.T6G(SCH_1):PAGE193
  PU35    1    VOS ISL99390FRZTR5935-ISL99390FRZ-TR5935,SMLF,IC,AL099A    I91 @T6G_MB_LIB.T6G(SCH_1):PAGE193

PVDDCR_CPU1_P1_VOS2 @T6G_MB_LIB.T6G(SCH_1):PVDDCR_CPU1_P1_VOS2
   PU5    1    VOS ISL99390FRZTR5935-ISL99390FRZ-TR5935,SMLF,IC,AL099A    I31 @T6G_MB_LIB.T6G(SCH_1):PAGE193
 PR260    1      A Q_RES_0402LF-0,5%,1/16W,CHIP,CS00002JB13    I38 @T6G_MB_LIB.T6G(SCH_1):PAGE193

PVDDCR_CPU1_P1_VOS3 @T6G_MB_LIB.T6G(SCH_1):PVDDCR_CPU1_P1_VOS3
 PR269    1      A Q_RES_0402LF-0,5%,1/16W,CHIP,CS00002JB13    I49 @T6G_MB_LIB.T6G(SCH_1):PAGE194
  PU37    1    VOS ISL99390FRZTR5935-ISL99390FRZ-TR5935,SMLF,IC,AL099A    I72 @T6G_MB_LIB.T6G(SCH_1):PAGE194

PVDDCR_CPU1_P1_VOS4 @T6G_MB_LIB.T6G(SCH_1):PVDDCR_CPU1_P1_VOS4
 PR268    1      A Q_RES_0402LF-0,5%,1/16W,CHIP,CS00002JB13    I38 @T6G_MB_LIB.T6G(SCH_1):PAGE194
  PU36    1    VOS ISL99390FRZTR5935-ISL99390FRZ-TR5935,SMLF,IC,AL099A    I21 @T6G_MB_LIB.T6G(SCH_1):PAGE194

PVDDCR_CPU1_P1_VOS5 @T6G_MB_LIB.T6G(SCH_1):PVDDCR_CPU1_P1_VOS5
 PR273    1      A Q_RES_0402LF-0,5%,1/16W,CHIP,CS00002JB13    I49 @T6G_MB_LIB.T6G(SCH_1):PAGE195
  PU38    1    VOS ISL99390FRZTR5935-ISL99390FRZ-TR5935,SMLF,IC,AL099A    I73 @T6G_MB_LIB.T6G(SCH_1):PAGE195

PVDDCR_CPU1_P1_VOS6 @T6G_MB_LIB.T6G(SCH_1):PVDDCR_CPU1_P1_VOS6
  PU33    1    VOS ISL99390FRZTR5935-ISL99390FRZ-TR5935,SMLF,IC,AL099A    I19 @T6G_MB_LIB.T6G(SCH_1):PAGE195
 PR429    1      A Q_RES_0402LF-0,5%,1/16W,CHIP,CS00002JB13    I35 @T6G_MB_LIB.T6G(SCH_1):PAGE195

PVDDCR_SOC_P0 @T6G_MB_LIB.T6G(SCH_1):PVDDCR_SOC_P0
   U25 AA22 VDDCR_SOC_AA22 GENOA_SP5-SOCKET6096_13568-001,SMLF,IO,DGA^6000030    I50 @T6G_MB_LIB.T6G(SCH_1):PAGE30
   U25  AC4 VDDCR_SOC_AC4 GENOA_SP5-SOCKET6096_13568-001,SMLF,IO,DGA^6000030    I50 @T6G_MB_LIB.T6G(SCH_1):PAGE30
   U25 AC11 VDDCR_SOC_AC11 GENOA_SP5-SOCKET6096_13568-001,SMLF,IO,DGA^6000030    I50 @T6G_MB_LIB.T6G(SCH_1):PAGE30
   U25 AC18 VDDCR_SOC_AC18 GENOA_SP5-SOCKET6096_13568-001,SMLF,IO,DGA^6000030    I50 @T6G_MB_LIB.T6G(SCH_1):PAGE30
   U25 AD22 VDDCR_SOC_AD22 GENOA_SP5-SOCKET6096_13568-001,SMLF,IO,DGA^6000030    I50 @T6G_MB_LIB.T6G(SCH_1):PAGE30
   U25  AF5 VDDCR_SOC_AF5 GENOA_SP5-SOCKET6096_13568-001,SMLF,IO,DGA^6000030    I50 @T6G_MB_LIB.T6G(SCH_1):PAGE30
   U25 AF12 VDDCR_SOC_AF12 GENOA_SP5-SOCKET6096_13568-001,SMLF,IO,DGA^6000030    I50 @T6G_MB_LIB.T6G(SCH_1):PAGE30
   U25 AF19 VDDCR_SOC_AF19 GENOA_SP5-SOCKET6096_13568-001,SMLF,IO,DGA^6000030    I50 @T6G_MB_LIB.T6G(SCH_1):PAGE30
   U25 AH22 VDDCR_SOC_AH22 GENOA_SP5-SOCKET6096_13568-001,SMLF,IO,DGA^6000030    I50 @T6G_MB_LIB.T6G(SCH_1):PAGE30
   U25  AJ4 VDDCR_SOC_AJ4 GENOA_SP5-SOCKET6096_13568-001,SMLF,IO,DGA^6000030    I50 @T6G_MB_LIB.T6G(SCH_1):PAGE30
   U25 AJ11 VDDCR_SOC_AJ11 GENOA_SP5-SOCKET6096_13568-001,SMLF,IO,DGA^6000030    I50 @T6G_MB_LIB.T6G(SCH_1):PAGE30
   U25 AJ18 VDDCR_SOC_AJ18 GENOA_SP5-SOCKET6096_13568-001,SMLF,IO,DGA^6000030    I50 @T6G_MB_LIB.T6G(SCH_1):PAGE30
   U25  AM5 VDDCR_SOC_AM5 GENOA_SP5-SOCKET6096_13568-001,SMLF,IO,DGA^6000030    I50 @T6G_MB_LIB.T6G(SCH_1):PAGE30
   U25 AM12 VDDCR_SOC_AM12 GENOA_SP5-SOCKET6096_13568-001,SMLF,IO,DGA^6000030    I50 @T6G_MB_LIB.T6G(SCH_1):PAGE30
   U25 AM19 VDDCR_SOC_AM19 GENOA_SP5-SOCKET6096_13568-001,SMLF,IO,DGA^6000030    I50 @T6G_MB_LIB.T6G(SCH_1):PAGE30
   U25 AM22 VDDCR_SOC_AM22 GENOA_SP5-SOCKET6096_13568-001,SMLF,IO,DGA^6000030    I50 @T6G_MB_LIB.T6G(SCH_1):PAGE30
   U25  AR4 VDDCR_SOC_AR4 GENOA_SP5-SOCKET6096_13568-001,SMLF,IO,DGA^6000030    I50 @T6G_MB_LIB.T6G(SCH_1):PAGE30
   U25 AR11 VDDCR_SOC_AR11 GENOA_SP5-SOCKET6096_13568-001,SMLF,IO,DGA^6000030    I50 @T6G_MB_LIB.T6G(SCH_1):PAGE30
   U25 AR18 VDDCR_SOC_AR18 GENOA_SP5-SOCKET6096_13568-001,SMLF,IO,DGA^6000030    I50 @T6G_MB_LIB.T6G(SCH_1):PAGE30
   U25 AT22 VDDCR_SOC_AT22 GENOA_SP5-SOCKET6096_13568-001,SMLF,IO,DGA^6000030    I50 @T6G_MB_LIB.T6G(SCH_1):PAGE30
   U25 AU23 VDDCR_SOC_AU23 GENOA_SP5-SOCKET6096_13568-001,SMLF,IO,DGA^6000030    I50 @T6G_MB_LIB.T6G(SCH_1):PAGE30
   U25 AU27 VDDCR_SOC_AU27 GENOA_SP5-SOCKET6096_13568-001,SMLF,IO,DGA^6000030    I50 @T6G_MB_LIB.T6G(SCH_1):PAGE30
   U25 AU31 VDDCR_SOC_AU31 GENOA_SP5-SOCKET6096_13568-001,SMLF,IO,DGA^6000030    I50 @T6G_MB_LIB.T6G(SCH_1):PAGE30
   U25 AU35 VDDCR_SOC_AU35 GENOA_SP5-SOCKET6096_13568-001,SMLF,IO,DGA^6000030    I50 @T6G_MB_LIB.T6G(SCH_1):PAGE30
   U25 AU40 VDDCR_SOC_AU40 GENOA_SP5-SOCKET6096_13568-001,SMLF,IO,DGA^6000030    I50 @T6G_MB_LIB.T6G(SCH_1):PAGE30
   U25  AV5 VDDCR_SOC_AV5 GENOA_SP5-SOCKET6096_13568-001,SMLF,IO,DGA^6000030    I50 @T6G_MB_LIB.T6G(SCH_1):PAGE30
   U25 AV12 VDDCR_SOC_AV12 GENOA_SP5-SOCKET6096_13568-001,SMLF,IO,DGA^6000030    I50 @T6G_MB_LIB.T6G(SCH_1):PAGE30
   U25 AV19 VDDCR_SOC_AV19 GENOA_SP5-SOCKET6096_13568-001,SMLF,IO,DGA^6000030    I50 @T6G_MB_LIB.T6G(SCH_1):PAGE30
   U25 AV22 VDDCR_SOC_AV22 GENOA_SP5-SOCKET6096_13568-001,SMLF,IO,DGA^6000030    I50 @T6G_MB_LIB.T6G(SCH_1):PAGE30
   U25 AV24 VDDCR_SOC_AV24 GENOA_SP5-SOCKET6096_13568-001,SMLF,IO,DGA^6000030    I50 @T6G_MB_LIB.T6G(SCH_1):PAGE30
   U25 AV26 VDDCR_SOC_AV26 GENOA_SP5-SOCKET6096_13568-001,SMLF,IO,DGA^6000030    I50 @T6G_MB_LIB.T6G(SCH_1):PAGE30
   U25 AV28 VDDCR_SOC_AV28 GENOA_SP5-SOCKET6096_13568-001,SMLF,IO,DGA^6000030    I50 @T6G_MB_LIB.T6G(SCH_1):PAGE30
   U25 AV30 VDDCR_SOC_AV30 GENOA_SP5-SOCKET6096_13568-001,SMLF,IO,DGA^6000030    I50 @T6G_MB_LIB.T6G(SCH_1):PAGE30
   U25 AV32 VDDCR_SOC_AV32 GENOA_SP5-SOCKET6096_13568-001,SMLF,IO,DGA^6000030    I50 @T6G_MB_LIB.T6G(SCH_1):PAGE30
   U25 AV34 VDDCR_SOC_AV34 GENOA_SP5-SOCKET6096_13568-001,SMLF,IO,DGA^6000030    I50 @T6G_MB_LIB.T6G(SCH_1):PAGE30
   U25 AV36 VDDCR_SOC_AV36 GENOA_SP5-SOCKET6096_13568-001,SMLF,IO,DGA^6000030    I50 @T6G_MB_LIB.T6G(SCH_1):PAGE30
   U25 AV39 VDDCR_SOC_AV39 GENOA_SP5-SOCKET6096_13568-001,SMLF,IO,DGA^6000030    I50 @T6G_MB_LIB.T6G(SCH_1):PAGE30
   U25 AV41 VDDCR_SOC_AV41 GENOA_SP5-SOCKET6096_13568-001,SMLF,IO,DGA^6000030    I50 @T6G_MB_LIB.T6G(SCH_1):PAGE30
   U25 AV43 VDDCR_SOC_AV43 GENOA_SP5-SOCKET6096_13568-001,SMLF,IO,DGA^6000030    I50 @T6G_MB_LIB.T6G(SCH_1):PAGE30
   U25 AV45 VDDCR_SOC_AV45 GENOA_SP5-SOCKET6096_13568-001,SMLF,IO,DGA^6000030    I50 @T6G_MB_LIB.T6G(SCH_1):PAGE30
   U25 AV47 VDDCR_SOC_AV47 GENOA_SP5-SOCKET6096_13568-001,SMLF,IO,DGA^6000030    I50 @T6G_MB_LIB.T6G(SCH_1):PAGE30
   U25 AW23 VDDCR_SOC_AW23 GENOA_SP5-SOCKET6096_13568-001,SMLF,IO,DGA^6000030    I50 @T6G_MB_LIB.T6G(SCH_1):PAGE30
   U25 AW25 VDDCR_SOC_AW25 GENOA_SP5-SOCKET6096_13568-001,SMLF,IO,DGA^6000030    I50 @T6G_MB_LIB.T6G(SCH_1):PAGE30
   U25 AW27 VDDCR_SOC_AW27 GENOA_SP5-SOCKET6096_13568-001,SMLF,IO,DGA^6000030    I50 @T6G_MB_LIB.T6G(SCH_1):PAGE30
   U25 AW48 VDDCR_SOC_AW48 GENOA_SP5-SOCKET6096_13568-001,SMLF,IO,DGA^6000030    I50 @T6G_MB_LIB.T6G(SCH_1):PAGE30
   U25 AY22 VDDCR_SOC_AY22 GENOA_SP5-SOCKET6096_13568-001,SMLF,IO,DGA^6000030    I50 @T6G_MB_LIB.T6G(SCH_1):PAGE30
   U25 AY24 VDDCR_SOC_AY24 GENOA_SP5-SOCKET6096_13568-001,SMLF,IO,DGA^6000030    I50 @T6G_MB_LIB.T6G(SCH_1):PAGE30
   U25 AY26 VDDCR_SOC_AY26 GENOA_SP5-SOCKET6096_13568-001,SMLF,IO,DGA^6000030    I50 @T6G_MB_LIB.T6G(SCH_1):PAGE30
   U25 AY28 VDDCR_SOC_AY28 GENOA_SP5-SOCKET6096_13568-001,SMLF,IO,DGA^6000030    I50 @T6G_MB_LIB.T6G(SCH_1):PAGE30
   U25 AY49 VDDCR_SOC_AY49 GENOA_SP5-SOCKET6096_13568-001,SMLF,IO,DGA^6000030    I50 @T6G_MB_LIB.T6G(SCH_1):PAGE30
   U25   B5 VDDCR_SOC_B5 GENOA_SP5-SOCKET6096_13568-001,SMLF,IO,DGA^6000030    I50 @T6G_MB_LIB.T6G(SCH_1):PAGE30
   U25  BA4 VDDCR_SOC_BA4 GENOA_SP5-SOCKET6096_13568-001,SMLF,IO,DGA^6000030    I50 @T6G_MB_LIB.T6G(SCH_1):PAGE30
   U25 BA11 VDDCR_SOC_BA11 GENOA_SP5-SOCKET6096_13568-001,SMLF,IO,DGA^6000030    I50 @T6G_MB_LIB.T6G(SCH_1):PAGE30
   U25 BA18 VDDCR_SOC_BA18 GENOA_SP5-SOCKET6096_13568-001,SMLF,IO,DGA^6000030    I50 @T6G_MB_LIB.T6G(SCH_1):PAGE30
   U25 BA23 VDDCR_SOC_BA23 GENOA_SP5-SOCKET6096_13568-001,SMLF,IO,DGA^6000030    I50 @T6G_MB_LIB.T6G(SCH_1):PAGE30
   U25 BA25 VDDCR_SOC_BA25 GENOA_SP5-SOCKET6096_13568-001,SMLF,IO,DGA^6000030    I50 @T6G_MB_LIB.T6G(SCH_1):PAGE30
   U25 BA27 VDDCR_SOC_BA27 GENOA_SP5-SOCKET6096_13568-001,SMLF,IO,DGA^6000030    I50 @T6G_MB_LIB.T6G(SCH_1):PAGE30
   U25 BA48 VDDCR_SOC_BA48 GENOA_SP5-SOCKET6096_13568-001,SMLF,IO,DGA^6000030    I50 @T6G_MB_LIB.T6G(SCH_1):PAGE30
   U25 BB22 VDDCR_SOC_BB22 GENOA_SP5-SOCKET6096_13568-001,SMLF,IO,DGA^6000030    I50 @T6G_MB_LIB.T6G(SCH_1):PAGE30
   U25 BB24 VDDCR_SOC_BB24 GENOA_SP5-SOCKET6096_13568-001,SMLF,IO,DGA^6000030    I50 @T6G_MB_LIB.T6G(SCH_1):PAGE30
   U25 BB26 VDDCR_SOC_BB26 GENOA_SP5-SOCKET6096_13568-001,SMLF,IO,DGA^6000030    I50 @T6G_MB_LIB.T6G(SCH_1):PAGE30
   U25 BB28 VDDCR_SOC_BB28 GENOA_SP5-SOCKET6096_13568-001,SMLF,IO,DGA^6000030    I50 @T6G_MB_LIB.T6G(SCH_1):PAGE30
   U25 BB49 VDDCR_SOC_BB49 GENOA_SP5-SOCKET6096_13568-001,SMLF,IO,DGA^6000030    I50 @T6G_MB_LIB.T6G(SCH_1):PAGE30
   U25 BC23 VDDCR_SOC_BC23 GENOA_SP5-SOCKET6096_13568-001,SMLF,IO,DGA^6000030    I50 @T6G_MB_LIB.T6G(SCH_1):PAGE30
   U25 BC25 VDDCR_SOC_BC25 GENOA_SP5-SOCKET6096_13568-001,SMLF,IO,DGA^6000030    I50 @T6G_MB_LIB.T6G(SCH_1):PAGE30
   U25 BC27 VDDCR_SOC_BC27 GENOA_SP5-SOCKET6096_13568-001,SMLF,IO,DGA^6000030    I50 @T6G_MB_LIB.T6G(SCH_1):PAGE30
   U25 BC48 VDDCR_SOC_BC48 GENOA_SP5-SOCKET6096_13568-001,SMLF,IO,DGA^6000030    I50 @T6G_MB_LIB.T6G(SCH_1):PAGE30
   U25  BD5 VDDCR_SOC_BD5 GENOA_SP5-SOCKET6096_13568-001,SMLF,IO,DGA^6000030    I50 @T6G_MB_LIB.T6G(SCH_1):PAGE30
   U25 BD12 VDDCR_SOC_BD12 GENOA_SP5-SOCKET6096_13568-001,SMLF,IO,DGA^6000030    I50 @T6G_MB_LIB.T6G(SCH_1):PAGE30
   U25 BD19 VDDCR_SOC_BD19 GENOA_SP5-SOCKET6096_13568-001,SMLF,IO,DGA^6000030    I50 @T6G_MB_LIB.T6G(SCH_1):PAGE30
   U25 BD22 VDDCR_SOC_BD22 GENOA_SP5-SOCKET6096_13568-001,SMLF,IO,DGA^6000030    I50 @T6G_MB_LIB.T6G(SCH_1):PAGE30
   U25 BD24 VDDCR_SOC_BD24 GENOA_SP5-SOCKET6096_13568-001,SMLF,IO,DGA^6000030    I50 @T6G_MB_LIB.T6G(SCH_1):PAGE30
   U25 BD26 VDDCR_SOC_BD26 GENOA_SP5-SOCKET6096_13568-001,SMLF,IO,DGA^6000030    I50 @T6G_MB_LIB.T6G(SCH_1):PAGE30
   U25 BD28 VDDCR_SOC_BD28 GENOA_SP5-SOCKET6096_13568-001,SMLF,IO,DGA^6000030    I50 @T6G_MB_LIB.T6G(SCH_1):PAGE30
   U25 BD48 VDDCR_SOC_BD48 GENOA_SP5-SOCKET6096_13568-001,SMLF,IO,DGA^6000030    I50 @T6G_MB_LIB.T6G(SCH_1):PAGE30
   U25 BF23 VDDCR_SOC_BF23 GENOA_SP5-SOCKET6096_13568-001,SMLF,IO,DGA^6000030    I50 @T6G_MB_LIB.T6G(SCH_1):PAGE30
   U25 BF25 VDDCR_SOC_BF25 GENOA_SP5-SOCKET6096_13568-001,SMLF,IO,DGA^6000030    I50 @T6G_MB_LIB.T6G(SCH_1):PAGE30
   U25 BF27 VDDCR_SOC_BF27 GENOA_SP5-SOCKET6096_13568-001,SMLF,IO,DGA^6000030    I50 @T6G_MB_LIB.T6G(SCH_1):PAGE30
   U25 BF48 VDDCR_SOC_BF48 GENOA_SP5-SOCKET6096_13568-001,SMLF,IO,DGA^6000030    I50 @T6G_MB_LIB.T6G(SCH_1):PAGE30
   U25 BG22 VDDCR_SOC_BG22 GENOA_SP5-SOCKET6096_13568-001,SMLF,IO,DGA^6000030    I50 @T6G_MB_LIB.T6G(SCH_1):PAGE30
   U25 BG24 VDDCR_SOC_BG24 GENOA_SP5-SOCKET6096_13568-001,SMLF,IO,DGA^6000030    I50 @T6G_MB_LIB.T6G(SCH_1):PAGE30
   U25 BG26 VDDCR_SOC_BG26 GENOA_SP5-SOCKET6096_13568-001,SMLF,IO,DGA^6000030    I50 @T6G_MB_LIB.T6G(SCH_1):PAGE30
   U25 BG28 VDDCR_SOC_BG28 GENOA_SP5-SOCKET6096_13568-001,SMLF,IO,DGA^6000030    I50 @T6G_MB_LIB.T6G(SCH_1):PAGE30
   U25 BG48 VDDCR_SOC_BG48 GENOA_SP5-SOCKET6096_13568-001,SMLF,IO,DGA^6000030    I50 @T6G_MB_LIB.T6G(SCH_1):PAGE30
   U25 BH23 VDDCR_SOC_BH23 GENOA_SP5-SOCKET6096_13568-001,SMLF,IO,DGA^6000030    I50 @T6G_MB_LIB.T6G(SCH_1):PAGE30
   U25 BH25 VDDCR_SOC_BH25 GENOA_SP5-SOCKET6096_13568-001,SMLF,IO,DGA^6000030    I50 @T6G_MB_LIB.T6G(SCH_1):PAGE30
   U25 BH48 VDDCR_SOC_BH48 GENOA_SP5-SOCKET6096_13568-001,SMLF,IO,DGA^6000030    I50 @T6G_MB_LIB.T6G(SCH_1):PAGE30
   U25  BJ4 VDDCR_SOC_BJ4 GENOA_SP5-SOCKET6096_13568-001,SMLF,IO,DGA^6000030    I50 @T6G_MB_LIB.T6G(SCH_1):PAGE30
   U25 BJ11 VDDCR_SOC_BJ11 GENOA_SP5-SOCKET6096_13568-001,SMLF,IO,DGA^6000030    I50 @T6G_MB_LIB.T6G(SCH_1):PAGE30
   U25 BJ48 VDDCR_SOC_BJ48 GENOA_SP5-SOCKET6096_13568-001,SMLF,IO,DGA^6000030    I50 @T6G_MB_LIB.T6G(SCH_1):PAGE30
   U25  BM5 VDDCR_SOC_BM5 GENOA_SP5-SOCKET6096_13568-001,SMLF,IO,DGA^6000030    I50 @T6G_MB_LIB.T6G(SCH_1):PAGE30
   U25   C4 VDDCR_SOC_C4 GENOA_SP5-SOCKET6096_13568-001,SMLF,IO,DGA^6000030    I50 @T6G_MB_LIB.T6G(SCH_1):PAGE30
   U25   E4 VDDCR_SOC_E4 GENOA_SP5-SOCKET6096_13568-001,SMLF,IO,DGA^6000030    I50 @T6G_MB_LIB.T6G(SCH_1):PAGE30
   U25  E11 VDDCR_SOC_E11 GENOA_SP5-SOCKET6096_13568-001,SMLF,IO,DGA^6000030    I50 @T6G_MB_LIB.T6G(SCH_1):PAGE30
   U25   H5 VDDCR_SOC_H5 GENOA_SP5-SOCKET6096_13568-001,SMLF,IO,DGA^6000030    I50 @T6G_MB_LIB.T6G(SCH_1):PAGE30
   U25  H12 VDDCR_SOC_H12 GENOA_SP5-SOCKET6096_13568-001,SMLF,IO,DGA^6000030    I50 @T6G_MB_LIB.T6G(SCH_1):PAGE30
   U25  H19 VDDCR_SOC_H19 GENOA_SP5-SOCKET6096_13568-001,SMLF,IO,DGA^6000030    I50 @T6G_MB_LIB.T6G(SCH_1):PAGE30
   U25  K22 VDDCR_SOC_K22 GENOA_SP5-SOCKET6096_13568-001,SMLF,IO,DGA^6000030    I50 @T6G_MB_LIB.T6G(SCH_1):PAGE30
   U25   L4 VDDCR_SOC_L4 GENOA_SP5-SOCKET6096_13568-001,SMLF,IO,DGA^6000030    I50 @T6G_MB_LIB.T6G(SCH_1):PAGE30
   U25  L11 VDDCR_SOC_L11 GENOA_SP5-SOCKET6096_13568-001,SMLF,IO,DGA^6000030    I50 @T6G_MB_LIB.T6G(SCH_1):PAGE30
   U25  L18 VDDCR_SOC_L18 GENOA_SP5-SOCKET6096_13568-001,SMLF,IO,DGA^6000030    I50 @T6G_MB_LIB.T6G(SCH_1):PAGE30
   U25   P5 VDDCR_SOC_P5 GENOA_SP5-SOCKET6096_13568-001,SMLF,IO,DGA^6000030    I50 @T6G_MB_LIB.T6G(SCH_1):PAGE30
   U25  P12 VDDCR_SOC_P12 GENOA_SP5-SOCKET6096_13568-001,SMLF,IO,DGA^6000030    I50 @T6G_MB_LIB.T6G(SCH_1):PAGE30
   U25  P19 VDDCR_SOC_P19 GENOA_SP5-SOCKET6096_13568-001,SMLF,IO,DGA^6000030    I50 @T6G_MB_LIB.T6G(SCH_1):PAGE30
   U25  P22 VDDCR_SOC_P22 GENOA_SP5-SOCKET6096_13568-001,SMLF,IO,DGA^6000030    I50 @T6G_MB_LIB.T6G(SCH_1):PAGE30
   U25   U4 VDDCR_SOC_U4 GENOA_SP5-SOCKET6096_13568-001,SMLF,IO,DGA^6000030    I50 @T6G_MB_LIB.T6G(SCH_1):PAGE30
   U25  U11 VDDCR_SOC_U11 GENOA_SP5-SOCKET6096_13568-001,SMLF,IO,DGA^6000030    I50 @T6G_MB_LIB.T6G(SCH_1):PAGE30
   U25  U18 VDDCR_SOC_U18 GENOA_SP5-SOCKET6096_13568-001,SMLF,IO,DGA^6000030    I50 @T6G_MB_LIB.T6G(SCH_1):PAGE30
   U25  V22 VDDCR_SOC_V22 GENOA_SP5-SOCKET6096_13568-001,SMLF,IO,DGA^6000030    I50 @T6G_MB_LIB.T6G(SCH_1):PAGE30
   U25   Y5 VDDCR_SOC_Y5 GENOA_SP5-SOCKET6096_13568-001,SMLF,IO,DGA^6000030    I50 @T6G_MB_LIB.T6G(SCH_1):PAGE30
   U25  Y12 VDDCR_SOC_Y12 GENOA_SP5-SOCKET6096_13568-001,SMLF,IO,DGA^6000030    I50 @T6G_MB_LIB.T6G(SCH_1):PAGE30
   U25  Y19 VDDCR_SOC_Y19 GENOA_SP5-SOCKET6096_13568-001,SMLF,IO,DGA^6000030    I50 @T6G_MB_LIB.T6G(SCH_1):PAGE30
 C3888    1      A Q_CAP_C0402-22UF,4V,20%,X6S,CH622KMEB02    I83 @T6G_MB_LIB.T6G(SCH_1):PAGE67
 C2130    1      A Q_CAP_C0402-22UF,4V,20%,X6S,CH622KMEB02    I85 @T6G_MB_LIB.T6G(SCH_1):PAGE67
 C3889    1      A Q_CAP_C0402-22UF,4V,20%,X6S,CH622KMEB02    I86 @T6G_MB_LIB.T6G(SCH_1):PAGE67
 C2135    1      A Q_CAP_C0402-22UF,4V,20%,X6S,CH622KMEB02    I87 @T6G_MB_LIB.T6G(SCH_1):PAGE67
 C2129    1      A Q_CAP_C0402-22UF,4V,20%,X6S,CH622KMEB02    I89 @T6G_MB_LIB.T6G(SCH_1):PAGE67
 C2134    1      A Q_CAP_C0402-22UF,4V,20%,X6S,CH622KMEB02    I90 @T6G_MB_LIB.T6G(SCH_1):PAGE67
 C2140    1      A Q_CAP_C0402-22UF,4V,20%,X6S,CH622KMEB02    I92 @T6G_MB_LIB.T6G(SCH_1):PAGE67
 C2144    1      A Q_CAP_C0402-22UF,4V,20%,X6S,CH622KMEB02    I93 @T6G_MB_LIB.T6G(SCH_1):PAGE67
 C2148    1      A Q_CAP_C0402-22UF,4V,20%,X6S,CH622KMEB02    I94 @T6G_MB_LIB.T6G(SCH_1):PAGE67
 C2139    1      A Q_CAP_C0402-22UF,4V,20%,X6S,CH622KMEB02    I95 @T6G_MB_LIB.T6G(SCH_1):PAGE67
 C2143    1      A Q_CAP_C0402-22UF,4V,20%,X6S,CH622KMEB02    I96 @T6G_MB_LIB.T6G(SCH_1):PAGE67
 C2152    1      A Q_CAP_C0402-22UF,4V,20%,X6S,CH622KMEB02    I97 @T6G_MB_LIB.T6G(SCH_1):PAGE67
 C2155    1      A Q_CAP_C0402-22UF,4V,20%,X6S,CH622KMEB02    I98 @T6G_MB_LIB.T6G(SCH_1):PAGE67
 C2151    1      A Q_CAP_C0402-22UF,4V,20%,X6S,CH622KMEB02    I99 @T6G_MB_LIB.T6G(SCH_1):PAGE67
 C2154    1      A Q_CAP_C0402-22UF,4V,20%,X6S,CH622KMEB02   I100 @T6G_MB_LIB.T6G(SCH_1):PAGE67
 C3894    1      A Q_CAP_C0402-22UF,4V,20%,X6S,CH622KMEB02   I101 @T6G_MB_LIB.T6G(SCH_1):PAGE67
 C3895    1      A Q_CAP_C0402-22UF,4V,20%,X6S,CH622KMEB02   I102 @T6G_MB_LIB.T6G(SCH_1):PAGE67
 C2157    1      A Q_CAP_C0402-22UF,4V,20%,X6S,CH622KMEB02   I103 @T6G_MB_LIB.T6G(SCH_1):PAGE67
 C2159    1      A Q_CAP_C0402-22UF,4V,20%,X6S,CH622KMEB02   I104 @T6G_MB_LIB.T6G(SCH_1):PAGE67
 C3896    1      A Q_CAP_C0402-22UF,4V,20%,X6S,CH622KMEB02   I106 @T6G_MB_LIB.T6G(SCH_1):PAGE67
 C2161    1      A Q_CAP_C0402-22UF,4V,20%,X6S,CH622KMEB02   I108 @T6G_MB_LIB.T6G(SCH_1):PAGE67
 C2147    1      A Q_CAP_C0402-22UF,4V,20%,X6S,CH622KMEB02   I109 @T6G_MB_LIB.T6G(SCH_1):PAGE67
 C3925    1      A Q_CAP_C0402-22UF,4V,20%,X6S,CH622KMEB02     I1 @T6G_MB_LIB.T6G(SCH_1):PAGE69
 C3926    1      A Q_CAP_C0402-22UF,4V,20%,X6S,CH622KMEB02     I3 @T6G_MB_LIB.T6G(SCH_1):PAGE69
 C2533    1      A Q_CAP_C0402-22UF,4V,20%,X6S,CH622KMEB02     I4 @T6G_MB_LIB.T6G(SCH_1):PAGE69
 C2540    1      A Q_CAP_C0402-22UF,4V,20%,X6S,CH622KMEB02     I6 @T6G_MB_LIB.T6G(SCH_1):PAGE69
 C2532    1      A Q_CAP_C0402-22UF,4V,20%,X6S,CH622KMEB02     I7 @T6G_MB_LIB.T6G(SCH_1):PAGE69
 C2531    1      A Q_CAP_C0402-22UF,4V,20%,X6S,CH622KMEB02     I9 @T6G_MB_LIB.T6G(SCH_1):PAGE69
 C2539    1      A Q_CAP_C0402-22UF,4V,20%,X6S,CH622KMEB02    I10 @T6G_MB_LIB.T6G(SCH_1):PAGE69
 C2538    1      A Q_CAP_C0402-22UF,4V,20%,X6S,CH622KMEB02    I11 @T6G_MB_LIB.T6G(SCH_1):PAGE69
 C2530    1      A Q_CAP_C0402-22UF,4V,20%,X6S,CH622KMEB02    I13 @T6G_MB_LIB.T6G(SCH_1):PAGE69
 C2537    1      A Q_CAP_C0402-22UF,4V,20%,X6S,CH622KMEB02    I15 @T6G_MB_LIB.T6G(SCH_1):PAGE69
 C2529    1      A Q_CAP_C0402-22UF,4V,20%,X6S,CH622KMEB02    I16 @T6G_MB_LIB.T6G(SCH_1):PAGE69
 C2528    1      A Q_CAP_C0402-22UF,4V,20%,X6S,CH622KMEB02    I18 @T6G_MB_LIB.T6G(SCH_1):PAGE69
 C2536    1      A Q_CAP_C0402-22UF,4V,20%,X6S,CH622KMEB02    I19 @T6G_MB_LIB.T6G(SCH_1):PAGE69
 C2535    1      A Q_CAP_C0402-22UF,4V,20%,X6S,CH622KMEB02    I20 @T6G_MB_LIB.T6G(SCH_1):PAGE69
 C2527    1      A Q_CAP_C0402-22UF,4V,20%,X6S,CH622KMEB02    I22 @T6G_MB_LIB.T6G(SCH_1):PAGE69
 C2534    1      A Q_CAP_C0402-22UF,4V,20%,X6S,CH622KMEB02    I24 @T6G_MB_LIB.T6G(SCH_1):PAGE69
 C3927    1      A Q_CAP_C0402-22UF,4V,20%,X6S,CH622KMEB02    I25 @T6G_MB_LIB.T6G(SCH_1):PAGE69
 C3928    1      A Q_CAP_C0402-22UF,4V,20%,X6S,CH622KMEB02    I26 @T6G_MB_LIB.T6G(SCH_1):PAGE69
 C3929    1      A Q_CAP_C0402-22UF,4V,20%,X6S,CH622KMEB02    I27 @T6G_MB_LIB.T6G(SCH_1):PAGE69
 C2547    1      A Q_CAP_C0402-22UF,4V,20%,X6S,CH622KMEB02    I28 @T6G_MB_LIB.T6G(SCH_1):PAGE69
 C2554    1      A Q_CAP_C0402-22UF,4V,20%,X6S,CH622KMEB02    I29 @T6G_MB_LIB.T6G(SCH_1):PAGE69
 C2561    1      A Q_CAP_C0402-22UF,4V,20%,X6S,CH622KMEB02    I30 @T6G_MB_LIB.T6G(SCH_1):PAGE69
 C3930    1      A Q_CAP_C0402-22UF,4V,20%,X6S,CH622KMEB02    I31 @T6G_MB_LIB.T6G(SCH_1):PAGE69
 C3931    1      A Q_CAP_C0402-22UF,4V,20%,X6S,CH622KMEB02    I33 @T6G_MB_LIB.T6G(SCH_1):PAGE69
 C2568    1      A Q_CAP_C0402-22UF,4V,20%,X6S,CH622KMEB02    I34 @T6G_MB_LIB.T6G(SCH_1):PAGE69
 C2575    1      A Q_CAP_C0402-22UF,4V,20%,X6S,CH622KMEB02    I35 @T6G_MB_LIB.T6G(SCH_1):PAGE69
 C2546    1      A Q_CAP_C0402-22UF,4V,20%,X6S,CH622KMEB02    I36 @T6G_MB_LIB.T6G(SCH_1):PAGE69
 C2545    1      A Q_CAP_C0402-22UF,4V,20%,X6S,CH622KMEB02    I37 @T6G_MB_LIB.T6G(SCH_1):PAGE69
 C2553    1      A Q_CAP_C0402-22UF,4V,20%,X6S,CH622KMEB02    I38 @T6G_MB_LIB.T6G(SCH_1):PAGE69
 C2560    1      A Q_CAP_C0402-22UF,4V,20%,X6S,CH622KMEB02    I39 @T6G_MB_LIB.T6G(SCH_1):PAGE69
 C2552    1      A Q_CAP_C0402-22UF,4V,20%,X6S,CH622KMEB02    I40 @T6G_MB_LIB.T6G(SCH_1):PAGE69
 C2559    1      A Q_CAP_C0402-22UF,4V,20%,X6S,CH622KMEB02    I41 @T6G_MB_LIB.T6G(SCH_1):PAGE69
 C2544    1      A Q_CAP_C0402-22UF,4V,20%,X6S,CH622KMEB02    I42 @T6G_MB_LIB.T6G(SCH_1):PAGE69
 C2551    1      A Q_CAP_C0402-22UF,4V,20%,X6S,CH622KMEB02    I43 @T6G_MB_LIB.T6G(SCH_1):PAGE69
 C2558    1      A Q_CAP_C0402-22UF,4V,20%,X6S,CH622KMEB02    I44 @T6G_MB_LIB.T6G(SCH_1):PAGE69
 C2567    1      A Q_CAP_C0402-22UF,4V,20%,X6S,CH622KMEB02    I45 @T6G_MB_LIB.T6G(SCH_1):PAGE69
 C2566    1      A Q_CAP_C0402-22UF,4V,20%,X6S,CH622KMEB02    I46 @T6G_MB_LIB.T6G(SCH_1):PAGE69
 C2574    1      A Q_CAP_C0402-22UF,4V,20%,X6S,CH622KMEB02    I47 @T6G_MB_LIB.T6G(SCH_1):PAGE69
 C2573    1      A Q_CAP_C0402-22UF,4V,20%,X6S,CH622KMEB02    I48 @T6G_MB_LIB.T6G(SCH_1):PAGE69
 C2565    1      A Q_CAP_C0402-22UF,4V,20%,X6S,CH622KMEB02    I49 @T6G_MB_LIB.T6G(SCH_1):PAGE69
 C2572    1      A Q_CAP_C0402-22UF,4V,20%,X6S,CH622KMEB02    I50 @T6G_MB_LIB.T6G(SCH_1):PAGE69
 C2582    1      A Q_CAP_C0402-22UF,4V,20%,X6S,CH622KMEB02    I51 @T6G_MB_LIB.T6G(SCH_1):PAGE69
 C2589    1      A Q_CAP_C0402-22UF,4V,20%,X6S,CH622KMEB02    I52 @T6G_MB_LIB.T6G(SCH_1):PAGE69
 C2596    1      A Q_CAP_C0402-22UF,4V,20%,X6S,CH622KMEB02    I56 @T6G_MB_LIB.T6G(SCH_1):PAGE69
 C2581    1      A Q_CAP_C0402-22UF,4V,20%,X6S,CH622KMEB02    I61 @T6G_MB_LIB.T6G(SCH_1):PAGE69
 C2580    1      A Q_CAP_C0402-22UF,4V,20%,X6S,CH622KMEB02    I62 @T6G_MB_LIB.T6G(SCH_1):PAGE69
 C2588    1      A Q_CAP_C0402-22UF,4V,20%,X6S,CH622KMEB02    I63 @T6G_MB_LIB.T6G(SCH_1):PAGE69
 C2587    1      A Q_CAP_C0402-22UF,4V,20%,X6S,CH622KMEB02    I64 @T6G_MB_LIB.T6G(SCH_1):PAGE69
 C2579    1      A Q_CAP_C0402-22UF,4V,20%,X6S,CH622KMEB02    I65 @T6G_MB_LIB.T6G(SCH_1):PAGE69
 C2586    1      A Q_CAP_C0402-22UF,4V,20%,X6S,CH622KMEB02    I66 @T6G_MB_LIB.T6G(SCH_1):PAGE69
 C2595    1      A Q_CAP_C0402-22UF,4V,20%,X6S,CH622KMEB02    I67 @T6G_MB_LIB.T6G(SCH_1):PAGE69
 C2594    1      A Q_CAP_C0402-22UF,4V,20%,X6S,CH622KMEB02    I69 @T6G_MB_LIB.T6G(SCH_1):PAGE69
 C2593    1      A Q_CAP_C0402-22UF,4V,20%,X6S,CH622KMEB02    I74 @T6G_MB_LIB.T6G(SCH_1):PAGE69
 C2543    1      A Q_CAP_C0402-22UF,4V,20%,X6S,CH622KMEB02    I78 @T6G_MB_LIB.T6G(SCH_1):PAGE69
 C2542    1      A Q_CAP_C0402-22UF,4V,20%,X6S,CH622KMEB02    I79 @T6G_MB_LIB.T6G(SCH_1):PAGE69
 C2550    1      A Q_CAP_C0402-22UF,4V,20%,X6S,CH622KMEB02    I80 @T6G_MB_LIB.T6G(SCH_1):PAGE69
 C2549    1      A Q_CAP_C0402-22UF,4V,20%,X6S,CH622KMEB02    I81 @T6G_MB_LIB.T6G(SCH_1):PAGE69
 C2557    1      A Q_CAP_C0402-22UF,4V,20%,X6S,CH622KMEB02    I82 @T6G_MB_LIB.T6G(SCH_1):PAGE69
 C2556    1      A Q_CAP_C0402-22UF,4V,20%,X6S,CH622KMEB02    I83 @T6G_MB_LIB.T6G(SCH_1):PAGE69
 C2541    1      A Q_CAP_C0402-22UF,4V,20%,X6S,CH622KMEB02    I84 @T6G_MB_LIB.T6G(SCH_1):PAGE69
 C2548    1      A Q_CAP_C0402-22UF,4V,20%,X6S,CH622KMEB02    I85 @T6G_MB_LIB.T6G(SCH_1):PAGE69
 C2555    1      A Q_CAP_C0402-22UF,4V,20%,X6S,CH622KMEB02    I86 @T6G_MB_LIB.T6G(SCH_1):PAGE69
 C2564    1      A Q_CAP_C0402-22UF,4V,20%,X6S,CH622KMEB02    I87 @T6G_MB_LIB.T6G(SCH_1):PAGE69
 C2563    1      A Q_CAP_C0402-22UF,4V,20%,X6S,CH622KMEB02    I88 @T6G_MB_LIB.T6G(SCH_1):PAGE69
 C2571    1      A Q_CAP_C0402-22UF,4V,20%,X6S,CH622KMEB02    I89 @T6G_MB_LIB.T6G(SCH_1):PAGE69
 C2570    1      A Q_CAP_C0402-22UF,4V,20%,X6S,CH622KMEB02    I90 @T6G_MB_LIB.T6G(SCH_1):PAGE69
 C2562    1      A Q_CAP_C0402-22UF,4V,20%,X6S,CH622KMEB02    I91 @T6G_MB_LIB.T6G(SCH_1):PAGE69
 C2569    1      A Q_CAP_C0402-22UF,4V,20%,X6S,CH622KMEB02    I92 @T6G_MB_LIB.T6G(SCH_1):PAGE69
 C2578    1      A Q_CAP_C0402-22UF,4V,20%,X6S,CH622KMEB02    I93 @T6G_MB_LIB.T6G(SCH_1):PAGE69
 C2577    1      A Q_CAP_C0402-22UF,4V,20%,X6S,CH622KMEB02    I94 @T6G_MB_LIB.T6G(SCH_1):PAGE69
 C2585    1      A Q_CAP_C0402-22UF,4V,20%,X6S,CH622KMEB02    I95 @T6G_MB_LIB.T6G(SCH_1):PAGE69
 C2584    1      A Q_CAP_C0402-22UF,4V,20%,X6S,CH622KMEB02    I96 @T6G_MB_LIB.T6G(SCH_1):PAGE69
 C2576    1      A Q_CAP_C0402-22UF,4V,20%,X6S,CH622KMEB02    I97 @T6G_MB_LIB.T6G(SCH_1):PAGE69
 C2583    1      A Q_CAP_C0402-22UF,4V,20%,X6S,CH622KMEB02    I98 @T6G_MB_LIB.T6G(SCH_1):PAGE69
 C2592    1      A Q_CAP_C0402-22UF,4V,20%,X6S,CH622KMEB02    I99 @T6G_MB_LIB.T6G(SCH_1):PAGE69
 C2591    1      A Q_CAP_C0402-22UF,4V,20%,X6S,CH622KMEB02   I101 @T6G_MB_LIB.T6G(SCH_1):PAGE69
 C2590    1      A Q_CAP_C0402-22UF,4V,20%,X6S,CH622KMEB02   I106 @T6G_MB_LIB.T6G(SCH_1):PAGE69
 PC597    1      A Q_CAPP_SMLF-470UF,2.5V,20%,EMPTY,CH747LM8825    I63 @T6G_MB_LIB.T6G(SCH_1):PAGE173
 PC601    1      A Q_CAPP_SMLF-470UF,2.5V,20%,SPCAP,CH747LM8825    I66 @T6G_MB_LIB.T6G(SCH_1):PAGE173
  PL63    4      4 Q_INDUCTOR4P_14-150NH,SMLF,IND,CV+15^0TZ04    I69 @T6G_MB_LIB.T6G(SCH_1):PAGE173
 PC599    1      A Q_CAP_0402-0.1UF,25V,10%,X7R,CH4104K1B00    I79 @T6G_MB_LIB.T6G(SCH_1):PAGE173
PC604_1    1      A Q_CAP_C0805-22UF,4V,20%,X6S,CH622KMEA03    I83 @T6G_MB_LIB.T6G(SCH_1):PAGE173
  PL66    4      4 Q_INDUCTOR4P_14-150NH,SMLF,IND,CV+15^0TZ04    I25 @T6G_MB_LIB.T6G(SCH_1):PAGE174
PC615_3    1      A Q_CAP_C0805-22UF,4V,20%,X6S,CH622KMEA03    I29 @T6G_MB_LIB.T6G(SCH_1):PAGE174
 PR296    1      A Q_RES_0402LF-49.9,1%,1/16W,CHIP,CS04992FB07    I40 @T6G_MB_LIB.T6G(SCH_1):PAGE168
 PR363    2      B Q_RES_0402LF-0,5%,1/16W,CHIP,CS00002JB13    I18 @T6G_MB_LIB.T6G(SCH_1):PAGE173
 PR362    2      B Q_RES_0402LF-0,5%,1/16W,CHIP,CS00002JB13    I27 @T6G_MB_LIB.T6G(SCH_1):PAGE173
  PL64    4      4 Q_INDUCTOR4P_14-150NH,SMLF,IND,CV+15^0TZ04    I53 @T6G_MB_LIB.T6G(SCH_1):PAGE173
PC600_2    1      A Q_CAP_C0805-22UF,4V,20%,X6S,CH622KMEA03    I59 @T6G_MB_LIB.T6G(SCH_1):PAGE173
PC603_2    1      A Q_CAP_C0805-22UF,4V,20%,X6S,CH622KMEA03    I61 @T6G_MB_LIB.T6G(SCH_1):PAGE173
 PC598    1      A Q_CAPP_SMLF-470UF,2.5V,20%,SPCAP,CH747LM8825    I64 @T6G_MB_LIB.T6G(SCH_1):PAGE173
PC602_1    1      A Q_CAP_C0805-22UF,4V,20%,X6S,CH622KMEA03    I80 @T6G_MB_LIB.T6G(SCH_1):PAGE173
 PR334    1      A Q_RES_0402LF-1K,1%,1/16W,CHIP,CS21002FB06    I82 @T6G_MB_LIB.T6G(SCH_1):PAGE173
 PR367    2      B Q_RES_0402LF-0,5%,1/16W,CHIP,CS00002JB13    I11 @T6G_MB_LIB.T6G(SCH_1):PAGE174
PC614_3    1      A Q_CAP_C0805-22UF,4V,20%,X6S,CH622KMEA03    I27 @T6G_MB_LIB.T6G(SCH_1):PAGE174

PVDDCR_SOC_P0_EN @T6G_MB_LIB.T6G(SCH_1):PVDDCR_SOC_P0_EN
   U18   W3  PL29C LCMXO3LF9400C5BG484C-LCMXO3LF-9400C-5BG484C,SMLF,IA   I143 @T6G_MB_LIB.T6G(SCH_1):PAGE81
 R8282    1      A Q_RES_0402LF-0,5%,1/16W,CHIP,CS00002JB13     I2 @T6G_MB_LIB.T6G(SCH_1):PAGE168

PVDDCR_SOC_P0_EN//ADDR_CFG @T6G_MB_LIB.T6G(SCH_1):PVDDCR_SOC_P0_EN//ADDR_CFG
  PQ13    D      D MOSFET_PCH_GDS_ESD_PROTECTED-PJA3415AE,SMLF,IC,BAMA    I19 @T6G_MB_LIB.T6G(SCH_1):PAGE168
 PR292    1      A Q_RES_0402LF-681,1%,1/16W,CHIP,CS16812FB02    I27 @T6G_MB_LIB.T6G(SCH_1):PAGE168
  PU42   42 EN1||ADDR_CFG RAA229620GNPHA0-RAA229620GNP#HA0,SMLF,IC,ARF0TGP40A   I135 @T6G_MB_LIB.T6G(SCH_1):PAGE168

PVDDCR_SOC_P0_EN_GD @T6G_MB_LIB.T6G(SCH_1):PVDDCR_SOC_P0_EN_GD
  PQ17    D  DRAIN MOSFET_N_SMLF-BSS138K,BSS138K,IC,BAM138K0000    I17 @T6G_MB_LIB.T6G(SCH_1):PAGE168
 PR285    2      B Q_RES_0402LF-1K,1%,1/16W,CHIP,CS21002FB06    I18 @T6G_MB_LIB.T6G(SCH_1):PAGE168
  PQ13    G      G MOSFET_PCH_GDS_ESD_PROTECTED-PJA3415AE,SMLF,IC,BAMA    I19 @T6G_MB_LIB.T6G(SCH_1):PAGE168

PVDDCR_SOC_P0_EN_RC @T6G_MB_LIB.T6G(SCH_1):PVDDCR_SOC_P0_EN_RC
  C461    1      A Q_CAP_0402-1000PF,50V,5%,X7R,TMP_QCH21006JB10    I13 @T6G_MB_LIB.T6G(SCH_1):PAGE168
 R8282    2      B Q_RES_0402LF-0,5%,1/16W,CHIP,CS00002JB13     I2 @T6G_MB_LIB.T6G(SCH_1):PAGE168
  PQ17    G   GATE MOSFET_N_SMLF-BSS138K,BSS138K,IC,BAM138K0000    I17 @T6G_MB_LIB.T6G(SCH_1):PAGE168
 R6089    1      A Q_RES_0402LF-10K,1%,1/16W,EMPTY,CS31002FB08   I136 @T6G_MB_LIB.T6G(SCH_1):PAGE168

PVDDCR_SOC_P0_IMON1 @T6G_MB_LIB.T6G(SCH_1):PVDDCR_SOC_P0_IMON1
  PU42   38    CS0 RAA229620GNPHA0-RAA229620GNP#HA0,SMLF,IC,ARF0TGP40A   I135 @T6G_MB_LIB.T6G(SCH_1):PAGE168
  PU49   38   IOUT ISL99390FRZTR5935-ISL99390FRZ-TR5935,SMLF,IC,AL099A    I41 @T6G_MB_LIB.T6G(SCH_1):PAGE173

PVDDCR_SOC_P0_IMON2 @T6G_MB_LIB.T6G(SCH_1):PVDDCR_SOC_P0_IMON2
  PU42   37    CS1 RAA229620GNPHA0-RAA229620GNP#HA0,SMLF,IC,ARF0TGP40A   I135 @T6G_MB_LIB.T6G(SCH_1):PAGE168
  PU50   38   IOUT ISL99390FRZTR5935-ISL99390FRZ-TR5935,SMLF,IC,AL099A    I86 @T6G_MB_LIB.T6G(SCH_1):PAGE173

PVDDCR_SOC_P0_IMON3 @T6G_MB_LIB.T6G(SCH_1):PVDDCR_SOC_P0_IMON3
  PU51   38   IOUT ISL99390FRZTR5935-ISL99390FRZ-TR5935,SMLF,IC,AL099A    I38 @T6G_MB_LIB.T6G(SCH_1):PAGE174
  PU42   36    CS2 RAA229620GNPHA0-RAA229620GNP#HA0,SMLF,IC,ARF0TGP40A   I135 @T6G_MB_LIB.T6G(SCH_1):PAGE168

PVDDCR_SOC_P0_LSET1 @T6G_MB_LIB.T6G(SCH_1):PVDDCR_SOC_P0_LSET1
 PR358    2      B Q_RES_0402LF-8.87K,1%,1/16W,EMPTY,CS28872FB01    I32 @T6G_MB_LIB.T6G(SCH_1):PAGE173
  PU49   37   LSET ISL99390FRZTR5935-ISL99390FRZ-TR5935,SMLF,IC,AL099A    I41 @T6G_MB_LIB.T6G(SCH_1):PAGE173

PVDDCR_SOC_P0_LSET2 @T6G_MB_LIB.T6G(SCH_1):PVDDCR_SOC_P0_LSET2
 PR359    2      B Q_RES_0402LF-8.87K,1%,1/16W,EMPTY,CS28872FB01     I8 @T6G_MB_LIB.T6G(SCH_1):PAGE173
  PU50   37   LSET ISL99390FRZTR5935-ISL99390FRZ-TR5935,SMLF,IC,AL099A    I86 @T6G_MB_LIB.T6G(SCH_1):PAGE173

PVDDCR_SOC_P0_LSET3 @T6G_MB_LIB.T6G(SCH_1):PVDDCR_SOC_P0_LSET3
 PR365    2      B Q_RES_0402LF-8.87K,1%,1/16W,EMPTY,CS28872FB01     I7 @T6G_MB_LIB.T6G(SCH_1):PAGE174
  PU51   37   LSET ISL99390FRZTR5935-ISL99390FRZ-TR5935,SMLF,IC,AL099A    I38 @T6G_MB_LIB.T6G(SCH_1):PAGE174

PVDDCR_SOC_P0_PWM1 @T6G_MB_LIB.T6G(SCH_1):PVDDCR_SOC_P0_PWM1
  PU42    1   PWM0 RAA229620GNPHA0-RAA229620GNP#HA0,SMLF,IC,ARF0TGP40A   I135 @T6G_MB_LIB.T6G(SCH_1):PAGE168
  PU49   34    PWM ISL99390FRZTR5935-ISL99390FRZ-TR5935,SMLF,IC,AL099A    I41 @T6G_MB_LIB.T6G(SCH_1):PAGE173

PVDDCR_SOC_P0_PWM2 @T6G_MB_LIB.T6G(SCH_1):PVDDCR_SOC_P0_PWM2
  PU42    2   PWM1 RAA229620GNPHA0-RAA229620GNP#HA0,SMLF,IC,ARF0TGP40A   I135 @T6G_MB_LIB.T6G(SCH_1):PAGE168
  PU50   34    PWM ISL99390FRZTR5935-ISL99390FRZ-TR5935,SMLF,IC,AL099A    I86 @T6G_MB_LIB.T6G(SCH_1):PAGE173

PVDDCR_SOC_P0_PWM3 @T6G_MB_LIB.T6G(SCH_1):PVDDCR_SOC_P0_PWM3
  PU51   34    PWM ISL99390FRZTR5935-ISL99390FRZ-TR5935,SMLF,IC,AL099A    I38 @T6G_MB_LIB.T6G(SCH_1):PAGE174
  PU42    3   PWM2 RAA229620GNPHA0-RAA229620GNP#HA0,SMLF,IC,ARF0TGP40A   I135 @T6G_MB_LIB.T6G(SCH_1):PAGE168

PVDDCR_SOC_P0_TEMP1 @T6G_MB_LIB.T6G(SCH_1):PVDDCR_SOC_P0_TEMP1
  PU51   36 TOUT_FLT ISL99390FRZTR5935-ISL99390FRZ-TR5935,SMLF,IC,AL099A    I38 @T6G_MB_LIB.T6G(SCH_1):PAGE174
 PC472    1      A Q_CAP_0402-470PF,50V,10%,X7R,TMP_QCH14706KB18    I98 @T6G_MB_LIB.T6G(SCH_1):PAGE168
  PU42   43  TEMP1 RAA229620GNPHA0-RAA229620GNP#HA0,SMLF,IC,ARF0TGP40A   I135 @T6G_MB_LIB.T6G(SCH_1):PAGE168
  PU49   36 TOUT_FLT ISL99390FRZTR5935-ISL99390FRZ-TR5935,SMLF,IC,AL099A    I41 @T6G_MB_LIB.T6G(SCH_1):PAGE173
  PU50   36 TOUT_FLT ISL99390FRZTR5935-ISL99390FRZ-TR5935,SMLF,IC,AL099A    I86 @T6G_MB_LIB.T6G(SCH_1):PAGE173

PVDDCR_SOC_P0_VCC1 @T6G_MB_LIB.T6G(SCH_1):PVDDCR_SOC_P0_VCC1
 PC579    1      A Q_CAP_C0402-2.2UF,10V,10%,X6S,CH5222KEB01    I36 @T6G_MB_LIB.T6G(SCH_1):PAGE173
 PR356    2      B Q_RES_0402LF-2.2,1%,1/16W,CHIP,CS-2202FB01    I38 @T6G_MB_LIB.T6G(SCH_1):PAGE173
  PU49   35     EN ISL99390FRZTR5935-ISL99390FRZ-TR5935,SMLF,IC,AL099A    I41 @T6G_MB_LIB.T6G(SCH_1):PAGE173
  PU49    3    VCC ISL99390FRZTR5935-ISL99390FRZ-TR5935,SMLF,IC,AL099A    I41 @T6G_MB_LIB.T6G(SCH_1):PAGE173

PVDDCR_SOC_P0_VCC2 @T6G_MB_LIB.T6G(SCH_1):PVDDCR_SOC_P0_VCC2
 PC580    1      A Q_CAP_C0402-2.2UF,10V,10%,X6S,CH5222KEB01    I11 @T6G_MB_LIB.T6G(SCH_1):PAGE173
 PR357    2      B Q_RES_0402LF-2.2,1%,1/16W,CHIP,CS-2202FB01    I12 @T6G_MB_LIB.T6G(SCH_1):PAGE173
  PU50   35     EN ISL99390FRZTR5935-ISL99390FRZ-TR5935,SMLF,IC,AL099A    I86 @T6G_MB_LIB.T6G(SCH_1):PAGE173
  PU50    3    VCC ISL99390FRZTR5935-ISL99390FRZ-TR5935,SMLF,IC,AL099A    I86 @T6G_MB_LIB.T6G(SCH_1):PAGE173

PVDDCR_SOC_P0_VCC3 @T6G_MB_LIB.T6G(SCH_1):PVDDCR_SOC_P0_VCC3
  PU51   35     EN ISL99390FRZTR5935-ISL99390FRZ-TR5935,SMLF,IC,AL099A    I38 @T6G_MB_LIB.T6G(SCH_1):PAGE174
  PU51    3    VCC ISL99390FRZTR5935-ISL99390FRZ-TR5935,SMLF,IC,AL099A    I38 @T6G_MB_LIB.T6G(SCH_1):PAGE174
 PC606    1      A Q_CAP_C0402-2.2UF,10V,10%,X6S,CH5222KEB01    I14 @T6G_MB_LIB.T6G(SCH_1):PAGE174
 PR364    2      B Q_RES_0402LF-2.2,1%,1/16W,CHIP,CS-2202FB01    I15 @T6G_MB_LIB.T6G(SCH_1):PAGE174

PVDDCR_SOC_P0_VOS1 @T6G_MB_LIB.T6G(SCH_1):PVDDCR_SOC_P0_VOS1
 PR362    1      A Q_RES_0402LF-0,5%,1/16W,CHIP,CS00002JB13    I27 @T6G_MB_LIB.T6G(SCH_1):PAGE173
  PU49    1    VOS ISL99390FRZTR5935-ISL99390FRZ-TR5935,SMLF,IC,AL099A    I41 @T6G_MB_LIB.T6G(SCH_1):PAGE173

PVDDCR_SOC_P0_VOS2 @T6G_MB_LIB.T6G(SCH_1):PVDDCR_SOC_P0_VOS2
 PR363    1      A Q_RES_0402LF-0,5%,1/16W,CHIP,CS00002JB13    I18 @T6G_MB_LIB.T6G(SCH_1):PAGE173
  PU50    1    VOS ISL99390FRZTR5935-ISL99390FRZ-TR5935,SMLF,IC,AL099A    I86 @T6G_MB_LIB.T6G(SCH_1):PAGE173

PVDDCR_SOC_P0_VOS3 @T6G_MB_LIB.T6G(SCH_1):PVDDCR_SOC_P0_VOS3
  PU51    1    VOS ISL99390FRZTR5935-ISL99390FRZ-TR5935,SMLF,IC,AL099A    I38 @T6G_MB_LIB.T6G(SCH_1):PAGE174
 PR367    1      A Q_RES_0402LF-0,5%,1/16W,CHIP,CS00002JB13    I11 @T6G_MB_LIB.T6G(SCH_1):PAGE174

PVDDCR_SOC_P1 @T6G_MB_LIB.T6G(SCH_1):PVDDCR_SOC_P1
   U26 AA22 VDDCR_SOC_AA22 GENOA_SP5-SOCKET6096_13568-001,SMLF,IO,DGA^6000030    I49 @T6G_MB_LIB.T6G(SCH_1):PAGE57
   U26  AC4 VDDCR_SOC_AC4 GENOA_SP5-SOCKET6096_13568-001,SMLF,IO,DGA^6000030    I49 @T6G_MB_LIB.T6G(SCH_1):PAGE57
   U26 AC11 VDDCR_SOC_AC11 GENOA_SP5-SOCKET6096_13568-001,SMLF,IO,DGA^6000030    I49 @T6G_MB_LIB.T6G(SCH_1):PAGE57
   U26 AC18 VDDCR_SOC_AC18 GENOA_SP5-SOCKET6096_13568-001,SMLF,IO,DGA^6000030    I49 @T6G_MB_LIB.T6G(SCH_1):PAGE57
   U26 AD22 VDDCR_SOC_AD22 GENOA_SP5-SOCKET6096_13568-001,SMLF,IO,DGA^6000030    I49 @T6G_MB_LIB.T6G(SCH_1):PAGE57
   U26  AF5 VDDCR_SOC_AF5 GENOA_SP5-SOCKET6096_13568-001,SMLF,IO,DGA^6000030    I49 @T6G_MB_LIB.T6G(SCH_1):PAGE57
   U26 AF12 VDDCR_SOC_AF12 GENOA_SP5-SOCKET6096_13568-001,SMLF,IO,DGA^6000030    I49 @T6G_MB_LIB.T6G(SCH_1):PAGE57
   U26 AF19 VDDCR_SOC_AF19 GENOA_SP5-SOCKET6096_13568-001,SMLF,IO,DGA^6000030    I49 @T6G_MB_LIB.T6G(SCH_1):PAGE57
   U26 AH22 VDDCR_SOC_AH22 GENOA_SP5-SOCKET6096_13568-001,SMLF,IO,DGA^6000030    I49 @T6G_MB_LIB.T6G(SCH_1):PAGE57
   U26  AJ4 VDDCR_SOC_AJ4 GENOA_SP5-SOCKET6096_13568-001,SMLF,IO,DGA^6000030    I49 @T6G_MB_LIB.T6G(SCH_1):PAGE57
   U26 AJ11 VDDCR_SOC_AJ11 GENOA_SP5-SOCKET6096_13568-001,SMLF,IO,DGA^6000030    I49 @T6G_MB_LIB.T6G(SCH_1):PAGE57
   U26 AJ18 VDDCR_SOC_AJ18 GENOA_SP5-SOCKET6096_13568-001,SMLF,IO,DGA^6000030    I49 @T6G_MB_LIB.T6G(SCH_1):PAGE57
   U26  AM5 VDDCR_SOC_AM5 GENOA_SP5-SOCKET6096_13568-001,SMLF,IO,DGA^6000030    I49 @T6G_MB_LIB.T6G(SCH_1):PAGE57
   U26 AM12 VDDCR_SOC_AM12 GENOA_SP5-SOCKET6096_13568-001,SMLF,IO,DGA^6000030    I49 @T6G_MB_LIB.T6G(SCH_1):PAGE57
   U26 AM19 VDDCR_SOC_AM19 GENOA_SP5-SOCKET6096_13568-001,SMLF,IO,DGA^6000030    I49 @T6G_MB_LIB.T6G(SCH_1):PAGE57
   U26 AM22 VDDCR_SOC_AM22 GENOA_SP5-SOCKET6096_13568-001,SMLF,IO,DGA^6000030    I49 @T6G_MB_LIB.T6G(SCH_1):PAGE57
   U26  AR4 VDDCR_SOC_AR4 GENOA_SP5-SOCKET6096_13568-001,SMLF,IO,DGA^6000030    I49 @T6G_MB_LIB.T6G(SCH_1):PAGE57
   U26 AR11 VDDCR_SOC_AR11 GENOA_SP5-SOCKET6096_13568-001,SMLF,IO,DGA^6000030    I49 @T6G_MB_LIB.T6G(SCH_1):PAGE57
   U26 AR18 VDDCR_SOC_AR18 GENOA_SP5-SOCKET6096_13568-001,SMLF,IO,DGA^6000030    I49 @T6G_MB_LIB.T6G(SCH_1):PAGE57
   U26 AT22 VDDCR_SOC_AT22 GENOA_SP5-SOCKET6096_13568-001,SMLF,IO,DGA^6000030    I49 @T6G_MB_LIB.T6G(SCH_1):PAGE57
   U26 AU23 VDDCR_SOC_AU23 GENOA_SP5-SOCKET6096_13568-001,SMLF,IO,DGA^6000030    I49 @T6G_MB_LIB.T6G(SCH_1):PAGE57
   U26 AU27 VDDCR_SOC_AU27 GENOA_SP5-SOCKET6096_13568-001,SMLF,IO,DGA^6000030    I49 @T6G_MB_LIB.T6G(SCH_1):PAGE57
   U26 AU31 VDDCR_SOC_AU31 GENOA_SP5-SOCKET6096_13568-001,SMLF,IO,DGA^6000030    I49 @T6G_MB_LIB.T6G(SCH_1):PAGE57
   U26 AU35 VDDCR_SOC_AU35 GENOA_SP5-SOCKET6096_13568-001,SMLF,IO,DGA^6000030    I49 @T6G_MB_LIB.T6G(SCH_1):PAGE57
   U26 AU40 VDDCR_SOC_AU40 GENOA_SP5-SOCKET6096_13568-001,SMLF,IO,DGA^6000030    I49 @T6G_MB_LIB.T6G(SCH_1):PAGE57
   U26  AV5 VDDCR_SOC_AV5 GENOA_SP5-SOCKET6096_13568-001,SMLF,IO,DGA^6000030    I49 @T6G_MB_LIB.T6G(SCH_1):PAGE57
   U26 AV12 VDDCR_SOC_AV12 GENOA_SP5-SOCKET6096_13568-001,SMLF,IO,DGA^6000030    I49 @T6G_MB_LIB.T6G(SCH_1):PAGE57
   U26 AV19 VDDCR_SOC_AV19 GENOA_SP5-SOCKET6096_13568-001,SMLF,IO,DGA^6000030    I49 @T6G_MB_LIB.T6G(SCH_1):PAGE57
   U26 AV22 VDDCR_SOC_AV22 GENOA_SP5-SOCKET6096_13568-001,SMLF,IO,DGA^6000030    I49 @T6G_MB_LIB.T6G(SCH_1):PAGE57
   U26 AV24 VDDCR_SOC_AV24 GENOA_SP5-SOCKET6096_13568-001,SMLF,IO,DGA^6000030    I49 @T6G_MB_LIB.T6G(SCH_1):PAGE57
   U26 AV26 VDDCR_SOC_AV26 GENOA_SP5-SOCKET6096_13568-001,SMLF,IO,DGA^6000030    I49 @T6G_MB_LIB.T6G(SCH_1):PAGE57
   U26 AV28 VDDCR_SOC_AV28 GENOA_SP5-SOCKET6096_13568-001,SMLF,IO,DGA^6000030    I49 @T6G_MB_LIB.T6G(SCH_1):PAGE57
   U26 AV30 VDDCR_SOC_AV30 GENOA_SP5-SOCKET6096_13568-001,SMLF,IO,DGA^6000030    I49 @T6G_MB_LIB.T6G(SCH_1):PAGE57
   U26 AV32 VDDCR_SOC_AV32 GENOA_SP5-SOCKET6096_13568-001,SMLF,IO,DGA^6000030    I49 @T6G_MB_LIB.T6G(SCH_1):PAGE57
   U26 AV34 VDDCR_SOC_AV34 GENOA_SP5-SOCKET6096_13568-001,SMLF,IO,DGA^6000030    I49 @T6G_MB_LIB.T6G(SCH_1):PAGE57
   U26 AV36 VDDCR_SOC_AV36 GENOA_SP5-SOCKET6096_13568-001,SMLF,IO,DGA^6000030    I49 @T6G_MB_LIB.T6G(SCH_1):PAGE57
   U26 AV39 VDDCR_SOC_AV39 GENOA_SP5-SOCKET6096_13568-001,SMLF,IO,DGA^6000030    I49 @T6G_MB_LIB.T6G(SCH_1):PAGE57
   U26 AV41 VDDCR_SOC_AV41 GENOA_SP5-SOCKET6096_13568-001,SMLF,IO,DGA^6000030    I49 @T6G_MB_LIB.T6G(SCH_1):PAGE57
   U26 AV43 VDDCR_SOC_AV43 GENOA_SP5-SOCKET6096_13568-001,SMLF,IO,DGA^6000030    I49 @T6G_MB_LIB.T6G(SCH_1):PAGE57
   U26 AV45 VDDCR_SOC_AV45 GENOA_SP5-SOCKET6096_13568-001,SMLF,IO,DGA^6000030    I49 @T6G_MB_LIB.T6G(SCH_1):PAGE57
   U26 AV47 VDDCR_SOC_AV47 GENOA_SP5-SOCKET6096_13568-001,SMLF,IO,DGA^6000030    I49 @T6G_MB_LIB.T6G(SCH_1):PAGE57
   U26 AW23 VDDCR_SOC_AW23 GENOA_SP5-SOCKET6096_13568-001,SMLF,IO,DGA^6000030    I49 @T6G_MB_LIB.T6G(SCH_1):PAGE57
   U26 AW25 VDDCR_SOC_AW25 GENOA_SP5-SOCKET6096_13568-001,SMLF,IO,DGA^6000030    I49 @T6G_MB_LIB.T6G(SCH_1):PAGE57
   U26 AW27 VDDCR_SOC_AW27 GENOA_SP5-SOCKET6096_13568-001,SMLF,IO,DGA^6000030    I49 @T6G_MB_LIB.T6G(SCH_1):PAGE57
   U26 AW48 VDDCR_SOC_AW48 GENOA_SP5-SOCKET6096_13568-001,SMLF,IO,DGA^6000030    I49 @T6G_MB_LIB.T6G(SCH_1):PAGE57
   U26 AY22 VDDCR_SOC_AY22 GENOA_SP5-SOCKET6096_13568-001,SMLF,IO,DGA^6000030    I49 @T6G_MB_LIB.T6G(SCH_1):PAGE57
   U26 AY24 VDDCR_SOC_AY24 GENOA_SP5-SOCKET6096_13568-001,SMLF,IO,DGA^6000030    I49 @T6G_MB_LIB.T6G(SCH_1):PAGE57
   U26 AY26 VDDCR_SOC_AY26 GENOA_SP5-SOCKET6096_13568-001,SMLF,IO,DGA^6000030    I49 @T6G_MB_LIB.T6G(SCH_1):PAGE57
   U26 AY28 VDDCR_SOC_AY28 GENOA_SP5-SOCKET6096_13568-001,SMLF,IO,DGA^6000030    I49 @T6G_MB_LIB.T6G(SCH_1):PAGE57
   U26 AY49 VDDCR_SOC_AY49 GENOA_SP5-SOCKET6096_13568-001,SMLF,IO,DGA^6000030    I49 @T6G_MB_LIB.T6G(SCH_1):PAGE57
   U26   B5 VDDCR_SOC_B5 GENOA_SP5-SOCKET6096_13568-001,SMLF,IO,DGA^6000030    I49 @T6G_MB_LIB.T6G(SCH_1):PAGE57
   U26  BA4 VDDCR_SOC_BA4 GENOA_SP5-SOCKET6096_13568-001,SMLF,IO,DGA^6000030    I49 @T6G_MB_LIB.T6G(SCH_1):PAGE57
   U26 BA11 VDDCR_SOC_BA11 GENOA_SP5-SOCKET6096_13568-001,SMLF,IO,DGA^6000030    I49 @T6G_MB_LIB.T6G(SCH_1):PAGE57
   U26 BA18 VDDCR_SOC_BA18 GENOA_SP5-SOCKET6096_13568-001,SMLF,IO,DGA^6000030    I49 @T6G_MB_LIB.T6G(SCH_1):PAGE57
   U26 BA23 VDDCR_SOC_BA23 GENOA_SP5-SOCKET6096_13568-001,SMLF,IO,DGA^6000030    I49 @T6G_MB_LIB.T6G(SCH_1):PAGE57
   U26 BA25 VDDCR_SOC_BA25 GENOA_SP5-SOCKET6096_13568-001,SMLF,IO,DGA^6000030    I49 @T6G_MB_LIB.T6G(SCH_1):PAGE57
   U26 BA27 VDDCR_SOC_BA27 GENOA_SP5-SOCKET6096_13568-001,SMLF,IO,DGA^6000030    I49 @T6G_MB_LIB.T6G(SCH_1):PAGE57
   U26 BA48 VDDCR_SOC_BA48 GENOA_SP5-SOCKET6096_13568-001,SMLF,IO,DGA^6000030    I49 @T6G_MB_LIB.T6G(SCH_1):PAGE57
   U26 BB22 VDDCR_SOC_BB22 GENOA_SP5-SOCKET6096_13568-001,SMLF,IO,DGA^6000030    I49 @T6G_MB_LIB.T6G(SCH_1):PAGE57
   U26 BB24 VDDCR_SOC_BB24 GENOA_SP5-SOCKET6096_13568-001,SMLF,IO,DGA^6000030    I49 @T6G_MB_LIB.T6G(SCH_1):PAGE57
   U26 BB26 VDDCR_SOC_BB26 GENOA_SP5-SOCKET6096_13568-001,SMLF,IO,DGA^6000030    I49 @T6G_MB_LIB.T6G(SCH_1):PAGE57
   U26 BB28 VDDCR_SOC_BB28 GENOA_SP5-SOCKET6096_13568-001,SMLF,IO,DGA^6000030    I49 @T6G_MB_LIB.T6G(SCH_1):PAGE57
   U26 BB49 VDDCR_SOC_BB49 GENOA_SP5-SOCKET6096_13568-001,SMLF,IO,DGA^6000030    I49 @T6G_MB_LIB.T6G(SCH_1):PAGE57
   U26 BC23 VDDCR_SOC_BC23 GENOA_SP5-SOCKET6096_13568-001,SMLF,IO,DGA^6000030    I49 @T6G_MB_LIB.T6G(SCH_1):PAGE57
   U26 BC25 VDDCR_SOC_BC25 GENOA_SP5-SOCKET6096_13568-001,SMLF,IO,DGA^6000030    I49 @T6G_MB_LIB.T6G(SCH_1):PAGE57
   U26 BC27 VDDCR_SOC_BC27 GENOA_SP5-SOCKET6096_13568-001,SMLF,IO,DGA^6000030    I49 @T6G_MB_LIB.T6G(SCH_1):PAGE57
   U26 BC48 VDDCR_SOC_BC48 GENOA_SP5-SOCKET6096_13568-001,SMLF,IO,DGA^6000030    I49 @T6G_MB_LIB.T6G(SCH_1):PAGE57
   U26  BD5 VDDCR_SOC_BD5 GENOA_SP5-SOCKET6096_13568-001,SMLF,IO,DGA^6000030    I49 @T6G_MB_LIB.T6G(SCH_1):PAGE57
   U26 BD12 VDDCR_SOC_BD12 GENOA_SP5-SOCKET6096_13568-001,SMLF,IO,DGA^6000030    I49 @T6G_MB_LIB.T6G(SCH_1):PAGE57
   U26 BD19 VDDCR_SOC_BD19 GENOA_SP5-SOCKET6096_13568-001,SMLF,IO,DGA^6000030    I49 @T6G_MB_LIB.T6G(SCH_1):PAGE57
   U26 BD22 VDDCR_SOC_BD22 GENOA_SP5-SOCKET6096_13568-001,SMLF,IO,DGA^6000030    I49 @T6G_MB_LIB.T6G(SCH_1):PAGE57
   U26 BD24 VDDCR_SOC_BD24 GENOA_SP5-SOCKET6096_13568-001,SMLF,IO,DGA^6000030    I49 @T6G_MB_LIB.T6G(SCH_1):PAGE57
   U26 BD26 VDDCR_SOC_BD26 GENOA_SP5-SOCKET6096_13568-001,SMLF,IO,DGA^6000030    I49 @T6G_MB_LIB.T6G(SCH_1):PAGE57
   U26 BD28 VDDCR_SOC_BD28 GENOA_SP5-SOCKET6096_13568-001,SMLF,IO,DGA^6000030    I49 @T6G_MB_LIB.T6G(SCH_1):PAGE57
   U26 BD48 VDDCR_SOC_BD48 GENOA_SP5-SOCKET6096_13568-001,SMLF,IO,DGA^6000030    I49 @T6G_MB_LIB.T6G(SCH_1):PAGE57
   U26 BF23 VDDCR_SOC_BF23 GENOA_SP5-SOCKET6096_13568-001,SMLF,IO,DGA^6000030    I49 @T6G_MB_LIB.T6G(SCH_1):PAGE57
   U26 BF25 VDDCR_SOC_BF25 GENOA_SP5-SOCKET6096_13568-001,SMLF,IO,DGA^6000030    I49 @T6G_MB_LIB.T6G(SCH_1):PAGE57
   U26 BF27 VDDCR_SOC_BF27 GENOA_SP5-SOCKET6096_13568-001,SMLF,IO,DGA^6000030    I49 @T6G_MB_LIB.T6G(SCH_1):PAGE57
   U26 BF48 VDDCR_SOC_BF48 GENOA_SP5-SOCKET6096_13568-001,SMLF,IO,DGA^6000030    I49 @T6G_MB_LIB.T6G(SCH_1):PAGE57
   U26 BG22 VDDCR_SOC_BG22 GENOA_SP5-SOCKET6096_13568-001,SMLF,IO,DGA^6000030    I49 @T6G_MB_LIB.T6G(SCH_1):PAGE57
   U26 BG24 VDDCR_SOC_BG24 GENOA_SP5-SOCKET6096_13568-001,SMLF,IO,DGA^6000030    I49 @T6G_MB_LIB.T6G(SCH_1):PAGE57
   U26 BG26 VDDCR_SOC_BG26 GENOA_SP5-SOCKET6096_13568-001,SMLF,IO,DGA^6000030    I49 @T6G_MB_LIB.T6G(SCH_1):PAGE57
   U26 BG28 VDDCR_SOC_BG28 GENOA_SP5-SOCKET6096_13568-001,SMLF,IO,DGA^6000030    I49 @T6G_MB_LIB.T6G(SCH_1):PAGE57
   U26 BG48 VDDCR_SOC_BG48 GENOA_SP5-SOCKET6096_13568-001,SMLF,IO,DGA^6000030    I49 @T6G_MB_LIB.T6G(SCH_1):PAGE57
   U26 BH23 VDDCR_SOC_BH23 GENOA_SP5-SOCKET6096_13568-001,SMLF,IO,DGA^6000030    I49 @T6G_MB_LIB.T6G(SCH_1):PAGE57
   U26 BH25 VDDCR_SOC_BH25 GENOA_SP5-SOCKET6096_13568-001,SMLF,IO,DGA^6000030    I49 @T6G_MB_LIB.T6G(SCH_1):PAGE57
   U26 BH48 VDDCR_SOC_BH48 GENOA_SP5-SOCKET6096_13568-001,SMLF,IO,DGA^6000030    I49 @T6G_MB_LIB.T6G(SCH_1):PAGE57
   U26  BJ4 VDDCR_SOC_BJ4 GENOA_SP5-SOCKET6096_13568-001,SMLF,IO,DGA^6000030    I49 @T6G_MB_LIB.T6G(SCH_1):PAGE57
   U26 BJ11 VDDCR_SOC_BJ11 GENOA_SP5-SOCKET6096_13568-001,SMLF,IO,DGA^6000030    I49 @T6G_MB_LIB.T6G(SCH_1):PAGE57
   U26 BJ48 VDDCR_SOC_BJ48 GENOA_SP5-SOCKET6096_13568-001,SMLF,IO,DGA^6000030    I49 @T6G_MB_LIB.T6G(SCH_1):PAGE57
   U26  BM5 VDDCR_SOC_BM5 GENOA_SP5-SOCKET6096_13568-001,SMLF,IO,DGA^6000030    I49 @T6G_MB_LIB.T6G(SCH_1):PAGE57
   U26   C4 VDDCR_SOC_C4 GENOA_SP5-SOCKET6096_13568-001,SMLF,IO,DGA^6000030    I49 @T6G_MB_LIB.T6G(SCH_1):PAGE57
   U26   E4 VDDCR_SOC_E4 GENOA_SP5-SOCKET6096_13568-001,SMLF,IO,DGA^6000030    I49 @T6G_MB_LIB.T6G(SCH_1):PAGE57
   U26  E11 VDDCR_SOC_E11 GENOA_SP5-SOCKET6096_13568-001,SMLF,IO,DGA^6000030    I49 @T6G_MB_LIB.T6G(SCH_1):PAGE57
   U26   H5 VDDCR_SOC_H5 GENOA_SP5-SOCKET6096_13568-001,SMLF,IO,DGA^6000030    I49 @T6G_MB_LIB.T6G(SCH_1):PAGE57
   U26  H12 VDDCR_SOC_H12 GENOA_SP5-SOCKET6096_13568-001,SMLF,IO,DGA^6000030    I49 @T6G_MB_LIB.T6G(SCH_1):PAGE57
   U26  H19 VDDCR_SOC_H19 GENOA_SP5-SOCKET6096_13568-001,SMLF,IO,DGA^6000030    I49 @T6G_MB_LIB.T6G(SCH_1):PAGE57
   U26  K22 VDDCR_SOC_K22 GENOA_SP5-SOCKET6096_13568-001,SMLF,IO,DGA^6000030    I49 @T6G_MB_LIB.T6G(SCH_1):PAGE57
   U26   L4 VDDCR_SOC_L4 GENOA_SP5-SOCKET6096_13568-001,SMLF,IO,DGA^6000030    I49 @T6G_MB_LIB.T6G(SCH_1):PAGE57
   U26  L11 VDDCR_SOC_L11 GENOA_SP5-SOCKET6096_13568-001,SMLF,IO,DGA^6000030    I49 @T6G_MB_LIB.T6G(SCH_1):PAGE57
   U26  L18 VDDCR_SOC_L18 GENOA_SP5-SOCKET6096_13568-001,SMLF,IO,DGA^6000030    I49 @T6G_MB_LIB.T6G(SCH_1):PAGE57
   U26   P5 VDDCR_SOC_P5 GENOA_SP5-SOCKET6096_13568-001,SMLF,IO,DGA^6000030    I49 @T6G_MB_LIB.T6G(SCH_1):PAGE57
   U26  P12 VDDCR_SOC_P12 GENOA_SP5-SOCKET6096_13568-001,SMLF,IO,DGA^6000030    I49 @T6G_MB_LIB.T6G(SCH_1):PAGE57
   U26  P19 VDDCR_SOC_P19 GENOA_SP5-SOCKET6096_13568-001,SMLF,IO,DGA^6000030    I49 @T6G_MB_LIB.T6G(SCH_1):PAGE57
   U26  P22 VDDCR_SOC_P22 GENOA_SP5-SOCKET6096_13568-001,SMLF,IO,DGA^6000030    I49 @T6G_MB_LIB.T6G(SCH_1):PAGE57
   U26   U4 VDDCR_SOC_U4 GENOA_SP5-SOCKET6096_13568-001,SMLF,IO,DGA^6000030    I49 @T6G_MB_LIB.T6G(SCH_1):PAGE57
   U26  U11 VDDCR_SOC_U11 GENOA_SP5-SOCKET6096_13568-001,SMLF,IO,DGA^6000030    I49 @T6G_MB_LIB.T6G(SCH_1):PAGE57
   U26  U18 VDDCR_SOC_U18 GENOA_SP5-SOCKET6096_13568-001,SMLF,IO,DGA^6000030    I49 @T6G_MB_LIB.T6G(SCH_1):PAGE57
   U26  V22 VDDCR_SOC_V22 GENOA_SP5-SOCKET6096_13568-001,SMLF,IO,DGA^6000030    I49 @T6G_MB_LIB.T6G(SCH_1):PAGE57
   U26   Y5 VDDCR_SOC_Y5 GENOA_SP5-SOCKET6096_13568-001,SMLF,IO,DGA^6000030    I49 @T6G_MB_LIB.T6G(SCH_1):PAGE57
   U26  Y12 VDDCR_SOC_Y12 GENOA_SP5-SOCKET6096_13568-001,SMLF,IO,DGA^6000030    I49 @T6G_MB_LIB.T6G(SCH_1):PAGE57
   U26  Y19 VDDCR_SOC_Y19 GENOA_SP5-SOCKET6096_13568-001,SMLF,IO,DGA^6000030    I49 @T6G_MB_LIB.T6G(SCH_1):PAGE57
 C3900    1      A Q_CAP_C0402-22UF,4V,20%,X6S,CH622KMEB02     I5 @T6G_MB_LIB.T6G(SCH_1):PAGE71
 C2259    1      A Q_CAP_C0402-22UF,4V,20%,X6S,CH622KMEB02     I7 @T6G_MB_LIB.T6G(SCH_1):PAGE71
 C2258    1      A Q_CAP_C0402-22UF,4V,20%,X6S,CH622KMEB02     I9 @T6G_MB_LIB.T6G(SCH_1):PAGE71
 C3901    1      A Q_CAP_C0402-22UF,4V,20%,X6S,CH622KMEB02    I23 @T6G_MB_LIB.T6G(SCH_1):PAGE71
 C2264    1      A Q_CAP_C0402-22UF,4V,20%,X6S,CH622KMEB02    I30 @T6G_MB_LIB.T6G(SCH_1):PAGE71
 C2263    1      A Q_CAP_C0402-22UF,4V,20%,X6S,CH622KMEB02    I31 @T6G_MB_LIB.T6G(SCH_1):PAGE71
 C2269    1      A Q_CAP_C0402-22UF,4V,20%,X6S,CH622KMEB02    I32 @T6G_MB_LIB.T6G(SCH_1):PAGE71
 C2268    1      A Q_CAP_C0402-22UF,4V,20%,X6S,CH622KMEB02    I33 @T6G_MB_LIB.T6G(SCH_1):PAGE71
 C2272    1      A Q_CAP_C0402-22UF,4V,20%,X6S,CH622KMEB02    I34 @T6G_MB_LIB.T6G(SCH_1):PAGE71
 C2273    1      A Q_CAP_C0402-22UF,4V,20%,X6S,CH622KMEB02    I35 @T6G_MB_LIB.T6G(SCH_1):PAGE71
 C2277    1      A Q_CAP_C0402-22UF,4V,20%,X6S,CH622KMEB02    I36 @T6G_MB_LIB.T6G(SCH_1):PAGE71
 C2281    1      A Q_CAP_C0402-22UF,4V,20%,X6S,CH622KMEB02    I37 @T6G_MB_LIB.T6G(SCH_1):PAGE71
 C2280    1      A Q_CAP_C0402-22UF,4V,20%,X6S,CH622KMEB02    I38 @T6G_MB_LIB.T6G(SCH_1):PAGE71
 C2284    1      A Q_CAP_C0402-22UF,4V,20%,X6S,CH622KMEB02    I39 @T6G_MB_LIB.T6G(SCH_1):PAGE71
 C2283    1      A Q_CAP_C0402-22UF,4V,20%,X6S,CH622KMEB02    I40 @T6G_MB_LIB.T6G(SCH_1):PAGE71
 C3906    1      A Q_CAP_C0402-22UF,4V,20%,X6S,CH622KMEB02    I41 @T6G_MB_LIB.T6G(SCH_1):PAGE71
 C2286    1      A Q_CAP_C0402-22UF,4V,20%,X6S,CH622KMEB02    I42 @T6G_MB_LIB.T6G(SCH_1):PAGE71
 C3907    1      A Q_CAP_C0402-22UF,4V,20%,X6S,CH622KMEB02    I43 @T6G_MB_LIB.T6G(SCH_1):PAGE71
 C2288    1      A Q_CAP_C0402-22UF,4V,20%,X6S,CH622KMEB02    I44 @T6G_MB_LIB.T6G(SCH_1):PAGE71
 C3908    1      A Q_CAP_C0402-22UF,4V,20%,X6S,CH622KMEB02    I45 @T6G_MB_LIB.T6G(SCH_1):PAGE71
 C2290    1      A Q_CAP_C0402-22UF,4V,20%,X6S,CH622KMEB02    I47 @T6G_MB_LIB.T6G(SCH_1):PAGE71
 C2276    1      A Q_CAP_C0402-22UF,4V,20%,X6S,CH622KMEB02    I62 @T6G_MB_LIB.T6G(SCH_1):PAGE71
 C3912    1      A Q_CAP_C0402-22UF,4V,20%,X6S,CH622KMEB02     I1 @T6G_MB_LIB.T6G(SCH_1):PAGE73
 C2413    1      A Q_CAP_C0402-22UF,4V,20%,X6S,CH622KMEB02     I3 @T6G_MB_LIB.T6G(SCH_1):PAGE73
 C3913    1      A Q_CAP_C0402-22UF,4V,20%,X6S,CH622KMEB02     I4 @T6G_MB_LIB.T6G(SCH_1):PAGE73
 C2420    1      A Q_CAP_C0402-22UF,4V,20%,X6S,CH622KMEB02     I5 @T6G_MB_LIB.T6G(SCH_1):PAGE73
 C3914    1      A Q_CAP_C0402-22UF,4V,20%,X6S,CH622KMEB02     I6 @T6G_MB_LIB.T6G(SCH_1):PAGE73
 C2427    1      A Q_CAP_C0402-22UF,4V,20%,X6S,CH622KMEB02     I7 @T6G_MB_LIB.T6G(SCH_1):PAGE73
 C3915    1      A Q_CAP_C0402-22UF,4V,20%,X6S,CH622KMEB02     I8 @T6G_MB_LIB.T6G(SCH_1):PAGE73
 C2434    1      A Q_CAP_C0402-22UF,4V,20%,X6S,CH622KMEB02     I9 @T6G_MB_LIB.T6G(SCH_1):PAGE73
 C2412    1      A Q_CAP_C0402-22UF,4V,20%,X6S,CH622KMEB02    I11 @T6G_MB_LIB.T6G(SCH_1):PAGE73
 C2419    1      A Q_CAP_C0402-22UF,4V,20%,X6S,CH622KMEB02    I13 @T6G_MB_LIB.T6G(SCH_1):PAGE73
 C2411    1      A Q_CAP_C0402-22UF,4V,20%,X6S,CH622KMEB02    I14 @T6G_MB_LIB.T6G(SCH_1):PAGE73
 C2410    1      A Q_CAP_C0402-22UF,4V,20%,X6S,CH622KMEB02    I16 @T6G_MB_LIB.T6G(SCH_1):PAGE73
 C2418    1      A Q_CAP_C0402-22UF,4V,20%,X6S,CH622KMEB02    I17 @T6G_MB_LIB.T6G(SCH_1):PAGE73
 C2417    1      A Q_CAP_C0402-22UF,4V,20%,X6S,CH622KMEB02    I18 @T6G_MB_LIB.T6G(SCH_1):PAGE73
 C2426    1      A Q_CAP_C0402-22UF,4V,20%,X6S,CH622KMEB02    I19 @T6G_MB_LIB.T6G(SCH_1):PAGE73
 C2433    1      A Q_CAP_C0402-22UF,4V,20%,X6S,CH622KMEB02    I20 @T6G_MB_LIB.T6G(SCH_1):PAGE73
 C2425    1      A Q_CAP_C0402-22UF,4V,20%,X6S,CH622KMEB02    I21 @T6G_MB_LIB.T6G(SCH_1):PAGE73
 C2424    1      A Q_CAP_C0402-22UF,4V,20%,X6S,CH622KMEB02    I22 @T6G_MB_LIB.T6G(SCH_1):PAGE73
 C2432    1      A Q_CAP_C0402-22UF,4V,20%,X6S,CH622KMEB02    I23 @T6G_MB_LIB.T6G(SCH_1):PAGE73
 C2431    1      A Q_CAP_C0402-22UF,4V,20%,X6S,CH622KMEB02    I24 @T6G_MB_LIB.T6G(SCH_1):PAGE73
 C3916    1      A Q_CAP_C0402-22UF,4V,20%,X6S,CH622KMEB02    I25 @T6G_MB_LIB.T6G(SCH_1):PAGE73
 C2441    1      A Q_CAP_C0402-22UF,4V,20%,X6S,CH622KMEB02    I26 @T6G_MB_LIB.T6G(SCH_1):PAGE73
 C3917    1      A Q_CAP_C0402-22UF,4V,20%,X6S,CH622KMEB02    I27 @T6G_MB_LIB.T6G(SCH_1):PAGE73
 C2448    1      A Q_CAP_C0402-22UF,4V,20%,X6S,CH622KMEB02    I28 @T6G_MB_LIB.T6G(SCH_1):PAGE73
 C2455    1      A Q_CAP_C0402-22UF,4V,20%,X6S,CH622KMEB02    I29 @T6G_MB_LIB.T6G(SCH_1):PAGE73
 C3918    1      A Q_CAP_C0402-22UF,4V,20%,X6S,CH622KMEB02    I30 @T6G_MB_LIB.T6G(SCH_1):PAGE73
 C2462    1      A Q_CAP_C0402-22UF,4V,20%,X6S,CH622KMEB02    I32 @T6G_MB_LIB.T6G(SCH_1):PAGE73
 C2469    1      A Q_CAP_C0402-22UF,4V,20%,X6S,CH622KMEB02    I33 @T6G_MB_LIB.T6G(SCH_1):PAGE73
 C2440    1      A Q_CAP_C0402-22UF,4V,20%,X6S,CH622KMEB02    I34 @T6G_MB_LIB.T6G(SCH_1):PAGE73
 C2447    1      A Q_CAP_C0402-22UF,4V,20%,X6S,CH622KMEB02    I35 @T6G_MB_LIB.T6G(SCH_1):PAGE73
 C2439    1      A Q_CAP_C0402-22UF,4V,20%,X6S,CH622KMEB02    I36 @T6G_MB_LIB.T6G(SCH_1):PAGE73
 C2438    1      A Q_CAP_C0402-22UF,4V,20%,X6S,CH622KMEB02    I37 @T6G_MB_LIB.T6G(SCH_1):PAGE73
 C2446    1      A Q_CAP_C0402-22UF,4V,20%,X6S,CH622KMEB02    I38 @T6G_MB_LIB.T6G(SCH_1):PAGE73
 C2445    1      A Q_CAP_C0402-22UF,4V,20%,X6S,CH622KMEB02    I39 @T6G_MB_LIB.T6G(SCH_1):PAGE73
 C2452    1      A Q_CAP_C0402-22UF,4V,20%,X6S,CH622KMEB02    I40 @T6G_MB_LIB.T6G(SCH_1):PAGE73
 C2453    1      A Q_CAP_C0402-22UF,4V,20%,X6S,CH622KMEB02    I41 @T6G_MB_LIB.T6G(SCH_1):PAGE73
 C2454    1      A Q_CAP_C0402-22UF,4V,20%,X6S,CH622KMEB02    I42 @T6G_MB_LIB.T6G(SCH_1):PAGE73
 C2461    1      A Q_CAP_C0402-22UF,4V,20%,X6S,CH622KMEB02    I43 @T6G_MB_LIB.T6G(SCH_1):PAGE73
 C2468    1      A Q_CAP_C0402-22UF,4V,20%,X6S,CH622KMEB02    I44 @T6G_MB_LIB.T6G(SCH_1):PAGE73
 C2460    1      A Q_CAP_C0402-22UF,4V,20%,X6S,CH622KMEB02    I45 @T6G_MB_LIB.T6G(SCH_1):PAGE73
 C2459    1      A Q_CAP_C0402-22UF,4V,20%,X6S,CH622KMEB02    I46 @T6G_MB_LIB.T6G(SCH_1):PAGE73
 C2467    1      A Q_CAP_C0402-22UF,4V,20%,X6S,CH622KMEB02    I47 @T6G_MB_LIB.T6G(SCH_1):PAGE73
 C2466    1      A Q_CAP_C0402-22UF,4V,20%,X6S,CH622KMEB02    I48 @T6G_MB_LIB.T6G(SCH_1):PAGE73
 C2409    1      A Q_CAP_C0402-22UF,4V,20%,X6S,CH622KMEB02    I50 @T6G_MB_LIB.T6G(SCH_1):PAGE73
 C2416    1      A Q_CAP_C0402-22UF,4V,20%,X6S,CH622KMEB02    I52 @T6G_MB_LIB.T6G(SCH_1):PAGE73
 C2408    1      A Q_CAP_C0402-22UF,4V,20%,X6S,CH622KMEB02    I53 @T6G_MB_LIB.T6G(SCH_1):PAGE73
 C2407    1      A Q_CAP_C0402-22UF,4V,20%,X6S,CH622KMEB02    I55 @T6G_MB_LIB.T6G(SCH_1):PAGE73
 C2415    1      A Q_CAP_C0402-22UF,4V,20%,X6S,CH622KMEB02    I56 @T6G_MB_LIB.T6G(SCH_1):PAGE73
 C2414    1      A Q_CAP_C0402-22UF,4V,20%,X6S,CH622KMEB02    I57 @T6G_MB_LIB.T6G(SCH_1):PAGE73
 C2423    1      A Q_CAP_C0402-22UF,4V,20%,X6S,CH622KMEB02    I58 @T6G_MB_LIB.T6G(SCH_1):PAGE73
 C2430    1      A Q_CAP_C0402-22UF,4V,20%,X6S,CH622KMEB02    I59 @T6G_MB_LIB.T6G(SCH_1):PAGE73
 C2422    1      A Q_CAP_C0402-22UF,4V,20%,X6S,CH622KMEB02    I60 @T6G_MB_LIB.T6G(SCH_1):PAGE73
 C2421    1      A Q_CAP_C0402-22UF,4V,20%,X6S,CH622KMEB02    I61 @T6G_MB_LIB.T6G(SCH_1):PAGE73
 C2429    1      A Q_CAP_C0402-22UF,4V,20%,X6S,CH622KMEB02    I62 @T6G_MB_LIB.T6G(SCH_1):PAGE73
 C2437    1      A Q_CAP_C0402-22UF,4V,20%,X6S,CH622KMEB02    I64 @T6G_MB_LIB.T6G(SCH_1):PAGE73
 C2444    1      A Q_CAP_C0402-22UF,4V,20%,X6S,CH622KMEB02    I65 @T6G_MB_LIB.T6G(SCH_1):PAGE73
 C2436    1      A Q_CAP_C0402-22UF,4V,20%,X6S,CH622KMEB02    I66 @T6G_MB_LIB.T6G(SCH_1):PAGE73
 C2443    1      A Q_CAP_C0402-22UF,4V,20%,X6S,CH622KMEB02    I67 @T6G_MB_LIB.T6G(SCH_1):PAGE73
 C2449    1      A Q_CAP_C0402-22UF,4V,20%,X6S,CH622KMEB02    I68 @T6G_MB_LIB.T6G(SCH_1):PAGE73
 C2450    1      A Q_CAP_C0402-22UF,4V,20%,X6S,CH622KMEB02    I69 @T6G_MB_LIB.T6G(SCH_1):PAGE73
 C2451    1      A Q_CAP_C0402-22UF,4V,20%,X6S,CH622KMEB02    I70 @T6G_MB_LIB.T6G(SCH_1):PAGE73
 C2458    1      A Q_CAP_C0402-22UF,4V,20%,X6S,CH622KMEB02    I71 @T6G_MB_LIB.T6G(SCH_1):PAGE73
 C2465    1      A Q_CAP_C0402-22UF,4V,20%,X6S,CH622KMEB02    I72 @T6G_MB_LIB.T6G(SCH_1):PAGE73
 C2457    1      A Q_CAP_C0402-22UF,4V,20%,X6S,CH622KMEB02    I73 @T6G_MB_LIB.T6G(SCH_1):PAGE73
 C2456    1      A Q_CAP_C0402-22UF,4V,20%,X6S,CH622KMEB02    I74 @T6G_MB_LIB.T6G(SCH_1):PAGE73
 C2464    1      A Q_CAP_C0402-22UF,4V,20%,X6S,CH622KMEB02    I75 @T6G_MB_LIB.T6G(SCH_1):PAGE73
 C2463    1      A Q_CAP_C0402-22UF,4V,20%,X6S,CH622KMEB02    I76 @T6G_MB_LIB.T6G(SCH_1):PAGE73
 C2476    1      A Q_CAP_C0402-22UF,4V,20%,X6S,CH622KMEB02    I79 @T6G_MB_LIB.T6G(SCH_1):PAGE73
 C2475    1      A Q_CAP_C0402-22UF,4V,20%,X6S,CH622KMEB02    I88 @T6G_MB_LIB.T6G(SCH_1):PAGE73
 C2474    1      A Q_CAP_C0402-22UF,4V,20%,X6S,CH622KMEB02    I94 @T6G_MB_LIB.T6G(SCH_1):PAGE73
 C2473    1      A Q_CAP_C0402-22UF,4V,20%,X6S,CH622KMEB02    I96 @T6G_MB_LIB.T6G(SCH_1):PAGE73
 C2472    1      A Q_CAP_C0402-22UF,4V,20%,X6S,CH622KMEB02   I127 @T6G_MB_LIB.T6G(SCH_1):PAGE73
 C2471    1      A Q_CAP_C0402-22UF,4V,20%,X6S,CH622KMEB02   I131 @T6G_MB_LIB.T6G(SCH_1):PAGE73
 C2470    1      A Q_CAP_C0402-22UF,4V,20%,X6S,CH622KMEB02   I133 @T6G_MB_LIB.T6G(SCH_1):PAGE73
 C2442    1      A Q_CAP_C0402-22UF,4V,20%,X6S,CH622KMEB02   I173 @T6G_MB_LIB.T6G(SCH_1):PAGE73
 C2435    1      A Q_CAP_C0402-22UF,4V,20%,X6S,CH622KMEB02   I174 @T6G_MB_LIB.T6G(SCH_1):PAGE73
 C2428    1      A Q_CAP_C0402-22UF,4V,20%,X6S,CH622KMEB02   I175 @T6G_MB_LIB.T6G(SCH_1):PAGE73
  PL36    4      4 Q_INDUCTOR4P_14-150NH,SMLF,IND,CV+15^0TZ04    I52 @T6G_MB_LIB.T6G(SCH_1):PAGE190
 PC340    1      A Q_CAPP_SMLF-470UF,2.5V,20%,EMPTY,CH747LM8825    I63 @T6G_MB_LIB.T6G(SCH_1):PAGE190
 PC343    1      A Q_CAPP_SMLF-470UF,2.5V,20%,SPCAP,CH747LM8825    I66 @T6G_MB_LIB.T6G(SCH_1):PAGE190
  PL35    4      4 Q_INDUCTOR4P_14-150NH,SMLF,IND,CV+15^0TZ04    I69 @T6G_MB_LIB.T6G(SCH_1):PAGE190
 PC338    1      A Q_CAP_0402-0.1UF,25V,10%,X7R,CH4104K1B00    I79 @T6G_MB_LIB.T6G(SCH_1):PAGE190
PC344_1    1      A Q_CAP_C0805-22UF,4V,20%,X6S,CH622KMEA03    I81 @T6G_MB_LIB.T6G(SCH_1):PAGE190
 PR339    1      A Q_RES_0402LF-1K,1%,1/16W,CHIP,CS21002FB06    I83 @T6G_MB_LIB.T6G(SCH_1):PAGE190
  PL38    4      4 Q_INDUCTOR4P_14-150NH,SMLF,IND,CV+15^0TZ04    I26 @T6G_MB_LIB.T6G(SCH_1):PAGE191
 PR163    1      A Q_RES_0402LF-49.9,1%,1/16W,CHIP,CS04992FB07    I39 @T6G_MB_LIB.T6G(SCH_1):PAGE185
 PR216    2      B Q_RES_0402LF-0,5%,1/16W,CHIP,CS00002JB13    I23 @T6G_MB_LIB.T6G(SCH_1):PAGE191
PC354_3    1      A Q_CAP_C0805-22UF,4V,20%,X6S,CH622KMEA03    I28 @T6G_MB_LIB.T6G(SCH_1):PAGE191
PC355_3    1      A Q_CAP_C0805-22UF,4V,20%,X6S,CH622KMEA03    I30 @T6G_MB_LIB.T6G(SCH_1):PAGE191
 PR211    2      B Q_RES_0402LF-0,5%,1/16W,CHIP,CS00002JB13    I30 @T6G_MB_LIB.T6G(SCH_1):PAGE190
 PC337    1      A Q_CAPP_SMLF-470UF,2.5V,20%,SPCAP,CH747LM8825    I59 @T6G_MB_LIB.T6G(SCH_1):PAGE190
PC339_2    1      A Q_CAP_C0805-22UF,4V,20%,X6S,CH622KMEA03    I60 @T6G_MB_LIB.T6G(SCH_1):PAGE190
PC342_2    1      A Q_CAP_C0805-22UF,4V,20%,X6S,CH622KMEA03    I62 @T6G_MB_LIB.T6G(SCH_1):PAGE190
PC341_1    1      A Q_CAP_C0805-22UF,4V,20%,X6S,CH622KMEA03    I80 @T6G_MB_LIB.T6G(SCH_1):PAGE190
 PR212    2      B Q_RES_0402LF-0,5%,1/16W,CHIP,CS00002JB13    I85 @T6G_MB_LIB.T6G(SCH_1):PAGE190

PVDDCR_SOC_P1_EN @T6G_MB_LIB.T6G(SCH_1):PVDDCR_SOC_P1_EN
  R149    1      A Q_RES_0402LF-0,5%,1/16W,CHIP,CS00002JB13     I2 @T6G_MB_LIB.T6G(SCH_1):PAGE185
   U18  C15  PT38C LCMXO3LF9400C5BG484C-LCMXO3LF-9400C-5BG484C,SMLF,IA    I94 @T6G_MB_LIB.T6G(SCH_1):PAGE79

PVDDCR_SOC_P1_EN//ADDR_CFG @T6G_MB_LIB.T6G(SCH_1):PVDDCR_SOC_P1_EN//ADDR_CFG
  PQ11    D      D MOSFET_PCH_GDS_ESD_PROTECTED-PJA3415AE,SMLF,IC,BAMA    I18 @T6G_MB_LIB.T6G(SCH_1):PAGE185
  PU25   42 EN1||ADDR_CFG RAA229620GNPHA0-RAA229620GNP#HA0,SMLF,IC,ARF0TGP40A   I133 @T6G_MB_LIB.T6G(SCH_1):PAGE185
 PR159    1      A Q_RES_0402LF-5.23K,1%,1/16W,CHIP,CS25232FB08   I142 @T6G_MB_LIB.T6G(SCH_1):PAGE185

PVDDCR_SOC_P1_EN_GD @T6G_MB_LIB.T6G(SCH_1):PVDDCR_SOC_P1_EN_GD
  PQ15    D  DRAIN MOSFET_N_SMLF-BSS138K,BSS138K,IC,BAM138K0000    I16 @T6G_MB_LIB.T6G(SCH_1):PAGE185
 PR152    2      B Q_RES_0402LF-1K,1%,1/16W,CHIP,CS21002FB06    I17 @T6G_MB_LIB.T6G(SCH_1):PAGE185
  PQ11    G      G MOSFET_PCH_GDS_ESD_PROTECTED-PJA3415AE,SMLF,IC,BAMA    I18 @T6G_MB_LIB.T6G(SCH_1):PAGE185

PVDDCR_SOC_P1_EN_RC @T6G_MB_LIB.T6G(SCH_1):PVDDCR_SOC_P1_EN_RC
  C242    1      A Q_CAP_0402-1000PF,50V,5%,X7R,TMP_QCH21006JB10    I13 @T6G_MB_LIB.T6G(SCH_1):PAGE185
  R149    2      B Q_RES_0402LF-0,5%,1/16W,CHIP,CS00002JB13     I2 @T6G_MB_LIB.T6G(SCH_1):PAGE185
  PQ15    G   GATE MOSFET_N_SMLF-BSS138K,BSS138K,IC,BAM138K0000    I16 @T6G_MB_LIB.T6G(SCH_1):PAGE185
 R6087    1      A Q_RES_0402LF-10K,1%,1/16W,EMPTY,CS31002FB08   I135 @T6G_MB_LIB.T6G(SCH_1):PAGE185

PVDDCR_SOC_P1_IMON1 @T6G_MB_LIB.T6G(SCH_1):PVDDCR_SOC_P1_IMON1
  PU25   38    CS0 RAA229620GNPHA0-RAA229620GNP#HA0,SMLF,IC,ARF0TGP40A   I133 @T6G_MB_LIB.T6G(SCH_1):PAGE185
  PU30   38   IOUT ISL99390FRZTR5935-ISL99390FRZ-TR5935,SMLF,IC,AL099A    I17 @T6G_MB_LIB.T6G(SCH_1):PAGE190

PVDDCR_SOC_P1_IMON2 @T6G_MB_LIB.T6G(SCH_1):PVDDCR_SOC_P1_IMON2
  PU25   37    CS1 RAA229620GNPHA0-RAA229620GNP#HA0,SMLF,IC,ARF0TGP40A   I133 @T6G_MB_LIB.T6G(SCH_1):PAGE185
  PU31   38   IOUT ISL99390FRZTR5935-ISL99390FRZ-TR5935,SMLF,IC,AL099A    I86 @T6G_MB_LIB.T6G(SCH_1):PAGE190

PVDDCR_SOC_P1_IMON3 @T6G_MB_LIB.T6G(SCH_1):PVDDCR_SOC_P1_IMON3
  PU32   38   IOUT ISL99390FRZTR5935-ISL99390FRZ-TR5935,SMLF,IC,AL099A    I38 @T6G_MB_LIB.T6G(SCH_1):PAGE191
  PU25   36    CS2 RAA229620GNPHA0-RAA229620GNP#HA0,SMLF,IC,ARF0TGP40A   I133 @T6G_MB_LIB.T6G(SCH_1):PAGE185

PVDDCR_SOC_P1_LSET1 @T6G_MB_LIB.T6G(SCH_1):PVDDCR_SOC_P1_LSET1
  PU30   37   LSET ISL99390FRZTR5935-ISL99390FRZ-TR5935,SMLF,IC,AL099A    I17 @T6G_MB_LIB.T6G(SCH_1):PAGE190
 PR207    2      B Q_RES_0402LF-8.87K,1%,1/16W,EMPTY,CS28872FB01    I35 @T6G_MB_LIB.T6G(SCH_1):PAGE190

PVDDCR_SOC_P1_LSET2 @T6G_MB_LIB.T6G(SCH_1):PVDDCR_SOC_P1_LSET2
 PR208    2      B Q_RES_0402LF-8.87K,1%,1/16W,EMPTY,CS28872FB01     I8 @T6G_MB_LIB.T6G(SCH_1):PAGE190
  PU31   37   LSET ISL99390FRZTR5935-ISL99390FRZ-TR5935,SMLF,IC,AL099A    I86 @T6G_MB_LIB.T6G(SCH_1):PAGE190

PVDDCR_SOC_P1_LSET3 @T6G_MB_LIB.T6G(SCH_1):PVDDCR_SOC_P1_LSET3
 PR214    2      B Q_RES_0402LF-8.87K,1%,1/16W,EMPTY,CS28872FB01     I7 @T6G_MB_LIB.T6G(SCH_1):PAGE191
  PU32   37   LSET ISL99390FRZTR5935-ISL99390FRZ-TR5935,SMLF,IC,AL099A    I38 @T6G_MB_LIB.T6G(SCH_1):PAGE191

PVDDCR_SOC_P1_PWM1 @T6G_MB_LIB.T6G(SCH_1):PVDDCR_SOC_P1_PWM1
  PU25    1   PWM0 RAA229620GNPHA0-RAA229620GNP#HA0,SMLF,IC,ARF0TGP40A   I133 @T6G_MB_LIB.T6G(SCH_1):PAGE185
  PU30   34    PWM ISL99390FRZTR5935-ISL99390FRZ-TR5935,SMLF,IC,AL099A    I17 @T6G_MB_LIB.T6G(SCH_1):PAGE190

PVDDCR_SOC_P1_PWM2 @T6G_MB_LIB.T6G(SCH_1):PVDDCR_SOC_P1_PWM2
  PU25    2   PWM1 RAA229620GNPHA0-RAA229620GNP#HA0,SMLF,IC,ARF0TGP40A   I133 @T6G_MB_LIB.T6G(SCH_1):PAGE185
  PU31   34    PWM ISL99390FRZTR5935-ISL99390FRZ-TR5935,SMLF,IC,AL099A    I86 @T6G_MB_LIB.T6G(SCH_1):PAGE190

PVDDCR_SOC_P1_PWM3 @T6G_MB_LIB.T6G(SCH_1):PVDDCR_SOC_P1_PWM3
  PU32   34    PWM ISL99390FRZTR5935-ISL99390FRZ-TR5935,SMLF,IC,AL099A    I38 @T6G_MB_LIB.T6G(SCH_1):PAGE191
  PU25    3   PWM2 RAA229620GNPHA0-RAA229620GNP#HA0,SMLF,IC,ARF0TGP40A   I133 @T6G_MB_LIB.T6G(SCH_1):PAGE185

PVDDCR_SOC_P1_TEMP1 @T6G_MB_LIB.T6G(SCH_1):PVDDCR_SOC_P1_TEMP1
  PU32   36 TOUT_FLT ISL99390FRZTR5935-ISL99390FRZ-TR5935,SMLF,IC,AL099A    I38 @T6G_MB_LIB.T6G(SCH_1):PAGE191
 PC253    1      A Q_CAP_0402-470PF,50V,10%,X7R,TMP_QCH14706KB18    I94 @T6G_MB_LIB.T6G(SCH_1):PAGE185
  PU25   43  TEMP1 RAA229620GNPHA0-RAA229620GNP#HA0,SMLF,IC,ARF0TGP40A   I133 @T6G_MB_LIB.T6G(SCH_1):PAGE185
  PU30   36 TOUT_FLT ISL99390FRZTR5935-ISL99390FRZ-TR5935,SMLF,IC,AL099A    I17 @T6G_MB_LIB.T6G(SCH_1):PAGE190
  PU31   36 TOUT_FLT ISL99390FRZTR5935-ISL99390FRZ-TR5935,SMLF,IC,AL099A    I86 @T6G_MB_LIB.T6G(SCH_1):PAGE190

PVDDCR_SOC_P1_VCC1 @T6G_MB_LIB.T6G(SCH_1):PVDDCR_SOC_P1_VCC1
 PR205    2      B Q_RES_0402LF-2.2,1%,1/16W,CHIP,CS-2202FB01    I39 @T6G_MB_LIB.T6G(SCH_1):PAGE190
  PU30   35     EN ISL99390FRZTR5935-ISL99390FRZ-TR5935,SMLF,IC,AL099A    I17 @T6G_MB_LIB.T6G(SCH_1):PAGE190
  PU30    3    VCC ISL99390FRZTR5935-ISL99390FRZ-TR5935,SMLF,IC,AL099A    I17 @T6G_MB_LIB.T6G(SCH_1):PAGE190
 PC319    1      A Q_CAP_C0402-2.2UF,10V,10%,X6S,CH5222KEB01    I36 @T6G_MB_LIB.T6G(SCH_1):PAGE190

PVDDCR_SOC_P1_VCC2 @T6G_MB_LIB.T6G(SCH_1):PVDDCR_SOC_P1_VCC2
 PC320    1      A Q_CAP_C0402-2.2UF,10V,10%,X6S,CH5222KEB01    I11 @T6G_MB_LIB.T6G(SCH_1):PAGE190
 PR206    2      B Q_RES_0402LF-2.2,1%,1/16W,CHIP,CS-2202FB01    I12 @T6G_MB_LIB.T6G(SCH_1):PAGE190
  PU31   35     EN ISL99390FRZTR5935-ISL99390FRZ-TR5935,SMLF,IC,AL099A    I86 @T6G_MB_LIB.T6G(SCH_1):PAGE190
  PU31    3    VCC ISL99390FRZTR5935-ISL99390FRZ-TR5935,SMLF,IC,AL099A    I86 @T6G_MB_LIB.T6G(SCH_1):PAGE190

PVDDCR_SOC_P1_VCC3 @T6G_MB_LIB.T6G(SCH_1):PVDDCR_SOC_P1_VCC3
  PU32   35     EN ISL99390FRZTR5935-ISL99390FRZ-TR5935,SMLF,IC,AL099A    I38 @T6G_MB_LIB.T6G(SCH_1):PAGE191
  PU32    3    VCC ISL99390FRZTR5935-ISL99390FRZ-TR5935,SMLF,IC,AL099A    I38 @T6G_MB_LIB.T6G(SCH_1):PAGE191
 PC346    1      A Q_CAP_C0402-2.2UF,10V,10%,X6S,CH5222KEB01    I13 @T6G_MB_LIB.T6G(SCH_1):PAGE191
 PR213    2      B Q_RES_0402LF-2.2,1%,1/16W,CHIP,CS-2202FB01    I14 @T6G_MB_LIB.T6G(SCH_1):PAGE191

PVDDCR_SOC_P1_VOS1 @T6G_MB_LIB.T6G(SCH_1):PVDDCR_SOC_P1_VOS1
  PU30    1    VOS ISL99390FRZTR5935-ISL99390FRZ-TR5935,SMLF,IC,AL099A    I17 @T6G_MB_LIB.T6G(SCH_1):PAGE190
 PR211    1      A Q_RES_0402LF-0,5%,1/16W,CHIP,CS00002JB13    I30 @T6G_MB_LIB.T6G(SCH_1):PAGE190

PVDDCR_SOC_P1_VOS2 @T6G_MB_LIB.T6G(SCH_1):PVDDCR_SOC_P1_VOS2
 PR212    1      A Q_RES_0402LF-0,5%,1/16W,CHIP,CS00002JB13    I85 @T6G_MB_LIB.T6G(SCH_1):PAGE190
  PU31    1    VOS ISL99390FRZTR5935-ISL99390FRZ-TR5935,SMLF,IC,AL099A    I86 @T6G_MB_LIB.T6G(SCH_1):PAGE190

PVDDCR_SOC_P1_VOS3 @T6G_MB_LIB.T6G(SCH_1):PVDDCR_SOC_P1_VOS3
  PU32    1    VOS ISL99390FRZTR5935-ISL99390FRZ-TR5935,SMLF,IC,AL099A    I38 @T6G_MB_LIB.T6G(SCH_1):PAGE191
 PR216    1      A Q_RES_0402LF-0,5%,1/16W,CHIP,CS00002JB13    I23 @T6G_MB_LIB.T6G(SCH_1):PAGE191

PVDDIO_P0 @T6G_MB_LIB.T6G(SCH_1):PVDDIO_P0
   U25 AA54 VDDIO_AA54 GENOA_SP5-SOCKET6096_13568-001,SMLF,IO,DGA^6000030    I28 @T6G_MB_LIB.T6G(SCH_1):PAGE30
   U25 AC58 VDDIO_AC58 GENOA_SP5-SOCKET6096_13568-001,SMLF,IO,DGA^6000030    I28 @T6G_MB_LIB.T6G(SCH_1):PAGE30
   U25 AC65 VDDIO_AC65 GENOA_SP5-SOCKET6096_13568-001,SMLF,IO,DGA^6000030    I28 @T6G_MB_LIB.T6G(SCH_1):PAGE30
   U25 AC72 VDDIO_AC72 GENOA_SP5-SOCKET6096_13568-001,SMLF,IO,DGA^6000030    I28 @T6G_MB_LIB.T6G(SCH_1):PAGE30
   U25 AD54 VDDIO_AD54 GENOA_SP5-SOCKET6096_13568-001,SMLF,IO,DGA^6000030    I28 @T6G_MB_LIB.T6G(SCH_1):PAGE30
   U25 AF57 VDDIO_AF57 GENOA_SP5-SOCKET6096_13568-001,SMLF,IO,DGA^6000030    I28 @T6G_MB_LIB.T6G(SCH_1):PAGE30
   U25 AF64 VDDIO_AF64 GENOA_SP5-SOCKET6096_13568-001,SMLF,IO,DGA^6000030    I28 @T6G_MB_LIB.T6G(SCH_1):PAGE30
   U25 AF71 VDDIO_AF71 GENOA_SP5-SOCKET6096_13568-001,SMLF,IO,DGA^6000030    I28 @T6G_MB_LIB.T6G(SCH_1):PAGE30
   U25 AH54 VDDIO_AH54 GENOA_SP5-SOCKET6096_13568-001,SMLF,IO,DGA^6000030    I28 @T6G_MB_LIB.T6G(SCH_1):PAGE30
   U25 AJ58 VDDIO_AJ58 GENOA_SP5-SOCKET6096_13568-001,SMLF,IO,DGA^6000030    I28 @T6G_MB_LIB.T6G(SCH_1):PAGE30
   U25 AJ65 VDDIO_AJ65 GENOA_SP5-SOCKET6096_13568-001,SMLF,IO,DGA^6000030    I28 @T6G_MB_LIB.T6G(SCH_1):PAGE30
   U25 AJ72 VDDIO_AJ72 GENOA_SP5-SOCKET6096_13568-001,SMLF,IO,DGA^6000030    I28 @T6G_MB_LIB.T6G(SCH_1):PAGE30
   U25 AM54 VDDIO_AM54 GENOA_SP5-SOCKET6096_13568-001,SMLF,IO,DGA^6000030    I28 @T6G_MB_LIB.T6G(SCH_1):PAGE30
   U25 AM57 VDDIO_AM57 GENOA_SP5-SOCKET6096_13568-001,SMLF,IO,DGA^6000030    I28 @T6G_MB_LIB.T6G(SCH_1):PAGE30
   U25 AM64 VDDIO_AM64 GENOA_SP5-SOCKET6096_13568-001,SMLF,IO,DGA^6000030    I28 @T6G_MB_LIB.T6G(SCH_1):PAGE30
   U25 AM71 VDDIO_AM71 GENOA_SP5-SOCKET6096_13568-001,SMLF,IO,DGA^6000030    I28 @T6G_MB_LIB.T6G(SCH_1):PAGE30
   U25 AR58 VDDIO_AR58 GENOA_SP5-SOCKET6096_13568-001,SMLF,IO,DGA^6000030    I28 @T6G_MB_LIB.T6G(SCH_1):PAGE30
   U25 AR65 VDDIO_AR65 GENOA_SP5-SOCKET6096_13568-001,SMLF,IO,DGA^6000030    I28 @T6G_MB_LIB.T6G(SCH_1):PAGE30
   U25 AR72 VDDIO_AR72 GENOA_SP5-SOCKET6096_13568-001,SMLF,IO,DGA^6000030    I28 @T6G_MB_LIB.T6G(SCH_1):PAGE30
   U25 AV57 VDDIO_AV57 GENOA_SP5-SOCKET6096_13568-001,SMLF,IO,DGA^6000030    I28 @T6G_MB_LIB.T6G(SCH_1):PAGE30
   U25 AV64 VDDIO_AV64 GENOA_SP5-SOCKET6096_13568-001,SMLF,IO,DGA^6000030    I28 @T6G_MB_LIB.T6G(SCH_1):PAGE30
   U25 AV71 VDDIO_AV71 GENOA_SP5-SOCKET6096_13568-001,SMLF,IO,DGA^6000030    I28 @T6G_MB_LIB.T6G(SCH_1):PAGE30
   U25 BA58 VDDIO_BA58 GENOA_SP5-SOCKET6096_13568-001,SMLF,IO,DGA^6000030    I28 @T6G_MB_LIB.T6G(SCH_1):PAGE30
   U25 BA65 VDDIO_BA65 GENOA_SP5-SOCKET6096_13568-001,SMLF,IO,DGA^6000030    I28 @T6G_MB_LIB.T6G(SCH_1):PAGE30
   U25 BA72 VDDIO_BA72 GENOA_SP5-SOCKET6096_13568-001,SMLF,IO,DGA^6000030    I28 @T6G_MB_LIB.T6G(SCH_1):PAGE30
   U25 BD50 VDDIO_BD50 GENOA_SP5-SOCKET6096_13568-001,SMLF,IO,DGA^6000030    I28 @T6G_MB_LIB.T6G(SCH_1):PAGE30
   U25 BD52 VDDIO_BD52 GENOA_SP5-SOCKET6096_13568-001,SMLF,IO,DGA^6000030    I28 @T6G_MB_LIB.T6G(SCH_1):PAGE30
   U25 BD54 VDDIO_BD54 GENOA_SP5-SOCKET6096_13568-001,SMLF,IO,DGA^6000030    I28 @T6G_MB_LIB.T6G(SCH_1):PAGE30
   U25 BF51 VDDIO_BF51 GENOA_SP5-SOCKET6096_13568-001,SMLF,IO,DGA^6000030    I28 @T6G_MB_LIB.T6G(SCH_1):PAGE30
   U25 BF53 VDDIO_BF53 GENOA_SP5-SOCKET6096_13568-001,SMLF,IO,DGA^6000030    I28 @T6G_MB_LIB.T6G(SCH_1):PAGE30
   U25 BF57 VDDIO_BF57 GENOA_SP5-SOCKET6096_13568-001,SMLF,IO,DGA^6000030    I28 @T6G_MB_LIB.T6G(SCH_1):PAGE30
   U25 BF64 VDDIO_BF64 GENOA_SP5-SOCKET6096_13568-001,SMLF,IO,DGA^6000030    I28 @T6G_MB_LIB.T6G(SCH_1):PAGE30
   U25 BF71 VDDIO_BF71 GENOA_SP5-SOCKET6096_13568-001,SMLF,IO,DGA^6000030    I28 @T6G_MB_LIB.T6G(SCH_1):PAGE30
   U25 BG50 VDDIO_BG50 GENOA_SP5-SOCKET6096_13568-001,SMLF,IO,DGA^6000030    I28 @T6G_MB_LIB.T6G(SCH_1):PAGE30
   U25 BG52 VDDIO_BG52 GENOA_SP5-SOCKET6096_13568-001,SMLF,IO,DGA^6000030    I28 @T6G_MB_LIB.T6G(SCH_1):PAGE30
   U25 BG54 VDDIO_BG54 GENOA_SP5-SOCKET6096_13568-001,SMLF,IO,DGA^6000030    I28 @T6G_MB_LIB.T6G(SCH_1):PAGE30
   U25 BH51 VDDIO_BH51 GENOA_SP5-SOCKET6096_13568-001,SMLF,IO,DGA^6000030    I28 @T6G_MB_LIB.T6G(SCH_1):PAGE30
   U25 BH53 VDDIO_BH53 GENOA_SP5-SOCKET6096_13568-001,SMLF,IO,DGA^6000030    I28 @T6G_MB_LIB.T6G(SCH_1):PAGE30
   U25 BJ50 VDDIO_BJ50 GENOA_SP5-SOCKET6096_13568-001,SMLF,IO,DGA^6000030    I28 @T6G_MB_LIB.T6G(SCH_1):PAGE30
   U25 BJ52 VDDIO_BJ52 GENOA_SP5-SOCKET6096_13568-001,SMLF,IO,DGA^6000030    I28 @T6G_MB_LIB.T6G(SCH_1):PAGE30
   U25 BJ54 VDDIO_BJ54 GENOA_SP5-SOCKET6096_13568-001,SMLF,IO,DGA^6000030    I28 @T6G_MB_LIB.T6G(SCH_1):PAGE30
   U25 BJ58 VDDIO_BJ58 GENOA_SP5-SOCKET6096_13568-001,SMLF,IO,DGA^6000030    I28 @T6G_MB_LIB.T6G(SCH_1):PAGE30
   U25 BJ65 VDDIO_BJ65 GENOA_SP5-SOCKET6096_13568-001,SMLF,IO,DGA^6000030    I28 @T6G_MB_LIB.T6G(SCH_1):PAGE30
   U25 BJ72 VDDIO_BJ72 GENOA_SP5-SOCKET6096_13568-001,SMLF,IO,DGA^6000030    I28 @T6G_MB_LIB.T6G(SCH_1):PAGE30
   U25 BK51 VDDIO_BK51 GENOA_SP5-SOCKET6096_13568-001,SMLF,IO,DGA^6000030    I28 @T6G_MB_LIB.T6G(SCH_1):PAGE30
   U25 BK53 VDDIO_BK53 GENOA_SP5-SOCKET6096_13568-001,SMLF,IO,DGA^6000030    I28 @T6G_MB_LIB.T6G(SCH_1):PAGE30
   U25 BL50 VDDIO_BL50 GENOA_SP5-SOCKET6096_13568-001,SMLF,IO,DGA^6000030    I28 @T6G_MB_LIB.T6G(SCH_1):PAGE30
   U25 BL52 VDDIO_BL52 GENOA_SP5-SOCKET6096_13568-001,SMLF,IO,DGA^6000030    I28 @T6G_MB_LIB.T6G(SCH_1):PAGE30
   U25 BL54 VDDIO_BL54 GENOA_SP5-SOCKET6096_13568-001,SMLF,IO,DGA^6000030    I28 @T6G_MB_LIB.T6G(SCH_1):PAGE30
   U25 BM51 VDDIO_BM51 GENOA_SP5-SOCKET6096_13568-001,SMLF,IO,DGA^6000030    I28 @T6G_MB_LIB.T6G(SCH_1):PAGE30
   U25 BM53 VDDIO_BM53 GENOA_SP5-SOCKET6096_13568-001,SMLF,IO,DGA^6000030    I28 @T6G_MB_LIB.T6G(SCH_1):PAGE30
   U25 BM57 VDDIO_BM57 GENOA_SP5-SOCKET6096_13568-001,SMLF,IO,DGA^6000030    I28 @T6G_MB_LIB.T6G(SCH_1):PAGE30
   U25 BM64 VDDIO_BM64 GENOA_SP5-SOCKET6096_13568-001,SMLF,IO,DGA^6000030    I28 @T6G_MB_LIB.T6G(SCH_1):PAGE30
   U25 BM71 VDDIO_BM71 GENOA_SP5-SOCKET6096_13568-001,SMLF,IO,DGA^6000030    I28 @T6G_MB_LIB.T6G(SCH_1):PAGE30
   U25 BN54 VDDIO_BN54 GENOA_SP5-SOCKET6096_13568-001,SMLF,IO,DGA^6000030    I28 @T6G_MB_LIB.T6G(SCH_1):PAGE30
   U25 BR58 VDDIO_BR58 GENOA_SP5-SOCKET6096_13568-001,SMLF,IO,DGA^6000030    I28 @T6G_MB_LIB.T6G(SCH_1):PAGE30
   U25 BR65 VDDIO_BR65 GENOA_SP5-SOCKET6096_13568-001,SMLF,IO,DGA^6000030    I28 @T6G_MB_LIB.T6G(SCH_1):PAGE30
   U25 BR72 VDDIO_BR72 GENOA_SP5-SOCKET6096_13568-001,SMLF,IO,DGA^6000030    I28 @T6G_MB_LIB.T6G(SCH_1):PAGE30
   U25 BV54 VDDIO_BV54 GENOA_SP5-SOCKET6096_13568-001,SMLF,IO,DGA^6000030    I28 @T6G_MB_LIB.T6G(SCH_1):PAGE30
   U25 BV57 VDDIO_BV57 GENOA_SP5-SOCKET6096_13568-001,SMLF,IO,DGA^6000030    I28 @T6G_MB_LIB.T6G(SCH_1):PAGE30
   U25 BV64 VDDIO_BV64 GENOA_SP5-SOCKET6096_13568-001,SMLF,IO,DGA^6000030    I28 @T6G_MB_LIB.T6G(SCH_1):PAGE30
   U25 BV71 VDDIO_BV71 GENOA_SP5-SOCKET6096_13568-001,SMLF,IO,DGA^6000030    I28 @T6G_MB_LIB.T6G(SCH_1):PAGE30
   U25 CA58 VDDIO_CA58 GENOA_SP5-SOCKET6096_13568-001,SMLF,IO,DGA^6000030    I28 @T6G_MB_LIB.T6G(SCH_1):PAGE30
   U25 CA65 VDDIO_CA65 GENOA_SP5-SOCKET6096_13568-001,SMLF,IO,DGA^6000030    I28 @T6G_MB_LIB.T6G(SCH_1):PAGE30
   U25 CA72 VDDIO_CA72 GENOA_SP5-SOCKET6096_13568-001,SMLF,IO,DGA^6000030    I28 @T6G_MB_LIB.T6G(SCH_1):PAGE30
   U25 CB54 VDDIO_CB54 GENOA_SP5-SOCKET6096_13568-001,SMLF,IO,DGA^6000030    I28 @T6G_MB_LIB.T6G(SCH_1):PAGE30
   U25 CD57 VDDIO_CD57 GENOA_SP5-SOCKET6096_13568-001,SMLF,IO,DGA^6000030    I28 @T6G_MB_LIB.T6G(SCH_1):PAGE30
   U25 CD64 VDDIO_CD64 GENOA_SP5-SOCKET6096_13568-001,SMLF,IO,DGA^6000030    I28 @T6G_MB_LIB.T6G(SCH_1):PAGE30
   U25 CD71 VDDIO_CD71 GENOA_SP5-SOCKET6096_13568-001,SMLF,IO,DGA^6000030    I28 @T6G_MB_LIB.T6G(SCH_1):PAGE30
   U25 CF54 VDDIO_CF54 GENOA_SP5-SOCKET6096_13568-001,SMLF,IO,DGA^6000030    I28 @T6G_MB_LIB.T6G(SCH_1):PAGE30
   U25 CG58 VDDIO_CG58 GENOA_SP5-SOCKET6096_13568-001,SMLF,IO,DGA^6000030    I28 @T6G_MB_LIB.T6G(SCH_1):PAGE30
   U25 CG65 VDDIO_CG65 GENOA_SP5-SOCKET6096_13568-001,SMLF,IO,DGA^6000030    I28 @T6G_MB_LIB.T6G(SCH_1):PAGE30
   U25 CG72 VDDIO_CG72 GENOA_SP5-SOCKET6096_13568-001,SMLF,IO,DGA^6000030    I28 @T6G_MB_LIB.T6G(SCH_1):PAGE30
   U25 CJ54 VDDIO_CJ54 GENOA_SP5-SOCKET6096_13568-001,SMLF,IO,DGA^6000030    I28 @T6G_MB_LIB.T6G(SCH_1):PAGE30
   U25 CK57 VDDIO_CK57 GENOA_SP5-SOCKET6096_13568-001,SMLF,IO,DGA^6000030    I28 @T6G_MB_LIB.T6G(SCH_1):PAGE30
   U25 CK64 VDDIO_CK64 GENOA_SP5-SOCKET6096_13568-001,SMLF,IO,DGA^6000030    I28 @T6G_MB_LIB.T6G(SCH_1):PAGE30
   U25 CK71 VDDIO_CK71 GENOA_SP5-SOCKET6096_13568-001,SMLF,IO,DGA^6000030    I28 @T6G_MB_LIB.T6G(SCH_1):PAGE30
   U25 CM54 VDDIO_CM54 GENOA_SP5-SOCKET6096_13568-001,SMLF,IO,DGA^6000030    I28 @T6G_MB_LIB.T6G(SCH_1):PAGE30
   U25 CN58 VDDIO_CN58 GENOA_SP5-SOCKET6096_13568-001,SMLF,IO,DGA^6000030    I28 @T6G_MB_LIB.T6G(SCH_1):PAGE30
   U25 CN65 VDDIO_CN65 GENOA_SP5-SOCKET6096_13568-001,SMLF,IO,DGA^6000030    I28 @T6G_MB_LIB.T6G(SCH_1):PAGE30
   U25 CN72 VDDIO_CN72 GENOA_SP5-SOCKET6096_13568-001,SMLF,IO,DGA^6000030    I28 @T6G_MB_LIB.T6G(SCH_1):PAGE30
   U25 CT54 VDDIO_CT54 GENOA_SP5-SOCKET6096_13568-001,SMLF,IO,DGA^6000030    I28 @T6G_MB_LIB.T6G(SCH_1):PAGE30
   U25 CT57 VDDIO_CT57 GENOA_SP5-SOCKET6096_13568-001,SMLF,IO,DGA^6000030    I28 @T6G_MB_LIB.T6G(SCH_1):PAGE30
   U25 CT64 VDDIO_CT64 GENOA_SP5-SOCKET6096_13568-001,SMLF,IO,DGA^6000030    I28 @T6G_MB_LIB.T6G(SCH_1):PAGE30
   U25 CT71 VDDIO_CT71 GENOA_SP5-SOCKET6096_13568-001,SMLF,IO,DGA^6000030    I28 @T6G_MB_LIB.T6G(SCH_1):PAGE30
   U25 CW58 VDDIO_CW58 GENOA_SP5-SOCKET6096_13568-001,SMLF,IO,DGA^6000030    I28 @T6G_MB_LIB.T6G(SCH_1):PAGE30
   U25 CW65 VDDIO_CW65 GENOA_SP5-SOCKET6096_13568-001,SMLF,IO,DGA^6000030    I28 @T6G_MB_LIB.T6G(SCH_1):PAGE30
   U25 CW72 VDDIO_CW72 GENOA_SP5-SOCKET6096_13568-001,SMLF,IO,DGA^6000030    I28 @T6G_MB_LIB.T6G(SCH_1):PAGE30
   U25 CY54 VDDIO_CY54 GENOA_SP5-SOCKET6096_13568-001,SMLF,IO,DGA^6000030    I28 @T6G_MB_LIB.T6G(SCH_1):PAGE30
   U25 DB57 VDDIO_DB57 GENOA_SP5-SOCKET6096_13568-001,SMLF,IO,DGA^6000030    I28 @T6G_MB_LIB.T6G(SCH_1):PAGE30
   U25 DB64 VDDIO_DB64 GENOA_SP5-SOCKET6096_13568-001,SMLF,IO,DGA^6000030    I28 @T6G_MB_LIB.T6G(SCH_1):PAGE30
   U25 DB71 VDDIO_DB71 GENOA_SP5-SOCKET6096_13568-001,SMLF,IO,DGA^6000030    I28 @T6G_MB_LIB.T6G(SCH_1):PAGE30
   U25 DE58 VDDIO_DE58 GENOA_SP5-SOCKET6096_13568-001,SMLF,IO,DGA^6000030    I28 @T6G_MB_LIB.T6G(SCH_1):PAGE30
   U25 DE65 VDDIO_DE65 GENOA_SP5-SOCKET6096_13568-001,SMLF,IO,DGA^6000030    I28 @T6G_MB_LIB.T6G(SCH_1):PAGE30
   U25 DE72 VDDIO_DE72 GENOA_SP5-SOCKET6096_13568-001,SMLF,IO,DGA^6000030    I28 @T6G_MB_LIB.T6G(SCH_1):PAGE30
   U25 DG64 VDDIO_DG64 GENOA_SP5-SOCKET6096_13568-001,SMLF,IO,DGA^6000030    I28 @T6G_MB_LIB.T6G(SCH_1):PAGE30
   U25 DG71 VDDIO_DG71 GENOA_SP5-SOCKET6096_13568-001,SMLF,IO,DGA^6000030    I28 @T6G_MB_LIB.T6G(SCH_1):PAGE30
   U25  H57 VDDIO_H57 GENOA_SP5-SOCKET6096_13568-001,SMLF,IO,DGA^6000030    I28 @T6G_MB_LIB.T6G(SCH_1):PAGE30
   U25  H64 VDDIO_H64 GENOA_SP5-SOCKET6096_13568-001,SMLF,IO,DGA^6000030    I28 @T6G_MB_LIB.T6G(SCH_1):PAGE30
   U25  H71 VDDIO_H71 GENOA_SP5-SOCKET6096_13568-001,SMLF,IO,DGA^6000030    I28 @T6G_MB_LIB.T6G(SCH_1):PAGE30
   U25  K54 VDDIO_K54 GENOA_SP5-SOCKET6096_13568-001,SMLF,IO,DGA^6000030    I28 @T6G_MB_LIB.T6G(SCH_1):PAGE30
   U25  L58 VDDIO_L58 GENOA_SP5-SOCKET6096_13568-001,SMLF,IO,DGA^6000030    I28 @T6G_MB_LIB.T6G(SCH_1):PAGE30
   U25  L65 VDDIO_L65 GENOA_SP5-SOCKET6096_13568-001,SMLF,IO,DGA^6000030    I28 @T6G_MB_LIB.T6G(SCH_1):PAGE30
   U25  L72 VDDIO_L72 GENOA_SP5-SOCKET6096_13568-001,SMLF,IO,DGA^6000030    I28 @T6G_MB_LIB.T6G(SCH_1):PAGE30
   U25  P54 VDDIO_P54 GENOA_SP5-SOCKET6096_13568-001,SMLF,IO,DGA^6000030    I28 @T6G_MB_LIB.T6G(SCH_1):PAGE30
   U25  P57 VDDIO_P57 GENOA_SP5-SOCKET6096_13568-001,SMLF,IO,DGA^6000030    I28 @T6G_MB_LIB.T6G(SCH_1):PAGE30
   U25  P64 VDDIO_P64 GENOA_SP5-SOCKET6096_13568-001,SMLF,IO,DGA^6000030    I28 @T6G_MB_LIB.T6G(SCH_1):PAGE30
   U25  P71 VDDIO_P71 GENOA_SP5-SOCKET6096_13568-001,SMLF,IO,DGA^6000030    I28 @T6G_MB_LIB.T6G(SCH_1):PAGE30
   U25  U58 VDDIO_U58 GENOA_SP5-SOCKET6096_13568-001,SMLF,IO,DGA^6000030    I28 @T6G_MB_LIB.T6G(SCH_1):PAGE30
   U25  U65 VDDIO_U65 GENOA_SP5-SOCKET6096_13568-001,SMLF,IO,DGA^6000030    I28 @T6G_MB_LIB.T6G(SCH_1):PAGE30
   U25  U72 VDDIO_U72 GENOA_SP5-SOCKET6096_13568-001,SMLF,IO,DGA^6000030    I28 @T6G_MB_LIB.T6G(SCH_1):PAGE30
   U25  V54 VDDIO_V54 GENOA_SP5-SOCKET6096_13568-001,SMLF,IO,DGA^6000030    I28 @T6G_MB_LIB.T6G(SCH_1):PAGE30
   U25  Y57 VDDIO_Y57 GENOA_SP5-SOCKET6096_13568-001,SMLF,IO,DGA^6000030    I28 @T6G_MB_LIB.T6G(SCH_1):PAGE30
   U25  Y64 VDDIO_Y64 GENOA_SP5-SOCKET6096_13568-001,SMLF,IO,DGA^6000030    I28 @T6G_MB_LIB.T6G(SCH_1):PAGE30
   U25  Y71 VDDIO_Y71 GENOA_SP5-SOCKET6096_13568-001,SMLF,IO,DGA^6000030    I28 @T6G_MB_LIB.T6G(SCH_1):PAGE30
 C2131    1      A Q_CAP_C0402-22UF,4V,20%,X6S,CH622KMEB02   I135 @T6G_MB_LIB.T6G(SCH_1):PAGE67
 C2136    1      A Q_CAP_C0402-22UF,4V,20%,X6S,CH622KMEB02   I136 @T6G_MB_LIB.T6G(SCH_1):PAGE67
 C2141    1      A Q_CAP_C0402-22UF,4V,20%,X6S,CH622KMEB02   I137 @T6G_MB_LIB.T6G(SCH_1):PAGE67
 C2145    1      A Q_CAP_C0402-22UF,4V,20%,X6S,CH622KMEB02   I138 @T6G_MB_LIB.T6G(SCH_1):PAGE67
 C2149    1      A Q_CAP_C0402-22UF,4V,20%,X6S,CH622KMEB02   I139 @T6G_MB_LIB.T6G(SCH_1):PAGE67
 C3898    1      A Q_CAP_C0402-22UF,4V,20%,X6S,CH622KMEB02   I141 @T6G_MB_LIB.T6G(SCH_1):PAGE67
 C3899    1      A Q_CAP_C0402-22UF,4V,20%,X6S,CH622KMEB02   I143 @T6G_MB_LIB.T6G(SCH_1):PAGE67
 C2599    1      A Q_CAP_C0402-22UF,4V,20%,X6S,CH622KMEB02   I102 @T6G_MB_LIB.T6G(SCH_1):PAGE69
 C2598    1      A Q_CAP_C0402-22UF,4V,20%,X6S,CH622KMEB02   I104 @T6G_MB_LIB.T6G(SCH_1):PAGE69
 C2597    1      A Q_CAP_C0402-22UF,4V,20%,X6S,CH622KMEB02   I108 @T6G_MB_LIB.T6G(SCH_1):PAGE69
 C2606    1      A Q_CAP_C0402-22UF,4V,20%,X6S,CH622KMEB02   I153 @T6G_MB_LIB.T6G(SCH_1):PAGE69
 C2605    1      A Q_CAP_C0402-22UF,4V,20%,X6S,CH622KMEB02   I154 @T6G_MB_LIB.T6G(SCH_1):PAGE69
 C2613    1      A Q_CAP_C0402-22UF,4V,20%,X6S,CH622KMEB02   I155 @T6G_MB_LIB.T6G(SCH_1):PAGE69
 C2612    1      A Q_CAP_C0402-22UF,4V,20%,X6S,CH622KMEB02   I156 @T6G_MB_LIB.T6G(SCH_1):PAGE69
 C2619    1      A Q_CAP_C0402-22UF,4V,20%,X6S,CH622KMEB02   I157 @T6G_MB_LIB.T6G(SCH_1):PAGE69
 C2604    1      A Q_CAP_C0402-22UF,4V,20%,X6S,CH622KMEB02   I158 @T6G_MB_LIB.T6G(SCH_1):PAGE69
 C2611    1      A Q_CAP_C0402-22UF,4V,20%,X6S,CH622KMEB02   I159 @T6G_MB_LIB.T6G(SCH_1):PAGE69
 C2618    1      A Q_CAP_C0402-22UF,4V,20%,X6S,CH622KMEB02   I160 @T6G_MB_LIB.T6G(SCH_1):PAGE69
 C2620    1      A Q_CAP_C0402-22UF,4V,20%,X6S,CH622KMEB02   I161 @T6G_MB_LIB.T6G(SCH_1):PAGE69
 C2626    1      A Q_CAP_C0402-22UF,4V,20%,X6S,CH622KMEB02   I162 @T6G_MB_LIB.T6G(SCH_1):PAGE69
 C2632    1      A Q_CAP_C0402-22UF,4V,20%,X6S,CH622KMEB02   I163 @T6G_MB_LIB.T6G(SCH_1):PAGE69
 C2625    1      A Q_CAP_C0402-22UF,4V,20%,X6S,CH622KMEB02   I164 @T6G_MB_LIB.T6G(SCH_1):PAGE69
 C2631    1      A Q_CAP_C0402-22UF,4V,20%,X6S,CH622KMEB02   I165 @T6G_MB_LIB.T6G(SCH_1):PAGE69
 C2638    1      A Q_CAP_C0402-22UF,4V,20%,X6S,CH622KMEB02   I166 @T6G_MB_LIB.T6G(SCH_1):PAGE69
 C2644    1      A Q_CAP_C0402-22UF,4V,20%,X6S,CH622KMEB02   I167 @T6G_MB_LIB.T6G(SCH_1):PAGE69
 C2637    1      A Q_CAP_C0402-22UF,4V,20%,X6S,CH622KMEB02   I168 @T6G_MB_LIB.T6G(SCH_1):PAGE69
 C2643    1      A Q_CAP_C0402-22UF,4V,20%,X6S,CH622KMEB02   I169 @T6G_MB_LIB.T6G(SCH_1):PAGE69
 C2650    1      A Q_CAP_C0402-22UF,4V,20%,X6S,CH622KMEB02   I170 @T6G_MB_LIB.T6G(SCH_1):PAGE69
 C2655    1      A Q_CAP_C0402-22UF,4V,20%,X6S,CH622KMEB02   I172 @T6G_MB_LIB.T6G(SCH_1):PAGE69
 C2649    1      A Q_CAP_C0402-22UF,4V,20%,X6S,CH622KMEB02   I173 @T6G_MB_LIB.T6G(SCH_1):PAGE69
 C2654    1      A Q_CAP_C0402-22UF,4V,20%,X6S,CH622KMEB02   I175 @T6G_MB_LIB.T6G(SCH_1):PAGE69
PC191_4    1      A Q_CAP_C0805-22UF,4V,20%,X6S,CH622KMEA03    I68 @T6G_MB_LIB.T6G(SCH_1):PAGE181
PC192_3    1      A Q_CAP_C0805-22UF,4V,20%,X6S,CH622KMEA03    I71 @T6G_MB_LIB.T6G(SCH_1):PAGE181
  PR52    2      B Q_RES_0402LF-49.9,1%,1/16W,CHIP,CS04992FB07    I22 @T6G_MB_LIB.T6G(SCH_1):PAGE175
 PR104    2      B Q_RES_0402LF-0,5%,1/16W,CHIP,CS00002JB13    I39 @T6G_MB_LIB.T6G(SCH_1):PAGE180
  PL18    4      4 Q_INDUCTOR4P_14-150NH,SMLF,IND,CV+15^0TZ04    I40 @T6G_MB_LIB.T6G(SCH_1):PAGE180
 PR103    2      B Q_RES_0402LF-0,5%,1/16W,CHIP,CS00002JB13    I49 @T6G_MB_LIB.T6G(SCH_1):PAGE180
PC168_2    1      A Q_CAP_C0805-22UF,4V,20%,X6S,CH622KMEA03    I51 @T6G_MB_LIB.T6G(SCH_1):PAGE180
PC170_2    1      A Q_CAP_C0805-22UF,4V,20%,X6S,CH622KMEA03    I53 @T6G_MB_LIB.T6G(SCH_1):PAGE180
 PC160    1      A Q_CAPP_SMLF-470UF,2.5V,20%,EMPTY,CH747LM8825    I54 @T6G_MB_LIB.T6G(SCH_1):PAGE180
 PC162    1      A Q_CAPP_SMLF-470UF,2.5V,20%,SPCAP,CH747LM8825    I57 @T6G_MB_LIB.T6G(SCH_1):PAGE180
 PC165    1      A Q_CAPP_SMLF-470UF,2.5V,20%,SPCAP,CH747LM8825    I58 @T6G_MB_LIB.T6G(SCH_1):PAGE180
  PL17    4      4 Q_INDUCTOR4P_14-150NH,SMLF,IND,CV+15^0TZ04    I64 @T6G_MB_LIB.T6G(SCH_1):PAGE180
 PC107    1      A Q_CAP_0402-0.1UF,25V,10%,X7R,CH4104K1B00    I73 @T6G_MB_LIB.T6G(SCH_1):PAGE180
PC166_1    1      A Q_CAP_C0805-22UF,4V,20%,X6S,CH622KMEA03    I74 @T6G_MB_LIB.T6G(SCH_1):PAGE180
PC169_1    1      A Q_CAP_C0805-22UF,4V,20%,X6S,CH622KMEA03    I75 @T6G_MB_LIB.T6G(SCH_1):PAGE180
 PR410    1      A Q_RES_0402LF-1K,1%,1/16W,CHIP,CS21002FB06    I78 @T6G_MB_LIB.T6G(SCH_1):PAGE180
 PR112    2      B Q_RES_0402LF-0,5%,1/16W,CHIP,CS00002JB13    I41 @T6G_MB_LIB.T6G(SCH_1):PAGE181
  PL20    4      4 Q_INDUCTOR4P_14-150NH,SMLF,IND,CV+15^0TZ04    I42 @T6G_MB_LIB.T6G(SCH_1):PAGE181
 PR111    2      B Q_RES_0402LF-0,5%,1/16W,CHIP,CS00002JB13    I50 @T6G_MB_LIB.T6G(SCH_1):PAGE181
PC189_4    1      A Q_CAP_C0805-22UF,4V,20%,X6S,CH622KMEA03    I53 @T6G_MB_LIB.T6G(SCH_1):PAGE181
  PL21    4      4 Q_INDUCTOR4P_14-150NH,SMLF,IND,CV+15^0TZ04    I61 @T6G_MB_LIB.T6G(SCH_1):PAGE181
PC190_3    1      A Q_CAP_C0805-22UF,4V,20%,X6S,CH622KMEA03    I66 @T6G_MB_LIB.T6G(SCH_1):PAGE181

PVDDIO_P0_EN @T6G_MB_LIB.T6G(SCH_1):PVDDIO_P0_EN
 R8047    1      A Q_RES_0402LF-0,5%,1/16W,CHIP,CS00002JB13     I2 @T6G_MB_LIB.T6G(SCH_1):PAGE175
  R229    1      A Q_RES_0402LF-33,5%,1/16W,CHIP,CS03302JB10    I68 @T6G_MB_LIB.T6G(SCH_1):PAGE80

PVDDIO_P0_EN_G @T6G_MB_LIB.T6G(SCH_1):PVDDIO_P0_EN_G
  PQ14    D  DRAIN MOSFET_N_SMLF-BSS138K,BSS138K,IC,BAM138K0000     I6 @T6G_MB_LIB.T6G(SCH_1):PAGE175
  PQ10    G      G MOSFET_PCH_GDS_ESD_PROTECTED-PJA3415AE,SMLF,IC,BAMA    I13 @T6G_MB_LIB.T6G(SCH_1):PAGE175
  PR55    2      B Q_RES_0402LF-1K,1%,1/16W,CHIP,CS21002FB06    I17 @T6G_MB_LIB.T6G(SCH_1):PAGE175

PVDDIO_P0_EN_R @T6G_MB_LIB.T6G(SCH_1):PVDDIO_P0_EN_R
 R8047    2      B Q_RES_0402LF-0,5%,1/16W,CHIP,CS00002JB13     I2 @T6G_MB_LIB.T6G(SCH_1):PAGE175
 C8066    1      A Q_CAP_0402-1000PF,50V,5%,X7R,TMP_QCH21006JB10     I3 @T6G_MB_LIB.T6G(SCH_1):PAGE175
  PQ14    G   GATE MOSFET_N_SMLF-BSS138K,BSS138K,IC,BAM138K0000     I6 @T6G_MB_LIB.T6G(SCH_1):PAGE175
 R6086    1      A Q_RES_0402LF-10K,1%,1/16W,EMPTY,CS31002FB08   I129 @T6G_MB_LIB.T6G(SCH_1):PAGE175

PVDDIO_P0_IMON1 @T6G_MB_LIB.T6G(SCH_1):PVDDIO_P0_IMON1
  PU12   38    CS0 RAA229620GNPHA0-RAA229620GNP#HA0,SMLF,IC,ARF0TGP40A   I128 @T6G_MB_LIB.T6G(SCH_1):PAGE175
  PU17   38   IOUT ISL99390FRZTR5935-ISL99390FRZ-TR5935,SMLF,IC,AL099A    I84 @T6G_MB_LIB.T6G(SCH_1):PAGE180

PVDDIO_P0_IMON2 @T6G_MB_LIB.T6G(SCH_1):PVDDIO_P0_IMON2
  PU12   37    CS1 RAA229620GNPHA0-RAA229620GNP#HA0,SMLF,IC,ARF0TGP40A   I128 @T6G_MB_LIB.T6G(SCH_1):PAGE175
  PU18   38   IOUT ISL99390FRZTR5935-ISL99390FRZ-TR5935,SMLF,IC,AL099A    I15 @T6G_MB_LIB.T6G(SCH_1):PAGE180

PVDDIO_P0_IMON3 @T6G_MB_LIB.T6G(SCH_1):PVDDIO_P0_IMON3
  PU12   36    CS2 RAA229620GNPHA0-RAA229620GNP#HA0,SMLF,IC,ARF0TGP40A   I128 @T6G_MB_LIB.T6G(SCH_1):PAGE175
  PU19   38   IOUT ISL99390FRZTR5935-ISL99390FRZ-TR5935,SMLF,IC,AL099A    I32 @T6G_MB_LIB.T6G(SCH_1):PAGE181

PVDDIO_P0_IMON4 @T6G_MB_LIB.T6G(SCH_1):PVDDIO_P0_IMON4
  PU12   35    CS3 RAA229620GNPHA0-RAA229620GNP#HA0,SMLF,IC,ARF0TGP40A   I128 @T6G_MB_LIB.T6G(SCH_1):PAGE175
  PU20   38   IOUT ISL99390FRZTR5935-ISL99390FRZ-TR5935,SMLF,IC,AL099A    I73 @T6G_MB_LIB.T6G(SCH_1):PAGE181

PVDDIO_P0_LSET1 @T6G_MB_LIB.T6G(SCH_1):PVDDIO_P0_LSET1
  PR98    1      A Q_RES_0402LF-8.87K,1%,1/16W,EMPTY,CS28872FB01    I22 @T6G_MB_LIB.T6G(SCH_1):PAGE180
  PU17   37   LSET ISL99390FRZTR5935-ISL99390FRZ-TR5935,SMLF,IC,AL099A    I84 @T6G_MB_LIB.T6G(SCH_1):PAGE180

PVDDIO_P0_LSET2 @T6G_MB_LIB.T6G(SCH_1):PVDDIO_P0_LSET2
  PR97    1      A Q_RES_0402LF-8.87K,1%,1/16W,EMPTY,CS28872FB01     I4 @T6G_MB_LIB.T6G(SCH_1):PAGE180
  PU18   37   LSET ISL99390FRZTR5935-ISL99390FRZ-TR5935,SMLF,IC,AL099A    I15 @T6G_MB_LIB.T6G(SCH_1):PAGE180

PVDDIO_P0_LSET3 @T6G_MB_LIB.T6G(SCH_1):PVDDIO_P0_LSET3
 PR106    1      A Q_RES_0402LF-8.87K,1%,1/16W,EMPTY,CS28872FB01    I21 @T6G_MB_LIB.T6G(SCH_1):PAGE181
  PU19   37   LSET ISL99390FRZTR5935-ISL99390FRZ-TR5935,SMLF,IC,AL099A    I32 @T6G_MB_LIB.T6G(SCH_1):PAGE181

PVDDIO_P0_LSET4 @T6G_MB_LIB.T6G(SCH_1):PVDDIO_P0_LSET4
 PR105    1      A Q_RES_0402LF-8.87K,1%,1/16W,EMPTY,CS28872FB01     I4 @T6G_MB_LIB.T6G(SCH_1):PAGE181
  PU20   37   LSET ISL99390FRZTR5935-ISL99390FRZ-TR5935,SMLF,IC,AL099A    I73 @T6G_MB_LIB.T6G(SCH_1):PAGE181

PVDDIO_P0_PWM1 @T6G_MB_LIB.T6G(SCH_1):PVDDIO_P0_PWM1
  PU12    1   PWM0 RAA229620GNPHA0-RAA229620GNP#HA0,SMLF,IC,ARF0TGP40A   I128 @T6G_MB_LIB.T6G(SCH_1):PAGE175
  PU17   34    PWM ISL99390FRZTR5935-ISL99390FRZ-TR5935,SMLF,IC,AL099A    I84 @T6G_MB_LIB.T6G(SCH_1):PAGE180

PVDDIO_P0_PWM2 @T6G_MB_LIB.T6G(SCH_1):PVDDIO_P0_PWM2
  PU12    2   PWM1 RAA229620GNPHA0-RAA229620GNP#HA0,SMLF,IC,ARF0TGP40A   I128 @T6G_MB_LIB.T6G(SCH_1):PAGE175
  PU18   34    PWM ISL99390FRZTR5935-ISL99390FRZ-TR5935,SMLF,IC,AL099A    I15 @T6G_MB_LIB.T6G(SCH_1):PAGE180

PVDDIO_P0_PWM3 @T6G_MB_LIB.T6G(SCH_1):PVDDIO_P0_PWM3
  PU12    3   PWM2 RAA229620GNPHA0-RAA229620GNP#HA0,SMLF,IC,ARF0TGP40A   I128 @T6G_MB_LIB.T6G(SCH_1):PAGE175
  PU19   34    PWM ISL99390FRZTR5935-ISL99390FRZ-TR5935,SMLF,IC,AL099A    I32 @T6G_MB_LIB.T6G(SCH_1):PAGE181

PVDDIO_P0_PWM4 @T6G_MB_LIB.T6G(SCH_1):PVDDIO_P0_PWM4
  PU12    4   PWM3 RAA229620GNPHA0-RAA229620GNP#HA0,SMLF,IC,ARF0TGP40A   I128 @T6G_MB_LIB.T6G(SCH_1):PAGE175
  PU20   34    PWM ISL99390FRZTR5935-ISL99390FRZ-TR5935,SMLF,IC,AL099A    I73 @T6G_MB_LIB.T6G(SCH_1):PAGE181

PVDDIO_P0_TEMP1 @T6G_MB_LIB.T6G(SCH_1):PVDDIO_P0_TEMP1
  PC77    1      A Q_CAP_0402-470PF,50V,10%,X7R,TMP_QCH14706KB18    I75 @T6G_MB_LIB.T6G(SCH_1):PAGE175
  PU12   43  TEMP1 RAA229620GNPHA0-RAA229620GNP#HA0,SMLF,IC,ARF0TGP40A   I128 @T6G_MB_LIB.T6G(SCH_1):PAGE175
  PU18   36 TOUT_FLT ISL99390FRZTR5935-ISL99390FRZ-TR5935,SMLF,IC,AL099A    I15 @T6G_MB_LIB.T6G(SCH_1):PAGE180
  PU17   36 TOUT_FLT ISL99390FRZTR5935-ISL99390FRZ-TR5935,SMLF,IC,AL099A    I84 @T6G_MB_LIB.T6G(SCH_1):PAGE180
  PU19   36 TOUT_FLT ISL99390FRZTR5935-ISL99390FRZ-TR5935,SMLF,IC,AL099A    I32 @T6G_MB_LIB.T6G(SCH_1):PAGE181
  PU20   36 TOUT_FLT ISL99390FRZTR5935-ISL99390FRZ-TR5935,SMLF,IC,AL099A    I73 @T6G_MB_LIB.T6G(SCH_1):PAGE181

PVDDIO_P0_VCC1 @T6G_MB_LIB.T6G(SCH_1):PVDDIO_P0_VCC1
 PC143    1      A Q_CAP_C0402-2.2UF,10V,10%,X6S,CH5222KEB01    I28 @T6G_MB_LIB.T6G(SCH_1):PAGE180
 PR100    2      B Q_RES_0402LF-2.2,1%,1/16W,CHIP,CS-2202FB01    I29 @T6G_MB_LIB.T6G(SCH_1):PAGE180
  PU17   35     EN ISL99390FRZTR5935-ISL99390FRZ-TR5935,SMLF,IC,AL099A    I84 @T6G_MB_LIB.T6G(SCH_1):PAGE180
  PU17    3    VCC ISL99390FRZTR5935-ISL99390FRZ-TR5935,SMLF,IC,AL099A    I84 @T6G_MB_LIB.T6G(SCH_1):PAGE180

PVDDIO_P0_VCC2 @T6G_MB_LIB.T6G(SCH_1):PVDDIO_P0_VCC2
 PC142    1      A Q_CAP_C0402-2.2UF,10V,10%,X6S,CH5222KEB01    I10 @T6G_MB_LIB.T6G(SCH_1):PAGE180
  PR99    2      B Q_RES_0402LF-2.2,1%,1/16W,CHIP,CS-2202FB01    I12 @T6G_MB_LIB.T6G(SCH_1):PAGE180
  PU18   35     EN ISL99390FRZTR5935-ISL99390FRZ-TR5935,SMLF,IC,AL099A    I15 @T6G_MB_LIB.T6G(SCH_1):PAGE180
  PU18    3    VCC ISL99390FRZTR5935-ISL99390FRZ-TR5935,SMLF,IC,AL099A    I15 @T6G_MB_LIB.T6G(SCH_1):PAGE180

PVDDIO_P0_VCC3 @T6G_MB_LIB.T6G(SCH_1):PVDDIO_P0_VCC3
 PR108    2      B Q_RES_0402LF-2.2,1%,1/16W,CHIP,CS-2202FB01    I28 @T6G_MB_LIB.T6G(SCH_1):PAGE181
 PC172    1      A Q_CAP_C0402-2.2UF,10V,10%,X6S,CH5222KEB01    I27 @T6G_MB_LIB.T6G(SCH_1):PAGE181
  PU19   35     EN ISL99390FRZTR5935-ISL99390FRZ-TR5935,SMLF,IC,AL099A    I32 @T6G_MB_LIB.T6G(SCH_1):PAGE181
  PU19    3    VCC ISL99390FRZTR5935-ISL99390FRZ-TR5935,SMLF,IC,AL099A    I32 @T6G_MB_LIB.T6G(SCH_1):PAGE181

PVDDIO_P0_VCC4 @T6G_MB_LIB.T6G(SCH_1):PVDDIO_P0_VCC4
 PC171    1      A Q_CAP_C0402-2.2UF,10V,10%,X6S,CH5222KEB01    I10 @T6G_MB_LIB.T6G(SCH_1):PAGE181
 PR107    2      B Q_RES_0402LF-2.2,1%,1/16W,CHIP,CS-2202FB01    I12 @T6G_MB_LIB.T6G(SCH_1):PAGE181
  PU20   35     EN ISL99390FRZTR5935-ISL99390FRZ-TR5935,SMLF,IC,AL099A    I73 @T6G_MB_LIB.T6G(SCH_1):PAGE181
  PU20    3    VCC ISL99390FRZTR5935-ISL99390FRZ-TR5935,SMLF,IC,AL099A    I73 @T6G_MB_LIB.T6G(SCH_1):PAGE181

PVDDIO_P0_VOS1 @T6G_MB_LIB.T6G(SCH_1):PVDDIO_P0_VOS1
 PR103    1      A Q_RES_0402LF-0,5%,1/16W,CHIP,CS00002JB13    I49 @T6G_MB_LIB.T6G(SCH_1):PAGE180
  PU17    1    VOS ISL99390FRZTR5935-ISL99390FRZ-TR5935,SMLF,IC,AL099A    I84 @T6G_MB_LIB.T6G(SCH_1):PAGE180

PVDDIO_P0_VOS2 @T6G_MB_LIB.T6G(SCH_1):PVDDIO_P0_VOS2
  PU18    1    VOS ISL99390FRZTR5935-ISL99390FRZ-TR5935,SMLF,IC,AL099A    I15 @T6G_MB_LIB.T6G(SCH_1):PAGE180
 PR104    1      A Q_RES_0402LF-0,5%,1/16W,CHIP,CS00002JB13    I39 @T6G_MB_LIB.T6G(SCH_1):PAGE180

PVDDIO_P0_VOS3 @T6G_MB_LIB.T6G(SCH_1):PVDDIO_P0_VOS3
  PU19    1    VOS ISL99390FRZTR5935-ISL99390FRZ-TR5935,SMLF,IC,AL099A    I32 @T6G_MB_LIB.T6G(SCH_1):PAGE181
 PR111    1      A Q_RES_0402LF-0,5%,1/16W,CHIP,CS00002JB13    I50 @T6G_MB_LIB.T6G(SCH_1):PAGE181

PVDDIO_P0_VOS4 @T6G_MB_LIB.T6G(SCH_1):PVDDIO_P0_VOS4
 PR112    1      A Q_RES_0402LF-0,5%,1/16W,CHIP,CS00002JB13    I41 @T6G_MB_LIB.T6G(SCH_1):PAGE181
  PU20    1    VOS ISL99390FRZTR5935-ISL99390FRZ-TR5935,SMLF,IC,AL099A    I73 @T6G_MB_LIB.T6G(SCH_1):PAGE181

PVDDIO_P1 @T6G_MB_LIB.T6G(SCH_1):PVDDIO_P1
   U26 AA54 VDDIO_AA54 GENOA_SP5-SOCKET6096_13568-001,SMLF,IO,DGA^6000030    I45 @T6G_MB_LIB.T6G(SCH_1):PAGE57
   U26 AC58 VDDIO_AC58 GENOA_SP5-SOCKET6096_13568-001,SMLF,IO,DGA^6000030    I45 @T6G_MB_LIB.T6G(SCH_1):PAGE57
   U26 AC65 VDDIO_AC65 GENOA_SP5-SOCKET6096_13568-001,SMLF,IO,DGA^6000030    I45 @T6G_MB_LIB.T6G(SCH_1):PAGE57
   U26 AC72 VDDIO_AC72 GENOA_SP5-SOCKET6096_13568-001,SMLF,IO,DGA^6000030    I45 @T6G_MB_LIB.T6G(SCH_1):PAGE57
   U26 AD54 VDDIO_AD54 GENOA_SP5-SOCKET6096_13568-001,SMLF,IO,DGA^6000030    I45 @T6G_MB_LIB.T6G(SCH_1):PAGE57
   U26 AF57 VDDIO_AF57 GENOA_SP5-SOCKET6096_13568-001,SMLF,IO,DGA^6000030    I45 @T6G_MB_LIB.T6G(SCH_1):PAGE57
   U26 AF64 VDDIO_AF64 GENOA_SP5-SOCKET6096_13568-001,SMLF,IO,DGA^6000030    I45 @T6G_MB_LIB.T6G(SCH_1):PAGE57
   U26 AF71 VDDIO_AF71 GENOA_SP5-SOCKET6096_13568-001,SMLF,IO,DGA^6000030    I45 @T6G_MB_LIB.T6G(SCH_1):PAGE57
   U26 AH54 VDDIO_AH54 GENOA_SP5-SOCKET6096_13568-001,SMLF,IO,DGA^6000030    I45 @T6G_MB_LIB.T6G(SCH_1):PAGE57
   U26 AJ58 VDDIO_AJ58 GENOA_SP5-SOCKET6096_13568-001,SMLF,IO,DGA^6000030    I45 @T6G_MB_LIB.T6G(SCH_1):PAGE57
   U26 AJ65 VDDIO_AJ65 GENOA_SP5-SOCKET6096_13568-001,SMLF,IO,DGA^6000030    I45 @T6G_MB_LIB.T6G(SCH_1):PAGE57
   U26 AJ72 VDDIO_AJ72 GENOA_SP5-SOCKET6096_13568-001,SMLF,IO,DGA^6000030    I45 @T6G_MB_LIB.T6G(SCH_1):PAGE57
   U26 AM54 VDDIO_AM54 GENOA_SP5-SOCKET6096_13568-001,SMLF,IO,DGA^6000030    I45 @T6G_MB_LIB.T6G(SCH_1):PAGE57
   U26 AM57 VDDIO_AM57 GENOA_SP5-SOCKET6096_13568-001,SMLF,IO,DGA^6000030    I45 @T6G_MB_LIB.T6G(SCH_1):PAGE57
   U26 AM64 VDDIO_AM64 GENOA_SP5-SOCKET6096_13568-001,SMLF,IO,DGA^6000030    I45 @T6G_MB_LIB.T6G(SCH_1):PAGE57
   U26 AM71 VDDIO_AM71 GENOA_SP5-SOCKET6096_13568-001,SMLF,IO,DGA^6000030    I45 @T6G_MB_LIB.T6G(SCH_1):PAGE57
   U26 AR58 VDDIO_AR58 GENOA_SP5-SOCKET6096_13568-001,SMLF,IO,DGA^6000030    I45 @T6G_MB_LIB.T6G(SCH_1):PAGE57
   U26 AR65 VDDIO_AR65 GENOA_SP5-SOCKET6096_13568-001,SMLF,IO,DGA^6000030    I45 @T6G_MB_LIB.T6G(SCH_1):PAGE57
   U26 AR72 VDDIO_AR72 GENOA_SP5-SOCKET6096_13568-001,SMLF,IO,DGA^6000030    I45 @T6G_MB_LIB.T6G(SCH_1):PAGE57
   U26 AV57 VDDIO_AV57 GENOA_SP5-SOCKET6096_13568-001,SMLF,IO,DGA^6000030    I45 @T6G_MB_LIB.T6G(SCH_1):PAGE57
   U26 AV64 VDDIO_AV64 GENOA_SP5-SOCKET6096_13568-001,SMLF,IO,DGA^6000030    I45 @T6G_MB_LIB.T6G(SCH_1):PAGE57
   U26 AV71 VDDIO_AV71 GENOA_SP5-SOCKET6096_13568-001,SMLF,IO,DGA^6000030    I45 @T6G_MB_LIB.T6G(SCH_1):PAGE57
   U26 BA58 VDDIO_BA58 GENOA_SP5-SOCKET6096_13568-001,SMLF,IO,DGA^6000030    I45 @T6G_MB_LIB.T6G(SCH_1):PAGE57
   U26 BA65 VDDIO_BA65 GENOA_SP5-SOCKET6096_13568-001,SMLF,IO,DGA^6000030    I45 @T6G_MB_LIB.T6G(SCH_1):PAGE57
   U26 BA72 VDDIO_BA72 GENOA_SP5-SOCKET6096_13568-001,SMLF,IO,DGA^6000030    I45 @T6G_MB_LIB.T6G(SCH_1):PAGE57
   U26 BD50 VDDIO_BD50 GENOA_SP5-SOCKET6096_13568-001,SMLF,IO,DGA^6000030    I45 @T6G_MB_LIB.T6G(SCH_1):PAGE57
   U26 BD52 VDDIO_BD52 GENOA_SP5-SOCKET6096_13568-001,SMLF,IO,DGA^6000030    I45 @T6G_MB_LIB.T6G(SCH_1):PAGE57
   U26 BD54 VDDIO_BD54 GENOA_SP5-SOCKET6096_13568-001,SMLF,IO,DGA^6000030    I45 @T6G_MB_LIB.T6G(SCH_1):PAGE57
   U26 BF51 VDDIO_BF51 GENOA_SP5-SOCKET6096_13568-001,SMLF,IO,DGA^6000030    I45 @T6G_MB_LIB.T6G(SCH_1):PAGE57
   U26 BF53 VDDIO_BF53 GENOA_SP5-SOCKET6096_13568-001,SMLF,IO,DGA^6000030    I45 @T6G_MB_LIB.T6G(SCH_1):PAGE57
   U26 BF57 VDDIO_BF57 GENOA_SP5-SOCKET6096_13568-001,SMLF,IO,DGA^6000030    I45 @T6G_MB_LIB.T6G(SCH_1):PAGE57
   U26 BF64 VDDIO_BF64 GENOA_SP5-SOCKET6096_13568-001,SMLF,IO,DGA^6000030    I45 @T6G_MB_LIB.T6G(SCH_1):PAGE57
   U26 BF71 VDDIO_BF71 GENOA_SP5-SOCKET6096_13568-001,SMLF,IO,DGA^6000030    I45 @T6G_MB_LIB.T6G(SCH_1):PAGE57
   U26 BG50 VDDIO_BG50 GENOA_SP5-SOCKET6096_13568-001,SMLF,IO,DGA^6000030    I45 @T6G_MB_LIB.T6G(SCH_1):PAGE57
   U26 BG52 VDDIO_BG52 GENOA_SP5-SOCKET6096_13568-001,SMLF,IO,DGA^6000030    I45 @T6G_MB_LIB.T6G(SCH_1):PAGE57
   U26 BG54 VDDIO_BG54 GENOA_SP5-SOCKET6096_13568-001,SMLF,IO,DGA^6000030    I45 @T6G_MB_LIB.T6G(SCH_1):PAGE57
   U26 BH51 VDDIO_BH51 GENOA_SP5-SOCKET6096_13568-001,SMLF,IO,DGA^6000030    I45 @T6G_MB_LIB.T6G(SCH_1):PAGE57
   U26 BH53 VDDIO_BH53 GENOA_SP5-SOCKET6096_13568-001,SMLF,IO,DGA^6000030    I45 @T6G_MB_LIB.T6G(SCH_1):PAGE57
   U26 BJ50 VDDIO_BJ50 GENOA_SP5-SOCKET6096_13568-001,SMLF,IO,DGA^6000030    I45 @T6G_MB_LIB.T6G(SCH_1):PAGE57
   U26 BJ52 VDDIO_BJ52 GENOA_SP5-SOCKET6096_13568-001,SMLF,IO,DGA^6000030    I45 @T6G_MB_LIB.T6G(SCH_1):PAGE57
   U26 BJ54 VDDIO_BJ54 GENOA_SP5-SOCKET6096_13568-001,SMLF,IO,DGA^6000030    I45 @T6G_MB_LIB.T6G(SCH_1):PAGE57
   U26 BJ58 VDDIO_BJ58 GENOA_SP5-SOCKET6096_13568-001,SMLF,IO,DGA^6000030    I45 @T6G_MB_LIB.T6G(SCH_1):PAGE57
   U26 BJ65 VDDIO_BJ65 GENOA_SP5-SOCKET6096_13568-001,SMLF,IO,DGA^6000030    I45 @T6G_MB_LIB.T6G(SCH_1):PAGE57
   U26 BJ72 VDDIO_BJ72 GENOA_SP5-SOCKET6096_13568-001,SMLF,IO,DGA^6000030    I45 @T6G_MB_LIB.T6G(SCH_1):PAGE57
   U26 BK51 VDDIO_BK51 GENOA_SP5-SOCKET6096_13568-001,SMLF,IO,DGA^6000030    I45 @T6G_MB_LIB.T6G(SCH_1):PAGE57
   U26 BK53 VDDIO_BK53 GENOA_SP5-SOCKET6096_13568-001,SMLF,IO,DGA^6000030    I45 @T6G_MB_LIB.T6G(SCH_1):PAGE57
   U26 BL50 VDDIO_BL50 GENOA_SP5-SOCKET6096_13568-001,SMLF,IO,DGA^6000030    I45 @T6G_MB_LIB.T6G(SCH_1):PAGE57
   U26 BL52 VDDIO_BL52 GENOA_SP5-SOCKET6096_13568-001,SMLF,IO,DGA^6000030    I45 @T6G_MB_LIB.T6G(SCH_1):PAGE57
   U26 BL54 VDDIO_BL54 GENOA_SP5-SOCKET6096_13568-001,SMLF,IO,DGA^6000030    I45 @T6G_MB_LIB.T6G(SCH_1):PAGE57
   U26 BM51 VDDIO_BM51 GENOA_SP5-SOCKET6096_13568-001,SMLF,IO,DGA^6000030    I45 @T6G_MB_LIB.T6G(SCH_1):PAGE57
   U26 BM53 VDDIO_BM53 GENOA_SP5-SOCKET6096_13568-001,SMLF,IO,DGA^6000030    I45 @T6G_MB_LIB.T6G(SCH_1):PAGE57
   U26 BM57 VDDIO_BM57 GENOA_SP5-SOCKET6096_13568-001,SMLF,IO,DGA^6000030    I45 @T6G_MB_LIB.T6G(SCH_1):PAGE57
   U26 BM64 VDDIO_BM64 GENOA_SP5-SOCKET6096_13568-001,SMLF,IO,DGA^6000030    I45 @T6G_MB_LIB.T6G(SCH_1):PAGE57
   U26 BM71 VDDIO_BM71 GENOA_SP5-SOCKET6096_13568-001,SMLF,IO,DGA^6000030    I45 @T6G_MB_LIB.T6G(SCH_1):PAGE57
   U26 BN54 VDDIO_BN54 GENOA_SP5-SOCKET6096_13568-001,SMLF,IO,DGA^6000030    I45 @T6G_MB_LIB.T6G(SCH_1):PAGE57
   U26 BR58 VDDIO_BR58 GENOA_SP5-SOCKET6096_13568-001,SMLF,IO,DGA^6000030    I45 @T6G_MB_LIB.T6G(SCH_1):PAGE57
   U26 BR65 VDDIO_BR65 GENOA_SP5-SOCKET6096_13568-001,SMLF,IO,DGA^6000030    I45 @T6G_MB_LIB.T6G(SCH_1):PAGE57
   U26 BR72 VDDIO_BR72 GENOA_SP5-SOCKET6096_13568-001,SMLF,IO,DGA^6000030    I45 @T6G_MB_LIB.T6G(SCH_1):PAGE57
   U26 BV54 VDDIO_BV54 GENOA_SP5-SOCKET6096_13568-001,SMLF,IO,DGA^6000030    I45 @T6G_MB_LIB.T6G(SCH_1):PAGE57
   U26 BV57 VDDIO_BV57 GENOA_SP5-SOCKET6096_13568-001,SMLF,IO,DGA^6000030    I45 @T6G_MB_LIB.T6G(SCH_1):PAGE57
   U26 BV64 VDDIO_BV64 GENOA_SP5-SOCKET6096_13568-001,SMLF,IO,DGA^6000030    I45 @T6G_MB_LIB.T6G(SCH_1):PAGE57
   U26 BV71 VDDIO_BV71 GENOA_SP5-SOCKET6096_13568-001,SMLF,IO,DGA^6000030    I45 @T6G_MB_LIB.T6G(SCH_1):PAGE57
   U26 CA58 VDDIO_CA58 GENOA_SP5-SOCKET6096_13568-001,SMLF,IO,DGA^6000030    I45 @T6G_MB_LIB.T6G(SCH_1):PAGE57
   U26 CA65 VDDIO_CA65 GENOA_SP5-SOCKET6096_13568-001,SMLF,IO,DGA^6000030    I45 @T6G_MB_LIB.T6G(SCH_1):PAGE57
   U26 CA72 VDDIO_CA72 GENOA_SP5-SOCKET6096_13568-001,SMLF,IO,DGA^6000030    I45 @T6G_MB_LIB.T6G(SCH_1):PAGE57
   U26 CB54 VDDIO_CB54 GENOA_SP5-SOCKET6096_13568-001,SMLF,IO,DGA^6000030    I45 @T6G_MB_LIB.T6G(SCH_1):PAGE57
   U26 CD57 VDDIO_CD57 GENOA_SP5-SOCKET6096_13568-001,SMLF,IO,DGA^6000030    I45 @T6G_MB_LIB.T6G(SCH_1):PAGE57
   U26 CD64 VDDIO_CD64 GENOA_SP5-SOCKET6096_13568-001,SMLF,IO,DGA^6000030    I45 @T6G_MB_LIB.T6G(SCH_1):PAGE57
   U26 CD71 VDDIO_CD71 GENOA_SP5-SOCKET6096_13568-001,SMLF,IO,DGA^6000030    I45 @T6G_MB_LIB.T6G(SCH_1):PAGE57
   U26 CF54 VDDIO_CF54 GENOA_SP5-SOCKET6096_13568-001,SMLF,IO,DGA^6000030    I45 @T6G_MB_LIB.T6G(SCH_1):PAGE57
   U26 CG58 VDDIO_CG58 GENOA_SP5-SOCKET6096_13568-001,SMLF,IO,DGA^6000030    I45 @T6G_MB_LIB.T6G(SCH_1):PAGE57
   U26 CG65 VDDIO_CG65 GENOA_SP5-SOCKET6096_13568-001,SMLF,IO,DGA^6000030    I45 @T6G_MB_LIB.T6G(SCH_1):PAGE57
   U26 CG72 VDDIO_CG72 GENOA_SP5-SOCKET6096_13568-001,SMLF,IO,DGA^6000030    I45 @T6G_MB_LIB.T6G(SCH_1):PAGE57
   U26 CJ54 VDDIO_CJ54 GENOA_SP5-SOCKET6096_13568-001,SMLF,IO,DGA^6000030    I45 @T6G_MB_LIB.T6G(SCH_1):PAGE57
   U26 CK57 VDDIO_CK57 GENOA_SP5-SOCKET6096_13568-001,SMLF,IO,DGA^6000030    I45 @T6G_MB_LIB.T6G(SCH_1):PAGE57
   U26 CK64 VDDIO_CK64 GENOA_SP5-SOCKET6096_13568-001,SMLF,IO,DGA^6000030    I45 @T6G_MB_LIB.T6G(SCH_1):PAGE57
   U26 CK71 VDDIO_CK71 GENOA_SP5-SOCKET6096_13568-001,SMLF,IO,DGA^6000030    I45 @T6G_MB_LIB.T6G(SCH_1):PAGE57
   U26 CM54 VDDIO_CM54 GENOA_SP5-SOCKET6096_13568-001,SMLF,IO,DGA^6000030    I45 @T6G_MB_LIB.T6G(SCH_1):PAGE57
   U26 CN58 VDDIO_CN58 GENOA_SP5-SOCKET6096_13568-001,SMLF,IO,DGA^6000030    I45 @T6G_MB_LIB.T6G(SCH_1):PAGE57
   U26 CN65 VDDIO_CN65 GENOA_SP5-SOCKET6096_13568-001,SMLF,IO,DGA^6000030    I45 @T6G_MB_LIB.T6G(SCH_1):PAGE57
   U26 CN72 VDDIO_CN72 GENOA_SP5-SOCKET6096_13568-001,SMLF,IO,DGA^6000030    I45 @T6G_MB_LIB.T6G(SCH_1):PAGE57
   U26 CT54 VDDIO_CT54 GENOA_SP5-SOCKET6096_13568-001,SMLF,IO,DGA^6000030    I45 @T6G_MB_LIB.T6G(SCH_1):PAGE57
   U26 CT57 VDDIO_CT57 GENOA_SP5-SOCKET6096_13568-001,SMLF,IO,DGA^6000030    I45 @T6G_MB_LIB.T6G(SCH_1):PAGE57
   U26 CT64 VDDIO_CT64 GENOA_SP5-SOCKET6096_13568-001,SMLF,IO,DGA^6000030    I45 @T6G_MB_LIB.T6G(SCH_1):PAGE57
   U26 CT71 VDDIO_CT71 GENOA_SP5-SOCKET6096_13568-001,SMLF,IO,DGA^6000030    I45 @T6G_MB_LIB.T6G(SCH_1):PAGE57
   U26 CW58 VDDIO_CW58 GENOA_SP5-SOCKET6096_13568-001,SMLF,IO,DGA^6000030    I45 @T6G_MB_LIB.T6G(SCH_1):PAGE57
   U26 CW65 VDDIO_CW65 GENOA_SP5-SOCKET6096_13568-001,SMLF,IO,DGA^6000030    I45 @T6G_MB_LIB.T6G(SCH_1):PAGE57
   U26 CW72 VDDIO_CW72 GENOA_SP5-SOCKET6096_13568-001,SMLF,IO,DGA^6000030    I45 @T6G_MB_LIB.T6G(SCH_1):PAGE57
   U26 CY54 VDDIO_CY54 GENOA_SP5-SOCKET6096_13568-001,SMLF,IO,DGA^6000030    I45 @T6G_MB_LIB.T6G(SCH_1):PAGE57
   U26 DB57 VDDIO_DB57 GENOA_SP5-SOCKET6096_13568-001,SMLF,IO,DGA^6000030    I45 @T6G_MB_LIB.T6G(SCH_1):PAGE57
   U26 DB64 VDDIO_DB64 GENOA_SP5-SOCKET6096_13568-001,SMLF,IO,DGA^6000030    I45 @T6G_MB_LIB.T6G(SCH_1):PAGE57
   U26 DB71 VDDIO_DB71 GENOA_SP5-SOCKET6096_13568-001,SMLF,IO,DGA^6000030    I45 @T6G_MB_LIB.T6G(SCH_1):PAGE57
   U26 DE58 VDDIO_DE58 GENOA_SP5-SOCKET6096_13568-001,SMLF,IO,DGA^6000030    I45 @T6G_MB_LIB.T6G(SCH_1):PAGE57
   U26 DE65 VDDIO_DE65 GENOA_SP5-SOCKET6096_13568-001,SMLF,IO,DGA^6000030    I45 @T6G_MB_LIB.T6G(SCH_1):PAGE57
   U26 DE72 VDDIO_DE72 GENOA_SP5-SOCKET6096_13568-001,SMLF,IO,DGA^6000030    I45 @T6G_MB_LIB.T6G(SCH_1):PAGE57
   U26 DG64 VDDIO_DG64 GENOA_SP5-SOCKET6096_13568-001,SMLF,IO,DGA^6000030    I45 @T6G_MB_LIB.T6G(SCH_1):PAGE57
   U26 DG71 VDDIO_DG71 GENOA_SP5-SOCKET6096_13568-001,SMLF,IO,DGA^6000030    I45 @T6G_MB_LIB.T6G(SCH_1):PAGE57
   U26  H57 VDDIO_H57 GENOA_SP5-SOCKET6096_13568-001,SMLF,IO,DGA^6000030    I45 @T6G_MB_LIB.T6G(SCH_1):PAGE57
   U26  H64 VDDIO_H64 GENOA_SP5-SOCKET6096_13568-001,SMLF,IO,DGA^6000030    I45 @T6G_MB_LIB.T6G(SCH_1):PAGE57
   U26  H71 VDDIO_H71 GENOA_SP5-SOCKET6096_13568-001,SMLF,IO,DGA^6000030    I45 @T6G_MB_LIB.T6G(SCH_1):PAGE57
   U26  K54 VDDIO_K54 GENOA_SP5-SOCKET6096_13568-001,SMLF,IO,DGA^6000030    I45 @T6G_MB_LIB.T6G(SCH_1):PAGE57
   U26  L58 VDDIO_L58 GENOA_SP5-SOCKET6096_13568-001,SMLF,IO,DGA^6000030    I45 @T6G_MB_LIB.T6G(SCH_1):PAGE57
   U26  L65 VDDIO_L65 GENOA_SP5-SOCKET6096_13568-001,SMLF,IO,DGA^6000030    I45 @T6G_MB_LIB.T6G(SCH_1):PAGE57
   U26  L72 VDDIO_L72 GENOA_SP5-SOCKET6096_13568-001,SMLF,IO,DGA^6000030    I45 @T6G_MB_LIB.T6G(SCH_1):PAGE57
   U26  P54 VDDIO_P54 GENOA_SP5-SOCKET6096_13568-001,SMLF,IO,DGA^6000030    I45 @T6G_MB_LIB.T6G(SCH_1):PAGE57
   U26  P57 VDDIO_P57 GENOA_SP5-SOCKET6096_13568-001,SMLF,IO,DGA^6000030    I45 @T6G_MB_LIB.T6G(SCH_1):PAGE57
   U26  P64 VDDIO_P64 GENOA_SP5-SOCKET6096_13568-001,SMLF,IO,DGA^6000030    I45 @T6G_MB_LIB.T6G(SCH_1):PAGE57
   U26  P71 VDDIO_P71 GENOA_SP5-SOCKET6096_13568-001,SMLF,IO,DGA^6000030    I45 @T6G_MB_LIB.T6G(SCH_1):PAGE57
   U26  U58 VDDIO_U58 GENOA_SP5-SOCKET6096_13568-001,SMLF,IO,DGA^6000030    I45 @T6G_MB_LIB.T6G(SCH_1):PAGE57
   U26  U65 VDDIO_U65 GENOA_SP5-SOCKET6096_13568-001,SMLF,IO,DGA^6000030    I45 @T6G_MB_LIB.T6G(SCH_1):PAGE57
   U26  U72 VDDIO_U72 GENOA_SP5-SOCKET6096_13568-001,SMLF,IO,DGA^6000030    I45 @T6G_MB_LIB.T6G(SCH_1):PAGE57
   U26  V54 VDDIO_V54 GENOA_SP5-SOCKET6096_13568-001,SMLF,IO,DGA^6000030    I45 @T6G_MB_LIB.T6G(SCH_1):PAGE57
   U26  Y57 VDDIO_Y57 GENOA_SP5-SOCKET6096_13568-001,SMLF,IO,DGA^6000030    I45 @T6G_MB_LIB.T6G(SCH_1):PAGE57
   U26  Y64 VDDIO_Y64 GENOA_SP5-SOCKET6096_13568-001,SMLF,IO,DGA^6000030    I45 @T6G_MB_LIB.T6G(SCH_1):PAGE57
   U26  Y71 VDDIO_Y71 GENOA_SP5-SOCKET6096_13568-001,SMLF,IO,DGA^6000030    I45 @T6G_MB_LIB.T6G(SCH_1):PAGE57
 C2260    1      A Q_CAP_C0402-22UF,4V,20%,X6S,CH622KMEB02    I53 @T6G_MB_LIB.T6G(SCH_1):PAGE71
 C2265    1      A Q_CAP_C0402-22UF,4V,20%,X6S,CH622KMEB02    I54 @T6G_MB_LIB.T6G(SCH_1):PAGE71
 C2270    1      A Q_CAP_C0402-22UF,4V,20%,X6S,CH622KMEB02    I56 @T6G_MB_LIB.T6G(SCH_1):PAGE71
 C2274    1      A Q_CAP_C0402-22UF,4V,20%,X6S,CH622KMEB02    I57 @T6G_MB_LIB.T6G(SCH_1):PAGE71
 C2278    1      A Q_CAP_C0402-22UF,4V,20%,X6S,CH622KMEB02    I58 @T6G_MB_LIB.T6G(SCH_1):PAGE71
 C3910    1      A Q_CAP_C0402-22UF,4V,20%,X6S,CH622KMEB02    I59 @T6G_MB_LIB.T6G(SCH_1):PAGE71
 C3911    1      A Q_CAP_C0402-22UF,4V,20%,X6S,CH622KMEB02    I61 @T6G_MB_LIB.T6G(SCH_1):PAGE71
 C2479    1      A Q_CAP_C0402-22UF,4V,20%,X6S,CH622KMEB02   I129 @T6G_MB_LIB.T6G(SCH_1):PAGE73
 C2478    1      A Q_CAP_C0402-22UF,4V,20%,X6S,CH622KMEB02   I134 @T6G_MB_LIB.T6G(SCH_1):PAGE73
 C2477    1      A Q_CAP_C0402-22UF,4V,20%,X6S,CH622KMEB02   I136 @T6G_MB_LIB.T6G(SCH_1):PAGE73
 C2103    1      A Q_CAP_C0402-22UF,4V,20%,X6S,CH622KMEB02   I137 @T6G_MB_LIB.T6G(SCH_1):PAGE73
 C2106    1      A Q_CAP_C0402-22UF,4V,20%,X6S,CH622KMEB02   I138 @T6G_MB_LIB.T6G(SCH_1):PAGE73
 C2484    1      A Q_CAP_C0402-22UF,4V,20%,X6S,CH622KMEB02   I139 @T6G_MB_LIB.T6G(SCH_1):PAGE73
 C2102    1      A Q_CAP_C0402-22UF,4V,20%,X6S,CH622KMEB02   I140 @T6G_MB_LIB.T6G(SCH_1):PAGE73
 C2105    1      A Q_CAP_C0402-22UF,4V,20%,X6S,CH622KMEB02   I141 @T6G_MB_LIB.T6G(SCH_1):PAGE73
 C2104    1      A Q_CAP_C0402-22UF,4V,20%,X6S,CH622KMEB02   I142 @T6G_MB_LIB.T6G(SCH_1):PAGE73
 C2108    1      A Q_CAP_C0402-22UF,4V,20%,X6S,CH622KMEB02   I144 @T6G_MB_LIB.T6G(SCH_1):PAGE73
 C2107    1      A Q_CAP_C0402-22UF,4V,20%,X6S,CH622KMEB02   I145 @T6G_MB_LIB.T6G(SCH_1):PAGE73
 C2493    1      A Q_CAP_C0402-22UF,4V,20%,X6S,CH622KMEB02   I146 @T6G_MB_LIB.T6G(SCH_1):PAGE73
 C2498    1      A Q_CAP_C0402-22UF,4V,20%,X6S,CH622KMEB02   I147 @T6G_MB_LIB.T6G(SCH_1):PAGE73
 C2109    1      A Q_CAP_C0402-22UF,4V,20%,X6S,CH622KMEB02   I148 @T6G_MB_LIB.T6G(SCH_1):PAGE73
 C2111    1      A Q_CAP_C0402-22UF,4V,20%,X6S,CH622KMEB02   I149 @T6G_MB_LIB.T6G(SCH_1):PAGE73
 C2112    1      A Q_CAP_C0402-22UF,4V,20%,X6S,CH622KMEB02   I150 @T6G_MB_LIB.T6G(SCH_1):PAGE73
 C2110    1      A Q_CAP_C0402-22UF,4V,20%,X6S,CH622KMEB02   I151 @T6G_MB_LIB.T6G(SCH_1):PAGE73
 C2507    1      A Q_CAP_C0402-22UF,4V,20%,X6S,CH622KMEB02   I152 @T6G_MB_LIB.T6G(SCH_1):PAGE73
 C2117    1      A Q_CAP_C0402-22UF,4V,20%,X6S,CH622KMEB02   I153 @T6G_MB_LIB.T6G(SCH_1):PAGE73
 C2116    1      A Q_CAP_C0402-22UF,4V,20%,X6S,CH622KMEB02   I154 @T6G_MB_LIB.T6G(SCH_1):PAGE73
 C2123    1      A Q_CAP_C0402-22UF,4V,20%,X6S,CH622KMEB02   I168 @T6G_MB_LIB.T6G(SCH_1):PAGE73
 C2122    1      A Q_CAP_C0402-22UF,4V,20%,X6S,CH622KMEB02   I169 @T6G_MB_LIB.T6G(SCH_1):PAGE73
 C2509    1      A Q_CAP_C0402-22UF,4V,20%,X6S,CH622KMEB02   I170 @T6G_MB_LIB.T6G(SCH_1):PAGE73
 C2127    1      A Q_CAP_C0402-22UF,4V,20%,X6S,CH622KMEB02   I172 @T6G_MB_LIB.T6G(SCH_1):PAGE73
PC634_4    1      A Q_CAP_C0805-22UF,4V,20%,X6S,CH622KMEA03    I51 @T6G_MB_LIB.T6G(SCH_1):PAGE198
 PR374    2      B Q_RES_0402LF-0,5%,1/16W,CHIP,CS00002JB13    I55 @T6G_MB_LIB.T6G(SCH_1):PAGE198
PC635_3    1      A Q_CAP_C0805-22UF,4V,20%,X6S,CH622KMEA03    I68 @T6G_MB_LIB.T6G(SCH_1):PAGE198
 PR227    2      B Q_RES_0402LF-49.9,1%,1/16W,CHIP,CS04992FB07    I22 @T6G_MB_LIB.T6G(SCH_1):PAGE192
 PR281    2      B Q_RES_0402LF-0,5%,1/16W,CHIP,CS00002JB13    I45 @T6G_MB_LIB.T6G(SCH_1):PAGE197
 PR280    2      B Q_RES_0402LF-0,5%,1/16W,CHIP,CS00002JB13    I50 @T6G_MB_LIB.T6G(SCH_1):PAGE197
PC458_2    1      A Q_CAP_C0805-22UF,4V,20%,X6S,CH622KMEA03    I55 @T6G_MB_LIB.T6G(SCH_1):PAGE197
PC460_2    1      A Q_CAP_C0805-22UF,4V,20%,X6S,CH622KMEA03    I57 @T6G_MB_LIB.T6G(SCH_1):PAGE197
 PC450    1      A Q_CAPP_SMLF-470UF,2.5V,20%,SPCAP,CH747LM8825    I58 @T6G_MB_LIB.T6G(SCH_1):PAGE197
 PC452    1      A Q_CAPP_SMLF-470UF,2.5V,20%,SPCAP,CH747LM8825    I59 @T6G_MB_LIB.T6G(SCH_1):PAGE197
 PC455    1      A Q_CAPP_SMLF-470UF,2.5V,20%,EMPTY,CH747LM8825    I62 @T6G_MB_LIB.T6G(SCH_1):PAGE197
  PL47    4      4 Q_INDUCTOR4P_14-150NH,SMLF,IND,CV+15^0TZ04    I71 @T6G_MB_LIB.T6G(SCH_1):PAGE197
 PC451    1      A Q_CAP_C0402-100NF,50V,10%,X7R,CH4106K1B01    I77 @T6G_MB_LIB.T6G(SCH_1):PAGE197
PC456_1    1      A Q_CAP_C0805-22UF,4V,20%,X6S,CH622KMEA03    I78 @T6G_MB_LIB.T6G(SCH_1):PAGE197
PC459_1    1      A Q_CAP_C0805-22UF,4V,20%,X6S,CH622KMEA03    I79 @T6G_MB_LIB.T6G(SCH_1):PAGE197
 PR378    1      A Q_RES_0402LF-1K,1%,1/16W,CHIP,CS21002FB06    I81 @T6G_MB_LIB.T6G(SCH_1):PAGE197
  PL48    4      4 Q_INDUCTOR4P_14-150NH,SMLF,IND,CV+15^0TZ04    I83 @T6G_MB_LIB.T6G(SCH_1):PAGE197
 PR375    2      B Q_RES_0402LF-0,5%,1/16W,CHIP,CS00002JB13    I41 @T6G_MB_LIB.T6G(SCH_1):PAGE198
  PL67    4      4 Q_INDUCTOR4P_14-150NH,SMLF,IND,CV+15^0TZ04    I42 @T6G_MB_LIB.T6G(SCH_1):PAGE198
PC636_4    1      A Q_CAP_C0805-22UF,4V,20%,X6S,CH622KMEA03    I53 @T6G_MB_LIB.T6G(SCH_1):PAGE198
  PL68    4      4 Q_INDUCTOR4P_14-150NH,SMLF,IND,CV+15^0TZ04    I62 @T6G_MB_LIB.T6G(SCH_1):PAGE198
PC637_3    1      A Q_CAP_C0805-22UF,4V,20%,X6S,CH622KMEA03    I70 @T6G_MB_LIB.T6G(SCH_1):PAGE198

PVDDIO_P1_EN @T6G_MB_LIB.T6G(SCH_1):PVDDIO_P1_EN
  R282    1      A Q_RES_0402LF-33,5%,1/16W,CHIP,CS03302JB10    I31 @T6G_MB_LIB.T6G(SCH_1):PAGE80
 R8224    1      A Q_RES_0402LF-0,5%,1/16W,CHIP,CS00002JB13     I2 @T6G_MB_LIB.T6G(SCH_1):PAGE192

PVDDIO_P1_EN_G @T6G_MB_LIB.T6G(SCH_1):PVDDIO_P1_EN_G
  PQ16    D  DRAIN MOSFET_N_SMLF-BSS138K,BSS138K,IC,BAM138K0000     I6 @T6G_MB_LIB.T6G(SCH_1):PAGE192
  PQ12    G      G MOSFET_PCH_GDS_ESD_PROTECTED-PJA3415AE,SMLF,IC,BAMA    I13 @T6G_MB_LIB.T6G(SCH_1):PAGE192
 PR232    2      B Q_RES_0402LF-1K,1%,1/16W,CHIP,CS21002FB06    I17 @T6G_MB_LIB.T6G(SCH_1):PAGE192

PVDDIO_P1_EN_R @T6G_MB_LIB.T6G(SCH_1):PVDDIO_P1_EN_R
 R8224    2      B Q_RES_0402LF-0,5%,1/16W,CHIP,CS00002JB13     I2 @T6G_MB_LIB.T6G(SCH_1):PAGE192
 C8356    1      A Q_CAP_0402-1000PF,50V,5%,X7R,TMP_QCH21006JB10     I3 @T6G_MB_LIB.T6G(SCH_1):PAGE192
  PQ16    G   GATE MOSFET_N_SMLF-BSS138K,BSS138K,IC,BAM138K0000     I6 @T6G_MB_LIB.T6G(SCH_1):PAGE192
 R6088    1      A Q_RES_0402LF-10K,1%,1/16W,EMPTY,CS31002FB08   I130 @T6G_MB_LIB.T6G(SCH_1):PAGE192

PVDDIO_P1_IMON1 @T6G_MB_LIB.T6G(SCH_1):PVDDIO_P1_IMON1
  PU34   38    CS0 RAA229620GNPHA0-RAA229620GNP#HA0,SMLF,IC,ARF0TGP40A   I128 @T6G_MB_LIB.T6G(SCH_1):PAGE192
  PU39   38   IOUT ISL99390FRZTR5935-ISL99390FRZ-TR5935,SMLF,IC,AL099A    I39 @T6G_MB_LIB.T6G(SCH_1):PAGE197

PVDDIO_P1_IMON2 @T6G_MB_LIB.T6G(SCH_1):PVDDIO_P1_IMON2
  PU34   37    CS1 RAA229620GNPHA0-RAA229620GNP#HA0,SMLF,IC,ARF0TGP40A   I128 @T6G_MB_LIB.T6G(SCH_1):PAGE192
  PU40   38   IOUT ISL99390FRZTR5935-ISL99390FRZ-TR5935,SMLF,IC,AL099A    I84 @T6G_MB_LIB.T6G(SCH_1):PAGE197

PVDDIO_P1_IMON3 @T6G_MB_LIB.T6G(SCH_1):PVDDIO_P1_IMON3
  PU34   36    CS2 RAA229620GNPHA0-RAA229620GNP#HA0,SMLF,IC,ARF0TGP40A   I128 @T6G_MB_LIB.T6G(SCH_1):PAGE192
  PU52   38   IOUT ISL99390FRZTR5935-ISL99390FRZ-TR5935,SMLF,IC,AL099A    I73 @T6G_MB_LIB.T6G(SCH_1):PAGE198

PVDDIO_P1_IMON4 @T6G_MB_LIB.T6G(SCH_1):PVDDIO_P1_IMON4
  PU53   38   IOUT ISL99390FRZTR5935-ISL99390FRZ-TR5935,SMLF,IC,AL099A    I15 @T6G_MB_LIB.T6G(SCH_1):PAGE198
  PU34   35    CS3 RAA229620GNPHA0-RAA229620GNP#HA0,SMLF,IC,ARF0TGP40A   I128 @T6G_MB_LIB.T6G(SCH_1):PAGE192

PVDDIO_P1_LSET1 @T6G_MB_LIB.T6G(SCH_1):PVDDIO_P1_LSET1
 PR275    1      A Q_RES_0402LF-8.87K,1%,1/16W,EMPTY,CS28872FB01    I28 @T6G_MB_LIB.T6G(SCH_1):PAGE197
  PU39   37   LSET ISL99390FRZTR5935-ISL99390FRZ-TR5935,SMLF,IC,AL099A    I39 @T6G_MB_LIB.T6G(SCH_1):PAGE197

PVDDIO_P1_LSET2 @T6G_MB_LIB.T6G(SCH_1):PVDDIO_P1_LSET2
 PR274    1      A Q_RES_0402LF-8.87K,1%,1/16W,EMPTY,CS28872FB01     I6 @T6G_MB_LIB.T6G(SCH_1):PAGE197
  PU40   37   LSET ISL99390FRZTR5935-ISL99390FRZ-TR5935,SMLF,IC,AL099A    I84 @T6G_MB_LIB.T6G(SCH_1):PAGE197

PVDDIO_P1_LSET3 @T6G_MB_LIB.T6G(SCH_1):PVDDIO_P1_LSET3
 PR369    1      A Q_RES_0402LF-8.87K,1%,1/16W,EMPTY,CS28872FB01    I22 @T6G_MB_LIB.T6G(SCH_1):PAGE198
  PU52   37   LSET ISL99390FRZTR5935-ISL99390FRZ-TR5935,SMLF,IC,AL099A    I73 @T6G_MB_LIB.T6G(SCH_1):PAGE198

PVDDIO_P1_LSET4 @T6G_MB_LIB.T6G(SCH_1):PVDDIO_P1_LSET4
  PU53   37   LSET ISL99390FRZTR5935-ISL99390FRZ-TR5935,SMLF,IC,AL099A    I15 @T6G_MB_LIB.T6G(SCH_1):PAGE198
 PR368    1      A Q_RES_0402LF-8.87K,1%,1/16W,EMPTY,CS28872FB01     I4 @T6G_MB_LIB.T6G(SCH_1):PAGE198

PVDDIO_P1_PWM1 @T6G_MB_LIB.T6G(SCH_1):PVDDIO_P1_PWM1
  PU34    1   PWM0 RAA229620GNPHA0-RAA229620GNP#HA0,SMLF,IC,ARF0TGP40A   I128 @T6G_MB_LIB.T6G(SCH_1):PAGE192
  PU39   34    PWM ISL99390FRZTR5935-ISL99390FRZ-TR5935,SMLF,IC,AL099A    I39 @T6G_MB_LIB.T6G(SCH_1):PAGE197

PVDDIO_P1_PWM2 @T6G_MB_LIB.T6G(SCH_1):PVDDIO_P1_PWM2
  PU34    2   PWM1 RAA229620GNPHA0-RAA229620GNP#HA0,SMLF,IC,ARF0TGP40A   I128 @T6G_MB_LIB.T6G(SCH_1):PAGE192
  PU40   34    PWM ISL99390FRZTR5935-ISL99390FRZ-TR5935,SMLF,IC,AL099A    I84 @T6G_MB_LIB.T6G(SCH_1):PAGE197

PVDDIO_P1_PWM3 @T6G_MB_LIB.T6G(SCH_1):PVDDIO_P1_PWM3
  PU34    3   PWM2 RAA229620GNPHA0-RAA229620GNP#HA0,SMLF,IC,ARF0TGP40A   I128 @T6G_MB_LIB.T6G(SCH_1):PAGE192
  PU52   34    PWM ISL99390FRZTR5935-ISL99390FRZ-TR5935,SMLF,IC,AL099A    I73 @T6G_MB_LIB.T6G(SCH_1):PAGE198

PVDDIO_P1_PWM4 @T6G_MB_LIB.T6G(SCH_1):PVDDIO_P1_PWM4
  PU53   34    PWM ISL99390FRZTR5935-ISL99390FRZ-TR5935,SMLF,IC,AL099A    I15 @T6G_MB_LIB.T6G(SCH_1):PAGE198
  PU34    4   PWM3 RAA229620GNPHA0-RAA229620GNP#HA0,SMLF,IC,ARF0TGP40A   I128 @T6G_MB_LIB.T6G(SCH_1):PAGE192

PVDDIO_P1_TEMP1 @T6G_MB_LIB.T6G(SCH_1):PVDDIO_P1_TEMP1
  PU53   36 TOUT_FLT ISL99390FRZTR5935-ISL99390FRZ-TR5935,SMLF,IC,AL099A    I15 @T6G_MB_LIB.T6G(SCH_1):PAGE198
 PC367    1      A Q_CAP_0402-470PF,50V,10%,X7R,TMP_QCH14706KB18    I75 @T6G_MB_LIB.T6G(SCH_1):PAGE192
  PU34   43  TEMP1 RAA229620GNPHA0-RAA229620GNP#HA0,SMLF,IC,ARF0TGP40A   I128 @T6G_MB_LIB.T6G(SCH_1):PAGE192
  PU39   36 TOUT_FLT ISL99390FRZTR5935-ISL99390FRZ-TR5935,SMLF,IC,AL099A    I39 @T6G_MB_LIB.T6G(SCH_1):PAGE197
  PU40   36 TOUT_FLT ISL99390FRZTR5935-ISL99390FRZ-TR5935,SMLF,IC,AL099A    I84 @T6G_MB_LIB.T6G(SCH_1):PAGE197
  PU52   36 TOUT_FLT ISL99390FRZTR5935-ISL99390FRZ-TR5935,SMLF,IC,AL099A    I73 @T6G_MB_LIB.T6G(SCH_1):PAGE198

PVDDIO_P1_VCC1 @T6G_MB_LIB.T6G(SCH_1):PVDDIO_P1_VCC1
 PC433    1      A Q_CAP_C0402-2.2UF,10V,10%,X6S,CH5222KEB01    I34 @T6G_MB_LIB.T6G(SCH_1):PAGE197
 PR277    2      B Q_RES_0402LF-2.2,1%,1/16W,CHIP,CS-2202FB01    I35 @T6G_MB_LIB.T6G(SCH_1):PAGE197
  PU39   35     EN ISL99390FRZTR5935-ISL99390FRZ-TR5935,SMLF,IC,AL099A    I39 @T6G_MB_LIB.T6G(SCH_1):PAGE197
  PU39    3    VCC ISL99390FRZTR5935-ISL99390FRZ-TR5935,SMLF,IC,AL099A    I39 @T6G_MB_LIB.T6G(SCH_1):PAGE197

PVDDIO_P1_VCC2 @T6G_MB_LIB.T6G(SCH_1):PVDDIO_P1_VCC2
 PC432    1      A Q_CAP_C0402-2.2UF,10V,10%,X6S,CH5222KEB01    I12 @T6G_MB_LIB.T6G(SCH_1):PAGE197
 PR276    2      B Q_RES_0402LF-2.2,1%,1/16W,CHIP,CS-2202FB01    I13 @T6G_MB_LIB.T6G(SCH_1):PAGE197
  PU40   35     EN ISL99390FRZTR5935-ISL99390FRZ-TR5935,SMLF,IC,AL099A    I84 @T6G_MB_LIB.T6G(SCH_1):PAGE197
  PU40    3    VCC ISL99390FRZTR5935-ISL99390FRZ-TR5935,SMLF,IC,AL099A    I84 @T6G_MB_LIB.T6G(SCH_1):PAGE197

PVDDIO_P1_VCC3 @T6G_MB_LIB.T6G(SCH_1):PVDDIO_P1_VCC3
 PC617    1      A Q_CAP_C0402-2.2UF,10V,10%,X6S,CH5222KEB01    I28 @T6G_MB_LIB.T6G(SCH_1):PAGE198
 PR371    2      B Q_RES_0402LF-2.2,1%,1/16W,CHIP,CS-2202FB01    I29 @T6G_MB_LIB.T6G(SCH_1):PAGE198
  PU52   35     EN ISL99390FRZTR5935-ISL99390FRZ-TR5935,SMLF,IC,AL099A    I73 @T6G_MB_LIB.T6G(SCH_1):PAGE198
  PU52    3    VCC ISL99390FRZTR5935-ISL99390FRZ-TR5935,SMLF,IC,AL099A    I73 @T6G_MB_LIB.T6G(SCH_1):PAGE198

PVDDIO_P1_VCC4 @T6G_MB_LIB.T6G(SCH_1):PVDDIO_P1_VCC4
  PU53   35     EN ISL99390FRZTR5935-ISL99390FRZ-TR5935,SMLF,IC,AL099A    I15 @T6G_MB_LIB.T6G(SCH_1):PAGE198
  PU53    3    VCC ISL99390FRZTR5935-ISL99390FRZ-TR5935,SMLF,IC,AL099A    I15 @T6G_MB_LIB.T6G(SCH_1):PAGE198
 PC616    1      A Q_CAP_C0402-2.2UF,10V,10%,X6S,CH5222KEB01    I10 @T6G_MB_LIB.T6G(SCH_1):PAGE198
 PR370    2      B Q_RES_0402LF-2.2,1%,1/16W,CHIP,CS-2202FB01    I12 @T6G_MB_LIB.T6G(SCH_1):PAGE198

PVDDIO_P1_VOS1 @T6G_MB_LIB.T6G(SCH_1):PVDDIO_P1_VOS1
  PU39    1    VOS ISL99390FRZTR5935-ISL99390FRZ-TR5935,SMLF,IC,AL099A    I39 @T6G_MB_LIB.T6G(SCH_1):PAGE197
 PR280    1      A Q_RES_0402LF-0,5%,1/16W,CHIP,CS00002JB13    I50 @T6G_MB_LIB.T6G(SCH_1):PAGE197

PVDDIO_P1_VOS2 @T6G_MB_LIB.T6G(SCH_1):PVDDIO_P1_VOS2
 PR281    1      A Q_RES_0402LF-0,5%,1/16W,CHIP,CS00002JB13    I45 @T6G_MB_LIB.T6G(SCH_1):PAGE197
  PU40    1    VOS ISL99390FRZTR5935-ISL99390FRZ-TR5935,SMLF,IC,AL099A    I84 @T6G_MB_LIB.T6G(SCH_1):PAGE197

PVDDIO_P1_VOS3 @T6G_MB_LIB.T6G(SCH_1):PVDDIO_P1_VOS3
 PR374    1      A Q_RES_0402LF-0,5%,1/16W,CHIP,CS00002JB13    I55 @T6G_MB_LIB.T6G(SCH_1):PAGE198
  PU52    1    VOS ISL99390FRZTR5935-ISL99390FRZ-TR5935,SMLF,IC,AL099A    I73 @T6G_MB_LIB.T6G(SCH_1):PAGE198

PVDDIO_P1_VOS4 @T6G_MB_LIB.T6G(SCH_1):PVDDIO_P1_VOS4
  PU53    1    VOS ISL99390FRZTR5935-ISL99390FRZ-TR5935,SMLF,IC,AL099A    I15 @T6G_MB_LIB.T6G(SCH_1):PAGE198
 PR375    1      A Q_RES_0402LF-0,5%,1/16W,CHIP,CS00002JB13    I41 @T6G_MB_LIB.T6G(SCH_1):PAGE198

PVDD_33_S5 @T6G_MB_LIB.T6G(SCH_1):PVDD_33_S5
   U25 BN52 VDD_33_S5_BN52 GENOA_SP5-SOCKET6096_13568-001,SMLF,IO,DGA^6000030    I28 @T6G_MB_LIB.T6G(SCH_1):PAGE30
   U25 BP51 VDD_33_S5_BP51 GENOA_SP5-SOCKET6096_13568-001,SMLF,IO,DGA^6000030    I28 @T6G_MB_LIB.T6G(SCH_1):PAGE30
   U26 BN52 VDD_33_S5_BN52 GENOA_SP5-SOCKET6096_13568-001,SMLF,IO,DGA^6000030    I45 @T6G_MB_LIB.T6G(SCH_1):PAGE57
   U26 BP51 VDD_33_S5_BP51 GENOA_SP5-SOCKET6096_13568-001,SMLF,IO,DGA^6000030    I45 @T6G_MB_LIB.T6G(SCH_1):PAGE57
 PC132    2      B Q_CAP_0402-100PF,50V,5%,NPO,CH11006JB00    I24 @T6G_MB_LIB.T6G(SCH_1):PAGE167
 PR455    2      B Q_RES_0402LF-56K,1%,1/16W,CHIP,CS35602FB00    I25 @T6G_MB_LIB.T6G(SCH_1):PAGE167
 PC129    1      A Q_CAP_C0805-22UF,16V,20%,X6S,CH6223MEA01    I27 @T6G_MB_LIB.T6G(SCH_1):PAGE167
 PC130    1      A Q_CAP_C0805-22UF,16V,20%,X6S,CH6223MEA01    I28 @T6G_MB_LIB.T6G(SCH_1):PAGE167
 PC134    1      A Q_CAP_C0805-22UF,16V,20%,X6S,CH6223MEA01    I35 @T6G_MB_LIB.T6G(SCH_1):PAGE167
 PC135    1      A Q_CAP_C0805-22UF,16V,20%,X6S,CH6223MEA01    I36 @T6G_MB_LIB.T6G(SCH_1):PAGE167
 PC136    1      A Q_CAP_0402-0.1UF,25V,10%,X7R,CH4104K1B00    I37 @T6G_MB_LIB.T6G(SCH_1):PAGE167
  PL72    2      2 Q_INDUCTOR_SMLF-1.5UH,IND,CV-15I0MZ28    I47 @T6G_MB_LIB.T6G(SCH_1):PAGE167
 C2515    1      A Q_CAP_C0402-10UF,6.3V,20%,X6S,CH6101MEB01    I25 @T6G_MB_LIB.T6G(SCH_1):PAGE70
 C2512    1      A Q_CAP_C0402-10UF,6.3V,20%,X6S,CH6101MEB01    I26 @T6G_MB_LIB.T6G(SCH_1):PAGE70
 C2662    1      A Q_CAP_C0402-10UF,6.3V,20%,X6S,CH6101MEB01    I25 @T6G_MB_LIB.T6G(SCH_1):PAGE74
 C2659    1      A Q_CAP_C0402-10UF,6.3V,20%,X6S,CH6101MEB01    I26 @T6G_MB_LIB.T6G(SCH_1):PAGE74
 R1235    1      A Q_RES_0402LF-5.11K,1%,1/16W,CHIP,CS25112FB04   I215 @T6G_MB_LIB.T6G(SCH_1):PAGE263

PVDD_33_S5_ADC @T6G_MB_LIB.T6G(SCH_1):PVDD_33_S5_ADC
 R1248    1      A Q_RES_0402LF-0,5%,1/16W,EMPTY,CS00002JB13   I213 @T6G_MB_LIB.T6G(SCH_1):PAGE263
 R1255    1      A Q_RES_0402LF-0,5%,1/16W,CHIP,CS00002JB13   I214 @T6G_MB_LIB.T6G(SCH_1):PAGE263
 R1235    2      B Q_RES_0402LF-5.11K,1%,1/16W,CHIP,CS25112FB04   I215 @T6G_MB_LIB.T6G(SCH_1):PAGE263
 R1224    1      A Q_RES_0402LF-4.7K,1%,1/16W,CHIP,CS24702FB06   I216 @T6G_MB_LIB.T6G(SCH_1):PAGE263

PVDD_33_S5_ADC_MAM @T6G_MB_LIB.T6G(SCH_1):PVDD_33_S5_ADC_MAM
   U50   10   AIN5 MAX11617EEET-MAX11617EEE+T,SMLF,EMPTY,AL011617W00   I156 @T6G_MB_LIB.T6G(SCH_1):PAGE263
 C1082    1      A Q_CAP_0402-100PF,50V,5%,EMPTY,CH11006JB18   I209 @T6G_MB_LIB.T6G(SCH_1):PAGE263
 R1248    2      B Q_RES_0402LF-0,5%,1/16W,EMPTY,CS00002JB13   I213 @T6G_MB_LIB.T6G(SCH_1):PAGE263

PVDD_33_S5_ADC_TIC @T6G_MB_LIB.T6G(SCH_1):PVDD_33_S5_ADC_TIC
   U51   11    IN5 ADC128D818CIMTXNOPB-ADC128D818CIMTX/NOPB,SMLF,IC,AA   I142 @T6G_MB_LIB.T6G(SCH_1):PAGE263
 C1089    1      A Q_CAP_0402-0.1UF,25V,10%,X7R,CH4104K1B00   I211 @T6G_MB_LIB.T6G(SCH_1):PAGE263
 R1255    2      B Q_RES_0402LF-0,5%,1/16W,CHIP,CS00002JB13   I214 @T6G_MB_LIB.T6G(SCH_1):PAGE263

PVDD_33_S5_CS @T6G_MB_LIB.T6G(SCH_1):PVDD_33_S5_CS
 PR452    1      A Q_RES_0402LF-6.98K,1%,1/16W,CHIP,CS26982FB08    I15 @T6G_MB_LIB.T6G(SCH_1):PAGE167
  PU55    3     CS MPQ8633AGLEC807Z-MPQ8633AGLE-C807-Z,SMLF,IC,AL0086A    I41 @T6G_MB_LIB.T6G(SCH_1):PAGE167

PVDD_33_S5_FB @T6G_MB_LIB.T6G(SCH_1):PVDD_33_S5_FB
 PR454    1      A Q_RES_0402LF-12.4K,1%,1/16W,CHIP,CS31242FB02    I23 @T6G_MB_LIB.T6G(SCH_1):PAGE167
 PC132    1      A Q_CAP_0402-100PF,50V,5%,NPO,CH11006JB00    I24 @T6G_MB_LIB.T6G(SCH_1):PAGE167
 PR455    1      A Q_RES_0402LF-56K,1%,1/16W,CHIP,CS35602FB00    I25 @T6G_MB_LIB.T6G(SCH_1):PAGE167
  PU55    7     FB MPQ8633AGLEC807Z-MPQ8633AGLE-C807-Z,SMLF,IC,AL0086A    I41 @T6G_MB_LIB.T6G(SCH_1):PAGE167

PVDD_33_S5_MODE @T6G_MB_LIB.T6G(SCH_1):PVDD_33_S5_MODE
PR6000    2      B Q_RES_0402LF-0,5%,1/16W,CHIP,CS00002JB13    I17 @T6G_MB_LIB.T6G(SCH_1):PAGE167
  PU55    4   MODE MPQ8633AGLEC807Z-MPQ8633AGLE-C807-Z,SMLF,IC,AL0086A    I41 @T6G_MB_LIB.T6G(SCH_1):PAGE167

PVDD_33_S5_REF @T6G_MB_LIB.T6G(SCH_1):PVDD_33_S5_REF
 PC127    1      A Q_CAP_0402-0.1UF,25V,10%,X7R,CH4104K1B00    I19 @T6G_MB_LIB.T6G(SCH_1):PAGE167
  PU55    5 TRK_REF MPQ8633AGLEC807Z-MPQ8633AGLE-C807-Z,SMLF,IC,AL0086A    I41 @T6G_MB_LIB.T6G(SCH_1):PAGE167

PVDD_33_S5_VCC @T6G_MB_LIB.T6G(SCH_1):PVDD_33_S5_VCC
 PC118    1      A Q_CAP_C0402-1UF,25V,10%,X6S,CH5104KEB02     I2 @T6G_MB_LIB.T6G(SCH_1):PAGE167
  R453    1      A Q_RES_0402LF-10K,5%,1/16W,CHIP,CS31002JB08    I31 @T6G_MB_LIB.T6G(SCH_1):PAGE167
  PU55   19    VCC MPQ8633AGLEC807Z-MPQ8633AGLE-C807-Z,SMLF,IC,AL0086A    I41 @T6G_MB_LIB.T6G(SCH_1):PAGE167

PWRGD_CHAF_CPU0 @T6G_MB_LIB.T6G(SCH_1):PWRGD_CHAF_CPU0
  R291    2      B Q_RES_0402LF-1K,1%,1/16W,CHIP,CS21002FB06   I525 @T6G_MB_LIB.T6G(SCH_1):PAGE85
   R88    2      B Q_RES_0402LF-1K,1%,1/16W,EMPTY,CS21002FB06   I526 @T6G_MB_LIB.T6G(SCH_1):PAGE85
  R292    2      B Q_RES_0402LF-1K,1%,1/16W,CHIP,CS21002FB06   I364 @T6G_MB_LIB.T6G(SCH_1):PAGE86
  R293    2      B Q_RES_0402LF-1K,1%,1/16W,CHIP,CS21002FB06   I364 @T6G_MB_LIB.T6G(SCH_1):PAGE87
  R294    2      B Q_RES_0402LF-1K,1%,1/16W,CHIP,CS21002FB06   I369 @T6G_MB_LIB.T6G(SCH_1):PAGE88
  R295    2      B Q_RES_0402LF-1K,1%,1/16W,CHIP,CS21002FB06   I362 @T6G_MB_LIB.T6G(SCH_1):PAGE89
  R296    2      B Q_RES_0402LF-1K,1%,1/16W,CHIP,CS21002FB06   I364 @T6G_MB_LIB.T6G(SCH_1):PAGE90
 R8037    2      B Q_RES_0402LF-10K,1%,1/16W,CHIP,CS31002FB08   I540 @T6G_MB_LIB.T6G(SCH_1):PAGE85
 R8080    1      A Q_RES_0402LF-0,5%,1/16W,CHIP,CS00002JB13   I544 @T6G_MB_LIB.T6G(SCH_1):PAGE85

PWRGD_CHAF_CPU0_R1 @T6G_MB_LIB.T6G(SCH_1):PWRGD_CHAF_CPU0_R1
 R8080    2      B Q_RES_0402LF-0,5%,1/16W,CHIP,CS00002JB13   I544 @T6G_MB_LIB.T6G(SCH_1):PAGE85
 R8081    1      A Q_RES_0402LF-0,5%,1/16W,CHIP,CS00002JB13   I545 @T6G_MB_LIB.T6G(SCH_1):PAGE85
 R8082    2      B Q_RES_0402LF-10K,1%,1/16W,EMPTY,CS31002FB08   I547 @T6G_MB_LIB.T6G(SCH_1):PAGE85
 D8003    1      A SCHOTTKY_12-B0530WS7F,SMLF,EMPTY,BC000530Z41   I549 @T6G_MB_LIB.T6G(SCH_1):PAGE85

PWRGD_CHAF_CPU0_R2 @T6G_MB_LIB.T6G(SCH_1):PWRGD_CHAF_CPU0_R2
   U18   W1  PL28A LCMXO3LF9400C5BG484C-LCMXO3LF-9400C-5BG484C,SMLF,IA   I143 @T6G_MB_LIB.T6G(SCH_1):PAGE81
 R8081    2      B Q_RES_0402LF-0,5%,1/16W,CHIP,CS00002JB13   I545 @T6G_MB_LIB.T6G(SCH_1):PAGE85

PWRGD_CHAF_CPU1 @T6G_MB_LIB.T6G(SCH_1):PWRGD_CHAF_CPU1
  R102    2      B Q_RES_0402LF-1K,1%,1/16W,EMPTY,CS21002FB06   I189 @T6G_MB_LIB.T6G(SCH_1):PAGE97
  R303    2      B Q_RES_0402LF-1K,1%,1/16W,CHIP,CS21002FB06   I190 @T6G_MB_LIB.T6G(SCH_1):PAGE97
  R304    2      B Q_RES_0402LF-1K,1%,1/16W,CHIP,CS21002FB06   I188 @T6G_MB_LIB.T6G(SCH_1):PAGE98
  R305    2      B Q_RES_0402LF-1K,1%,1/16W,CHIP,CS21002FB06   I188 @T6G_MB_LIB.T6G(SCH_1):PAGE99
  R306    2      B Q_RES_0402LF-1K,1%,1/16W,CHIP,CS21002FB06   I188 @T6G_MB_LIB.T6G(SCH_1):PAGE100
  R307    2      B Q_RES_0402LF-1K,1%,1/16W,CHIP,CS21002FB06   I188 @T6G_MB_LIB.T6G(SCH_1):PAGE101
 R1183    2      B Q_RES_0402LF-1K,1%,1/16W,CHIP,CS21002FB06   I188 @T6G_MB_LIB.T6G(SCH_1):PAGE102
 R8039    2      B Q_RES_0402LF-10K,1%,1/16W,CHIP,CS31002FB08   I245 @T6G_MB_LIB.T6G(SCH_1):PAGE97
 R8086    1      A Q_RES_0402LF-0,5%,1/16W,CHIP,CS00002JB13   I250 @T6G_MB_LIB.T6G(SCH_1):PAGE97

PWRGD_CHAF_CPU1_R1 @T6G_MB_LIB.T6G(SCH_1):PWRGD_CHAF_CPU1_R1
 R8086    2      B Q_RES_0402LF-0,5%,1/16W,CHIP,CS00002JB13   I250 @T6G_MB_LIB.T6G(SCH_1):PAGE97
 R8088    2      B Q_RES_0402LF-10K,1%,1/16W,EMPTY,CS31002FB08   I251 @T6G_MB_LIB.T6G(SCH_1):PAGE97
 R8087    1      A Q_RES_0402LF-0,5%,1/16W,CHIP,CS00002JB13   I252 @T6G_MB_LIB.T6G(SCH_1):PAGE97
 D8005    1      A SCHOTTKY_12-B0530WS7F,SMLF,EMPTY,BC000530Z41   I253 @T6G_MB_LIB.T6G(SCH_1):PAGE97

PWRGD_CHAF_CPU1_R2 @T6G_MB_LIB.T6G(SCH_1):PWRGD_CHAF_CPU1_R2
   U18   R6  PL25C LCMXO3LF9400C5BG484C-LCMXO3LF-9400C-5BG484C,SMLF,IA   I143 @T6G_MB_LIB.T6G(SCH_1):PAGE81
 R8087    2      B Q_RES_0402LF-0,5%,1/16W,CHIP,CS00002JB13   I252 @T6G_MB_LIB.T6G(SCH_1):PAGE97

PWRGD_CHA_CPU0_DIMM0 @T6G_MB_LIB.T6G(SCH_1):PWRGD_CHA_CPU0_DIMM0
  R291    1      A Q_RES_0402LF-1K,1%,1/16W,CHIP,CS21002FB06   I525 @T6G_MB_LIB.T6G(SCH_1):PAGE85
   R89    2      B Q_RES_0402LF-1K,1%,1/16W,EMPTY,CS21002FB06   I528 @T6G_MB_LIB.T6G(SCH_1):PAGE85
    J1  147 PWR_GOOD||FAIL_N SCONN288_DDR506112002KQ-SCONN288_DDR506112002KQ,SMA   I536 @T6G_MB_LIB.T6G(SCH_1):PAGE85

PWRGD_CHA_CPU1_DIMM0 @T6G_MB_LIB.T6G(SCH_1):PWRGD_CHA_CPU1_DIMM0
   J24  147 PWR_GOOD||FAIL_N SCONN288_DDR506112002KQ-SCONN288_DDR506112002KQ,SMA    I22 @T6G_MB_LIB.T6G(SCH_1):PAGE97
  R303    1      A Q_RES_0402LF-1K,1%,1/16W,CHIP,CS21002FB06   I190 @T6G_MB_LIB.T6G(SCH_1):PAGE97
  R103    2      B Q_RES_0402LF-1K,1%,1/16W,EMPTY,CS21002FB06   I191 @T6G_MB_LIB.T6G(SCH_1):PAGE97

PWRGD_CHB_CPU0_DIMM @T6G_MB_LIB.T6G(SCH_1):PWRGD_CHB_CPU0_DIMM
   J15  147 PWR_GOOD||FAIL_N SCONN288_DDR506112002KQ-SCONN288_DDR506112002KQ,SMA   I350 @T6G_MB_LIB.T6G(SCH_1):PAGE86
  R292    1      A Q_RES_0402LF-1K,1%,1/16W,CHIP,CS21002FB06   I364 @T6G_MB_LIB.T6G(SCH_1):PAGE86
   R90    2      B Q_RES_0402LF-1K,1%,1/16W,EMPTY,CS21002FB06   I365 @T6G_MB_LIB.T6G(SCH_1):PAGE86

PWRGD_CHB_CPU1_DIMM @T6G_MB_LIB.T6G(SCH_1):PWRGD_CHB_CPU1_DIMM
   J26  147 PWR_GOOD||FAIL_N SCONN288_DDR506112002KQ-SCONN288_DDR506112002KQ,SMA    I22 @T6G_MB_LIB.T6G(SCH_1):PAGE98
  R304    1      A Q_RES_0402LF-1K,1%,1/16W,CHIP,CS21002FB06   I188 @T6G_MB_LIB.T6G(SCH_1):PAGE98
  R104    2      B Q_RES_0402LF-1K,1%,1/16W,EMPTY,CS21002FB06   I190 @T6G_MB_LIB.T6G(SCH_1):PAGE98

PWRGD_CHC_CPU0_DIMM @T6G_MB_LIB.T6G(SCH_1):PWRGD_CHC_CPU0_DIMM
   J17  147 PWR_GOOD||FAIL_N SCONN288_DDR506112002KQ-SCONN288_DDR506112002KQ,SMA   I350 @T6G_MB_LIB.T6G(SCH_1):PAGE87
  R293    1      A Q_RES_0402LF-1K,1%,1/16W,CHIP,CS21002FB06   I364 @T6G_MB_LIB.T6G(SCH_1):PAGE87
   R91    2      B Q_RES_0402LF-1K,1%,1/16W,EMPTY,CS21002FB06   I365 @T6G_MB_LIB.T6G(SCH_1):PAGE87

PWRGD_CHC_CPU1_DIMM @T6G_MB_LIB.T6G(SCH_1):PWRGD_CHC_CPU1_DIMM
   J28  147 PWR_GOOD||FAIL_N SCONN288_DDR506112002KQ-SCONN288_DDR506112002KQ,SMA    I22 @T6G_MB_LIB.T6G(SCH_1):PAGE99
  R305    1      A Q_RES_0402LF-1K,1%,1/16W,CHIP,CS21002FB06   I188 @T6G_MB_LIB.T6G(SCH_1):PAGE99
  R105    2      B Q_RES_0402LF-1K,1%,1/16W,EMPTY,CS21002FB06   I190 @T6G_MB_LIB.T6G(SCH_1):PAGE99

PWRGD_CHD_CPU0_DIMM @T6G_MB_LIB.T6G(SCH_1):PWRGD_CHD_CPU0_DIMM
   J19  147 PWR_GOOD||FAIL_N SCONN288_DDR506112002KQ-SCONN288_DDR506112002KQ,SMA   I350 @T6G_MB_LIB.T6G(SCH_1):PAGE88
   R92    2      B Q_RES_0402LF-1K,1%,1/16W,EMPTY,CS21002FB06   I367 @T6G_MB_LIB.T6G(SCH_1):PAGE88
  R294    1      A Q_RES_0402LF-1K,1%,1/16W,CHIP,CS21002FB06   I369 @T6G_MB_LIB.T6G(SCH_1):PAGE88

PWRGD_CHD_CPU1_DIMM @T6G_MB_LIB.T6G(SCH_1):PWRGD_CHD_CPU1_DIMM
   J30  147 PWR_GOOD||FAIL_N SCONN288_DDR506112002KQ-SCONN288_DDR506112002KQ,SMA    I52 @T6G_MB_LIB.T6G(SCH_1):PAGE100
  R306    1      A Q_RES_0402LF-1K,1%,1/16W,CHIP,CS21002FB06   I188 @T6G_MB_LIB.T6G(SCH_1):PAGE100
  R106    2      B Q_RES_0402LF-1K,1%,1/16W,EMPTY,CS21002FB06   I190 @T6G_MB_LIB.T6G(SCH_1):PAGE100

PWRGD_CHE_CPU0_DIMM @T6G_MB_LIB.T6G(SCH_1):PWRGD_CHE_CPU0_DIMM
   J21  147 PWR_GOOD||FAIL_N SCONN288_DDR506112002KQ-SCONN288_DDR506112002KQ,SMA   I348 @T6G_MB_LIB.T6G(SCH_1):PAGE89
  R295    1      A Q_RES_0402LF-1K,1%,1/16W,CHIP,CS21002FB06   I362 @T6G_MB_LIB.T6G(SCH_1):PAGE89
   R93    2      B Q_RES_0402LF-1K,1%,1/16W,EMPTY,CS21002FB06   I364 @T6G_MB_LIB.T6G(SCH_1):PAGE89

PWRGD_CHE_CPU1_DIMM @T6G_MB_LIB.T6G(SCH_1):PWRGD_CHE_CPU1_DIMM
   J32  147 PWR_GOOD||FAIL_N SCONN288_DDR506112002KQ-SCONN288_DDR506112002KQ,SMA    I52 @T6G_MB_LIB.T6G(SCH_1):PAGE101
  R307    1      A Q_RES_0402LF-1K,1%,1/16W,CHIP,CS21002FB06   I188 @T6G_MB_LIB.T6G(SCH_1):PAGE101
  R107    2      B Q_RES_0402LF-1K,1%,1/16W,EMPTY,CS21002FB06   I190 @T6G_MB_LIB.T6G(SCH_1):PAGE101

PWRGD_CHF_CPU0_DIMM @T6G_MB_LIB.T6G(SCH_1):PWRGD_CHF_CPU0_DIMM
   J23  147 PWR_GOOD||FAIL_N SCONN288_DDR506112002KQ-SCONN288_DDR506112002KQ,SMA   I350 @T6G_MB_LIB.T6G(SCH_1):PAGE90
  R296    1      A Q_RES_0402LF-1K,1%,1/16W,CHIP,CS21002FB06   I364 @T6G_MB_LIB.T6G(SCH_1):PAGE90
   R94    2      B Q_RES_0402LF-1K,1%,1/16W,EMPTY,CS21002FB06   I365 @T6G_MB_LIB.T6G(SCH_1):PAGE90

PWRGD_CHF_CPU1_DIMM @T6G_MB_LIB.T6G(SCH_1):PWRGD_CHF_CPU1_DIMM
   J33  147 PWR_GOOD||FAIL_N SCONN288_DDR506112002KQ-SCONN288_DDR506112002KQ,SMA    I22 @T6G_MB_LIB.T6G(SCH_1):PAGE102
 R1183    1      A Q_RES_0402LF-1K,1%,1/16W,CHIP,CS21002FB06   I188 @T6G_MB_LIB.T6G(SCH_1):PAGE102
  R108    2      B Q_RES_0402LF-1K,1%,1/16W,EMPTY,CS21002FB06   I190 @T6G_MB_LIB.T6G(SCH_1):PAGE102

PWRGD_CHGL_CPU0 @T6G_MB_LIB.T6G(SCH_1):PWRGD_CHGL_CPU0
  R297    2      B Q_RES_0402LF-1K,1%,1/16W,CHIP,CS21002FB06   I186 @T6G_MB_LIB.T6G(SCH_1):PAGE91
   R95    2      B Q_RES_0402LF-1K,1%,1/16W,EMPTY,CS21002FB06   I190 @T6G_MB_LIB.T6G(SCH_1):PAGE91
  R298    2      B Q_RES_0402LF-1K,1%,1/16W,CHIP,CS21002FB06   I189 @T6G_MB_LIB.T6G(SCH_1):PAGE92
  R299    2      B Q_RES_0402LF-1K,1%,1/16W,CHIP,CS21002FB06   I188 @T6G_MB_LIB.T6G(SCH_1):PAGE93
  R300    2      B Q_RES_0402LF-1K,1%,1/16W,CHIP,CS21002FB06   I188 @T6G_MB_LIB.T6G(SCH_1):PAGE94
  R301    2      B Q_RES_0402LF-1K,1%,1/16W,CHIP,CS21002FB06   I188 @T6G_MB_LIB.T6G(SCH_1):PAGE95
  R302    2      B Q_RES_0402LF-1K,1%,1/16W,CHIP,CS21002FB06   I188 @T6G_MB_LIB.T6G(SCH_1):PAGE96
 R8038    2      B Q_RES_0402LF-10K,1%,1/16W,CHIP,CS31002FB08   I243 @T6G_MB_LIB.T6G(SCH_1):PAGE91
 R8083    1      A Q_RES_0402LF-0,5%,1/16W,CHIP,CS00002JB13   I248 @T6G_MB_LIB.T6G(SCH_1):PAGE91

PWRGD_CHGL_CPU0_R1 @T6G_MB_LIB.T6G(SCH_1):PWRGD_CHGL_CPU0_R1
 R8083    2      B Q_RES_0402LF-0,5%,1/16W,CHIP,CS00002JB13   I248 @T6G_MB_LIB.T6G(SCH_1):PAGE91
 R8085    2      B Q_RES_0402LF-10K,1%,1/16W,EMPTY,CS31002FB08   I249 @T6G_MB_LIB.T6G(SCH_1):PAGE91
 R8084    1      A Q_RES_0402LF-0,5%,1/16W,CHIP,CS00002JB13   I250 @T6G_MB_LIB.T6G(SCH_1):PAGE91
 D8004    1      A SCHOTTKY_12-B0530WS7F,SMLF,EMPTY,BC000530Z41   I251 @T6G_MB_LIB.T6G(SCH_1):PAGE91

PWRGD_CHGL_CPU0_R2 @T6G_MB_LIB.T6G(SCH_1):PWRGD_CHGL_CPU0_R2
   U18   Y1  PL29A LCMXO3LF9400C5BG484C-LCMXO3LF-9400C-5BG484C,SMLF,IA   I143 @T6G_MB_LIB.T6G(SCH_1):PAGE81
 R8084    2      B Q_RES_0402LF-0,5%,1/16W,CHIP,CS00002JB13   I250 @T6G_MB_LIB.T6G(SCH_1):PAGE91

PWRGD_CHGL_CPU1 @T6G_MB_LIB.T6G(SCH_1):PWRGD_CHGL_CPU1
 R1184    2      B Q_RES_0402LF-1K,1%,1/16W,CHIP,CS21002FB06   I188 @T6G_MB_LIB.T6G(SCH_1):PAGE103
  R109    2      B Q_RES_0402LF-1K,1%,1/16W,EMPTY,CS21002FB06   I189 @T6G_MB_LIB.T6G(SCH_1):PAGE103
  R310    2      B Q_RES_0402LF-1K,1%,1/16W,CHIP,CS21002FB06   I189 @T6G_MB_LIB.T6G(SCH_1):PAGE104
  R311    2      B Q_RES_0402LF-1K,1%,1/16W,CHIP,CS21002FB06   I188 @T6G_MB_LIB.T6G(SCH_1):PAGE105
  R312    2      B Q_RES_0402LF-1K,1%,1/16W,CHIP,CS21002FB06   I188 @T6G_MB_LIB.T6G(SCH_1):PAGE106
  R313    2      B Q_RES_0402LF-1K,1%,1/16W,CHIP,CS21002FB06   I188 @T6G_MB_LIB.T6G(SCH_1):PAGE107
  R314    2      B Q_RES_0402LF-1K,1%,1/16W,CHIP,CS21002FB06   I188 @T6G_MB_LIB.T6G(SCH_1):PAGE108
 R8040    2      B Q_RES_0402LF-10K,1%,1/16W,CHIP,CS31002FB08   I245 @T6G_MB_LIB.T6G(SCH_1):PAGE103
 R8089    1      A Q_RES_0402LF-0,5%,1/16W,CHIP,CS00002JB13   I249 @T6G_MB_LIB.T6G(SCH_1):PAGE103

PWRGD_CHGL_CPU1_R1 @T6G_MB_LIB.T6G(SCH_1):PWRGD_CHGL_CPU1_R1
 R8089    2      B Q_RES_0402LF-0,5%,1/16W,CHIP,CS00002JB13   I249 @T6G_MB_LIB.T6G(SCH_1):PAGE103
 R8091    2      B Q_RES_0402LF-10K,1%,1/16W,EMPTY,CS31002FB08   I251 @T6G_MB_LIB.T6G(SCH_1):PAGE103
 R8090    1      A Q_RES_0402LF-0,5%,1/16W,CHIP,CS00002JB13   I252 @T6G_MB_LIB.T6G(SCH_1):PAGE103
 D8006    1      A SCHOTTKY_12-B0530WS7F,SMLF,EMPTY,BC000530Z41   I253 @T6G_MB_LIB.T6G(SCH_1):PAGE103

PWRGD_CHGL_CPU1_R2 @T6G_MB_LIB.T6G(SCH_1):PWRGD_CHGL_CPU1_R2
   U18   T6  PL26D LCMXO3LF9400C5BG484C-LCMXO3LF-9400C-5BG484C,SMLF,IA   I143 @T6G_MB_LIB.T6G(SCH_1):PAGE81
 R8090    2      B Q_RES_0402LF-0,5%,1/16W,CHIP,CS00002JB13   I252 @T6G_MB_LIB.T6G(SCH_1):PAGE103

PWRGD_CHG_CPU0_DIMM0 @T6G_MB_LIB.T6G(SCH_1):PWRGD_CHG_CPU0_DIMM0
   J16  147 PWR_GOOD||FAIL_N SCONN288_DDR506112002KQ-SCONN288_DDR506112002KQ,SMA    I22 @T6G_MB_LIB.T6G(SCH_1):PAGE91
  R297    1      A Q_RES_0402LF-1K,1%,1/16W,CHIP,CS21002FB06   I186 @T6G_MB_LIB.T6G(SCH_1):PAGE91
   R96    2      B Q_RES_0402LF-1K,1%,1/16W,EMPTY,CS21002FB06   I187 @T6G_MB_LIB.T6G(SCH_1):PAGE91

PWRGD_CHG_CPU1_DIMM0 @T6G_MB_LIB.T6G(SCH_1):PWRGD_CHG_CPU1_DIMM0
  J102  147 PWR_GOOD||FAIL_N SCONN288_DDR506112002KQ-SCONN288_DDR506112002KQ,SMA    I22 @T6G_MB_LIB.T6G(SCH_1):PAGE103
 R1184    1      A Q_RES_0402LF-1K,1%,1/16W,CHIP,CS21002FB06   I188 @T6G_MB_LIB.T6G(SCH_1):PAGE103
  R110    2      B Q_RES_0402LF-1K,1%,1/16W,EMPTY,CS21002FB06   I192 @T6G_MB_LIB.T6G(SCH_1):PAGE103

PWRGD_CHH_CPU0_DIMM @T6G_MB_LIB.T6G(SCH_1):PWRGD_CHH_CPU0_DIMM
   J69  147 PWR_GOOD||FAIL_N SCONN288_DDR506112002KQ-SCONN288_DDR506112002KQ,SMA    I22 @T6G_MB_LIB.T6G(SCH_1):PAGE92
  R298    1      A Q_RES_0402LF-1K,1%,1/16W,CHIP,CS21002FB06   I189 @T6G_MB_LIB.T6G(SCH_1):PAGE92
   R97    2      B Q_RES_0402LF-1K,1%,1/16W,EMPTY,CS21002FB06   I191 @T6G_MB_LIB.T6G(SCH_1):PAGE92

PWRGD_CHH_CPU1_DIMM @T6G_MB_LIB.T6G(SCH_1):PWRGD_CHH_CPU1_DIMM
   J27  147 PWR_GOOD||FAIL_N SCONN288_DDR506112002KQ-SCONN288_DDR506112002KQ,SMA    I22 @T6G_MB_LIB.T6G(SCH_1):PAGE104
  R310    1      A Q_RES_0402LF-1K,1%,1/16W,CHIP,CS21002FB06   I189 @T6G_MB_LIB.T6G(SCH_1):PAGE104
  R111    2      B Q_RES_0402LF-1K,1%,1/16W,EMPTY,CS21002FB06   I190 @T6G_MB_LIB.T6G(SCH_1):PAGE104

PWRGD_CHI_CPU0_DIMM @T6G_MB_LIB.T6G(SCH_1):PWRGD_CHI_CPU0_DIMM
   J18  147 PWR_GOOD||FAIL_N SCONN288_DDR506112002KQ-SCONN288_DDR506112002KQ,SMA    I22 @T6G_MB_LIB.T6G(SCH_1):PAGE93
  R299    1      A Q_RES_0402LF-1K,1%,1/16W,CHIP,CS21002FB06   I188 @T6G_MB_LIB.T6G(SCH_1):PAGE93
   R98    2      B Q_RES_0402LF-1K,1%,1/16W,EMPTY,CS21002FB06   I189 @T6G_MB_LIB.T6G(SCH_1):PAGE93

PWRGD_CHI_CPU1_DIMM @T6G_MB_LIB.T6G(SCH_1):PWRGD_CHI_CPU1_DIMM
  J100  147 PWR_GOOD||FAIL_N SCONN288_DDR506112002KQ-SCONN288_DDR506112002KQ,SMA    I22 @T6G_MB_LIB.T6G(SCH_1):PAGE105
  R311    1      A Q_RES_0402LF-1K,1%,1/16W,CHIP,CS21002FB06   I188 @T6G_MB_LIB.T6G(SCH_1):PAGE105
  R112    2      B Q_RES_0402LF-1K,1%,1/16W,EMPTY,CS21002FB06   I190 @T6G_MB_LIB.T6G(SCH_1):PAGE105

PWRGD_CHJ_CPU0_DIMM @T6G_MB_LIB.T6G(SCH_1):PWRGD_CHJ_CPU0_DIMM
   J68  147 PWR_GOOD||FAIL_N SCONN288_DDR506112002KQ-SCONN288_DDR506112002KQ,SMA    I22 @T6G_MB_LIB.T6G(SCH_1):PAGE94
  R300    1      A Q_RES_0402LF-1K,1%,1/16W,CHIP,CS21002FB06   I188 @T6G_MB_LIB.T6G(SCH_1):PAGE94
   R99    2      B Q_RES_0402LF-1K,1%,1/16W,EMPTY,CS21002FB06   I189 @T6G_MB_LIB.T6G(SCH_1):PAGE94

PWRGD_CHJ_CPU1_DIMM @T6G_MB_LIB.T6G(SCH_1):PWRGD_CHJ_CPU1_DIMM
   J29  147 PWR_GOOD||FAIL_N SCONN288_DDR506112002KQ-SCONN288_DDR506112002KQ,SMA    I22 @T6G_MB_LIB.T6G(SCH_1):PAGE106
  R312    1      A Q_RES_0402LF-1K,1%,1/16W,CHIP,CS21002FB06   I188 @T6G_MB_LIB.T6G(SCH_1):PAGE106
  R113    2      B Q_RES_0402LF-1K,1%,1/16W,EMPTY,CS21002FB06   I190 @T6G_MB_LIB.T6G(SCH_1):PAGE106

PWRGD_CHK_CPU0_DIMM @T6G_MB_LIB.T6G(SCH_1):PWRGD_CHK_CPU0_DIMM
   J20  147 PWR_GOOD||FAIL_N SCONN288_DDR506112002KQ-SCONN288_DDR506112002KQ,SMA    I22 @T6G_MB_LIB.T6G(SCH_1):PAGE95
  R301    1      A Q_RES_0402LF-1K,1%,1/16W,CHIP,CS21002FB06   I188 @T6G_MB_LIB.T6G(SCH_1):PAGE95
  R100    2      B Q_RES_0402LF-1K,1%,1/16W,EMPTY,CS21002FB06   I189 @T6G_MB_LIB.T6G(SCH_1):PAGE95

PWRGD_CHK_CPU1_DIMM @T6G_MB_LIB.T6G(SCH_1):PWRGD_CHK_CPU1_DIMM
   J99  147 PWR_GOOD||FAIL_N SCONN288_DDR506112002KQ-SCONN288_DDR506112002KQ,SMA    I22 @T6G_MB_LIB.T6G(SCH_1):PAGE107
  R313    1      A Q_RES_0402LF-1K,1%,1/16W,CHIP,CS21002FB06   I188 @T6G_MB_LIB.T6G(SCH_1):PAGE107
  R114    2      B Q_RES_0402LF-1K,1%,1/16W,EMPTY,CS21002FB06   I190 @T6G_MB_LIB.T6G(SCH_1):PAGE107

PWRGD_CHL_CPU0_DIMM @T6G_MB_LIB.T6G(SCH_1):PWRGD_CHL_CPU0_DIMM
   J67  147 PWR_GOOD||FAIL_N SCONN288_DDR506112002KQ-SCONN288_DDR506112002KQ,SMA    I22 @T6G_MB_LIB.T6G(SCH_1):PAGE96
  R302    1      A Q_RES_0402LF-1K,1%,1/16W,CHIP,CS21002FB06   I188 @T6G_MB_LIB.T6G(SCH_1):PAGE96
  R101    2      B Q_RES_0402LF-1K,1%,1/16W,EMPTY,CS21002FB06   I189 @T6G_MB_LIB.T6G(SCH_1):PAGE96

PWRGD_CHL_CPU1_DIMM @T6G_MB_LIB.T6G(SCH_1):PWRGD_CHL_CPU1_DIMM
   J37  147 PWR_GOOD||FAIL_N SCONN288_DDR506112002KQ-SCONN288_DDR506112002KQ,SMA    I22 @T6G_MB_LIB.T6G(SCH_1):PAGE108
  R314    1      A Q_RES_0402LF-1K,1%,1/16W,CHIP,CS21002FB06   I188 @T6G_MB_LIB.T6G(SCH_1):PAGE108
  R115    2      B Q_RES_0402LF-1K,1%,1/16W,EMPTY,CS21002FB06   I190 @T6G_MB_LIB.T6G(SCH_1):PAGE108

PWRGD_CPU0_PWROK @T6G_MB_LIB.T6G(SCH_1):PWRGD_CPU0_PWROK
  R702    1      A Q_RES_0402LF-10K,5%,1/16W,EMPTY,CS31002JB08     I1 @T6G_MB_LIB.T6G(SCH_1):PAGE77
   U29    1     1A SN74LVC2G07DCKR_SMLF-SN74LVC2G07DCKR,IC,AL002G07006    I15 @T6G_MB_LIB.T6G(SCH_1):PAGE77
   U29    3     2A SN74LVC2G07DCKR_SMLF-SN74LVC2G07DCKR,IC,AL002G07006    I15 @T6G_MB_LIB.T6G(SCH_1):PAGE77
  R443    1      A Q_RES_0402LF-1K,1%,1/16W,CHIP,CS21002FB06    I53 @T6G_MB_LIB.T6G(SCH_1):PAGE28
  R242    1      A Q_RES_0402LF-0,5%,1/16W,CHIP,CS00002JB13   I110 @T6G_MB_LIB.T6G(SCH_1):PAGE80
   U25  D69 PWROK||SVI_RST_L GENOA_SP5-SOCKET6096_13568-001,SMLF,IO,DGA^6000030   I188 @T6G_MB_LIB.T6G(SCH_1):PAGE28
 R1422    1      A Q_RES_0402LF-100,1%,1/16W,CHIP,CS11002FB07   I104 @T6G_MB_LIB.T6G(SCH_1):PAGE84

PWRGD_CPU1_PWROK @T6G_MB_LIB.T6G(SCH_1):PWRGD_CPU1_PWROK
   U26  D69 PWROK||SVI_RST_L GENOA_SP5-SOCKET6096_13568-001,SMLF,IO,DGA^6000030   I182 @T6G_MB_LIB.T6G(SCH_1):PAGE55
  R703    1      A Q_RES_0402LF-10K,5%,1/16W,EMPTY,CS31002JB08     I5 @T6G_MB_LIB.T6G(SCH_1):PAGE77
   U40    1     1A SN74LVC2G07DCKR_SMLF-SN74LVC2G07DCKR,IC,AL002G07006    I21 @T6G_MB_LIB.T6G(SCH_1):PAGE77
   U40    3     2A SN74LVC2G07DCKR_SMLF-SN74LVC2G07DCKR,IC,AL002G07006    I21 @T6G_MB_LIB.T6G(SCH_1):PAGE77
  R203    1      A Q_RES_0402LF-0,5%,1/16W,CHIP,CS00002JB13   I106 @T6G_MB_LIB.T6G(SCH_1):PAGE80
  R557    2      B Q_RES_0402LF-1K,1%,1/16W,EMPTY,CS21002FB06   I364 @T6G_MB_LIB.T6G(SCH_1):PAGE55
 R1422    2      B Q_RES_0402LF-100,1%,1/16W,CHIP,CS11002FB07   I104 @T6G_MB_LIB.T6G(SCH_1):PAGE84

PWRGD_OCP_SFF_PWR_GOOD @T6G_MB_LIB.T6G(SCH_1):PWRGD_OCP_SFF_PWR_GOOD
   U18   N4  PL18D LCMXO3LF9400C5BG484C-LCMXO3LF-9400C-5BG484C,SMLF,IA   I143 @T6G_MB_LIB.T6G(SCH_1):PAGE81
 R6054    2      B Q_RES_0402LF-0,5%,1/16W,CHIP,CS00002JB13    I83 @T6G_MB_LIB.T6G(SCH_1):PAGE81

PWRGD_P0V9_RETIMER_CPU0 @T6G_MB_LIB.T6G(SCH_1):PWRGD_P0V9_RETIMER_CPU0
  R650    1      A Q_RES_0402LF-0,5%,1/16W,CHIP,CS00002JB13   I119 @T6G_MB_LIB.T6G(SCH_1):PAGE475
 R6852    1      A Q_RES_0402LF-0,5%,1/16W,CHIP,CS00002JB13   I360 @T6G_MB_LIB.T6G(SCH_1):PAGE80

PWRGD_P0V9_RETIMER_CPU0_R @T6G_MB_LIB.T6G(SCH_1):PWRGD_P0V9_RETIMER_CPU0_R
PU6502   12    PG0 ISL69260IRAZT-ISL69260IRAZ-T,SMLF,IC,AL069260000    I42 @T6G_MB_LIB.T6G(SCH_1):PAGE475
  C101    1      A Q_CAP_0402-1000PF,50V,5%,EMPTY,TMP_QCH21006JB10   I118 @T6G_MB_LIB.T6G(SCH_1):PAGE475
  R650    2      B Q_RES_0402LF-0,5%,1/16W,CHIP,CS00002JB13   I119 @T6G_MB_LIB.T6G(SCH_1):PAGE475
  R643    2      B Q_RES_0402LF-1K,1%,1/16W,EMPTY,CS21002FB06   I212 @T6G_MB_LIB.T6G(SCH_1):PAGE475
 R6860    2      B Q_RES_0402LF-1K,1%,1/16W,CHIP,CS21002FB06   I213 @T6G_MB_LIB.T6G(SCH_1):PAGE475

PWRGD_P0V9_RETIMER_CPU0_R2 @T6G_MB_LIB.T6G(SCH_1):PWRGD_P0V9_RETIMER_CPU0_R2
   U18  D19   PR3C LCMXO3LF9400C5BG484C-LCMXO3LF-9400C-5BG484C,SMLF,IA   I217 @T6G_MB_LIB.T6G(SCH_1):PAGE80
 R6852    2      B Q_RES_0402LF-0,5%,1/16W,CHIP,CS00002JB13   I360 @T6G_MB_LIB.T6G(SCH_1):PAGE80

PWRGD_P0V9_RETIMER_CPU1 @T6G_MB_LIB.T6G(SCH_1):PWRGD_P0V9_RETIMER_CPU1
  R661    1      A Q_RES_0402LF-0,5%,1/16W,CHIP,CS00002JB13    I39 @T6G_MB_LIB.T6G(SCH_1):PAGE477
 R6853    1      A Q_RES_0402LF-0,5%,1/16W,CHIP,CS00002JB13   I362 @T6G_MB_LIB.T6G(SCH_1):PAGE80

PWRGD_P0V9_RETIMER_CPU1_R @T6G_MB_LIB.T6G(SCH_1):PWRGD_P0V9_RETIMER_CPU1_R
  R661    2      B Q_RES_0402LF-0,5%,1/16W,CHIP,CS00002JB13    I39 @T6G_MB_LIB.T6G(SCH_1):PAGE477
  C107    1      A Q_CAP_0402-1000PF,50V,5%,EMPTY,TMP_QCH21006JB10    I45 @T6G_MB_LIB.T6G(SCH_1):PAGE477
PU6510   12    PG0 ISL69260IRAZT-ISL69260IRAZ-T,SMLF,IC,AL069260000    I88 @T6G_MB_LIB.T6G(SCH_1):PAGE477
  R656    2      B Q_RES_0402LF-1K,1%,1/16W,EMPTY,CS21002FB06    I92 @T6G_MB_LIB.T6G(SCH_1):PAGE477
 R6861    2      B Q_RES_0402LF-1K,1%,1/16W,CHIP,CS21002FB06    I93 @T6G_MB_LIB.T6G(SCH_1):PAGE477

PWRGD_P0V9_RETIMER_CPU1_R2 @T6G_MB_LIB.T6G(SCH_1):PWRGD_P0V9_RETIMER_CPU1_R2
   U18  E20   PR4D LCMXO3LF9400C5BG484C-LCMXO3LF-9400C-5BG484C,SMLF,IA   I217 @T6G_MB_LIB.T6G(SCH_1):PAGE80
 R6853    2      B Q_RES_0402LF-0,5%,1/16W,CHIP,CS00002JB13   I362 @T6G_MB_LIB.T6G(SCH_1):PAGE80

PWRGD_P12V_MEM @T6G_MB_LIB.T6G(SCH_1):PWRGD_P12V_MEM
   U38    4      Y SN74LVC1G11DCKR-SN74LVC1G11DCKR,SMLF,IC,ALLVC1G1000     I8 @T6G_MB_LIB.T6G(SCH_1):PAGE264
 R1363    1      A Q_RES_0402LF-33,5%,1/16W,CHIP,CS03302JB10    I17 @T6G_MB_LIB.T6G(SCH_1):PAGE264

PWRGD_P12V_MEM_CPU0 @T6G_MB_LIB.T6G(SCH_1):PWRGD_P12V_MEM_CPU0
 R1458    1      A Q_RES_0402LF-33,5%,1/16W,CHIP,CS03302JB10     I6 @T6G_MB_LIB.T6G(SCH_1):PAGE264
   Q18    3     D2 BSS138DW7F-BSS138DW-7-F,SMLF,IC,BAM01380032    I36 @T6G_MB_LIB.T6G(SCH_1):PAGE264
 R1457    2      B Q_RES_0402LF-10K,5%,1/16W,CHIP,CS31002JB08    I41 @T6G_MB_LIB.T6G(SCH_1):PAGE264

PWRGD_P12V_MEM_CPU0_EN @T6G_MB_LIB.T6G(SCH_1):PWRGD_P12V_MEM_CPU0_EN
 R1443    1      A Q_RES_0402LF-16.9K,1%,1/16W,CHIP,CS31692FB03    I27 @T6G_MB_LIB.T6G(SCH_1):PAGE264
 R1442    2      B Q_RES_0402LF-100K,1%,1/16W,CHIP,CS41002FB09    I30 @T6G_MB_LIB.T6G(SCH_1):PAGE264
   Q18    2     G1 BSS138DW7F-BSS138DW-7-F,SMLF,IC,BAM01380032    I36 @T6G_MB_LIB.T6G(SCH_1):PAGE264

PWRGD_P12V_MEM_CPU0_EN_N @T6G_MB_LIB.T6G(SCH_1):PWRGD_P12V_MEM_CPU0_EN_N
   Q18    6     D1 BSS138DW7F-BSS138DW-7-F,SMLF,IC,BAM01380032    I36 @T6G_MB_LIB.T6G(SCH_1):PAGE264
   Q18    5     G2 BSS138DW7F-BSS138DW-7-F,SMLF,IC,BAM01380032    I36 @T6G_MB_LIB.T6G(SCH_1):PAGE264
 R1450    2      B Q_RES_0402LF-10K,5%,1/16W,CHIP,CS31002JB08    I39 @T6G_MB_LIB.T6G(SCH_1):PAGE264

PWRGD_P12V_MEM_CPU0_R @T6G_MB_LIB.T6G(SCH_1):PWRGD_P12V_MEM_CPU0_R
 R1458    2      B Q_RES_0402LF-33,5%,1/16W,CHIP,CS03302JB10     I6 @T6G_MB_LIB.T6G(SCH_1):PAGE264
   U38    1      A SN74LVC1G11DCKR-SN74LVC1G11DCKR,SMLF,IC,ALLVC1G1000     I8 @T6G_MB_LIB.T6G(SCH_1):PAGE264

PWRGD_P12V_MEM_CPU1 @T6G_MB_LIB.T6G(SCH_1):PWRGD_P12V_MEM_CPU1
 R1459    1      A Q_RES_0402LF-33,5%,1/16W,CHIP,CS03302JB10     I5 @T6G_MB_LIB.T6G(SCH_1):PAGE264
   Q19    3     D2 BSS138DW7F-BSS138DW-7-F,SMLF,IC,BAM01380032    I33 @T6G_MB_LIB.T6G(SCH_1):PAGE264
 R1452    2      B Q_RES_0402LF-10K,5%,1/16W,CHIP,CS31002JB08    I43 @T6G_MB_LIB.T6G(SCH_1):PAGE264

PWRGD_P12V_MEM_CPU1_EN @T6G_MB_LIB.T6G(SCH_1):PWRGD_P12V_MEM_CPU1_EN
 R1441    1      A Q_RES_0402LF-16.9K,1%,1/16W,CHIP,CS31692FB03    I24 @T6G_MB_LIB.T6G(SCH_1):PAGE264
 R1440    2      B Q_RES_0402LF-100K,1%,1/16W,CHIP,CS41002FB09    I25 @T6G_MB_LIB.T6G(SCH_1):PAGE264
   Q19    2     G1 BSS138DW7F-BSS138DW-7-F,SMLF,IC,BAM01380032    I33 @T6G_MB_LIB.T6G(SCH_1):PAGE264

PWRGD_P12V_MEM_CPU1_EN_N @T6G_MB_LIB.T6G(SCH_1):PWRGD_P12V_MEM_CPU1_EN_N
 R1449    2      B Q_RES_0402LF-10K,5%,1/16W,CHIP,CS31002JB08    I26 @T6G_MB_LIB.T6G(SCH_1):PAGE264
   Q19    6     D1 BSS138DW7F-BSS138DW-7-F,SMLF,IC,BAM01380032    I33 @T6G_MB_LIB.T6G(SCH_1):PAGE264
   Q19    5     G2 BSS138DW7F-BSS138DW-7-F,SMLF,IC,BAM01380032    I33 @T6G_MB_LIB.T6G(SCH_1):PAGE264

PWRGD_P12V_MEM_CPU1_R @T6G_MB_LIB.T6G(SCH_1):PWRGD_P12V_MEM_CPU1_R
 R1459    2      B Q_RES_0402LF-33,5%,1/16W,CHIP,CS03302JB10     I5 @T6G_MB_LIB.T6G(SCH_1):PAGE264
   U38    3      B SN74LVC1G11DCKR-SN74LVC1G11DCKR,SMLF,IC,ALLVC1G1000     I8 @T6G_MB_LIB.T6G(SCH_1):PAGE264

PWRGD_P12V_MEM_R @T6G_MB_LIB.T6G(SCH_1):PWRGD_P12V_MEM_R
   U18  N19  PR19D LCMXO3LF9400C5BG484C-LCMXO3LF-9400C-5BG484C,SMLF,IA   I217 @T6G_MB_LIB.T6G(SCH_1):PAGE80
 R1363    2      B Q_RES_0402LF-33,5%,1/16W,CHIP,CS03302JB10    I17 @T6G_MB_LIB.T6G(SCH_1):PAGE264
 C5014    1      A Q_CAP_0402-1000PF,50V,5%,X7R,TMP_QCH21006JB10    I49 @T6G_MB_LIB.T6G(SCH_1):PAGE264

PWRGD_P1V2_AUX @T6G_MB_LIB.T6G(SCH_1):PWRGD_P1V2_AUX
PU6001    9  PGOOD MPQ8626GDZ-MPQ8626GD-Z,SMLF,IC,AL008626000    I16 @T6G_MB_LIB.T6G(SCH_1):PAGE380
 R6244    2      B Q_RES_0402LF-10K,1%,1/16W,CHIP,CS31002FB08    I19 @T6G_MB_LIB.T6G(SCH_1):PAGE380
 R6241    1      A Q_RES_0402LF-0,5%,1/16W,CHIP,CS00002JB13    I44 @T6G_MB_LIB.T6G(SCH_1):PAGE380

PWRGD_P1V2_AUX_R @T6G_MB_LIB.T6G(SCH_1):PWRGD_P1V2_AUX_R
   U18   Y9  PB21C LCMXO3LF9400C5BG484C-LCMXO3LF-9400C-5BG484C,SMLF,IA   I216 @T6G_MB_LIB.T6G(SCH_1):PAGE80
 R6241    2      B Q_RES_0402LF-0,5%,1/16W,CHIP,CS00002JB13    I44 @T6G_MB_LIB.T6G(SCH_1):PAGE380
 Q6000    2     G1 MOSFET_NCH_DUAL-PJT138K,SMLF,IC,BAM138K0003    I47 @T6G_MB_LIB.T6G(SCH_1):PAGE254

PWRGD_P1V8_AUX @T6G_MB_LIB.T6G(SCH_1):PWRGD_P1V8_AUX
PU6000    9  PGOOD MPQ8626GDZ-MPQ8626GD-Z,SMLF,IC,AL008626000    I18 @T6G_MB_LIB.T6G(SCH_1):PAGE315
 R6243    2      B Q_RES_0402LF-10K,1%,1/16W,CHIP,CS31002FB08    I32 @T6G_MB_LIB.T6G(SCH_1):PAGE315
  R214    1      A Q_RES_0402LF-33,5%,1/16W,CHIP,CS03302JB10    I44 @T6G_MB_LIB.T6G(SCH_1):PAGE315

PWRGD_P1V8_AUX_R @T6G_MB_LIB.T6G(SCH_1):PWRGD_P1V8_AUX_R
 R2476    2      B Q_RES_0402LF-200K,1%,1/16W,EMPTY,CS42002FB05    I70 @T6G_MB_LIB.T6G(SCH_1):PAGE346
   U18   Y8  PB18C LCMXO3LF9400C5BG484C-LCMXO3LF-9400C-5BG484C,SMLF,IA   I216 @T6G_MB_LIB.T6G(SCH_1):PAGE80
   Q78    2     G1 MOSFET_NCH_DUAL-PJT138K,SMLF,IC,BAM138K0003    I24 @T6G_MB_LIB.T6G(SCH_1):PAGE254
  R214    2      B Q_RES_0402LF-33,5%,1/16W,CHIP,CS03302JB10    I44 @T6G_MB_LIB.T6G(SCH_1):PAGE315
 R6240    1      A Q_RES_0402LF-0,5%,1/16W,CHIP,CS00002JB13    I40 @T6G_MB_LIB.T6G(SCH_1):PAGE380
 C6085    1      A Q_CAP_0402-0.1UF,25V,10%,EMPTY,CH4104K1B00    I41 @T6G_MB_LIB.T6G(SCH_1):PAGE380

PWRGD_P1V8_RETIMER_CPU0 @T6G_MB_LIB.T6G(SCH_1):PWRGD_P1V8_RETIMER_CPU0
 R6505    2      B Q_RES_0402LF-10K,5%,1/16W,CHIP,CS31002JB08    I28 @T6G_MB_LIB.T6G(SCH_1):PAGE469
 R6506    1      A Q_RES_0402LF-33,5%,1/16W,CHIP,CS03302JB10    I37 @T6G_MB_LIB.T6G(SCH_1):PAGE469
PU6500    9  PGOOD MPQ8633BGLEC838Z-MPQ8633BGLE-C838-Z,SMLF,IC,AL0086A    I51 @T6G_MB_LIB.T6G(SCH_1):PAGE469

PWRGD_P1V8_RETIMER_CPU1 @T6G_MB_LIB.T6G(SCH_1):PWRGD_P1V8_RETIMER_CPU1
  R644    2      B Q_RES_0402LF-10K,5%,1/16W,CHIP,CS31002JB08    I29 @T6G_MB_LIB.T6G(SCH_1):PAGE470
  R645    1      A Q_RES_0402LF-33,5%,1/16W,CHIP,CS03302JB10    I36 @T6G_MB_LIB.T6G(SCH_1):PAGE470
PU6501    9  PGOOD MPQ8633BGLEC838Z-MPQ8633BGLE-C838-Z,SMLF,IC,AL0086A    I51 @T6G_MB_LIB.T6G(SCH_1):PAGE470

PWRGD_P3V3_AUX @T6G_MB_LIB.T6G(SCH_1):PWRGD_P3V3_AUX
 R6047    1      A Q_RES_0402LF-0,5%,1/16W,CHIP,CS00002JB13    I34 @T6G_MB_LIB.T6G(SCH_1):PAGE80
 R6078    1      A Q_RES_0402LF-0,5%,1/16W,CHIP,CS00002JB13    I61 @T6G_MB_LIB.T6G(SCH_1):PAGE84
 R6099    2      B Q_RES_0402LF-0,5%,1/16W,CHIP,CS00002JB13    I67 @T6G_MB_LIB.T6G(SCH_1):PAGE245
 C5015    1      A Q_CAP_0402-1000PF,50V,5%,EMPTY,TMP_QCH21006JB10    I68 @T6G_MB_LIB.T6G(SCH_1):PAGE245
 R6119    1      A Q_RES_0402LF-0,5%,1/16W,CHIP,CS00002JB13    I40 @T6G_MB_LIB.T6G(SCH_1):PAGE315

PWRGD_P3V3_AUX_PDB @T6G_MB_LIB.T6G(SCH_1):PWRGD_P3V3_AUX_PDB
 R4268    1      A Q_RES_0402LF-0,5%,1/16W,CHIP,CS00002JB13    I41 @T6G_MB_LIB.T6G(SCH_1):PAGE364
 R6078    2      B Q_RES_0402LF-0,5%,1/16W,CHIP,CS00002JB13    I61 @T6G_MB_LIB.T6G(SCH_1):PAGE84

PWRGD_P3V3_AUX_PDB_BUF @T6G_MB_LIB.T6G(SCH_1):PWRGD_P3V3_AUX_PDB_BUF
 R4266    2      B Q_RES_0402LF-33.2,1%,1/16W,CHIP,CS03322FB03    I48 @T6G_MB_LIB.T6G(SCH_1):PAGE364
   J45   B2     B2 CONN60_101062636003K02LF-CONN60_10106263-6003K02LFA   I466 @T6G_MB_LIB.T6G(SCH_1):PAGE363

PWRGD_P3V3_AUX_PDB_BUF_R @T6G_MB_LIB.T6G(SCH_1):PWRGD_P3V3_AUX_PDB_BUF_R
  U308    6     1Y 74LVC2G07DW7-74LVC2G07DW-7,SMLF,IC,AL002G07003    I37 @T6G_MB_LIB.T6G(SCH_1):PAGE364
 R4265    1      A Q_RES_0402LF-4.7K,5%,1/16W,EMPTY,CS24702JB10    I43 @T6G_MB_LIB.T6G(SCH_1):PAGE364
 R4264    2      B Q_RES_0402LF-4.7K,5%,1/16W,CHIP,CS24702JB10    I47 @T6G_MB_LIB.T6G(SCH_1):PAGE364
 R4266    1      A Q_RES_0402LF-33.2,1%,1/16W,CHIP,CS03322FB03    I48 @T6G_MB_LIB.T6G(SCH_1):PAGE364

PWRGD_P3V3_AUX_PDB_R @T6G_MB_LIB.T6G(SCH_1):PWRGD_P3V3_AUX_PDB_R
  U308    1     1A 74LVC2G07DW7-74LVC2G07DW-7,SMLF,IC,AL002G07003    I37 @T6G_MB_LIB.T6G(SCH_1):PAGE364
 R4268    2      B Q_RES_0402LF-0,5%,1/16W,CHIP,CS00002JB13    I41 @T6G_MB_LIB.T6G(SCH_1):PAGE364

PWRGD_P3V3_AUX_R @T6G_MB_LIB.T6G(SCH_1):PWRGD_P3V3_AUX_R
 R6047    2      B Q_RES_0402LF-0,5%,1/16W,CHIP,CS00002JB13    I34 @T6G_MB_LIB.T6G(SCH_1):PAGE80
   U18   W8  PB16D LCMXO3LF9400C5BG484C-LCMXO3LF-9400C-5BG484C,SMLF,IA   I216 @T6G_MB_LIB.T6G(SCH_1):PAGE80

PWRGD_P3V3_AUX_R1 @T6G_MB_LIB.T6G(SCH_1):PWRGD_P3V3_AUX_R1
   PU9    2  PGOOD NCP3284AMNTXG-NCP3284AMNTXG,SMLF,IC,AL003284002    I21 @T6G_MB_LIB.T6G(SCH_1):PAGE245
PR8073    2      B Q_RES_0402LF-1K,1%,1/16W,CHIP,CS21002FB06    I65 @T6G_MB_LIB.T6G(SCH_1):PAGE245
 R6099    1      A Q_RES_0402LF-0,5%,1/16W,CHIP,CS00002JB13    I67 @T6G_MB_LIB.T6G(SCH_1):PAGE245

PWRGD_P3V3_EN @T6G_MB_LIB.T6G(SCH_1):PWRGD_P3V3_EN
   Q27    2     G1 BSS138DW7F-BSS138DW-7-F,SMLF,IC,BAM01380032   I123 @T6G_MB_LIB.T6G(SCH_1):PAGE273
 R6500    2      B Q_RES_0402LF-0,5%,1/16W,CHIP,CS00002JB13   I136 @T6G_MB_LIB.T6G(SCH_1):PAGE273

PWRGD_P3V3_EN_N @T6G_MB_LIB.T6G(SCH_1):PWRGD_P3V3_EN_N
 R1492    2      B Q_RES_0402LF-10K,5%,1/16W,CHIP,CS31002JB08   I120 @T6G_MB_LIB.T6G(SCH_1):PAGE273
   Q27    6     D1 BSS138DW7F-BSS138DW-7-F,SMLF,IC,BAM01380032   I123 @T6G_MB_LIB.T6G(SCH_1):PAGE273
   Q27    5     G2 BSS138DW7F-BSS138DW-7-F,SMLF,IC,BAM01380032   I123 @T6G_MB_LIB.T6G(SCH_1):PAGE273

PWRGD_P3V3_EN_R @T6G_MB_LIB.T6G(SCH_1):PWRGD_P3V3_EN_R
 U6006    2 RESET_L APX80929SAG7-APX809-29SAG-7,SMLF,IC,AL080929000   I131 @T6G_MB_LIB.T6G(SCH_1):PAGE273
 R6500    1      A Q_RES_0402LF-0,5%,1/16W,CHIP,CS00002JB13   I136 @T6G_MB_LIB.T6G(SCH_1):PAGE273
 R6501    1      A Q_RES_0402LF-100K,1%,1/16W,CHIP,CS41002FB09   I139 @T6G_MB_LIB.T6G(SCH_1):PAGE273
 R1491    2      B Q_RES_0402LF-10K,5%,1/16W,EMPTY,CS31002JB08   I141 @T6G_MB_LIB.T6G(SCH_1):PAGE273

PWRGD_P3V3_R1 @T6G_MB_LIB.T6G(SCH_1):PWRGD_P3V3_R1
   Q27    3     D2 BSS138DW7F-BSS138DW-7-F,SMLF,IC,BAM01380032   I123 @T6G_MB_LIB.T6G(SCH_1):PAGE273
 R1493    2      B Q_RES_0402LF-10K,5%,1/16W,CHIP,CS31002JB08   I125 @T6G_MB_LIB.T6G(SCH_1):PAGE273
 R1362    1      A Q_RES_0402LF-33,5%,1/16W,CHIP,CS03302JB10   I130 @T6G_MB_LIB.T6G(SCH_1):PAGE273

PWRGD_P3V3_R2 @T6G_MB_LIB.T6G(SCH_1):PWRGD_P3V3_R2
   U18  M16  PR18A LCMXO3LF9400C5BG484C-LCMXO3LF-9400C-5BG484C,SMLF,IA   I217 @T6G_MB_LIB.T6G(SCH_1):PAGE80
 R1362    2      B Q_RES_0402LF-33,5%,1/16W,CHIP,CS03302JB10   I130 @T6G_MB_LIB.T6G(SCH_1):PAGE273

PWRGD_P5V @T6G_MB_LIB.T6G(SCH_1):PWRGD_P5V
   U18  A16  PT39A LCMXO3LF9400C5BG484C-LCMXO3LF-9400C-5BG484C,SMLF,IA    I94 @T6G_MB_LIB.T6G(SCH_1):PAGE79
  R439    1      A Q_RES_0402LF-0,5%,1/16W,CHIP,CS00002JB13   I144 @T6G_MB_LIB.T6G(SCH_1):PAGE79

PWRGD_P5V_AUX @T6G_MB_LIB.T6G(SCH_1):PWRGD_P5V_AUX
 R1571    1      A Q_RES_0402LF-0,5%,1/16W,CHIP,CS00002JB13    I11 @T6G_MB_LIB.T6G(SCH_1):PAGE245
 R2316    2      B Q_RES_0402LF-0,5%,1/16W,CHIP,CS00002JB13    I26 @T6G_MB_LIB.T6G(SCH_1):PAGE244
 R2343    2      B Q_RES_0402LF-10K,1%,1/16W,EMPTY,CS31002FB08    I63 @T6G_MB_LIB.T6G(SCH_1):PAGE84
   Q50    2     G1 MOSFET_NCH_DUAL-PJT138K,SMLF,IC,BAM138K0003    I65 @T6G_MB_LIB.T6G(SCH_1):PAGE84

PWRGD_P5V_AUX_R @T6G_MB_LIB.T6G(SCH_1):PWRGD_P5V_AUX_R
 R2356    2      B Q_RES_0402LF-10K,1%,1/16W,CHIP,CS31002FB08    I25 @T6G_MB_LIB.T6G(SCH_1):PAGE244
 R2316    1      A Q_RES_0402LF-0,5%,1/16W,CHIP,CS00002JB13    I26 @T6G_MB_LIB.T6G(SCH_1):PAGE244
  U326    9  PGOOD MPQ8633AGLEC807Z-MPQ8633AGLE-C807-Z,SMLF,IC,AL0086A    I38 @T6G_MB_LIB.T6G(SCH_1):PAGE244

PWRGD_P5V_AUX_R1 @T6G_MB_LIB.T6G(SCH_1):PWRGD_P5V_AUX_R1
   Q50    6     D1 MOSFET_NCH_DUAL-PJT138K,SMLF,IC,BAM138K0003    I65 @T6G_MB_LIB.T6G(SCH_1):PAGE84
 R2344    2      B Q_RES_0402LF-4.7K,5%,1/16W,CHIP,CS24702JB10    I67 @T6G_MB_LIB.T6G(SCH_1):PAGE84
   Q50    5     G2 MOSFET_NCH_DUAL-PJT138K,SMLF,IC,BAM138K0003    I73 @T6G_MB_LIB.T6G(SCH_1):PAGE84

PWRGD_P5V_AUX_R2 @T6G_MB_LIB.T6G(SCH_1):PWRGD_P5V_AUX_R2
 R2346    2      B Q_RES_0402LF-100K,1%,1/16W,CHIP,CS41002FB09    I70 @T6G_MB_LIB.T6G(SCH_1):PAGE84
   Q50    3     D2 MOSFET_NCH_DUAL-PJT138K,SMLF,IC,BAM138K0003    I73 @T6G_MB_LIB.T6G(SCH_1):PAGE84
 R6118    2      B Q_RES_0402LF-0,5%,1/16W,CHIP,CS00002JB13   I103 @T6G_MB_LIB.T6G(SCH_1):PAGE84

PWRGD_P5V_AUX_R3 @T6G_MB_LIB.T6G(SCH_1):PWRGD_P5V_AUX_R3
   U18   U4  PL27D LCMXO3LF9400C5BG484C-LCMXO3LF-9400C-5BG484C,SMLF,IA   I143 @T6G_MB_LIB.T6G(SCH_1):PAGE81
 C8005    1      A Q_CAP_0402-0.1UF,25V,10%,X7R,CH4104K1B00   I101 @T6G_MB_LIB.T6G(SCH_1):PAGE84
 R6118    1      A Q_RES_0402LF-0,5%,1/16W,CHIP,CS00002JB13   I103 @T6G_MB_LIB.T6G(SCH_1):PAGE84

PWRGD_P5V_N @T6G_MB_LIB.T6G(SCH_1):PWRGD_P5V_N
    Q1    5     G2 MOSFET_NCH_DUAL-PJT138K,SMLF,IC,BAM138K0003    I98 @T6G_MB_LIB.T6G(SCH_1):PAGE273
  R494    2      B Q_RES_0402LF-0,5%,1/16W,CHIP,CS00002JB13   I102 @T6G_MB_LIB.T6G(SCH_1):PAGE273

PWRGD_P5V_R @T6G_MB_LIB.T6G(SCH_1):PWRGD_P5V_R
  U100    1 RESET# RT9818C44GV-RT9818C-44GV,SMLF,IC,AL009818001    I77 @T6G_MB_LIB.T6G(SCH_1):PAGE273
  R479    2      B Q_RES_0402LF-10K,1%,1/16W,CHIP,CS31002FB08    I83 @T6G_MB_LIB.T6G(SCH_1):PAGE273
  R480    1      A Q_RES_0402LF-100K,1%,1/16W,CHIP,CS41002FB09    I84 @T6G_MB_LIB.T6G(SCH_1):PAGE273
  R490    1      A Q_RES_0402LF-0,5%,1/16W,EMPTY,CS00002JB13    I88 @T6G_MB_LIB.T6G(SCH_1):PAGE273
  R482    1      A Q_RES_0402LF-0,5%,1/16W,CHIP,CS00002JB13    I96 @T6G_MB_LIB.T6G(SCH_1):PAGE273

PWRGD_P5V_R1 @T6G_MB_LIB.T6G(SCH_1):PWRGD_P5V_R1
  R482    2      B Q_RES_0402LF-0,5%,1/16W,CHIP,CS00002JB13    I96 @T6G_MB_LIB.T6G(SCH_1):PAGE273
    Q1    2     G1 MOSFET_NCH_DUAL-PJT138K,SMLF,IC,BAM138K0003    I97 @T6G_MB_LIB.T6G(SCH_1):PAGE273

PWRGD_P5V_R2 @T6G_MB_LIB.T6G(SCH_1):PWRGD_P5V_R2
    Q1    3     D2 MOSFET_NCH_DUAL-PJT138K,SMLF,IC,BAM138K0003    I98 @T6G_MB_LIB.T6G(SCH_1):PAGE273
  R552    2      B Q_RES_0402LF-4.7K,5%,1/16W,CHIP,CS24702JB10   I104 @T6G_MB_LIB.T6G(SCH_1):PAGE273
  R439    2      B Q_RES_0402LF-0,5%,1/16W,CHIP,CS00002JB13   I144 @T6G_MB_LIB.T6G(SCH_1):PAGE79

PWRGD_P5V_R_N @T6G_MB_LIB.T6G(SCH_1):PWRGD_P5V_R_N
    Q1    6     D1 MOSFET_NCH_DUAL-PJT138K,SMLF,IC,BAM138K0003    I97 @T6G_MB_LIB.T6G(SCH_1):PAGE273
  R492    2      B Q_RES_0402LF-4.7K,5%,1/16W,CHIP,CS24702JB10    I99 @T6G_MB_LIB.T6G(SCH_1):PAGE273
  R494    1      A Q_RES_0402LF-0,5%,1/16W,CHIP,CS00002JB13   I102 @T6G_MB_LIB.T6G(SCH_1):PAGE273

PWRGD_PS_PWROK @T6G_MB_LIB.T6G(SCH_1):PWRGD_PS_PWROK
 R1816    1      A Q_RES_0402LF-0,5%,1/16W,CHIP,CS00002JB13    I32 @T6G_MB_LIB.T6G(SCH_1):PAGE348
 R3048    2      B Q_RES_0402LF-0,5%,1/16W,CHIP,CS00002JB13     I7 @T6G_MB_LIB.T6G(SCH_1):PAGE368

PWRGD_PS_PWROK_PLD @T6G_MB_LIB.T6G(SCH_1):PWRGD_PS_PWROK_PLD
  Q144    2     G1 MOSFET_NCH_DUAL-PJT138K,SMLF,IC,BAM138K0003     I3 @T6G_MB_LIB.T6G(SCH_1):PAGE368
 R3047    2      B Q_RES_0402LF-0,5%,1/16W,CHIP,CS00002JB13     I8 @T6G_MB_LIB.T6G(SCH_1):PAGE368
   Q78    5     G2 MOSFET_NCH_DUAL-PJT138K,SMLF,IC,BAM138K0003    I18 @T6G_MB_LIB.T6G(SCH_1):PAGE254

PWRGD_PS_PWROK_PLD_ISO @T6G_MB_LIB.T6G(SCH_1):PWRGD_PS_PWROK_PLD_ISO
  Q144    3     D2 MOSFET_NCH_DUAL-PJT138K,SMLF,IC,BAM138K0003    I10 @T6G_MB_LIB.T6G(SCH_1):PAGE368
 R4605    2      B Q_RES_0402LF-1K,1%,1/16W,CHIP,CS21002FB06    I11 @T6G_MB_LIB.T6G(SCH_1):PAGE368
 R9446    1      A Q_RES_0402LF-33.2,1%,1/16W,CHIP,CS03322FB03    I13 @T6G_MB_LIB.T6G(SCH_1):PAGE368

PWRGD_PS_PWROK_PLD_ISO_R @T6G_MB_LIB.T6G(SCH_1):PWRGD_PS_PWROK_PLD_ISO_R
 R9446    2      B Q_RES_0402LF-33.2,1%,1/16W,CHIP,CS03322FB03    I13 @T6G_MB_LIB.T6G(SCH_1):PAGE368
   U18   F8  PT11C LCMXO3LF9400C5BG484C-LCMXO3LF-9400C-5BG484C,SMLF,IA    I94 @T6G_MB_LIB.T6G(SCH_1):PAGE79

PWRGD_PS_PWROK_PLD_N @T6G_MB_LIB.T6G(SCH_1):PWRGD_PS_PWROK_PLD_N
  Q144    6     D1 MOSFET_NCH_DUAL-PJT138K,SMLF,IC,BAM138K0003     I3 @T6G_MB_LIB.T6G(SCH_1):PAGE368
 R4604    2      B Q_RES_0402LF-4.7K,5%,1/16W,CHIP,CS24702JB10     I5 @T6G_MB_LIB.T6G(SCH_1):PAGE368
  Q144    5     G2 MOSFET_NCH_DUAL-PJT138K,SMLF,IC,BAM138K0003    I10 @T6G_MB_LIB.T6G(SCH_1):PAGE368

PWRGD_PS_PWROK_R @T6G_MB_LIB.T6G(SCH_1):PWRGD_PS_PWROK_R
 R1816    2      B Q_RES_0402LF-0,5%,1/16W,CHIP,CS00002JB13    I32 @T6G_MB_LIB.T6G(SCH_1):PAGE348
   J41  A44  PERN8 SCONN168_ME1016810202011-SCONN168_ME1016810202011,A   I176 @T6G_MB_LIB.T6G(SCH_1):PAGE348

PWRGD_PVDD11_S3_P0 @T6G_MB_LIB.T6G(SCH_1):PWRGD_PVDD11_S3_P0
  R228    1      A Q_RES_0402LF-0,5%,1/16W,CHIP,CS00002JB13    I66 @T6G_MB_LIB.T6G(SCH_1):PAGE80
  R122    1      A Q_RES_0402LF-0,5%,1/16W,CHIP,CS00002JB13    I44 @T6G_MB_LIB.T6G(SCH_1):PAGE182

PWRGD_PVDD11_S3_P0_R @T6G_MB_LIB.T6G(SCH_1):PWRGD_PVDD11_S3_P0_R
  C196    1      A Q_CAP_0402-1000PF,50V,5%,EMPTY,TMP_QCH21006JB10    I47 @T6G_MB_LIB.T6G(SCH_1):PAGE182
  PU21   12    PG0 RAA229621GNPHA0-RAA229621GNP#HA0,SMLF,IC,ARF0TGP40A    I24 @T6G_MB_LIB.T6G(SCH_1):PAGE182
  R117    2      B Q_RES_0402LF-1K,1%,1/16W,CHIP,CS21002FB06    I38 @T6G_MB_LIB.T6G(SCH_1):PAGE182
  R122    2      B Q_RES_0402LF-0,5%,1/16W,CHIP,CS00002JB13    I44 @T6G_MB_LIB.T6G(SCH_1):PAGE182

PWRGD_PVDD11_S3_P1 @T6G_MB_LIB.T6G(SCH_1):PWRGD_PVDD11_S3_P1
  R280    1      A Q_RES_0402LF-0,5%,1/16W,CHIP,CS00002JB13    I59 @T6G_MB_LIB.T6G(SCH_1):PAGE80
 R8385    1      A Q_RES_0402LF-0,5%,1/16W,CHIP,CS00002JB13    I43 @T6G_MB_LIB.T6G(SCH_1):PAGE199

PWRGD_PVDD11_S3_P1_R @T6G_MB_LIB.T6G(SCH_1):PWRGD_PVDD11_S3_P1_R
 R8380    2      B Q_RES_0402LF-1K,1%,1/16W,CHIP,CS21002FB06    I37 @T6G_MB_LIB.T6G(SCH_1):PAGE199
 R8385    2      B Q_RES_0402LF-0,5%,1/16W,CHIP,CS00002JB13    I43 @T6G_MB_LIB.T6G(SCH_1):PAGE199
 C8641    1      A Q_CAP_0402-1000PF,50V,5%,EMPTY,TMP_QCH21006JB10    I46 @T6G_MB_LIB.T6G(SCH_1):PAGE199
  PU54   12    PG0 RAA229621GNPHA0-RAA229621GNP#HA0,SMLF,IC,ARF0TGP40A    I86 @T6G_MB_LIB.T6G(SCH_1):PAGE199

PWRGD_PVDD18_S5_P0 @T6G_MB_LIB.T6G(SCH_1):PWRGD_PVDD18_S5_P0
  PU57    9  PGOOD MPQ8633BGLEC838Z-MPQ8633BGLE-C838-Z,SMLF,IC,AL0086A    I18 @T6G_MB_LIB.T6G(SCH_1):PAGE184
 R8465    2      B Q_RES_0402LF-10K,5%,1/16W,CHIP,CS31002JB08    I29 @T6G_MB_LIB.T6G(SCH_1):PAGE184
  R177    1      A Q_RES_0402LF-33,5%,1/16W,CHIP,CS03302JB10    I52 @T6G_MB_LIB.T6G(SCH_1):PAGE184

PWRGD_PVDD18_S5_P1 @T6G_MB_LIB.T6G(SCH_1):PWRGD_PVDD18_S5_P1
   PU3    9  PGOOD MPQ8633BGLEC838Z-MPQ8633BGLE-C838-Z,SMLF,IC,AL0086A    I15 @T6G_MB_LIB.T6G(SCH_1):PAGE201
 R8009    2      B Q_RES_0402LF-10K,5%,1/16W,CHIP,CS31002JB08    I26 @T6G_MB_LIB.T6G(SCH_1):PAGE201
  R259    1      A Q_RES_0402LF-33,5%,1/16W,CHIP,CS03302JB10    I48 @T6G_MB_LIB.T6G(SCH_1):PAGE201

PWRGD_PVDD18_S5_R_P1 @T6G_MB_LIB.T6G(SCH_1):PWRGD_PVDD18_S5_R_P1
  R259    2      B Q_RES_0402LF-33,5%,1/16W,CHIP,CS03302JB10    I48 @T6G_MB_LIB.T6G(SCH_1):PAGE201
   U18  AA6  PB11A LCMXO3LF9400C5BG484C-LCMXO3LF-9400C-5BG484C,SMLF,IA   I216 @T6G_MB_LIB.T6G(SCH_1):PAGE80
 C5016    1      A Q_CAP_0402-1000PF,50V,5%,X7R,TMP_QCH21006JB10    I55 @T6G_MB_LIB.T6G(SCH_1):PAGE201

PWRGD_PVDD33_S5 @T6G_MB_LIB.T6G(SCH_1):PWRGD_PVDD33_S5
  R453    2      B Q_RES_0402LF-10K,5%,1/16W,CHIP,CS31002JB08    I31 @T6G_MB_LIB.T6G(SCH_1):PAGE167
  R225    1      A Q_RES_0402LF-33,5%,1/16W,CHIP,CS03302JB10    I33 @T6G_MB_LIB.T6G(SCH_1):PAGE167
  PU55    9  PGOOD MPQ8633AGLEC807Z-MPQ8633AGLE-C807-Z,SMLF,IC,AL0086A    I41 @T6G_MB_LIB.T6G(SCH_1):PAGE167

PWRGD_PVDDCR_CPU0_P0 @T6G_MB_LIB.T6G(SCH_1):PWRGD_PVDDCR_CPU0_P0
   U18   Y3  PL30A LCMXO3LF9400C5BG484C-LCMXO3LF-9400C-5BG484C,SMLF,IA   I143 @T6G_MB_LIB.T6G(SCH_1):PAGE81
 R8311    1      A Q_RES_0402LF-33,5%,1/16W,CHIP,CS03302JB10    I89 @T6G_MB_LIB.T6G(SCH_1):PAGE168
 C5017    2      B Q_CAP_0402-1000PF,50V,5%,X7R,TMP_QCH21006JB10   I139 @T6G_MB_LIB.T6G(SCH_1):PAGE168

PWRGD_PVDDCR_CPU0_P0_R @T6G_MB_LIB.T6G(SCH_1):PWRGD_PVDDCR_CPU0_P0_R
 R8300    2      B Q_RES_0402LF-1K,1%,1/16W,CHIP,CS21002FB06    I82 @T6G_MB_LIB.T6G(SCH_1):PAGE168
 R8311    2      B Q_RES_0402LF-33,5%,1/16W,CHIP,CS03302JB10    I89 @T6G_MB_LIB.T6G(SCH_1):PAGE168
  C467    1      A Q_CAP_0402-1000PF,50V,5%,EMPTY,TMP_QCH21006JB10    I92 @T6G_MB_LIB.T6G(SCH_1):PAGE168
  PU42   16    PG0 RAA229620GNPHA0-RAA229620GNP#HA0,SMLF,IC,ARF0TGP40A   I135 @T6G_MB_LIB.T6G(SCH_1):PAGE168

PWRGD_PVDDCR_CPU0_P1 @T6G_MB_LIB.T6G(SCH_1):PWRGD_PVDDCR_CPU0_P1
  R209    1      A Q_RES_0402LF-0,5%,1/16W,CHIP,CS00002JB13    I61 @T6G_MB_LIB.T6G(SCH_1):PAGE80
 R8178    1      A Q_RES_0402LF-33,5%,1/16W,CHIP,CS03302JB10    I85 @T6G_MB_LIB.T6G(SCH_1):PAGE185
 C5003    2      B Q_CAP_0402-1000PF,50V,5%,X7R,TMP_QCH21006JB10   I141 @T6G_MB_LIB.T6G(SCH_1):PAGE185

PWRGD_PVDDCR_CPU0_P1_R @T6G_MB_LIB.T6G(SCH_1):PWRGD_PVDDCR_CPU0_P1_R
  C248    1      A Q_CAP_0402-1000PF,50V,5%,EMPTY,TMP_QCH21006JB10    I88 @T6G_MB_LIB.T6G(SCH_1):PAGE185
 R8167    2      B Q_RES_0402LF-1K,1%,1/16W,CHIP,CS21002FB06    I78 @T6G_MB_LIB.T6G(SCH_1):PAGE185
 R8178    2      B Q_RES_0402LF-33,5%,1/16W,CHIP,CS03302JB10    I85 @T6G_MB_LIB.T6G(SCH_1):PAGE185
  PU25   16    PG0 RAA229620GNPHA0-RAA229620GNP#HA0,SMLF,IC,ARF0TGP40A   I133 @T6G_MB_LIB.T6G(SCH_1):PAGE185

PWRGD_PVDDCR_CPU1_P0 @T6G_MB_LIB.T6G(SCH_1):PWRGD_PVDDCR_CPU1_P0
  R233    1      A Q_RES_0402LF-0,5%,1/16W,CHIP,CS00002JB13    I54 @T6G_MB_LIB.T6G(SCH_1):PAGE81
 R8057    1      A Q_RES_0402LF-33,5%,1/16W,CHIP,CS03302JB10    I89 @T6G_MB_LIB.T6G(SCH_1):PAGE175
 C5004    2      B Q_CAP_0402-1000PF,50V,5%,X7R,TMP_QCH21006JB10   I135 @T6G_MB_LIB.T6G(SCH_1):PAGE175

PWRGD_PVDDCR_CPU1_P0_R @T6G_MB_LIB.T6G(SCH_1):PWRGD_PVDDCR_CPU1_P0_R
 R8057    2      B Q_RES_0402LF-33,5%,1/16W,CHIP,CS03302JB10    I89 @T6G_MB_LIB.T6G(SCH_1):PAGE175
 R8056    2      B Q_RES_0402LF-1K,1%,1/16W,CHIP,CS21002FB06    I90 @T6G_MB_LIB.T6G(SCH_1):PAGE175
 C8070    1      A Q_CAP_0402-1000PF,50V,5%,EMPTY,TMP_QCH21006JB10    I91 @T6G_MB_LIB.T6G(SCH_1):PAGE175
  PU12   16    PG0 RAA229620GNPHA0-RAA229620GNP#HA0,SMLF,IC,ARF0TGP40A   I128 @T6G_MB_LIB.T6G(SCH_1):PAGE175

PWRGD_PVDDCR_CPU1_P1 @T6G_MB_LIB.T6G(SCH_1):PWRGD_PVDDCR_CPU1_P1
  R286    1      A Q_RES_0402LF-0,5%,1/16W,CHIP,CS00002JB13    I62 @T6G_MB_LIB.T6G(SCH_1):PAGE80
 R8234    1      A Q_RES_0402LF-33,5%,1/16W,CHIP,CS03302JB10    I88 @T6G_MB_LIB.T6G(SCH_1):PAGE192
 C5022    2      B Q_CAP_0402-1000PF,50V,5%,X7R,TMP_QCH21006JB10   I131 @T6G_MB_LIB.T6G(SCH_1):PAGE192

PWRGD_PVDDCR_CPU1_P1_R @T6G_MB_LIB.T6G(SCH_1):PWRGD_PVDDCR_CPU1_P1_R
 R8234    2      B Q_RES_0402LF-33,5%,1/16W,CHIP,CS03302JB10    I88 @T6G_MB_LIB.T6G(SCH_1):PAGE192
 R8233    2      B Q_RES_0402LF-1K,1%,1/16W,CHIP,CS21002FB06    I89 @T6G_MB_LIB.T6G(SCH_1):PAGE192
 C8360    1      A Q_CAP_0402-1000PF,50V,5%,EMPTY,TMP_QCH21006JB10    I90 @T6G_MB_LIB.T6G(SCH_1):PAGE192
  PU34   16    PG0 RAA229620GNPHA0-RAA229620GNP#HA0,SMLF,IC,ARF0TGP40A   I128 @T6G_MB_LIB.T6G(SCH_1):PAGE192

PWRGD_PVDDCR_SOC_P0 @T6G_MB_LIB.T6G(SCH_1):PWRGD_PVDDCR_SOC_P0
   U18   Y2  PL29D LCMXO3LF9400C5BG484C-LCMXO3LF-9400C-5BG484C,SMLF,IA   I143 @T6G_MB_LIB.T6G(SCH_1):PAGE81
 R8299    1      A Q_RES_0402LF-33,5%,1/16W,CHIP,CS03302JB10    I24 @T6G_MB_LIB.T6G(SCH_1):PAGE168
 C5018    2      B Q_CAP_0402-1000PF,50V,5%,X7R,TMP_QCH21006JB10   I138 @T6G_MB_LIB.T6G(SCH_1):PAGE168

PWRGD_PVDDCR_SOC_P0_R @T6G_MB_LIB.T6G(SCH_1):PWRGD_PVDDCR_SOC_P0_R
 R8299    2      B Q_RES_0402LF-33,5%,1/16W,CHIP,CS03302JB10    I24 @T6G_MB_LIB.T6G(SCH_1):PAGE168
 R8298    2      B Q_RES_0402LF-1K,1%,1/16W,CHIP,CS21002FB06    I28 @T6G_MB_LIB.T6G(SCH_1):PAGE168
  C465    1      A Q_CAP_0402-1000PF,50V,5%,EMPTY,TMP_QCH21006JB10    I51 @T6G_MB_LIB.T6G(SCH_1):PAGE168
  PU42   20    PG1 RAA229620GNPHA0-RAA229620GNP#HA0,SMLF,IC,ARF0TGP40A   I135 @T6G_MB_LIB.T6G(SCH_1):PAGE168

PWRGD_PVDDCR_SOC_P1 @T6G_MB_LIB.T6G(SCH_1):PWRGD_PVDDCR_SOC_P1
 R8166    1      A Q_RES_0402LF-33,5%,1/16W,CHIP,CS03302JB10    I23 @T6G_MB_LIB.T6G(SCH_1):PAGE185
   U18  A17  PT40A LCMXO3LF9400C5BG484C-LCMXO3LF-9400C-5BG484C,SMLF,IA    I94 @T6G_MB_LIB.T6G(SCH_1):PAGE79
 C5019    2      B Q_CAP_0402-1000PF,50V,5%,X7R,TMP_QCH21006JB10   I137 @T6G_MB_LIB.T6G(SCH_1):PAGE185

PWRGD_PVDDCR_SOC_P1_R @T6G_MB_LIB.T6G(SCH_1):PWRGD_PVDDCR_SOC_P1_R
 R8166    2      B Q_RES_0402LF-33,5%,1/16W,CHIP,CS03302JB10    I23 @T6G_MB_LIB.T6G(SCH_1):PAGE185
 R8165    2      B Q_RES_0402LF-1K,1%,1/16W,CHIP,CS21002FB06    I27 @T6G_MB_LIB.T6G(SCH_1):PAGE185
 C8246    1      A Q_CAP_0402-1000PF,50V,5%,EMPTY,TMP_QCH21006JB10    I52 @T6G_MB_LIB.T6G(SCH_1):PAGE185
  PU25   20    PG1 RAA229620GNPHA0-RAA229620GNP#HA0,SMLF,IC,ARF0TGP40A   I133 @T6G_MB_LIB.T6G(SCH_1):PAGE185

PWRGD_PVDDIO_P0 @T6G_MB_LIB.T6G(SCH_1):PWRGD_PVDDIO_P0
 R8066    1      A Q_RES_0402LF-33,5%,1/16W,CHIP,CS03302JB10    I53 @T6G_MB_LIB.T6G(SCH_1):PAGE175
  R230    1      A Q_RES_0402LF-0,5%,1/16W,CHIP,CS00002JB13    I67 @T6G_MB_LIB.T6G(SCH_1):PAGE80
 C5005    2      B Q_CAP_0402-1000PF,50V,5%,X7R,TMP_QCH21006JB10   I133 @T6G_MB_LIB.T6G(SCH_1):PAGE175

PWRGD_PVDDIO_P0_R @T6G_MB_LIB.T6G(SCH_1):PWRGD_PVDDIO_P0_R
 R8066    2      B Q_RES_0402LF-33,5%,1/16W,CHIP,CS03302JB10    I53 @T6G_MB_LIB.T6G(SCH_1):PAGE175
 R8065    2      B Q_RES_0402LF-1K,1%,1/16W,CHIP,CS21002FB06    I54 @T6G_MB_LIB.T6G(SCH_1):PAGE175
 C8072    1      A Q_CAP_0402-1000PF,50V,5%,EMPTY,TMP_QCH21006JB10    I55 @T6G_MB_LIB.T6G(SCH_1):PAGE175
  PU12   20    PG1 RAA229620GNPHA0-RAA229620GNP#HA0,SMLF,IC,ARF0TGP40A   I128 @T6G_MB_LIB.T6G(SCH_1):PAGE175

PWRGD_PVDDIO_P1 @T6G_MB_LIB.T6G(SCH_1):PWRGD_PVDDIO_P1
  R283    1      A Q_RES_0402LF-0,5%,1/16W,CHIP,CS00002JB13    I30 @T6G_MB_LIB.T6G(SCH_1):PAGE80
 R8243    1      A Q_RES_0402LF-33,5%,1/16W,CHIP,CS03302JB10    I50 @T6G_MB_LIB.T6G(SCH_1):PAGE192
 C5006    2      B Q_CAP_0402-1000PF,50V,5%,X7R,TMP_QCH21006JB10   I136 @T6G_MB_LIB.T6G(SCH_1):PAGE192

PWRGD_PVDDIO_P1_R @T6G_MB_LIB.T6G(SCH_1):PWRGD_PVDDIO_P1_R
 R8243    2      B Q_RES_0402LF-33,5%,1/16W,CHIP,CS03302JB10    I50 @T6G_MB_LIB.T6G(SCH_1):PAGE192
 R8242    2      B Q_RES_0402LF-1K,1%,1/16W,CHIP,CS21002FB06    I51 @T6G_MB_LIB.T6G(SCH_1):PAGE192
 C8362    1      A Q_CAP_0402-1000PF,50V,5%,EMPTY,TMP_QCH21006JB10    I52 @T6G_MB_LIB.T6G(SCH_1):PAGE192
  PU34   20    PG1 RAA229620GNPHA0-RAA229620GNP#HA0,SMLF,IC,ARF0TGP40A   I128 @T6G_MB_LIB.T6G(SCH_1):PAGE192

RMII_BMC_OCP_RX_ER @T6G_MB_LIB.T6G(SCH_1):RMII_BMC_OCP_RX_ER
   R87    1      A Q_RES_0402LF-1K,1%,1/16W,CHIP,CS21002FB06   I136 @T6G_MB_LIB.T6G(SCH_1):PAGE336
   J41  B23  PETN2 SCONN168_ME1016810202011-SCONN168_ME1016810202011,A   I176 @T6G_MB_LIB.T6G(SCH_1):PAGE348

RMII_BMC_OCP_TXD_0 @T6G_MB_LIB.T6G(SCH_1):RMII_BMC_OCP_TXD_0
 R3214    2      B Q_RES_0402LF-0,5%,1/16W,EMPTY,CS00002JB13    I60 @T6G_MB_LIB.T6G(SCH_1):PAGE307
   R75    2      B Q_RES_0402LF-0,5%,1/16W,CHIP,CS00002JB13   I103 @T6G_MB_LIB.T6G(SCH_1):PAGE336
   R83    1      A Q_RES_0402LF-100K,1%,1/16W,CHIP,CS41002FB09   I135 @T6G_MB_LIB.T6G(SCH_1):PAGE336
   J41  B21  PETP1 SCONN168_ME1016810202011-SCONN168_ME1016810202011,A   I176 @T6G_MB_LIB.T6G(SCH_1):PAGE348

RMII_BMC_OCP_TXD_1 @T6G_MB_LIB.T6G(SCH_1):RMII_BMC_OCP_TXD_1
 R3215    2      B Q_RES_0402LF-0,5%,1/16W,EMPTY,CS00002JB13    I56 @T6G_MB_LIB.T6G(SCH_1):PAGE307
   R76    2      B Q_RES_0402LF-0,5%,1/16W,CHIP,CS00002JB13   I104 @T6G_MB_LIB.T6G(SCH_1):PAGE336
   R84    1      A Q_RES_0402LF-100K,1%,1/16W,CHIP,CS41002FB09   I129 @T6G_MB_LIB.T6G(SCH_1):PAGE336
   J41  B22 GND_B22 SCONN168_ME1016810202011-SCONN168_ME1016810202011,A   I176 @T6G_MB_LIB.T6G(SCH_1):PAGE348

RMII_BMC_OCP_TX_EN @T6G_MB_LIB.T6G(SCH_1):RMII_BMC_OCP_TX_EN
 R3213    2      B Q_RES_0402LF-0,5%,1/16W,EMPTY,CS00002JB13    I61 @T6G_MB_LIB.T6G(SCH_1):PAGE307
   R74    2      B Q_RES_0402LF-0,5%,1/16W,CHIP,CS00002JB13   I102 @T6G_MB_LIB.T6G(SCH_1):PAGE336
   R82    1      A Q_RES_0402LF-100K,1%,1/16W,CHIP,CS41002FB09   I134 @T6G_MB_LIB.T6G(SCH_1):PAGE336
   J41  B20  PETN1 SCONN168_ME1016810202011-SCONN168_ME1016810202011,A   I176 @T6G_MB_LIB.T6G(SCH_1):PAGE348

RMII_OCP_BMC_CRSDV @T6G_MB_LIB.T6G(SCH_1):RMII_OCP_BMC_CRSDV
 R3210    2      B Q_RES_0402LF-22,1%,1/16W,EMPTY,CS02202FB02    I65 @T6G_MB_LIB.T6G(SCH_1):PAGE307
   R59    2      B Q_RES_0402LF-22,1%,1/16W,CHIP,CS02202FB02    I99 @T6G_MB_LIB.T6G(SCH_1):PAGE336
   R77    1      A Q_RES_0402LF-100K,1%,1/16W,CHIP,CS41002FB09   I131 @T6G_MB_LIB.T6G(SCH_1):PAGE336
   J41  B19 GND_B19 SCONN168_ME1016810202011-SCONN168_ME1016810202011,A   I176 @T6G_MB_LIB.T6G(SCH_1):PAGE348

RMII_OCP_BMC_RXD_0 @T6G_MB_LIB.T6G(SCH_1):RMII_OCP_BMC_RXD_0
 R3211    2      B Q_RES_0402LF-22,1%,1/16W,EMPTY,CS02202FB02    I63 @T6G_MB_LIB.T6G(SCH_1):PAGE307
   R72    2      B Q_RES_0402LF-22,1%,1/16W,CHIP,CS02202FB02   I100 @T6G_MB_LIB.T6G(SCH_1):PAGE336
   R79    1      A Q_RES_0402LF-100K,1%,1/16W,CHIP,CS41002FB09   I132 @T6G_MB_LIB.T6G(SCH_1):PAGE336
   J41  B24  PETP2 SCONN168_ME1016810202011-SCONN168_ME1016810202011,A   I176 @T6G_MB_LIB.T6G(SCH_1):PAGE348

RMII_OCP_BMC_RXD_1 @T6G_MB_LIB.T6G(SCH_1):RMII_OCP_BMC_RXD_1
 R3212    2      B Q_RES_0402LF-22,1%,1/16W,EMPTY,CS02202FB02    I62 @T6G_MB_LIB.T6G(SCH_1):PAGE307
   R73    2      B Q_RES_0402LF-22,1%,1/16W,CHIP,CS02202FB02   I101 @T6G_MB_LIB.T6G(SCH_1):PAGE336
   R80    1      A Q_RES_0402LF-100K,1%,1/16W,CHIP,CS41002FB09   I133 @T6G_MB_LIB.T6G(SCH_1):PAGE336
   J41  B25 GND_B25 SCONN168_ME1016810202011-SCONN168_ME1016810202011,A   I176 @T6G_MB_LIB.T6G(SCH_1):PAGE348

ROM_LS_EN @T6G_MB_LIB.T6G(SCH_1):ROM_LS_EN
   U54   12     EN PI4ULS3V304AZMAEX-PI4ULS3V304AZMAEX,SMLF,IC,AL0003A    I67 @T6G_MB_LIB.T6G(SCH_1):PAGE76
 R1567    2      B Q_RES_0402LF-4.7K,5%,1/16W,CHIP,CS24702JB10   I150 @T6G_MB_LIB.T6G(SCH_1):PAGE76
 R1564    2      B Q_RES_0402LF-33,5%,1/16W,CHIP,CS03302JB10   I156 @T6G_MB_LIB.T6G(SCH_1):PAGE80

ROM_SD_LS_OE @T6G_MB_LIB.T6G(SCH_1):ROM_SD_LS_OE
   U53    9     OE SN74AVC4T774PWR-SN74AVC4T774PWR,SMLF,IC,AL04T774K00    I63 @T6G_MB_LIB.T6G(SCH_1):PAGE76
 R1616    2      B Q_RES_0402LF-33,5%,1/16W,CHIP,CS03302JB10   I157 @T6G_MB_LIB.T6G(SCH_1):PAGE80

RST_BMC_FROM_SWB @T6G_MB_LIB.T6G(SCH_1):RST_BMC_FROM_SWB
 R2834    2      B Q_RES_0402LF-4.7K,5%,1/16W,CHIP,CS24702JB10    I18 @T6G_MB_LIB.T6G(SCH_1):PAGE333
   Q69    5     G2 MOSFET_NCH_DUAL-PJT138K,SMLF,IC,BAM138K0003    I88 @T6G_MB_LIB.T6G(SCH_1):PAGE333
   Q69    6     D1 MOSFET_NCH_DUAL-PJT138K,SMLF,IC,BAM138K0003   I117 @T6G_MB_LIB.T6G(SCH_1):PAGE333

RST_BMC_FROM_SWB_ISO_N @T6G_MB_LIB.T6G(SCH_1):RST_BMC_FROM_SWB_ISO_N
   Q69    3     D2 MOSFET_NCH_DUAL-PJT138K,SMLF,IC,BAM138K0003    I88 @T6G_MB_LIB.T6G(SCH_1):PAGE333
 R2919    2      B Q_RES_0402LF-100K,1%,1/16W,CHIP,CS41002FB09    I91 @T6G_MB_LIB.T6G(SCH_1):PAGE333
 C1772    1      A Q_CAP_0402-0.1UF,25V,10%,X7R,CH4104K1B00   I116 @T6G_MB_LIB.T6G(SCH_1):PAGE333
 R2847    2      B Q_RES_0402LF-33.2,1%,1/16W,CHIP,CS03322FB03   I266 @T6G_MB_LIB.T6G(SCH_1):PAGE80

RST_BMC_FROM_SWB_ISO_R_N @T6G_MB_LIB.T6G(SCH_1):RST_BMC_FROM_SWB_ISO_R_N
   U18  U15  PB38D LCMXO3LF9400C5BG484C-LCMXO3LF-9400C-5BG484C,SMLF,IA   I216 @T6G_MB_LIB.T6G(SCH_1):PAGE80
 R2847    1      A Q_RES_0402LF-33.2,1%,1/16W,CHIP,CS03322FB03   I266 @T6G_MB_LIB.T6G(SCH_1):PAGE80

RST_BMC_FROM_SWB_N @T6G_MB_LIB.T6G(SCH_1):RST_BMC_FROM_SWB_N
 R2829    1      A Q_RES_0402LF-100K,1%,1/16W,EMPTY,CS41002FB09    I58 @T6G_MB_LIB.T6G(SCH_1):PAGE333
 R2828    2      B Q_RES_0402LF-100K,1%,1/16W,CHIP,CS41002FB09    I66 @T6G_MB_LIB.T6G(SCH_1):PAGE333
   Q69    2     G1 MOSFET_NCH_DUAL-PJT138K,SMLF,IC,BAM138K0003   I117 @T6G_MB_LIB.T6G(SCH_1):PAGE333
  J105   N8     N8 CONN112_10137002101LF-CONN112_10137002-101LF,THLF,A    I76 @T6G_MB_LIB.T6G(SCH_1):PAGE326

RST_CPU0_KBRST_N @T6G_MB_LIB.T6G(SCH_1):RST_CPU0_KBRST_N
  R463    2      B Q_RES_0402LF-33,5%,1/16W,CHIP,CS03302JB10   I112 @T6G_MB_LIB.T6G(SCH_1):PAGE80
   U18  G17   PR7C LCMXO3LF9400C5BG484C-LCMXO3LF-9400C-5BG484C,SMLF,IA   I217 @T6G_MB_LIB.T6G(SCH_1):PAGE80

RST_CPU0_KBRST_R_N @T6G_MB_LIB.T6G(SCH_1):RST_CPU0_KBRST_R_N
   U25 DJ26 ESPI_RSTIN_L||KBRST_L||AGPIO129 GENOA_SP5-SOCKET6096_13568-001,SMLF,IO,DGA^6000030   I287 @T6G_MB_LIB.T6G(SCH_1):PAGE29
  R463    1      A Q_RES_0402LF-33,5%,1/16W,CHIP,CS03302JB10   I112 @T6G_MB_LIB.T6G(SCH_1):PAGE80
 R1351    1      A Q_RES_0402LF-2.2K,5%,1/16W,CHIP,CS22202JB07    I72 @T6G_MB_LIB.T6G(SCH_1):PAGE82

RST_CPU0_PERST0_N @T6G_MB_LIB.T6G(SCH_1):RST_CPU0_PERST0_N
  R254    1      A Q_RES_0402LF-0,5%,1/16W,CHIP,CS00002JB13   I123 @T6G_MB_LIB.T6G(SCH_1):PAGE80
   R16    1      A Q_RES_0402LF-10K,1%,1/16W,CHIP,CS31002FB08   I124 @T6G_MB_LIB.T6G(SCH_1):PAGE82
   U25  D18 PCIE_RST0_L||AGPIO266 GENOA_SP5-SOCKET6096_13568-001,SMLF,IO,DGA^6000030   I188 @T6G_MB_LIB.T6G(SCH_1):PAGE28

RST_CPU0_PERST0_R_N @T6G_MB_LIB.T6G(SCH_1):RST_CPU0_PERST0_R_N
  R254    2      B Q_RES_0402LF-0,5%,1/16W,CHIP,CS00002JB13   I123 @T6G_MB_LIB.T6G(SCH_1):PAGE80
   U18  F17   PR2C LCMXO3LF9400C5BG484C-LCMXO3LF-9400C-5BG484C,SMLF,IA   I217 @T6G_MB_LIB.T6G(SCH_1):PAGE80

RST_CPU0_PERST1_N @T6G_MB_LIB.T6G(SCH_1):RST_CPU0_PERST1_N
  R255    1      A Q_RES_0402LF-0,5%,1/16W,CHIP,CS00002JB13   I121 @T6G_MB_LIB.T6G(SCH_1):PAGE80
   R17    1      A Q_RES_0402LF-10K,1%,1/16W,CHIP,CS31002FB08   I125 @T6G_MB_LIB.T6G(SCH_1):PAGE82
   U25 DG36 PCIE_RST1_L||AGPIO26 GENOA_SP5-SOCKET6096_13568-001,SMLF,IO,DGA^6000030   I188 @T6G_MB_LIB.T6G(SCH_1):PAGE28

RST_CPU0_PERST1_R_N @T6G_MB_LIB.T6G(SCH_1):RST_CPU0_PERST1_R_N
  R255    2      B Q_RES_0402LF-0,5%,1/16W,CHIP,CS00002JB13   I121 @T6G_MB_LIB.T6G(SCH_1):PAGE80
   U18  D20   PR3D LCMXO3LF9400C5BG484C-LCMXO3LF-9400C-5BG484C,SMLF,IA   I217 @T6G_MB_LIB.T6G(SCH_1):PAGE80

RST_CPU0_RESETL_N @T6G_MB_LIB.T6G(SCH_1):RST_CPU0_RESETL_N
  R241    1      A Q_RES_0402LF-0,5%,1/16W,CHIP,CS00002JB13   I114 @T6G_MB_LIB.T6G(SCH_1):PAGE80
  R530    1      A Q_RES_0402LF-0,5%,1/16W,CHIP,CS00002JB13    I27 @T6G_MB_LIB.T6G(SCH_1):PAGE84
  R442    1      A Q_RES_0402LF-1K,1%,1/16W,CHIP,CS21002FB06    I56 @T6G_MB_LIB.T6G(SCH_1):PAGE28
   U25  B67 RESET_L GENOA_SP5-SOCKET6096_13568-001,SMLF,IO,DGA^6000030   I188 @T6G_MB_LIB.T6G(SCH_1):PAGE28

RST_CPU0_RSMRST_N @T6G_MB_LIB.T6G(SCH_1):RST_CPU0_RSMRST_N
  R217    1      A Q_RES_0402LF-33,5%,1/16W,CHIP,CS03302JB10   I118 @T6G_MB_LIB.T6G(SCH_1):PAGE80
  R582    2      B Q_RES_0402LF-4.7K,5%,1/16W,EMPTY,CS24702JB10    I33 @T6G_MB_LIB.T6G(SCH_1):PAGE28
  R581    1      A Q_RES_0402LF-4.7K,5%,1/16W,EMPTY,CS24702JB10    I34 @T6G_MB_LIB.T6G(SCH_1):PAGE28
   U25 DG10 RSMRST_L GENOA_SP5-SOCKET6096_13568-001,SMLF,IO,DGA^6000030   I188 @T6G_MB_LIB.T6G(SCH_1):PAGE28
 C5023    1      A Q_CAP_0402-1000PF,50V,5%,X7R,TMP_QCH21006JB10   I194 @T6G_MB_LIB.T6G(SCH_1):PAGE28
   Q87    2     G1 MOSFET_NCH_DUAL-PJT138K,SMLF,IC,BAM138K0003    I38 @T6G_MB_LIB.T6G(SCH_1):PAGE254

RST_CPU0_SYS_N @T6G_MB_LIB.T6G(SCH_1):RST_CPU0_SYS_N
  R216    1      A Q_RES_0402LF-33,5%,1/16W,CHIP,CS03302JB10   I117 @T6G_MB_LIB.T6G(SCH_1):PAGE80
    J6    3      3 CONN6_HBC1031L200D8H-CONN6_HBC1031-L200D-8H,THLF,IA    I28 @T6G_MB_LIB.T6G(SCH_1):PAGE28
  R422    2      B Q_RES_0402LF-2.2K,5%,1/16W,CHIP,CS22202JB07    I29 @T6G_MB_LIB.T6G(SCH_1):PAGE28
   U25  DH6 SYS_RESET_L||AGPIO1 GENOA_SP5-SOCKET6096_13568-001,SMLF,IO,DGA^6000030   I188 @T6G_MB_LIB.T6G(SCH_1):PAGE28

RST_CPU1_PERST0_N @T6G_MB_LIB.T6G(SCH_1):RST_CPU1_PERST0_N
   U26  D18 PCIE_RST0_L||AGPIO266 GENOA_SP5-SOCKET6096_13568-001,SMLF,IO,DGA^6000030   I182 @T6G_MB_LIB.T6G(SCH_1):PAGE55
  R197    1      A Q_RES_0402LF-0,5%,1/16W,CHIP,CS00002JB13   I120 @T6G_MB_LIB.T6G(SCH_1):PAGE80
   R18    1      A Q_RES_0402LF-10K,1%,1/16W,CHIP,CS31002FB08   I126 @T6G_MB_LIB.T6G(SCH_1):PAGE82

RST_CPU1_PERST0_R_N @T6G_MB_LIB.T6G(SCH_1):RST_CPU1_PERST0_R_N
  R197    2      B Q_RES_0402LF-0,5%,1/16W,CHIP,CS00002JB13   I120 @T6G_MB_LIB.T6G(SCH_1):PAGE80
   U18  E19   PR4C LCMXO3LF9400C5BG484C-LCMXO3LF-9400C-5BG484C,SMLF,IA   I217 @T6G_MB_LIB.T6G(SCH_1):PAGE80

RST_CPU1_PERST1_N @T6G_MB_LIB.T6G(SCH_1):RST_CPU1_PERST1_N
   U26 DG36 PCIE_RST1_L||AGPIO26 GENOA_SP5-SOCKET6096_13568-001,SMLF,IO,DGA^6000030   I182 @T6G_MB_LIB.T6G(SCH_1):PAGE55
  R198    1      A Q_RES_0402LF-0,5%,1/16W,CHIP,CS00002JB13   I122 @T6G_MB_LIB.T6G(SCH_1):PAGE80
   R19    1      A Q_RES_0402LF-10K,1%,1/16W,CHIP,CS31002FB08   I128 @T6G_MB_LIB.T6G(SCH_1):PAGE82

RST_CPU1_PERST1_R_N @T6G_MB_LIB.T6G(SCH_1):RST_CPU1_PERST1_R_N
  R198    2      B Q_RES_0402LF-0,5%,1/16W,CHIP,CS00002JB13   I122 @T6G_MB_LIB.T6G(SCH_1):PAGE80
   U18  G16   PR2D LCMXO3LF9400C5BG484C-LCMXO3LF-9400C-5BG484C,SMLF,IA   I217 @T6G_MB_LIB.T6G(SCH_1):PAGE80

RST_CPU1_RESETL_N @T6G_MB_LIB.T6G(SCH_1):RST_CPU1_RESETL_N
   U26  B67 RESET_L GENOA_SP5-SOCKET6096_13568-001,SMLF,IO,DGA^6000030   I182 @T6G_MB_LIB.T6G(SCH_1):PAGE55
   R57    1      A Q_RES_0402LF-0,5%,1/16W,CHIP,CS00002JB13   I113 @T6G_MB_LIB.T6G(SCH_1):PAGE80
  R556    2      B Q_RES_0402LF-1K,1%,1/16W,EMPTY,CS21002FB06   I357 @T6G_MB_LIB.T6G(SCH_1):PAGE55
  R530    2      B Q_RES_0402LF-0,5%,1/16W,CHIP,CS00002JB13    I27 @T6G_MB_LIB.T6G(SCH_1):PAGE84

RST_CPU1_RSMRST_N @T6G_MB_LIB.T6G(SCH_1):RST_CPU1_RSMRST_N
   U26 DG10 RSMRST_L GENOA_SP5-SOCKET6096_13568-001,SMLF,IO,DGA^6000030   I182 @T6G_MB_LIB.T6G(SCH_1):PAGE55
  R273    1      A Q_RES_0402LF-33,5%,1/16W,CHIP,CS03302JB10   I119 @T6G_MB_LIB.T6G(SCH_1):PAGE80
  R584    2      B Q_RES_0402LF-4.7K,5%,1/16W,EMPTY,CS24702JB10   I341 @T6G_MB_LIB.T6G(SCH_1):PAGE55
  R583    1      A Q_RES_0402LF-4.7K,5%,1/16W,EMPTY,CS24702JB10   I342 @T6G_MB_LIB.T6G(SCH_1):PAGE55
 C5024    1      A Q_CAP_0402-1000PF,50V,5%,X7R,TMP_QCH21006JB10   I388 @T6G_MB_LIB.T6G(SCH_1):PAGE55

RST_CPU1_SYS_N @T6G_MB_LIB.T6G(SCH_1):RST_CPU1_SYS_N
   U26  DH6 SYS_RESET_L||AGPIO1 GENOA_SP5-SOCKET6096_13568-001,SMLF,IO,DGA^6000030   I182 @T6G_MB_LIB.T6G(SCH_1):PAGE55
  R272    1      A Q_RES_0402LF-0,5%,1/16W,EMPTY,CS00002JB13   I115 @T6G_MB_LIB.T6G(SCH_1):PAGE80
  R559    2      B Q_RES_0402LF-2.2K,5%,1/16W,CHIP,CS22202JB07   I356 @T6G_MB_LIB.T6G(SCH_1):PAGE55

RST_ESPI_CPU0_RSTOUT_N @T6G_MB_LIB.T6G(SCH_1):RST_ESPI_CPU0_RSTOUT_N
  R457    2      B Q_RES_0402LF-4.7K,5%,1/16W,EMPTY,CS24702JB10   I282 @T6G_MB_LIB.T6G(SCH_1):PAGE29
  R474    1      A Q_RES_0402LF-0,5%,1/16W,CHIP,CS00002JB13   I332 @T6G_MB_LIB.T6G(SCH_1):PAGE29
   J41   B4 +12V_EDGE_B4 SCONN168_ME1016810202011-SCONN168_ME1016810202011,A   I176 @T6G_MB_LIB.T6G(SCH_1):PAGE348
 R1558    2      B Q_RES_0402LF-33,5%,1/16W,CHIP,CS03302JB10   I172 @T6G_MB_LIB.T6G(SCH_1):PAGE80

RST_ESPI_CPU0_RSTOUT_R_N @T6G_MB_LIB.T6G(SCH_1):RST_ESPI_CPU0_RSTOUT_R_N
 R1558    1      A Q_RES_0402LF-33,5%,1/16W,CHIP,CS03302JB10   I172 @T6G_MB_LIB.T6G(SCH_1):PAGE80
   U18  T22  PR21A LCMXO3LF9400C5BG484C-LCMXO3LF-9400C-5BG484C,SMLF,IA   I217 @T6G_MB_LIB.T6G(SCH_1):PAGE80

RST_ESPI_CPU0_R_RSTOUT_N @T6G_MB_LIB.T6G(SCH_1):RST_ESPI_CPU0_R_RSTOUT_N
   U25 DE27 ESPI_RSTOUT_L||AGPIO23 GENOA_SP5-SOCKET6096_13568-001,SMLF,IO,DGA^6000030   I287 @T6G_MB_LIB.T6G(SCH_1):PAGE29
  R474    2      B Q_RES_0402LF-0,5%,1/16W,CHIP,CS00002JB13   I332 @T6G_MB_LIB.T6G(SCH_1):PAGE29

RST_HP_OCP_SFF_R_N @T6G_MB_LIB.T6G(SCH_1):RST_HP_OCP_SFF_R_N
 R3232    1      A Q_RES_0402LF-100K,1%,1/16W,CHIP,CS41002FB09   I152 @T6G_MB_LIB.T6G(SCH_1):PAGE336
 R3233    1      A Q_RES_0402LF-0,5%,1/16W,CHIP,CS00002JB13   I153 @T6G_MB_LIB.T6G(SCH_1):PAGE336
  U224    4      Y 74LVC1G126SE7-74LVC1G126SE-7,SMLF,IC,AL1G0126009   I159 @T6G_MB_LIB.T6G(SCH_1):PAGE336

RST_HP_OCP_V3_2_R_N @T6G_MB_LIB.T6G(SCH_1):RST_HP_OCP_V3_2_R_N
 R3235    1      A Q_RES_0402LF-100K,1%,1/16W,CHIP,CS41002FB09    I24 @T6G_MB_LIB.T6G(SCH_1):PAGE342
  U225    4      Y 74LVC1G126SE7-74LVC1G126SE-7,SMLF,IC,AL1G0126009     I9 @T6G_MB_LIB.T6G(SCH_1):PAGE342
 R3236    1      A Q_RES_0402LF-0,5%,1/16W,CHIP,CS00002JB13    I25 @T6G_MB_LIB.T6G(SCH_1):PAGE342

RST_MB_STBY_N @T6G_MB_LIB.T6G(SCH_1):RST_MB_STBY_N
 R6033    1      A Q_RES_0402LF-0,5%,1/16W,CHIP,CS00002JB13    I30 @T6G_MB_LIB.T6G(SCH_1):PAGE348
 R1546    2      B Q_RES_0402LF-1K,1%,1/16W,CHIP,CS21002FB06    I30 @T6G_MB_LIB.T6G(SCH_1):PAGE349
   U18  D13  PT29D LCMXO3LF9400C5BG484C-LCMXO3LF-9400C-5BG484C,SMLF,IA    I94 @T6G_MB_LIB.T6G(SCH_1):PAGE79

RST_MB_STBY_R_N @T6G_MB_LIB.T6G(SCH_1):RST_MB_STBY_R_N
 R6033    2      B Q_RES_0402LF-0,5%,1/16W,CHIP,CS00002JB13    I30 @T6G_MB_LIB.T6G(SCH_1):PAGE348
   J41  A46 GND_A46 SCONN168_ME1016810202011-SCONN168_ME1016810202011,A   I176 @T6G_MB_LIB.T6G(SCH_1):PAGE348

RST_PCIE_E1S_PERST_N @T6G_MB_LIB.T6G(SCH_1):RST_PCIE_E1S_PERST_N
 R3779    2      B Q_RES_0402LF-0,5%,1/16W,CHIP,CS00002JB13    I30 @T6G_MB_LIB.T6G(SCH_1):PAGE297
   J90  B10 PERST0# SCONN56_123276793-SCONN56_1-2327679-3,SMLF,IO,DFHSA    I90 @T6G_MB_LIB.T6G(SCH_1):PAGE297

RST_PERST0_OCP_SFF_N @T6G_MB_LIB.T6G(SCH_1):RST_PERST0_OCP_SFF_N
   J38  B10 PERST0# SCONN168_ME1016810202011-SCONN168_ME1016810202011,A   I168 @T6G_MB_LIB.T6G(SCH_1):PAGE335
  R877    2      B Q_RES_0402LF-0,5%,1/16W,CHIP,CS00002JB13    I79 @T6G_MB_LIB.T6G(SCH_1):PAGE337

RST_PERST0_OCP_V3_2_N @T6G_MB_LIB.T6G(SCH_1):RST_PERST0_OCP_V3_2_N
   J35  B10 PERST0# SCONN168_ME1016810202011-SCONN168_ME1016810202011,A   I168 @T6G_MB_LIB.T6G(SCH_1):PAGE341
 R6056    2      B Q_RES_0402LF-0,5%,1/16W,CHIP,CS00002JB13    I72 @T6G_MB_LIB.T6G(SCH_1):PAGE342

RST_PERST1_OCP_SFF_N @T6G_MB_LIB.T6G(SCH_1):RST_PERST1_OCP_SFF_N
   J38  A11 PERST1# SCONN168_ME1016810202011-SCONN168_ME1016810202011,A   I168 @T6G_MB_LIB.T6G(SCH_1):PAGE335
  R899    2      B Q_RES_0402LF-0,5%,1/16W,CHIP,CS00002JB13    I78 @T6G_MB_LIB.T6G(SCH_1):PAGE337

RST_PERST1_OCP_V3_2_N @T6G_MB_LIB.T6G(SCH_1):RST_PERST1_OCP_V3_2_N
   J35  A11 PERST1# SCONN168_ME1016810202011-SCONN168_ME1016810202011,A   I168 @T6G_MB_LIB.T6G(SCH_1):PAGE341
 R6057    2      B Q_RES_0402LF-0,5%,1/16W,CHIP,CS00002JB13    I73 @T6G_MB_LIB.T6G(SCH_1):PAGE342

RST_PERST2_OCP_SFF_N @T6G_MB_LIB.T6G(SCH_1):RST_PERST2_OCP_SFF_N
   J38  OA1 PERST2# SCONN168_ME1016810202011-SCONN168_ME1016810202011,A   I168 @T6G_MB_LIB.T6G(SCH_1):PAGE335
  R905    2      B Q_RES_0402LF-0,5%,1/16W,CHIP,CS00002JB13    I80 @T6G_MB_LIB.T6G(SCH_1):PAGE337

RST_PERST2_OCP_V3_2_N @T6G_MB_LIB.T6G(SCH_1):RST_PERST2_OCP_V3_2_N
   J35  OA1 PERST2# SCONN168_ME1016810202011-SCONN168_ME1016810202011,A   I168 @T6G_MB_LIB.T6G(SCH_1):PAGE341
 R6058    2      B Q_RES_0402LF-0,5%,1/16W,CHIP,CS00002JB13    I74 @T6G_MB_LIB.T6G(SCH_1):PAGE342

RST_PERST3_OCP_SFF_N @T6G_MB_LIB.T6G(SCH_1):RST_PERST3_OCP_SFF_N
   J38  OA2 PERST3# SCONN168_ME1016810202011-SCONN168_ME1016810202011,A   I168 @T6G_MB_LIB.T6G(SCH_1):PAGE335
  R956    2      B Q_RES_0402LF-0,5%,1/16W,CHIP,CS00002JB13    I81 @T6G_MB_LIB.T6G(SCH_1):PAGE337

RST_PERST3_OCP_V3_2_N @T6G_MB_LIB.T6G(SCH_1):RST_PERST3_OCP_V3_2_N
   J35  OA2 PERST3# SCONN168_ME1016810202011-SCONN168_ME1016810202011,A   I168 @T6G_MB_LIB.T6G(SCH_1):PAGE341
 R6059    2      B Q_RES_0402LF-0,5%,1/16W,CHIP,CS00002JB13    I75 @T6G_MB_LIB.T6G(SCH_1):PAGE342

RST_PERST_0_SWB_BUF_N @T6G_MB_LIB.T6G(SCH_1):RST_PERST_0_SWB_BUF_N
 R3469    2      B Q_RES_0402LF-49.9,1%,1/16W,CHIP,CS04992FB07   I180 @T6G_MB_LIB.T6G(SCH_1):PAGE334
  J112   T8     T8 CONN160_10131762101LF-CONN160_10131762-101LF,THLF,A     I7 @T6G_MB_LIB.T6G(SCH_1):PAGE329

RST_PERST_0_SWB_BUF_R_N @T6G_MB_LIB.T6G(SCH_1):RST_PERST_0_SWB_BUF_R_N
  U252    6     B0 74LVC2G17GW-74LVC2G17GW,SMLF,IC,AL2G0017005   I153 @T6G_MB_LIB.T6G(SCH_1):PAGE334
 R3469    1      A Q_RES_0402LF-49.9,1%,1/16W,CHIP,CS04992FB07   I180 @T6G_MB_LIB.T6G(SCH_1):PAGE334
 R3467    1      A Q_RES_0402LF-10K,1%,1/16W,CHIP,CS31002FB08   I181 @T6G_MB_LIB.T6G(SCH_1):PAGE334

RST_PERST_1_SWB_BUF_N @T6G_MB_LIB.T6G(SCH_1):RST_PERST_1_SWB_BUF_N
 R3468    2      B Q_RES_0402LF-49.9,1%,1/16W,CHIP,CS04992FB07   I183 @T6G_MB_LIB.T6G(SCH_1):PAGE334
  J112   A5     A5 CONN160_10131762101LF-CONN160_10131762-101LF,THLF,A     I7 @T6G_MB_LIB.T6G(SCH_1):PAGE329

RST_PERST_1_SWB_BUF_R_N @T6G_MB_LIB.T6G(SCH_1):RST_PERST_1_SWB_BUF_R_N
  U256    6     B0 74LVC2G17GW-74LVC2G17GW,SMLF,IC,AL2G0017005   I173 @T6G_MB_LIB.T6G(SCH_1):PAGE334
 R3468    1      A Q_RES_0402LF-49.9,1%,1/16W,CHIP,CS04992FB07   I183 @T6G_MB_LIB.T6G(SCH_1):PAGE334
 R3466    1      A Q_RES_0402LF-10K,1%,1/16W,CHIP,CS31002FB08   I184 @T6G_MB_LIB.T6G(SCH_1):PAGE334

RST_PERST_2_SWB_BUF_N @T6G_MB_LIB.T6G(SCH_1):RST_PERST_2_SWB_BUF_N
 R3391    2      B Q_RES_0402LF-49.9,1%,1/16W,CHIP,CS04992FB07   I140 @T6G_MB_LIB.T6G(SCH_1):PAGE334
  J112   A1     A1 CONN160_10131762101LF-CONN160_10131762-101LF,THLF,A   I102 @T6G_MB_LIB.T6G(SCH_1):PAGE329

RST_PERST_2_SWB_BUF_R_N @T6G_MB_LIB.T6G(SCH_1):RST_PERST_2_SWB_BUF_R_N
 R3455    1      A Q_RES_0402LF-10K,1%,1/16W,CHIP,CS31002FB08   I139 @T6G_MB_LIB.T6G(SCH_1):PAGE334
 R3391    1      A Q_RES_0402LF-49.9,1%,1/16W,CHIP,CS04992FB07   I140 @T6G_MB_LIB.T6G(SCH_1):PAGE334
  U252    4     B1 74LVC2G17GW-74LVC2G17GW,SMLF,IC,AL2G0017005   I153 @T6G_MB_LIB.T6G(SCH_1):PAGE334

RST_PERST_BUF_M2_0_N @T6G_MB_LIB.T6G(SCH_1):RST_PERST_BUF_M2_0_N
  U259    4     2Y SN74LVC2G07DCKR_SMLF-SN74LVC2G07DCKR,IC,AL002G07006     I5 @T6G_MB_LIB.T6G(SCH_1):PAGE345
 R2121    2      B Q_RES_0402LF-4.7K,5%,1/16W,CHIP,CS24702JB10    I10 @T6G_MB_LIB.T6G(SCH_1):PAGE345
 R2113    1      A Q_RES_0402LF-0,5%,1/16W,CHIP,CS00002JB13    I12 @T6G_MB_LIB.T6G(SCH_1):PAGE345

RST_PERST_BUF_M2_0_R_N @T6G_MB_LIB.T6G(SCH_1):RST_PERST_BUF_M2_0_R_N
   J59   50 PERST# SCONN75K_APCI0155P004A-SCONN75K_APCI0155-P004A,SMLA    I88 @T6G_MB_LIB.T6G(SCH_1):PAGE345
 R2113    2      B Q_RES_0402LF-0,5%,1/16W,CHIP,CS00002JB13    I12 @T6G_MB_LIB.T6G(SCH_1):PAGE345

RST_PERST_CPU0_SWB_N @T6G_MB_LIB.T6G(SCH_1):RST_PERST_CPU0_SWB_N
   U18  T14  PB32B LCMXO3LF9400C5BG484C-LCMXO3LF-9400C-5BG484C,SMLF,IA   I216 @T6G_MB_LIB.T6G(SCH_1):PAGE80
 R6114    1      A Q_RES_0402LF-2K,1%,1/16W,CHIP,CS22002FB07   I137 @T6G_MB_LIB.T6G(SCH_1):PAGE82
 R6112    1      A Q_RES_0402LF-33.2,1%,1/16W,CHIP,CS03322FB03    I91 @T6G_MB_LIB.T6G(SCH_1):PAGE84

RST_PERST_CPU0_SWB_R_N @T6G_MB_LIB.T6G(SCH_1):RST_PERST_CPU0_SWB_R_N
  U256    1     A0 74LVC2G17GW-74LVC2G17GW,SMLF,IC,AL2G0017005   I173 @T6G_MB_LIB.T6G(SCH_1):PAGE334
 R6112    2      B Q_RES_0402LF-33.2,1%,1/16W,CHIP,CS03322FB03    I91 @T6G_MB_LIB.T6G(SCH_1):PAGE84

RST_PERST_CPU1_SWB_1_N @T6G_MB_LIB.T6G(SCH_1):RST_PERST_CPU1_SWB_1_N
   U18  V11  PB24C LCMXO3LF9400C5BG484C-LCMXO3LF-9400C-5BG484C,SMLF,IA   I216 @T6G_MB_LIB.T6G(SCH_1):PAGE80
    R2    1      A Q_RES_0402LF-33.2,1%,1/16W,CHIP,CS03322FB03    I94 @T6G_MB_LIB.T6G(SCH_1):PAGE84
    R3    1      A Q_RES_0402LF-2K,1%,1/16W,CHIP,CS22002FB07   I154 @T6G_MB_LIB.T6G(SCH_1):PAGE82

RST_PERST_CPU1_SWB_1_R_N @T6G_MB_LIB.T6G(SCH_1):RST_PERST_CPU1_SWB_1_R_N
  U252    3     A1 74LVC2G17GW-74LVC2G17GW,SMLF,IC,AL2G0017005   I153 @T6G_MB_LIB.T6G(SCH_1):PAGE334
    R2    2      B Q_RES_0402LF-33.2,1%,1/16W,CHIP,CS03322FB03    I94 @T6G_MB_LIB.T6G(SCH_1):PAGE84

RST_PERST_CPU1_SWB_N @T6G_MB_LIB.T6G(SCH_1):RST_PERST_CPU1_SWB_N
   U18  U14  PB32C LCMXO3LF9400C5BG484C-LCMXO3LF-9400C-5BG484C,SMLF,IA   I216 @T6G_MB_LIB.T6G(SCH_1):PAGE80
 R6113    1      A Q_RES_0402LF-33.2,1%,1/16W,CHIP,CS03322FB03    I75 @T6G_MB_LIB.T6G(SCH_1):PAGE84
 R6115    1      A Q_RES_0402LF-2K,1%,1/16W,CHIP,CS22002FB07   I141 @T6G_MB_LIB.T6G(SCH_1):PAGE82

RST_PERST_CPU1_SWB_R_N @T6G_MB_LIB.T6G(SCH_1):RST_PERST_CPU1_SWB_R_N
  U252    1     A0 74LVC2G17GW-74LVC2G17GW,SMLF,IC,AL2G0017005   I153 @T6G_MB_LIB.T6G(SCH_1):PAGE334
 R6113    2      B Q_RES_0402LF-33.2,1%,1/16W,CHIP,CS03322FB03    I75 @T6G_MB_LIB.T6G(SCH_1):PAGE84

RST_PERST_E1S_0_N @T6G_MB_LIB.T6G(SCH_1):RST_PERST_E1S_0_N
 R3779    1      A Q_RES_0402LF-0,5%,1/16W,CHIP,CS00002JB13    I30 @T6G_MB_LIB.T6G(SCH_1):PAGE297
  R685    2      B Q_RES_0402LF-33,5%,1/16W,CHIP,CS03302JB10   I131 @T6G_MB_LIB.T6G(SCH_1):PAGE80
  R800    1      A Q_RES_0402LF-10K,1%,1/16W,CHIP,CS31002FB08   I118 @T6G_MB_LIB.T6G(SCH_1):PAGE82

RST_PERST_E1S_0_R_N @T6G_MB_LIB.T6G(SCH_1):RST_PERST_E1S_0_R_N
  R685    1      A Q_RES_0402LF-33,5%,1/16W,CHIP,CS03302JB10   I131 @T6G_MB_LIB.T6G(SCH_1):PAGE80
   U18 AA13  PB30B LCMXO3LF9400C5BG484C-LCMXO3LF-9400C-5BG484C,SMLF,IA   I216 @T6G_MB_LIB.T6G(SCH_1):PAGE80

RST_PERST_M2_0_N @T6G_MB_LIB.T6G(SCH_1):RST_PERST_M2_0_N
  R798    2      B Q_RES_0402LF-33,5%,1/16W,CHIP,CS03302JB10   I125 @T6G_MB_LIB.T6G(SCH_1):PAGE80
  U259    3     2A SN74LVC2G07DCKR_SMLF-SN74LVC2G07DCKR,IC,AL002G07006     I5 @T6G_MB_LIB.T6G(SCH_1):PAGE345
  R804    1      A Q_RES_0402LF-10K,1%,1/16W,CHIP,CS31002FB08   I120 @T6G_MB_LIB.T6G(SCH_1):PAGE82

RST_PERST_M2_0_R_N @T6G_MB_LIB.T6G(SCH_1):RST_PERST_M2_0_R_N
  R798    1      A Q_RES_0402LF-33,5%,1/16W,CHIP,CS03302JB10   I125 @T6G_MB_LIB.T6G(SCH_1):PAGE80
   U18  V16  PB40D LCMXO3LF9400C5BG484C-LCMXO3LF-9400C-5BG484C,SMLF,IA   I216 @T6G_MB_LIB.T6G(SCH_1):PAGE80

RST_PERST_OCP_SFF_BUF2_N @T6G_MB_LIB.T6G(SCH_1):RST_PERST_OCP_SFF_BUF2_N
   U75    4      Y 74LVC1G17GW-74LVC1G17GW,SMLF,IC,AL1G0017K01    I64 @T6G_MB_LIB.T6G(SCH_1):PAGE337
  R899    1      A Q_RES_0402LF-0,5%,1/16W,CHIP,CS00002JB13    I78 @T6G_MB_LIB.T6G(SCH_1):PAGE337
  R877    1      A Q_RES_0402LF-0,5%,1/16W,CHIP,CS00002JB13    I79 @T6G_MB_LIB.T6G(SCH_1):PAGE337
  R905    1      A Q_RES_0402LF-0,5%,1/16W,CHIP,CS00002JB13    I80 @T6G_MB_LIB.T6G(SCH_1):PAGE337
  R956    1      A Q_RES_0402LF-0,5%,1/16W,CHIP,CS00002JB13    I81 @T6G_MB_LIB.T6G(SCH_1):PAGE337

RST_PERST_OCP_SFF_BUF_N @T6G_MB_LIB.T6G(SCH_1):RST_PERST_OCP_SFF_BUF_N
   U75    2      A 74LVC1G17GW-74LVC1G17GW,SMLF,IC,AL1G0017K01    I64 @T6G_MB_LIB.T6G(SCH_1):PAGE337
 R9033    2      B Q_RES_0402LF-33.2,1%,1/16W,CHIP,CS03322FB03    I29 @T6G_MB_LIB.T6G(SCH_1):PAGE340

RST_PERST_OCP_SFF_BUF_R_N @T6G_MB_LIB.T6G(SCH_1):RST_PERST_OCP_SFF_BUF_R_N
 U9001    4      Y 74LVC1G08W57-74LVC1G08W5-7,SMLF,IC,AL1G0008020    I25 @T6G_MB_LIB.T6G(SCH_1):PAGE340
 R9033    1      A Q_RES_0402LF-33.2,1%,1/16W,CHIP,CS03322FB03    I29 @T6G_MB_LIB.T6G(SCH_1):PAGE340

RST_PERST_OCP_SFF_N @T6G_MB_LIB.T6G(SCH_1):RST_PERST_OCP_SFF_N
   U18  W17  PB41D LCMXO3LF9400C5BG484C-LCMXO3LF-9400C-5BG484C,SMLF,IA   I216 @T6G_MB_LIB.T6G(SCH_1):PAGE80
 R9023    1      A Q_RES_0402LF-33.2,1%,1/16W,CHIP,CS03322FB03    I14 @T6G_MB_LIB.T6G(SCH_1):PAGE340

RST_PERST_OCP_SFF_R_N @T6G_MB_LIB.T6G(SCH_1):RST_PERST_OCP_SFF_R_N
 R9023    2      B Q_RES_0402LF-33.2,1%,1/16W,CHIP,CS03322FB03    I14 @T6G_MB_LIB.T6G(SCH_1):PAGE340
 U9001    1      A 74LVC1G08W57-74LVC1G08W5-7,SMLF,IC,AL1G0008020    I25 @T6G_MB_LIB.T6G(SCH_1):PAGE340

RST_PERST_OCP_V3_2_BUF2_N @T6G_MB_LIB.T6G(SCH_1):RST_PERST_OCP_V3_2_BUF2_N
  U207    4      Y 74LVC1G17GW-74LVC1G17GW,SMLF,IC,AL1G0017K01    I58 @T6G_MB_LIB.T6G(SCH_1):PAGE342
 R6056    1      A Q_RES_0402LF-0,5%,1/16W,CHIP,CS00002JB13    I72 @T6G_MB_LIB.T6G(SCH_1):PAGE342
 R6057    1      A Q_RES_0402LF-0,5%,1/16W,CHIP,CS00002JB13    I73 @T6G_MB_LIB.T6G(SCH_1):PAGE342
 R6058    1      A Q_RES_0402LF-0,5%,1/16W,CHIP,CS00002JB13    I74 @T6G_MB_LIB.T6G(SCH_1):PAGE342
 R6059    1      A Q_RES_0402LF-0,5%,1/16W,CHIP,CS00002JB13    I75 @T6G_MB_LIB.T6G(SCH_1):PAGE342

RST_PERST_OCP_V3_2_BUF_N @T6G_MB_LIB.T6G(SCH_1):RST_PERST_OCP_V3_2_BUF_N
  U207    2      A 74LVC1G17GW-74LVC1G17GW,SMLF,IC,AL1G0017K01    I58 @T6G_MB_LIB.T6G(SCH_1):PAGE342
 R1177    2      B Q_RES_0402LF-33.2,1%,1/16W,CHIP,CS03322FB03    I49 @T6G_MB_LIB.T6G(SCH_1):PAGE257

RST_PERST_OCP_V3_2_BUF_R_N @T6G_MB_LIB.T6G(SCH_1):RST_PERST_OCP_V3_2_BUF_R_N
 R1177    1      A Q_RES_0402LF-33.2,1%,1/16W,CHIP,CS03322FB03    I49 @T6G_MB_LIB.T6G(SCH_1):PAGE257
   U35    4      Y 74LVC1G08W57-74LVC1G08W5-7,SMLF,IC,AL1G0008020    I63 @T6G_MB_LIB.T6G(SCH_1):PAGE257

RST_PERST_OCP_V3_2_N @T6G_MB_LIB.T6G(SCH_1):RST_PERST_OCP_V3_2_N
   U18 AA19  PB43B LCMXO3LF9400C5BG484C-LCMXO3LF-9400C-5BG484C,SMLF,IA   I216 @T6G_MB_LIB.T6G(SCH_1):PAGE80
 R1174    1      A Q_RES_0402LF-33.2,1%,1/16W,CHIP,CS03322FB03    I17 @T6G_MB_LIB.T6G(SCH_1):PAGE257

RST_PERST_OCP_V3_2_R_N @T6G_MB_LIB.T6G(SCH_1):RST_PERST_OCP_V3_2_R_N
 R1174    2      B Q_RES_0402LF-33.2,1%,1/16W,CHIP,CS03322FB03    I17 @T6G_MB_LIB.T6G(SCH_1):PAGE257
   U35    1      A 74LVC1G08W57-74LVC1G08W5-7,SMLF,IC,AL1G0008020    I63 @T6G_MB_LIB.T6G(SCH_1):PAGE257

RST_RT_CPU0_P0_PERST_N @T6G_MB_LIB.T6G(SCH_1):RST_RT_CPU0_P0_PERST_N
 U6010   F2 PERST_N PT5161LRS-PT5161LRS,SMLF,IC,AJ051610U03    I53 @T6G_MB_LIB.T6G(SCH_1):PAGE385
  R953    1      A Q_RES_0201LF-0,5%,1/20W,CHIP,CS00001JE10    I76 @T6G_MB_LIB.T6G(SCH_1):PAGE385

RST_RT_CPU0_P0_PERST_R2_N @T6G_MB_LIB.T6G(SCH_1):RST_RT_CPU0_P0_PERST_R2_N
   U18  K22  PR16A LCMXO3LF9400C5BG484C-LCMXO3LF-9400C-5BG484C,SMLF,IA   I217 @T6G_MB_LIB.T6G(SCH_1):PAGE80
 R6804    2      B Q_RES_0402LF-0,5%,1/16W,CHIP,CS00002JB13   I342 @T6G_MB_LIB.T6G(SCH_1):PAGE80

RST_RT_CPU0_P0_PERST_R_N @T6G_MB_LIB.T6G(SCH_1):RST_RT_CPU0_P0_PERST_R_N
  R953    2      B Q_RES_0201LF-0,5%,1/20W,CHIP,CS00001JE10    I76 @T6G_MB_LIB.T6G(SCH_1):PAGE385
  R970    1      A Q_RES_0201LF-10K,1%,1/20W,CHIP,CS31001FE17    I97 @T6G_MB_LIB.T6G(SCH_1):PAGE385
 R6804    1      A Q_RES_0402LF-0,5%,1/16W,CHIP,CS00002JB13   I342 @T6G_MB_LIB.T6G(SCH_1):PAGE80

RST_RT_CPU0_P0_RESET_N @T6G_MB_LIB.T6G(SCH_1):RST_RT_CPU0_P0_RESET_N
 U6010 FF11 RESET_N PT5161LRS-PT5161LRS,SMLF,IC,AJ051610U03    I53 @T6G_MB_LIB.T6G(SCH_1):PAGE385
  R963    1      A Q_RES_0201LF-0,5%,1/20W,CHIP,CS00001JE10    I77 @T6G_MB_LIB.T6G(SCH_1):PAGE385

RST_RT_CPU0_P0_RESET_R2_N @T6G_MB_LIB.T6G(SCH_1):RST_RT_CPU0_P0_RESET_R2_N
   U18  L21  PR16B LCMXO3LF9400C5BG484C-LCMXO3LF-9400C-5BG484C,SMLF,IA   I217 @T6G_MB_LIB.T6G(SCH_1):PAGE80
 R6805    2      B Q_RES_0402LF-0,5%,1/16W,CHIP,CS00002JB13   I343 @T6G_MB_LIB.T6G(SCH_1):PAGE80

RST_RT_CPU0_P0_RESET_R_N @T6G_MB_LIB.T6G(SCH_1):RST_RT_CPU0_P0_RESET_R_N
  R963    2      B Q_RES_0201LF-0,5%,1/20W,CHIP,CS00001JE10    I77 @T6G_MB_LIB.T6G(SCH_1):PAGE385
  R971    1      A Q_RES_0201LF-10K,1%,1/20W,CHIP,CS31001FE17    I96 @T6G_MB_LIB.T6G(SCH_1):PAGE385
  R974    2      B Q_RES_0201LF-4.7K,5%,1/20W,EMPTY,CS24701JE04    I98 @T6G_MB_LIB.T6G(SCH_1):PAGE385
 R6805    1      A Q_RES_0402LF-0,5%,1/16W,CHIP,CS00002JB13   I343 @T6G_MB_LIB.T6G(SCH_1):PAGE80

RST_RT_CPU0_P1_PERST_N @T6G_MB_LIB.T6G(SCH_1):RST_RT_CPU0_P1_PERST_N
 R1004    1      A Q_RES_0201LF-0,5%,1/20W,CHIP,CS00001JE10    I56 @T6G_MB_LIB.T6G(SCH_1):PAGE408
 U6011   F2 PERST_N PT5161LRS-PT5161LRS,SMLF,IC,AJ051610U03    I83 @T6G_MB_LIB.T6G(SCH_1):PAGE408

RST_RT_CPU0_P1_PERST_R2_N @T6G_MB_LIB.T6G(SCH_1):RST_RT_CPU0_P1_PERST_R2_N
   U18  L22  PR16C LCMXO3LF9400C5BG484C-LCMXO3LF-9400C-5BG484C,SMLF,IA   I217 @T6G_MB_LIB.T6G(SCH_1):PAGE80
 R6806    2      B Q_RES_0402LF-0,5%,1/16W,CHIP,CS00002JB13   I344 @T6G_MB_LIB.T6G(SCH_1):PAGE80

RST_RT_CPU0_P1_PERST_R_N @T6G_MB_LIB.T6G(SCH_1):RST_RT_CPU0_P1_PERST_R_N
 R6806    1      A Q_RES_0402LF-0,5%,1/16W,CHIP,CS00002JB13   I344 @T6G_MB_LIB.T6G(SCH_1):PAGE80
 R1004    2      B Q_RES_0201LF-0,5%,1/20W,CHIP,CS00001JE10    I56 @T6G_MB_LIB.T6G(SCH_1):PAGE408
 R1019    1      A Q_RES_0201LF-10K,1%,1/20W,CHIP,CS31001FE17    I73 @T6G_MB_LIB.T6G(SCH_1):PAGE408

RST_RT_CPU0_P1_RESET_N @T6G_MB_LIB.T6G(SCH_1):RST_RT_CPU0_P1_RESET_N
 R1012    1      A Q_RES_0201LF-0,5%,1/20W,CHIP,CS00001JE10    I55 @T6G_MB_LIB.T6G(SCH_1):PAGE408
 U6011 FF11 RESET_N PT5161LRS-PT5161LRS,SMLF,IC,AJ051610U03    I83 @T6G_MB_LIB.T6G(SCH_1):PAGE408

RST_RT_CPU0_P1_RESET_R2_N @T6G_MB_LIB.T6G(SCH_1):RST_RT_CPU0_P1_RESET_R2_N
   U18  M17  PR16D LCMXO3LF9400C5BG484C-LCMXO3LF-9400C-5BG484C,SMLF,IA   I217 @T6G_MB_LIB.T6G(SCH_1):PAGE80
 R6807    2      B Q_RES_0402LF-0,5%,1/16W,CHIP,CS00002JB13   I345 @T6G_MB_LIB.T6G(SCH_1):PAGE80

RST_RT_CPU0_P1_RESET_R_N @T6G_MB_LIB.T6G(SCH_1):RST_RT_CPU0_P1_RESET_R_N
 R6807    1      A Q_RES_0402LF-0,5%,1/16W,CHIP,CS00002JB13   I345 @T6G_MB_LIB.T6G(SCH_1):PAGE80
 R1012    2      B Q_RES_0201LF-0,5%,1/20W,CHIP,CS00001JE10    I55 @T6G_MB_LIB.T6G(SCH_1):PAGE408
 R1020    1      A Q_RES_0201LF-10K,1%,1/20W,CHIP,CS31001FE17    I74 @T6G_MB_LIB.T6G(SCH_1):PAGE408
 R1023    2      B Q_RES_0201LF-4.7K,5%,1/20W,EMPTY,CS24701JE04    I78 @T6G_MB_LIB.T6G(SCH_1):PAGE408

RST_RT_CPU0_P2_PERST_N @T6G_MB_LIB.T6G(SCH_1):RST_RT_CPU0_P2_PERST_N
 R1047    1      A Q_RES_0201LF-0,5%,1/20W,CHIP,CS00001JE10    I56 @T6G_MB_LIB.T6G(SCH_1):PAGE419
 U6012   F2 PERST_N PT5161LRS-PT5161LRS,SMLF,IC,AJ051610U03    I83 @T6G_MB_LIB.T6G(SCH_1):PAGE419

RST_RT_CPU0_P2_PERST_R2_N @T6G_MB_LIB.T6G(SCH_1):RST_RT_CPU0_P2_PERST_R2_N
   U18  N18  PR18D LCMXO3LF9400C5BG484C-LCMXO3LF-9400C-5BG484C,SMLF,IA   I217 @T6G_MB_LIB.T6G(SCH_1):PAGE80
 R6823    1      A Q_RES_0402LF-0,5%,1/16W,CHIP,CS00002JB13   I350 @T6G_MB_LIB.T6G(SCH_1):PAGE80

RST_RT_CPU0_P2_PERST_R_N @T6G_MB_LIB.T6G(SCH_1):RST_RT_CPU0_P2_PERST_R_N
 R1047    2      B Q_RES_0201LF-0,5%,1/20W,CHIP,CS00001JE10    I56 @T6G_MB_LIB.T6G(SCH_1):PAGE419
 R1061    1      A Q_RES_0201LF-10K,1%,1/20W,CHIP,CS31001FE17    I77 @T6G_MB_LIB.T6G(SCH_1):PAGE419
 R6823    2      B Q_RES_0402LF-0,5%,1/16W,CHIP,CS00002JB13   I350 @T6G_MB_LIB.T6G(SCH_1):PAGE80

RST_RT_CPU0_P2_RESET_N @T6G_MB_LIB.T6G(SCH_1):RST_RT_CPU0_P2_RESET_N
 R1054    1      A Q_RES_0201LF-0,5%,1/20W,CHIP,CS00001JE10    I55 @T6G_MB_LIB.T6G(SCH_1):PAGE419
 U6012 FF11 RESET_N PT5161LRS-PT5161LRS,SMLF,IC,AJ051610U03    I83 @T6G_MB_LIB.T6G(SCH_1):PAGE419

RST_RT_CPU0_P2_RESET_R2_N @T6G_MB_LIB.T6G(SCH_1):RST_RT_CPU0_P2_RESET_R2_N
   U18  R20  PR25C LCMXO3LF9400C5BG484C-LCMXO3LF-9400C-5BG484C,SMLF,IA   I217 @T6G_MB_LIB.T6G(SCH_1):PAGE80
 R6824    1      A Q_RES_0402LF-0,5%,1/16W,CHIP,CS00002JB13   I351 @T6G_MB_LIB.T6G(SCH_1):PAGE80

RST_RT_CPU0_P2_RESET_R_N @T6G_MB_LIB.T6G(SCH_1):RST_RT_CPU0_P2_RESET_R_N
 R1054    2      B Q_RES_0201LF-0,5%,1/20W,CHIP,CS00001JE10    I55 @T6G_MB_LIB.T6G(SCH_1):PAGE419
 R1062    1      A Q_RES_0201LF-10K,1%,1/20W,CHIP,CS31001FE17    I76 @T6G_MB_LIB.T6G(SCH_1):PAGE419
 R1065    2      B Q_RES_0201LF-4.7K,5%,1/20W,EMPTY,CS24701JE04    I78 @T6G_MB_LIB.T6G(SCH_1):PAGE419
 R6824    2      B Q_RES_0402LF-0,5%,1/16W,CHIP,CS00002JB13   I351 @T6G_MB_LIB.T6G(SCH_1):PAGE80

RST_RT_CPU0_P3_PERST_N @T6G_MB_LIB.T6G(SCH_1):RST_RT_CPU0_P3_PERST_N
 R1088    1      A Q_RES_0201LF-0,5%,1/20W,CHIP,CS00001JE10    I56 @T6G_MB_LIB.T6G(SCH_1):PAGE430
 U6013   F2 PERST_N PT5161LRS-PT5161LRS,SMLF,IC,AJ051610U03    I83 @T6G_MB_LIB.T6G(SCH_1):PAGE430

RST_RT_CPU0_P3_PERST_R2_N @T6G_MB_LIB.T6G(SCH_1):RST_RT_CPU0_P3_PERST_R2_N
   U18  T19  PR27A LCMXO3LF9400C5BG484C-LCMXO3LF-9400C-5BG484C,SMLF,IA   I217 @T6G_MB_LIB.T6G(SCH_1):PAGE80
 R6825    1      A Q_RES_0402LF-0,5%,1/16W,CHIP,CS00002JB13   I352 @T6G_MB_LIB.T6G(SCH_1):PAGE80

RST_RT_CPU0_P3_PERST_R_N @T6G_MB_LIB.T6G(SCH_1):RST_RT_CPU0_P3_PERST_R_N
 R6825    2      B Q_RES_0402LF-0,5%,1/16W,CHIP,CS00002JB13   I352 @T6G_MB_LIB.T6G(SCH_1):PAGE80
 R1088    2      B Q_RES_0201LF-0,5%,1/20W,CHIP,CS00001JE10    I56 @T6G_MB_LIB.T6G(SCH_1):PAGE430
 R1103    1      A Q_RES_0201LF-10K,1%,1/20W,CHIP,CS31001FE17    I74 @T6G_MB_LIB.T6G(SCH_1):PAGE430

RST_RT_CPU0_P3_RESET_N @T6G_MB_LIB.T6G(SCH_1):RST_RT_CPU0_P3_RESET_N
 R1096    1      A Q_RES_0201LF-0,5%,1/20W,CHIP,CS00001JE10    I55 @T6G_MB_LIB.T6G(SCH_1):PAGE430
 U6013 FF11 RESET_N PT5161LRS-PT5161LRS,SMLF,IC,AJ051610U03    I83 @T6G_MB_LIB.T6G(SCH_1):PAGE430

RST_RT_CPU0_P3_RESET_R2_N @T6G_MB_LIB.T6G(SCH_1):RST_RT_CPU0_P3_RESET_R2_N
   U18  T17  PR27C LCMXO3LF9400C5BG484C-LCMXO3LF-9400C-5BG484C,SMLF,IA   I217 @T6G_MB_LIB.T6G(SCH_1):PAGE80
 R6826    1      A Q_RES_0402LF-0,5%,1/16W,CHIP,CS00002JB13   I353 @T6G_MB_LIB.T6G(SCH_1):PAGE80

RST_RT_CPU0_P3_RESET_R_N @T6G_MB_LIB.T6G(SCH_1):RST_RT_CPU0_P3_RESET_R_N
 R6826    2      B Q_RES_0402LF-0,5%,1/16W,CHIP,CS00002JB13   I353 @T6G_MB_LIB.T6G(SCH_1):PAGE80
 R1096    2      B Q_RES_0201LF-0,5%,1/20W,CHIP,CS00001JE10    I55 @T6G_MB_LIB.T6G(SCH_1):PAGE430
 R1104    1      A Q_RES_0201LF-10K,1%,1/20W,CHIP,CS31001FE17    I75 @T6G_MB_LIB.T6G(SCH_1):PAGE430
 R1107    2      B Q_RES_0201LF-4.7K,5%,1/20W,EMPTY,CS24701JE04    I79 @T6G_MB_LIB.T6G(SCH_1):PAGE430

RST_RT_CPU1_P0_PERST_N @T6G_MB_LIB.T6G(SCH_1):RST_RT_CPU1_P0_PERST_N
 U6014   F2 PERST_N PT5161LRS-PT5161LRS,SMLF,IC,AJ051610U03     I1 @T6G_MB_LIB.T6G(SCH_1):PAGE401
 R6708    1      A Q_RES_0201LF-0,5%,1/20W,CHIP,CS00001JE10    I62 @T6G_MB_LIB.T6G(SCH_1):PAGE401

RST_RT_CPU1_P0_PERST_R2_N @T6G_MB_LIB.T6G(SCH_1):RST_RT_CPU1_P0_PERST_R2_N
   U18  E22   PR4A LCMXO3LF9400C5BG484C-LCMXO3LF-9400C-5BG484C,SMLF,IA   I217 @T6G_MB_LIB.T6G(SCH_1):PAGE80
 R6710    2      B Q_RES_0402LF-0,5%,1/16W,CHIP,CS00002JB13   I322 @T6G_MB_LIB.T6G(SCH_1):PAGE80

RST_RT_CPU1_P0_PERST_R_N @T6G_MB_LIB.T6G(SCH_1):RST_RT_CPU1_P0_PERST_R_N
 R6708    2      B Q_RES_0201LF-0,5%,1/20W,CHIP,CS00001JE10    I62 @T6G_MB_LIB.T6G(SCH_1):PAGE401
 R6710    1      A Q_RES_0402LF-0,5%,1/16W,CHIP,CS00002JB13   I322 @T6G_MB_LIB.T6G(SCH_1):PAGE80
 R6720    1      A Q_RES_0201LF-10K,1%,1/20W,CHIP,CS31001FE17    I97 @T6G_MB_LIB.T6G(SCH_1):PAGE401

RST_RT_CPU1_P0_RESET_N @T6G_MB_LIB.T6G(SCH_1):RST_RT_CPU1_P0_RESET_N
 U6014 FF11 RESET_N PT5161LRS-PT5161LRS,SMLF,IC,AJ051610U03     I1 @T6G_MB_LIB.T6G(SCH_1):PAGE401
 R6709    1      A Q_RES_0201LF-0,5%,1/20W,CHIP,CS00001JE10    I65 @T6G_MB_LIB.T6G(SCH_1):PAGE401

RST_RT_CPU1_P0_RESET_R2_N @T6G_MB_LIB.T6G(SCH_1):RST_RT_CPU1_P0_RESET_R2_N
   U18  E21   PR4B LCMXO3LF9400C5BG484C-LCMXO3LF-9400C-5BG484C,SMLF,IA   I217 @T6G_MB_LIB.T6G(SCH_1):PAGE80
 R6711    2      B Q_RES_0402LF-0,5%,1/16W,CHIP,CS00002JB13   I324 @T6G_MB_LIB.T6G(SCH_1):PAGE80

RST_RT_CPU1_P0_RESET_R_N @T6G_MB_LIB.T6G(SCH_1):RST_RT_CPU1_P0_RESET_R_N
 R6709    2      B Q_RES_0201LF-0,5%,1/20W,CHIP,CS00001JE10    I65 @T6G_MB_LIB.T6G(SCH_1):PAGE401
 R6711    1      A Q_RES_0402LF-0,5%,1/16W,CHIP,CS00002JB13   I324 @T6G_MB_LIB.T6G(SCH_1):PAGE80
 R6721    1      A Q_RES_0201LF-10K,1%,1/20W,CHIP,CS31001FE17    I96 @T6G_MB_LIB.T6G(SCH_1):PAGE401
 R6724    2      B Q_RES_0201LF-4.7K,5%,1/20W,EMPTY,CS24701JE04   I101 @T6G_MB_LIB.T6G(SCH_1):PAGE401

RST_RT_CPU1_P1_PERST_N @T6G_MB_LIB.T6G(SCH_1):RST_RT_CPU1_P1_PERST_N
 U6015   F2 PERST_N PT5161LRS-PT5161LRS,SMLF,IC,AJ051610U03    I47 @T6G_MB_LIB.T6G(SCH_1):PAGE392
  R731    1      A Q_RES_0201LF-0,5%,1/20W,CHIP,CS00001JE10    I70 @T6G_MB_LIB.T6G(SCH_1):PAGE392

RST_RT_CPU1_P1_PERST_R2_N @T6G_MB_LIB.T6G(SCH_1):RST_RT_CPU1_P1_PERST_R2_N
   U18  G19   PR6C LCMXO3LF9400C5BG484C-LCMXO3LF-9400C-5BG484C,SMLF,IA   I217 @T6G_MB_LIB.T6G(SCH_1):PAGE80
 R6740    2      B Q_RES_0402LF-0,5%,1/16W,CHIP,CS00002JB13   I326 @T6G_MB_LIB.T6G(SCH_1):PAGE80

RST_RT_CPU1_P1_PERST_R_N @T6G_MB_LIB.T6G(SCH_1):RST_RT_CPU1_P1_PERST_R_N
  R731    2      B Q_RES_0201LF-0,5%,1/20W,CHIP,CS00001JE10    I70 @T6G_MB_LIB.T6G(SCH_1):PAGE392
  R749    1      A Q_RES_0201LF-10K,1%,1/20W,CHIP,CS31001FE17    I93 @T6G_MB_LIB.T6G(SCH_1):PAGE392
 R6740    1      A Q_RES_0402LF-0,5%,1/16W,CHIP,CS00002JB13   I326 @T6G_MB_LIB.T6G(SCH_1):PAGE80

RST_RT_CPU1_P1_RESET_N @T6G_MB_LIB.T6G(SCH_1):RST_RT_CPU1_P1_RESET_N
 U6015 FF11 RESET_N PT5161LRS-PT5161LRS,SMLF,IC,AJ051610U03    I47 @T6G_MB_LIB.T6G(SCH_1):PAGE392
  R732    1      A Q_RES_0201LF-0,5%,1/20W,CHIP,CS00001JE10    I71 @T6G_MB_LIB.T6G(SCH_1):PAGE392

RST_RT_CPU1_P1_RESET_R2_N @T6G_MB_LIB.T6G(SCH_1):RST_RT_CPU1_P1_RESET_R2_N
   U18  G18   PR6D LCMXO3LF9400C5BG484C-LCMXO3LF-9400C-5BG484C,SMLF,IA   I217 @T6G_MB_LIB.T6G(SCH_1):PAGE80
 R6741    2      B Q_RES_0402LF-0,5%,1/16W,CHIP,CS00002JB13   I327 @T6G_MB_LIB.T6G(SCH_1):PAGE80

RST_RT_CPU1_P1_RESET_R_N @T6G_MB_LIB.T6G(SCH_1):RST_RT_CPU1_P1_RESET_R_N
  R732    2      B Q_RES_0201LF-0,5%,1/20W,CHIP,CS00001JE10    I71 @T6G_MB_LIB.T6G(SCH_1):PAGE392
  R752    1      A Q_RES_0201LF-10K,1%,1/20W,CHIP,CS31001FE17    I92 @T6G_MB_LIB.T6G(SCH_1):PAGE392
  R758    2      B Q_RES_0201LF-4.7K,5%,1/20W,EMPTY,CS24701JE04    I94 @T6G_MB_LIB.T6G(SCH_1):PAGE392
 R6741    1      A Q_RES_0402LF-0,5%,1/16W,CHIP,CS00002JB13   I327 @T6G_MB_LIB.T6G(SCH_1):PAGE80

RST_RT_CPU1_P2_PERST_N @T6G_MB_LIB.T6G(SCH_1):RST_RT_CPU1_P2_PERST_N
  R854    1      A Q_RES_0201LF-0,5%,1/20W,CHIP,CS00001JE10    I63 @T6G_MB_LIB.T6G(SCH_1):PAGE451
 U6016   F2 PERST_N PT5161LRS-PT5161LRS,SMLF,IC,AJ051610U03    I97 @T6G_MB_LIB.T6G(SCH_1):PAGE451

RST_RT_CPU1_P2_PERST_R2_N @T6G_MB_LIB.T6G(SCH_1):RST_RT_CPU1_P2_PERST_R2_N
   U18  K20  PR12D LCMXO3LF9400C5BG484C-LCMXO3LF-9400C-5BG484C,SMLF,IA   I217 @T6G_MB_LIB.T6G(SCH_1):PAGE80
 R6792    2      B Q_RES_0402LF-0,5%,1/16W,CHIP,CS00002JB13   I334 @T6G_MB_LIB.T6G(SCH_1):PAGE80

RST_RT_CPU1_P2_PERST_R_N @T6G_MB_LIB.T6G(SCH_1):RST_RT_CPU1_P2_PERST_R_N
  R854    2      B Q_RES_0201LF-0,5%,1/20W,CHIP,CS00001JE10    I63 @T6G_MB_LIB.T6G(SCH_1):PAGE451
  R866    1      A Q_RES_0201LF-10K,1%,1/20W,CHIP,CS31001FE17    I82 @T6G_MB_LIB.T6G(SCH_1):PAGE451
 R6792    1      A Q_RES_0402LF-0,5%,1/16W,CHIP,CS00002JB13   I334 @T6G_MB_LIB.T6G(SCH_1):PAGE80

RST_RT_CPU1_P2_RESET_N @T6G_MB_LIB.T6G(SCH_1):RST_RT_CPU1_P2_RESET_N
  R860    1      A Q_RES_0201LF-0,5%,1/20W,CHIP,CS00001JE10    I62 @T6G_MB_LIB.T6G(SCH_1):PAGE451
 U6016 FF11 RESET_N PT5161LRS-PT5161LRS,SMLF,IC,AJ051610U03    I97 @T6G_MB_LIB.T6G(SCH_1):PAGE451

RST_RT_CPU1_P2_RESET_R2_N @T6G_MB_LIB.T6G(SCH_1):RST_RT_CPU1_P2_RESET_R2_N
   U18  K19  PR13A LCMXO3LF9400C5BG484C-LCMXO3LF-9400C-5BG484C,SMLF,IA   I217 @T6G_MB_LIB.T6G(SCH_1):PAGE80
 R6793    2      B Q_RES_0402LF-0,5%,1/16W,CHIP,CS00002JB13   I335 @T6G_MB_LIB.T6G(SCH_1):PAGE80

RST_RT_CPU1_P2_RESET_R_N @T6G_MB_LIB.T6G(SCH_1):RST_RT_CPU1_P2_RESET_R_N
  R860    2      B Q_RES_0201LF-0,5%,1/20W,CHIP,CS00001JE10    I62 @T6G_MB_LIB.T6G(SCH_1):PAGE451
  R867    1      A Q_RES_0201LF-10K,1%,1/20W,CHIP,CS31001FE17    I80 @T6G_MB_LIB.T6G(SCH_1):PAGE451
  R870    2      B Q_RES_0201LF-4.7K,5%,1/20W,EMPTY,CS24701JE04    I86 @T6G_MB_LIB.T6G(SCH_1):PAGE451
 R6793    1      A Q_RES_0402LF-0,5%,1/16W,CHIP,CS00002JB13   I335 @T6G_MB_LIB.T6G(SCH_1):PAGE80

RST_RT_CPU1_P3_PERST_N @T6G_MB_LIB.T6G(SCH_1):RST_RT_CPU1_P3_PERST_N
  R895    1      A Q_RES_0201LF-0,5%,1/20W,CHIP,CS00001JE10    I69 @T6G_MB_LIB.T6G(SCH_1):PAGE462
 U6017   F2 PERST_N PT5161LRS-PT5161LRS,SMLF,IC,AJ051610U03    I97 @T6G_MB_LIB.T6G(SCH_1):PAGE462

RST_RT_CPU1_P3_PERST_R2_N @T6G_MB_LIB.T6G(SCH_1):RST_RT_CPU1_P3_PERST_R2_N
   U18  L19  PR14C LCMXO3LF9400C5BG484C-LCMXO3LF-9400C-5BG484C,SMLF,IA   I217 @T6G_MB_LIB.T6G(SCH_1):PAGE80
 R6798    2      B Q_RES_0402LF-0,5%,1/16W,CHIP,CS00002JB13   I338 @T6G_MB_LIB.T6G(SCH_1):PAGE80

RST_RT_CPU1_P3_PERST_R_N @T6G_MB_LIB.T6G(SCH_1):RST_RT_CPU1_P3_PERST_R_N
  R895    2      B Q_RES_0201LF-0,5%,1/20W,CHIP,CS00001JE10    I69 @T6G_MB_LIB.T6G(SCH_1):PAGE462
  R907    1      A Q_RES_0201LF-10K,1%,1/20W,CHIP,CS31001FE17    I92 @T6G_MB_LIB.T6G(SCH_1):PAGE462
 R6798    1      A Q_RES_0402LF-0,5%,1/16W,CHIP,CS00002JB13   I338 @T6G_MB_LIB.T6G(SCH_1):PAGE80

RST_RT_CPU1_P3_RESET_N @T6G_MB_LIB.T6G(SCH_1):RST_RT_CPU1_P3_RESET_N
  R901    1      A Q_RES_0201LF-0,5%,1/20W,CHIP,CS00001JE10    I70 @T6G_MB_LIB.T6G(SCH_1):PAGE462
 U6017 FF11 RESET_N PT5161LRS-PT5161LRS,SMLF,IC,AJ051610U03    I97 @T6G_MB_LIB.T6G(SCH_1):PAGE462

RST_RT_CPU1_P3_RESET_R2_N @T6G_MB_LIB.T6G(SCH_1):RST_RT_CPU1_P3_RESET_R2_N
   U18  L20  PR14D LCMXO3LF9400C5BG484C-LCMXO3LF-9400C-5BG484C,SMLF,IA   I217 @T6G_MB_LIB.T6G(SCH_1):PAGE80
 R6799    2      B Q_RES_0402LF-0,5%,1/16W,CHIP,CS00002JB13   I339 @T6G_MB_LIB.T6G(SCH_1):PAGE80

RST_RT_CPU1_P3_RESET_R_N @T6G_MB_LIB.T6G(SCH_1):RST_RT_CPU1_P3_RESET_R_N
  R901    2      B Q_RES_0201LF-0,5%,1/20W,CHIP,CS00001JE10    I70 @T6G_MB_LIB.T6G(SCH_1):PAGE462
  R908    1      A Q_RES_0201LF-10K,1%,1/20W,CHIP,CS31001FE17    I90 @T6G_MB_LIB.T6G(SCH_1):PAGE462
  R911    2      B Q_RES_0201LF-4.7K,5%,1/20W,EMPTY,CS24701JE04    I93 @T6G_MB_LIB.T6G(SCH_1):PAGE462
 R6799    1      A Q_RES_0402LF-0,5%,1/16W,CHIP,CS00002JB13   I339 @T6G_MB_LIB.T6G(SCH_1):PAGE80

RST_SMB_BUF_E1S_0_N @T6G_MB_LIB.T6G(SCH_1):RST_SMB_BUF_E1S_0_N
  U134    6     1Y 74LVC2G07DW7-74LVC2G07DW-7,SMLF,IC,AL002G07003     I4 @T6G_MB_LIB.T6G(SCH_1):PAGE297
 R3772    1      A Q_RES_0402LF-0,5%,1/16W,CHIP,CS00002JB13    I38 @T6G_MB_LIB.T6G(SCH_1):PAGE297

RST_SMB_E1S_0_N @T6G_MB_LIB.T6G(SCH_1):RST_SMB_E1S_0_N
 R3772    2      B Q_RES_0402LF-0,5%,1/16W,CHIP,CS00002JB13    I38 @T6G_MB_LIB.T6G(SCH_1):PAGE297
   J90   A9 SMBRST# SCONN56_123276793-SCONN56_1-2327679-3,SMLF,IO,DFHSA    I90 @T6G_MB_LIB.T6G(SCH_1):PAGE297
 R1673    2      B Q_RES_0402LF-10K,1%,1/16W,CHIP,CS31002FB08   I105 @T6G_MB_LIB.T6G(SCH_1):PAGE297
 R3773    2      B Q_RES_0402LF-4.7K,5%,1/16W,EMPTY,CS24702JB10   I106 @T6G_MB_LIB.T6G(SCH_1):PAGE297

RST_SMB_E1S_N @T6G_MB_LIB.T6G(SCH_1):RST_SMB_E1S_N
 R3775    2      B Q_RES_0402LF-0,5%,1/16W,CHIP,CS00002JB13     I2 @T6G_MB_LIB.T6G(SCH_1):PAGE297
  U134    1     1A 74LVC2G07DW7-74LVC2G07DW-7,SMLF,IC,AL002G07003     I4 @T6G_MB_LIB.T6G(SCH_1):PAGE297
  U134    3     2A 74LVC2G07DW7-74LVC2G07DW-7,SMLF,IC,AL002G07003     I4 @T6G_MB_LIB.T6G(SCH_1):PAGE297

RST_SMB_OCP_SFF_N @T6G_MB_LIB.T6G(SCH_1):RST_SMB_OCP_SFF_N
   J38   A9 SMRST# SCONN168_ME1016810202011-SCONN168_ME1016810202011,A   I168 @T6G_MB_LIB.T6G(SCH_1):PAGE335
 R3233    2      B Q_RES_0402LF-0,5%,1/16W,CHIP,CS00002JB13   I153 @T6G_MB_LIB.T6G(SCH_1):PAGE336

RST_SMB_OCP_V3_2_N @T6G_MB_LIB.T6G(SCH_1):RST_SMB_OCP_V3_2_N
   J35   A9 SMRST# SCONN168_ME1016810202011-SCONN168_ME1016810202011,A   I168 @T6G_MB_LIB.T6G(SCH_1):PAGE341
 R3236    2      B Q_RES_0402LF-0,5%,1/16W,CHIP,CS00002JB13    I25 @T6G_MB_LIB.T6G(SCH_1):PAGE342

RST_SMB_RT_N @T6G_MB_LIB.T6G(SCH_1):RST_SMB_RT_N
 U6020    3 RESET# TCA9548APWR-TCA9548APWR,SMLF,IC,AL009548K02     I1 @T6G_MB_LIB.T6G(SCH_1):PAGE378
 R6776    2      B Q_RES_0201LF-0,5%,1/20W,CHIP,CS00001JE10   I104 @T6G_MB_LIB.T6G(SCH_1):PAGE378

RST_SMB_RT_R1_N @T6G_MB_LIB.T6G(SCH_1):RST_SMB_RT_R1_N
 R6776    1      A Q_RES_0201LF-0,5%,1/20W,CHIP,CS00001JE10   I104 @T6G_MB_LIB.T6G(SCH_1):PAGE378
 R6777    2      B Q_RES_0402LF-0,5%,1/16W,CHIP,CS00002JB13   I330 @T6G_MB_LIB.T6G(SCH_1):PAGE80
 R6778    1      A Q_RES_0201LF-10K,1%,1/20W,CHIP,CS31001FE17   I107 @T6G_MB_LIB.T6G(SCH_1):PAGE378

RST_SMB_RT_R2_N @T6G_MB_LIB.T6G(SCH_1):RST_SMB_RT_R2_N
   U18  Y20  PR30D LCMXO3LF9400C5BG484C-LCMXO3LF-9400C-5BG484C,SMLF,IA   I217 @T6G_MB_LIB.T6G(SCH_1):PAGE80
 R6777    1      A Q_RES_0402LF-0,5%,1/16W,CHIP,CS00002JB13   I330 @T6G_MB_LIB.T6G(SCH_1):PAGE80

RST_SMB_RT_ROM_N @T6G_MB_LIB.T6G(SCH_1):RST_SMB_RT_ROM_N
  R848    2      B Q_RES_0201LF-0,5%,1/20W,CHIP,CS00001JE10    I42 @T6G_MB_LIB.T6G(SCH_1):PAGE377
   U22    3 RESET# TCA9548APWR-TCA9548APWR,SMLF,IC,AL009548K02    I94 @T6G_MB_LIB.T6G(SCH_1):PAGE377

RST_SMB_RT_ROM_R1_N @T6G_MB_LIB.T6G(SCH_1):RST_SMB_RT_ROM_R1_N
  R849    1      A Q_RES_0201LF-10K,1%,1/20W,CHIP,CS31001FE17    I16 @T6G_MB_LIB.T6G(SCH_1):PAGE377
  R848    1      A Q_RES_0201LF-0,5%,1/20W,CHIP,CS00001JE10    I42 @T6G_MB_LIB.T6G(SCH_1):PAGE377
 R6781    2      B Q_RES_0402LF-0,5%,1/16W,CHIP,CS00002JB13   I332 @T6G_MB_LIB.T6G(SCH_1):PAGE80
 R1201    1      A Q_RES_0201LF-0,5%,1/20W,CHIP,CS00001JE10    I30 @T6G_MB_LIB.T6G(SCH_1):PAGE376
 R1199    1      A Q_RES_0201LF-0,5%,1/20W,CHIP,CS00001JE10    I40 @T6G_MB_LIB.T6G(SCH_1):PAGE376
 R1198    1      A Q_RES_0201LF-0,5%,1/20W,CHIP,CS00001JE10    I53 @T6G_MB_LIB.T6G(SCH_1):PAGE376
 R1200    1      A Q_RES_0201LF-0,5%,1/20W,CHIP,CS00001JE10    I68 @T6G_MB_LIB.T6G(SCH_1):PAGE376
 R1211    1      A Q_RES_0201LF-0,5%,1/20W,CHIP,CS00001JE10    I86 @T6G_MB_LIB.T6G(SCH_1):PAGE376
 R1210    1      A Q_RES_0201LF-0,5%,1/20W,CHIP,CS00001JE10   I109 @T6G_MB_LIB.T6G(SCH_1):PAGE376
 R1206    1      A Q_RES_0201LF-0,5%,1/20W,CHIP,CS00001JE10   I115 @T6G_MB_LIB.T6G(SCH_1):PAGE376
 R1209    1      A Q_RES_0201LF-0,5%,1/20W,CHIP,CS00001JE10   I123 @T6G_MB_LIB.T6G(SCH_1):PAGE376

RST_SMB_RT_ROM_R2_N @T6G_MB_LIB.T6G(SCH_1):RST_SMB_RT_ROM_R2_N
   U18  V18  PR30A LCMXO3LF9400C5BG484C-LCMXO3LF-9400C-5BG484C,SMLF,IA   I217 @T6G_MB_LIB.T6G(SCH_1):PAGE80
 R6781    1      A Q_RES_0402LF-0,5%,1/16W,CHIP,CS00002JB13   I332 @T6G_MB_LIB.T6G(SCH_1):PAGE80

RST_SMB_SWITCH_N @T6G_MB_LIB.T6G(SCH_1):RST_SMB_SWITCH_N
  U224    2      A 74LVC1G126SE7-74LVC1G126SE-7,SMLF,IC,AL1G0126009   I159 @T6G_MB_LIB.T6G(SCH_1):PAGE336
 R2905    1      A Q_RES_0402LF-0,5%,1/16W,CHIP,CS00002JB13   I441 @T6G_MB_LIB.T6G(SCH_1):PAGE363
 R2921    2      B Q_RES_0402LF-10K,1%,1/16W,EMPTY,CS31002FB08    I35 @T6G_MB_LIB.T6G(SCH_1):PAGE246
 R3705    2      B Q_RES_0402LF-10K,1%,1/16W,EMPTY,CS31002FB08    I27 @T6G_MB_LIB.T6G(SCH_1):PAGE251
 R3710    1      A Q_RES_0402LF-0,5%,1/16W,CHIP,CS00002JB13    I29 @T6G_MB_LIB.T6G(SCH_1):PAGE251
 R1822    2      B Q_RES_0402LF-10K,1%,1/16W,CHIP,CS31002FB08    I21 @T6G_MB_LIB.T6G(SCH_1):PAGE252
 R2268    1      A Q_RES_0402LF-0,5%,1/16W,CHIP,CS00002JB13    I28 @T6G_MB_LIB.T6G(SCH_1):PAGE252
   U18  D17  PT40D LCMXO3LF9400C5BG484C-LCMXO3LF-9400C-5BG484C,SMLF,IA    I94 @T6G_MB_LIB.T6G(SCH_1):PAGE79
  U225    2      A 74LVC1G126SE7-74LVC1G126SE-7,SMLF,IC,AL1G0126009     I9 @T6G_MB_LIB.T6G(SCH_1):PAGE342
 R2922    1      A Q_RES_0402LF-0,5%,1/16W,CHIP,CS00002JB13    I31 @T6G_MB_LIB.T6G(SCH_1):PAGE246

RST_SMB_SWITCH_R_N @T6G_MB_LIB.T6G(SCH_1):RST_SMB_SWITCH_R_N
 R2905    2      B Q_RES_0402LF-0,5%,1/16W,CHIP,CS00002JB13   I441 @T6G_MB_LIB.T6G(SCH_1):PAGE363
   C74    1      A Q_CAP_0402-0.1UF,25V,10%,EMPTY,CH4104K1B00   I452 @T6G_MB_LIB.T6G(SCH_1):PAGE363
   J45   B1     B1 CONN60_101062636003K02LF-CONN60_10106263-6003K02LFA   I466 @T6G_MB_LIB.T6G(SCH_1):PAGE363

RST_SRST_PLD_BMC_N @T6G_MB_LIB.T6G(SCH_1):RST_SRST_PLD_BMC_N
   J41 OB11 REFCLKN2 SCONN168_ME1016810202011-SCONN168_ME1016810202011,A   I176 @T6G_MB_LIB.T6G(SCH_1):PAGE348
  R419    1      A Q_RES_0402LF-0,5%,1/16W,CHIP,CS00002JB13   I141 @T6G_MB_LIB.T6G(SCH_1):PAGE79

RST_SRST_PLD_BMC_R_N @T6G_MB_LIB.T6G(SCH_1):RST_SRST_PLD_BMC_R_N
   U18  C17  PT39C LCMXO3LF9400C5BG484C-LCMXO3LF-9400C-5BG484C,SMLF,IA    I94 @T6G_MB_LIB.T6G(SCH_1):PAGE79
  R419    2      B Q_RES_0402LF-0,5%,1/16W,CHIP,CS00002JB13   I141 @T6G_MB_LIB.T6G(SCH_1):PAGE79

RST_SWB_BIC_BUF_N @T6G_MB_LIB.T6G(SCH_1):RST_SWB_BIC_BUF_N
 R2924    2      B Q_RES_0402LF-49.9,1%,1/16W,CHIP,CS04992FB07   I155 @T6G_MB_LIB.T6G(SCH_1):PAGE256
  J105   N6     N6 CONN112_10137002101LF-CONN112_10137002-101LF,THLF,A    I76 @T6G_MB_LIB.T6G(SCH_1):PAGE326

RST_SWB_BIC_BUF_R_N @T6G_MB_LIB.T6G(SCH_1):RST_SWB_BIC_BUF_R_N
  U195    4     B1 74LVC2G17GW-74LVC2G17GW,SMLF,IC,AL2G0017005    I65 @T6G_MB_LIB.T6G(SCH_1):PAGE256
 R2911    2      B Q_RES_0402LF-4.7K,5%,1/16W,EMPTY,CS24702JB10   I153 @T6G_MB_LIB.T6G(SCH_1):PAGE256
 R2924    1      A Q_RES_0402LF-49.9,1%,1/16W,CHIP,CS04992FB07   I155 @T6G_MB_LIB.T6G(SCH_1):PAGE256
 R2927    1      A Q_RES_0402LF-100K,1%,1/16W,CHIP,CS41002FB09   I203 @T6G_MB_LIB.T6G(SCH_1):PAGE256

RST_SWB_BIC_N @T6G_MB_LIB.T6G(SCH_1):RST_SWB_BIC_N
 R2848    1      A Q_RES_0402LF-0,5%,1/16W,CHIP,CS00002JB13    I59 @T6G_MB_LIB.T6G(SCH_1):PAGE246
  U181    5  IO0_1 PCA9539RPW-PCA9539RPW,SMLF,IC,AL009539K07    I83 @T6G_MB_LIB.T6G(SCH_1):PAGE246

RST_SWB_BIC_R_N @T6G_MB_LIB.T6G(SCH_1):RST_SWB_BIC_R_N
  U195    3     A1 74LVC2G17GW-74LVC2G17GW,SMLF,IC,AL2G0017005    I65 @T6G_MB_LIB.T6G(SCH_1):PAGE256
 R2916    1      A Q_RES_0402LF-4.7K,5%,1/16W,EMPTY,CS24702JB10    I93 @T6G_MB_LIB.T6G(SCH_1):PAGE256
 R2909    2      B Q_RES_0402LF-4.7K,5%,1/16W,CHIP,CS24702JB10   I198 @T6G_MB_LIB.T6G(SCH_1):PAGE256
 R2848    2      B Q_RES_0402LF-0,5%,1/16W,CHIP,CS00002JB13    I59 @T6G_MB_LIB.T6G(SCH_1):PAGE246

RST_USB_CPU0_HUB1_R_N @T6G_MB_LIB.T6G(SCH_1):RST_USB_CPU0_HUB1_R_N
 U6001   31 RESET# CYUSB330468LTXI-CYUSB3304-68LTXI,SMLF,IC,AJ0330400A     I1 @T6G_MB_LIB.T6G(SCH_1):PAGE153
 R4451    2      B Q_RES_0402LF-33.2,1%,1/16W,CHIP,CS03322FB03    I20 @T6G_MB_LIB.T6G(SCH_1):PAGE153
 R4453    1      A Q_RES_0402LF-47K,0.1%,1/16W,EMPTY,CS34702BB05    I23 @T6G_MB_LIB.T6G(SCH_1):PAGE153
 C2317    1      A Q_CAP_C0402-1UF,25V,10%,X6S,CH5104KEB02    I25 @T6G_MB_LIB.T6G(SCH_1):PAGE153
 R4452    2      B Q_RES_0402LF-10K,1%,1/16W,EMPTY,CS31002FB08    I93 @T6G_MB_LIB.T6G(SCH_1):PAGE153

RST_USB_HUB_N @T6G_MB_LIB.T6G(SCH_1):RST_USB_HUB_N
 R3654    1      A Q_RES_0402LF-33.2,1%,1/16W,CHIP,CS03322FB03   I155 @T6G_MB_LIB.T6G(SCH_1):PAGE358
 R4451    1      A Q_RES_0402LF-33.2,1%,1/16W,CHIP,CS03322FB03    I20 @T6G_MB_LIB.T6G(SCH_1):PAGE153
 R6328    1      A Q_RES_0402LF-0,5%,1/16W,CHIP,CS00002JB13   I114 @T6G_MB_LIB.T6G(SCH_1):PAGE155
 R6322    1      A Q_RES_0402LF-0,5%,1/16W,CHIP,CS00002JB13   I131 @T6G_MB_LIB.T6G(SCH_1):PAGE155
  U181    4  IO0_0 PCA9539RPW-PCA9539RPW,SMLF,IC,AL009539K07    I83 @T6G_MB_LIB.T6G(SCH_1):PAGE246

RST_USB_HUB_R_N @T6G_MB_LIB.T6G(SCH_1):RST_USB_HUB_R_N
  U268   17 RESET# GL852GOHY60-GL852G-OHY60,SMLF,IC,AL000852001   I100 @T6G_MB_LIB.T6G(SCH_1):PAGE358
 R3654    2      B Q_RES_0402LF-33.2,1%,1/16W,CHIP,CS03322FB03   I155 @T6G_MB_LIB.T6G(SCH_1):PAGE358
 C2041    1      A Q_CAP_C0402-1UF,25V,10%,X6S,CH5104KEB02   I158 @T6G_MB_LIB.T6G(SCH_1):PAGE358
 R3660    2      B Q_RES_0402LF-10K,1%,1/16W,CHIP,CS31002FB08   I159 @T6G_MB_LIB.T6G(SCH_1):PAGE358
 R3661    2      B Q_RES_0402LF-47K,0.1%,1/16W,EMPTY,CS34702BB05   I201 @T6G_MB_LIB.T6G(SCH_1):PAGE358

RT_BOARD_ID_ID0 @T6G_MB_LIB.T6G(SCH_1):RT_BOARD_ID_ID0
   U18   J4  PL11C LCMXO3LF9400C5BG484C-LCMXO3LF-9400C-5BG484C,SMLF,IA   I143 @T6G_MB_LIB.T6G(SCH_1):PAGE81
 R6745    1      A Q_RES_0402LF-1K,1%,1/16W,CHIP,CS21002FB06     I4 @T6G_MB_LIB.T6G(SCH_1):PAGE467
 R6743    2      B Q_RES_0402LF-1K,1%,1/16W,EMPTY,CS21002FB06     I6 @T6G_MB_LIB.T6G(SCH_1):PAGE467

RT_BOARD_ID_ID1 @T6G_MB_LIB.T6G(SCH_1):RT_BOARD_ID_ID1
   U18   H1  PL10B LCMXO3LF9400C5BG484C-LCMXO3LF-9400C-5BG484C,SMLF,IA   I143 @T6G_MB_LIB.T6G(SCH_1):PAGE81
 R6744    1      A Q_RES_0402LF-1K,1%,1/16W,CHIP,CS21002FB06     I2 @T6G_MB_LIB.T6G(SCH_1):PAGE467
 R6742    2      B Q_RES_0402LF-1K,1%,1/16W,EMPTY,CS21002FB06     I5 @T6G_MB_LIB.T6G(SCH_1):PAGE467

RT_CPU0_P0_ADDR1 @T6G_MB_LIB.T6G(SCH_1):RT_CPU0_P0_ADDR1
 U6010  F34 SMB_ADDR1 PT5161LRS-PT5161LRS,SMLF,IC,AJ051610U03    I53 @T6G_MB_LIB.T6G(SCH_1):PAGE385
  R969    1      A Q_RES_0201LF-1K,1%,1/20W,CHIP,CS21001FE07    I90 @T6G_MB_LIB.T6G(SCH_1):PAGE385
  R968    2      B Q_RES_0201LF-1K,1%,1/20W,EMPTY,CS21001FE07    I91 @T6G_MB_LIB.T6G(SCH_1):PAGE385

RT_CPU0_P0_ADDR2 @T6G_MB_LIB.T6G(SCH_1):RT_CPU0_P0_ADDR2
 U6010  B23 SMB_ADDR2 PT5161LRS-PT5161LRS,SMLF,IC,AJ051610U03    I53 @T6G_MB_LIB.T6G(SCH_1):PAGE385
  R967    1      A Q_RES_0201LF-20K,1%,1/20W,CHIP,CS32001FE00    I87 @T6G_MB_LIB.T6G(SCH_1):PAGE385
  R966    2      B Q_RES_0201LF-1K,1%,1/20W,EMPTY,CS21001FE07    I89 @T6G_MB_LIB.T6G(SCH_1):PAGE385

RT_CPU0_P0_ADDR3 @T6G_MB_LIB.T6G(SCH_1):RT_CPU0_P0_ADDR3
 U6010  B25 SMB_ADDR3 PT5161LRS-PT5161LRS,SMLF,IC,AJ051610U03    I53 @T6G_MB_LIB.T6G(SCH_1):PAGE385
  R965    1      A Q_RES_0201LF-1K,1%,1/20W,EMPTY,CS21001FE07    I86 @T6G_MB_LIB.T6G(SCH_1):PAGE385
  R964    2      B Q_RES_0201LF-1K,1%,1/20W,CHIP,CS21001FE07    I88 @T6G_MB_LIB.T6G(SCH_1):PAGE385

RT_CPU0_P0_SCAN_MODE @T6G_MB_LIB.T6G(SCH_1):RT_CPU0_P0_SCAN_MODE
  R972    2      B Q_RES_0201LF-4.7K,5%,1/20W,EMPTY,CS24701JE04    I25 @T6G_MB_LIB.T6G(SCH_1):PAGE385
 U6010 FF33 SCAN_MODE PT5161LRS-PT5161LRS,SMLF,IC,AJ051610U03    I53 @T6G_MB_LIB.T6G(SCH_1):PAGE385
  R973    1      A Q_RES_0201LF-200,1%,1/20W,CHIP,CS12001FE12   I121 @T6G_MB_LIB.T6G(SCH_1):PAGE385

RT_CPU0_P0_VQPS @T6G_MB_LIB.T6G(SCH_1):RT_CPU0_P0_VQPS
 U6010   G1   VQPS PT5161LRS-PT5161LRS,SMLF,IC,AJ051610U03     I3 @T6G_MB_LIB.T6G(SCH_1):PAGE386
 R6809    1      A Q_RES_0201LF-200,1%,1/20W,CHIP,CS12001FE12    I18 @T6G_MB_LIB.T6G(SCH_1):PAGE386
 R6808    2      B Q_RES_0201LF-1K,1%,1/20W,EMPTY,CS21001FE07    I19 @T6G_MB_LIB.T6G(SCH_1):PAGE386

RT_CPU0_P1_ADDR1 @T6G_MB_LIB.T6G(SCH_1):RT_CPU0_P1_ADDR1
 R1018    1      A Q_RES_0201LF-1K,1%,1/20W,CHIP,CS21001FE07    I68 @T6G_MB_LIB.T6G(SCH_1):PAGE408
 R1017    2      B Q_RES_0201LF-1K,1%,1/20W,EMPTY,CS21001FE07    I69 @T6G_MB_LIB.T6G(SCH_1):PAGE408
 U6011  F34 SMB_ADDR1 PT5161LRS-PT5161LRS,SMLF,IC,AJ051610U03    I83 @T6G_MB_LIB.T6G(SCH_1):PAGE408

RT_CPU0_P1_ADDR2 @T6G_MB_LIB.T6G(SCH_1):RT_CPU0_P1_ADDR2
 R1016    1      A Q_RES_0201LF-20K,1%,1/20W,CHIP,CS32001FE00    I65 @T6G_MB_LIB.T6G(SCH_1):PAGE408
 R1015    2      B Q_RES_0201LF-1K,1%,1/20W,EMPTY,CS21001FE07    I67 @T6G_MB_LIB.T6G(SCH_1):PAGE408
 U6011  B23 SMB_ADDR2 PT5161LRS-PT5161LRS,SMLF,IC,AJ051610U03    I83 @T6G_MB_LIB.T6G(SCH_1):PAGE408

RT_CPU0_P1_ADDR3 @T6G_MB_LIB.T6G(SCH_1):RT_CPU0_P1_ADDR3
 R1014    1      A Q_RES_0201LF-1K,1%,1/20W,EMPTY,CS21001FE07    I64 @T6G_MB_LIB.T6G(SCH_1):PAGE408
 R1013    2      B Q_RES_0201LF-1K,1%,1/20W,CHIP,CS21001FE07    I66 @T6G_MB_LIB.T6G(SCH_1):PAGE408
 U6011  B25 SMB_ADDR3 PT5161LRS-PT5161LRS,SMLF,IC,AJ051610U03    I83 @T6G_MB_LIB.T6G(SCH_1):PAGE408

RT_CPU0_P1_SCAN_MODE @T6G_MB_LIB.T6G(SCH_1):RT_CPU0_P1_SCAN_MODE
 R1021    2      B Q_RES_0201LF-4.7K,5%,1/20W,EMPTY,CS24701JE04     I5 @T6G_MB_LIB.T6G(SCH_1):PAGE408
 U6011 FF33 SCAN_MODE PT5161LRS-PT5161LRS,SMLF,IC,AJ051610U03    I83 @T6G_MB_LIB.T6G(SCH_1):PAGE408
 R1022    1      A Q_RES_0201LF-200,1%,1/20W,CHIP,CS12001FE12   I102 @T6G_MB_LIB.T6G(SCH_1):PAGE408

RT_CPU0_P1_VQPS @T6G_MB_LIB.T6G(SCH_1):RT_CPU0_P1_VQPS
 U6011   G1   VQPS PT5161LRS-PT5161LRS,SMLF,IC,AJ051610U03     I5 @T6G_MB_LIB.T6G(SCH_1):PAGE409
 R1041    1      A Q_RES_0201LF-200,1%,1/20W,CHIP,CS12001FE12    I18 @T6G_MB_LIB.T6G(SCH_1):PAGE409
 R1040    2      B Q_RES_0201LF-1K,1%,1/20W,EMPTY,CS21001FE07    I19 @T6G_MB_LIB.T6G(SCH_1):PAGE409

RT_CPU0_P2_ADDR1 @T6G_MB_LIB.T6G(SCH_1):RT_CPU0_P2_ADDR1
 R1060    1      A Q_RES_0201LF-1K,1%,1/20W,CHIP,CS21001FE07    I69 @T6G_MB_LIB.T6G(SCH_1):PAGE419
 R1059    2      B Q_RES_0201LF-1K,1%,1/20W,EMPTY,CS21001FE07    I70 @T6G_MB_LIB.T6G(SCH_1):PAGE419
 U6012  F34 SMB_ADDR1 PT5161LRS-PT5161LRS,SMLF,IC,AJ051610U03    I83 @T6G_MB_LIB.T6G(SCH_1):PAGE419

RT_CPU0_P2_ADDR2 @T6G_MB_LIB.T6G(SCH_1):RT_CPU0_P2_ADDR2
 R1058    1      A Q_RES_0201LF-20K,1%,1/20W,CHIP,CS32001FE00    I66 @T6G_MB_LIB.T6G(SCH_1):PAGE419
 R1057    2      B Q_RES_0201LF-1K,1%,1/20W,EMPTY,CS21001FE07    I68 @T6G_MB_LIB.T6G(SCH_1):PAGE419
 U6012  B23 SMB_ADDR2 PT5161LRS-PT5161LRS,SMLF,IC,AJ051610U03    I83 @T6G_MB_LIB.T6G(SCH_1):PAGE419

RT_CPU0_P2_ADDR3 @T6G_MB_LIB.T6G(SCH_1):RT_CPU0_P2_ADDR3
 R1056    1      A Q_RES_0201LF-1K,1%,1/20W,EMPTY,CS21001FE07    I65 @T6G_MB_LIB.T6G(SCH_1):PAGE419
 R1055    2      B Q_RES_0201LF-1K,1%,1/20W,CHIP,CS21001FE07    I67 @T6G_MB_LIB.T6G(SCH_1):PAGE419
 U6012  B25 SMB_ADDR3 PT5161LRS-PT5161LRS,SMLF,IC,AJ051610U03    I83 @T6G_MB_LIB.T6G(SCH_1):PAGE419

RT_CPU0_P2_SCAN_MODE @T6G_MB_LIB.T6G(SCH_1):RT_CPU0_P2_SCAN_MODE
 R1063    2      B Q_RES_0201LF-4.7K,5%,1/20W,EMPTY,CS24701JE04     I5 @T6G_MB_LIB.T6G(SCH_1):PAGE419
 U6012 FF33 SCAN_MODE PT5161LRS-PT5161LRS,SMLF,IC,AJ051610U03    I83 @T6G_MB_LIB.T6G(SCH_1):PAGE419
 R1064    1      A Q_RES_0201LF-200,1%,1/20W,CHIP,CS12001FE12   I102 @T6G_MB_LIB.T6G(SCH_1):PAGE419

RT_CPU0_P2_VQPS @T6G_MB_LIB.T6G(SCH_1):RT_CPU0_P2_VQPS
 U6012   G1   VQPS PT5161LRS-PT5161LRS,SMLF,IC,AJ051610U03     I6 @T6G_MB_LIB.T6G(SCH_1):PAGE420
 R1082    1      A Q_RES_0201LF-200,1%,1/20W,CHIP,CS12001FE12    I18 @T6G_MB_LIB.T6G(SCH_1):PAGE420
 R1081    2      B Q_RES_0201LF-1K,1%,1/20W,EMPTY,CS21001FE07    I19 @T6G_MB_LIB.T6G(SCH_1):PAGE420

RT_CPU0_P3_ADDR1 @T6G_MB_LIB.T6G(SCH_1):RT_CPU0_P3_ADDR1
 R1102    1      A Q_RES_0201LF-1K,1%,1/20W,CHIP,CS21001FE07    I69 @T6G_MB_LIB.T6G(SCH_1):PAGE430
 R1101    2      B Q_RES_0201LF-1K,1%,1/20W,EMPTY,CS21001FE07    I70 @T6G_MB_LIB.T6G(SCH_1):PAGE430
 U6013  F34 SMB_ADDR1 PT5161LRS-PT5161LRS,SMLF,IC,AJ051610U03    I83 @T6G_MB_LIB.T6G(SCH_1):PAGE430

RT_CPU0_P3_ADDR2 @T6G_MB_LIB.T6G(SCH_1):RT_CPU0_P3_ADDR2
 R1100    1      A Q_RES_0201LF-20K,1%,1/20W,CHIP,CS32001FE00    I66 @T6G_MB_LIB.T6G(SCH_1):PAGE430
 R1099    2      B Q_RES_0201LF-1K,1%,1/20W,EMPTY,CS21001FE07    I68 @T6G_MB_LIB.T6G(SCH_1):PAGE430
 U6013  B23 SMB_ADDR2 PT5161LRS-PT5161LRS,SMLF,IC,AJ051610U03    I83 @T6G_MB_LIB.T6G(SCH_1):PAGE430

RT_CPU0_P3_ADDR3 @T6G_MB_LIB.T6G(SCH_1):RT_CPU0_P3_ADDR3
 R1098    1      A Q_RES_0201LF-1K,1%,1/20W,EMPTY,CS21001FE07    I65 @T6G_MB_LIB.T6G(SCH_1):PAGE430
 R1097    2      B Q_RES_0201LF-1K,1%,1/20W,CHIP,CS21001FE07    I67 @T6G_MB_LIB.T6G(SCH_1):PAGE430
 U6013  B25 SMB_ADDR3 PT5161LRS-PT5161LRS,SMLF,IC,AJ051610U03    I83 @T6G_MB_LIB.T6G(SCH_1):PAGE430

RT_CPU0_P3_SCAN_MODE @T6G_MB_LIB.T6G(SCH_1):RT_CPU0_P3_SCAN_MODE
 R1105    2      B Q_RES_0201LF-4.7K,5%,1/20W,EMPTY,CS24701JE04     I5 @T6G_MB_LIB.T6G(SCH_1):PAGE430
 U6013 FF33 SCAN_MODE PT5161LRS-PT5161LRS,SMLF,IC,AJ051610U03    I83 @T6G_MB_LIB.T6G(SCH_1):PAGE430
 R1106    1      A Q_RES_0201LF-200,1%,1/20W,CHIP,CS12001FE12   I102 @T6G_MB_LIB.T6G(SCH_1):PAGE430

RT_CPU0_P3_VQPS @T6G_MB_LIB.T6G(SCH_1):RT_CPU0_P3_VQPS
 U6013   G1   VQPS PT5161LRS-PT5161LRS,SMLF,IC,AJ051610U03     I6 @T6G_MB_LIB.T6G(SCH_1):PAGE431
 R1124    1      A Q_RES_0201LF-200,1%,1/20W,CHIP,CS12001FE12    I18 @T6G_MB_LIB.T6G(SCH_1):PAGE431
 R1123    2      B Q_RES_0201LF-1K,1%,1/20W,EMPTY,CS21001FE07    I19 @T6G_MB_LIB.T6G(SCH_1):PAGE431

RT_CPU1_P0_ADDR1 @T6G_MB_LIB.T6G(SCH_1):RT_CPU1_P0_ADDR1
 U6014  F34 SMB_ADDR1 PT5161LRS-PT5161LRS,SMLF,IC,AJ051610U03     I1 @T6G_MB_LIB.T6G(SCH_1):PAGE401
 R6717    1      A Q_RES_0201LF-1K,1%,1/20W,CHIP,CS21001FE07   I106 @T6G_MB_LIB.T6G(SCH_1):PAGE401
 R6716    2      B Q_RES_0201LF-1K,1%,1/20W,EMPTY,CS21001FE07   I107 @T6G_MB_LIB.T6G(SCH_1):PAGE401

RT_CPU1_P0_ADDR2 @T6G_MB_LIB.T6G(SCH_1):RT_CPU1_P0_ADDR2
 U6014  B23 SMB_ADDR2 PT5161LRS-PT5161LRS,SMLF,IC,AJ051610U03     I1 @T6G_MB_LIB.T6G(SCH_1):PAGE401
 R6714    2      B Q_RES_0201LF-1K,1%,1/20W,EMPTY,CS21001FE07   I104 @T6G_MB_LIB.T6G(SCH_1):PAGE401
 R6715    1      A Q_RES_0201LF-20K,1%,1/20W,CHIP,CS32001FE00   I105 @T6G_MB_LIB.T6G(SCH_1):PAGE401

RT_CPU1_P0_ADDR3 @T6G_MB_LIB.T6G(SCH_1):RT_CPU1_P0_ADDR3
 U6014  B25 SMB_ADDR3 PT5161LRS-PT5161LRS,SMLF,IC,AJ051610U03     I1 @T6G_MB_LIB.T6G(SCH_1):PAGE401
 R6712    2      B Q_RES_0201LF-1K,1%,1/20W,CHIP,CS21001FE07   I102 @T6G_MB_LIB.T6G(SCH_1):PAGE401
 R6713    1      A Q_RES_0201LF-1K,1%,1/20W,EMPTY,CS21001FE07   I103 @T6G_MB_LIB.T6G(SCH_1):PAGE401

RT_CPU1_P0_SCAN_MODE @T6G_MB_LIB.T6G(SCH_1):RT_CPU1_P0_SCAN_MODE
 U6014 FF33 SCAN_MODE PT5161LRS-PT5161LRS,SMLF,IC,AJ051610U03     I1 @T6G_MB_LIB.T6G(SCH_1):PAGE401
 R6722    2      B Q_RES_0201LF-4.7K,5%,1/20W,EMPTY,CS24701JE04    I85 @T6G_MB_LIB.T6G(SCH_1):PAGE401
 R6723    1      A Q_RES_0201LF-200,1%,1/20W,CHIP,CS12001FE12   I128 @T6G_MB_LIB.T6G(SCH_1):PAGE401

RT_CPU1_P0_VQPS @T6G_MB_LIB.T6G(SCH_1):RT_CPU1_P0_VQPS
 U6014   G1   VQPS PT5161LRS-PT5161LRS,SMLF,IC,AJ051610U03     I1 @T6G_MB_LIB.T6G(SCH_1):PAGE400
  R701    1      A Q_RES_0201LF-200,1%,1/20W,CHIP,CS12001FE12   I105 @T6G_MB_LIB.T6G(SCH_1):PAGE400
  R699    2      B Q_RES_0201LF-1K,1%,1/20W,EMPTY,CS21001FE07   I106 @T6G_MB_LIB.T6G(SCH_1):PAGE400

RT_CPU1_P1_ADDR1 @T6G_MB_LIB.T6G(SCH_1):RT_CPU1_P1_ADDR1
 U6015  F34 SMB_ADDR1 PT5161LRS-PT5161LRS,SMLF,IC,AJ051610U03    I47 @T6G_MB_LIB.T6G(SCH_1):PAGE392
  R796    1      A Q_RES_0201LF-1K,1%,1/20W,CHIP,CS21001FE07   I105 @T6G_MB_LIB.T6G(SCH_1):PAGE392
  R795    2      B Q_RES_0201LF-1K,1%,1/20W,EMPTY,CS21001FE07   I110 @T6G_MB_LIB.T6G(SCH_1):PAGE392

RT_CPU1_P1_ADDR2 @T6G_MB_LIB.T6G(SCH_1):RT_CPU1_P1_ADDR2
 U6015  B23 SMB_ADDR2 PT5161LRS-PT5161LRS,SMLF,IC,AJ051610U03    I47 @T6G_MB_LIB.T6G(SCH_1):PAGE392
  R746    1      A Q_RES_0201LF-20K,1%,1/20W,CHIP,CS32001FE00   I102 @T6G_MB_LIB.T6G(SCH_1):PAGE392
  R745    2      B Q_RES_0201LF-1K,1%,1/20W,EMPTY,CS21001FE07   I104 @T6G_MB_LIB.T6G(SCH_1):PAGE392

RT_CPU1_P1_ADDR3 @T6G_MB_LIB.T6G(SCH_1):RT_CPU1_P1_ADDR3
 U6015  B25 SMB_ADDR3 PT5161LRS-PT5161LRS,SMLF,IC,AJ051610U03    I47 @T6G_MB_LIB.T6G(SCH_1):PAGE392
  R741    1      A Q_RES_0201LF-1K,1%,1/20W,EMPTY,CS21001FE07   I101 @T6G_MB_LIB.T6G(SCH_1):PAGE392
  R735    2      B Q_RES_0201LF-1K,1%,1/20W,CHIP,CS21001FE07   I103 @T6G_MB_LIB.T6G(SCH_1):PAGE392

RT_CPU1_P1_SCAN_MODE @T6G_MB_LIB.T6G(SCH_1):RT_CPU1_P1_SCAN_MODE
  R755    2      B Q_RES_0201LF-4.7K,5%,1/20W,EMPTY,CS24701JE04    I19 @T6G_MB_LIB.T6G(SCH_1):PAGE392
 U6015 FF33 SCAN_MODE PT5161LRS-PT5161LRS,SMLF,IC,AJ051610U03    I47 @T6G_MB_LIB.T6G(SCH_1):PAGE392
  R756    1      A Q_RES_0201LF-200,1%,1/20W,CHIP,CS12001FE12   I132 @T6G_MB_LIB.T6G(SCH_1):PAGE392

RT_CPU1_P1_VQPS @T6G_MB_LIB.T6G(SCH_1):RT_CPU1_P1_VQPS
 U6015   G1   VQPS PT5161LRS-PT5161LRS,SMLF,IC,AJ051610U03     I5 @T6G_MB_LIB.T6G(SCH_1):PAGE391
 R6731    1      A Q_RES_0201LF-200,1%,1/20W,CHIP,CS12001FE12    I20 @T6G_MB_LIB.T6G(SCH_1):PAGE391
 R6730    2      B Q_RES_0201LF-1K,1%,1/20W,EMPTY,CS21001FE07    I21 @T6G_MB_LIB.T6G(SCH_1):PAGE391

RT_CPU1_P2_ADDR1 @T6G_MB_LIB.T6G(SCH_1):RT_CPU1_P2_ADDR1
  R892    1      A Q_RES_0201LF-1K,1%,1/20W,CHIP,CS21001FE07    I76 @T6G_MB_LIB.T6G(SCH_1):PAGE451
  R887    2      B Q_RES_0201LF-1K,1%,1/20W,EMPTY,CS21001FE07    I77 @T6G_MB_LIB.T6G(SCH_1):PAGE451
 U6016  F34 SMB_ADDR1 PT5161LRS-PT5161LRS,SMLF,IC,AJ051610U03    I97 @T6G_MB_LIB.T6G(SCH_1):PAGE451

RT_CPU1_P2_ADDR2 @T6G_MB_LIB.T6G(SCH_1):RT_CPU1_P2_ADDR2
  R865    1      A Q_RES_0201LF-20K,1%,1/20W,CHIP,CS32001FE00    I72 @T6G_MB_LIB.T6G(SCH_1):PAGE451
  R864    2      B Q_RES_0201LF-1K,1%,1/20W,EMPTY,CS21001FE07    I75 @T6G_MB_LIB.T6G(SCH_1):PAGE451
 U6016  B23 SMB_ADDR2 PT5161LRS-PT5161LRS,SMLF,IC,AJ051610U03    I97 @T6G_MB_LIB.T6G(SCH_1):PAGE451

RT_CPU1_P2_ADDR3 @T6G_MB_LIB.T6G(SCH_1):RT_CPU1_P2_ADDR3
  R863    1      A Q_RES_0201LF-1K,1%,1/20W,EMPTY,CS21001FE07    I71 @T6G_MB_LIB.T6G(SCH_1):PAGE451
  R861    2      B Q_RES_0201LF-1K,1%,1/20W,CHIP,CS21001FE07    I74 @T6G_MB_LIB.T6G(SCH_1):PAGE451
 U6016  B25 SMB_ADDR3 PT5161LRS-PT5161LRS,SMLF,IC,AJ051610U03    I97 @T6G_MB_LIB.T6G(SCH_1):PAGE451

RT_CPU1_P2_SCAN_MODE @T6G_MB_LIB.T6G(SCH_1):RT_CPU1_P2_SCAN_MODE
  R868    2      B Q_RES_0201LF-4.7K,5%,1/20W,EMPTY,CS24701JE04    I17 @T6G_MB_LIB.T6G(SCH_1):PAGE451
 U6016 FF33 SCAN_MODE PT5161LRS-PT5161LRS,SMLF,IC,AJ051610U03    I97 @T6G_MB_LIB.T6G(SCH_1):PAGE451
  R869    1      A Q_RES_0201LF-200,1%,1/20W,CHIP,CS12001FE12   I119 @T6G_MB_LIB.T6G(SCH_1):PAGE451

RT_CPU1_P2_VQPS @T6G_MB_LIB.T6G(SCH_1):RT_CPU1_P2_VQPS
 U6016   G1   VQPS PT5161LRS-PT5161LRS,SMLF,IC,AJ051610U03     I7 @T6G_MB_LIB.T6G(SCH_1):PAGE452
 R6795    1      A Q_RES_0201LF-200,1%,1/20W,CHIP,CS12001FE12    I20 @T6G_MB_LIB.T6G(SCH_1):PAGE452
 R6794    2      B Q_RES_0201LF-1K,1%,1/20W,EMPTY,CS21001FE07    I21 @T6G_MB_LIB.T6G(SCH_1):PAGE452

RT_CPU1_P3_ADDR1 @T6G_MB_LIB.T6G(SCH_1):RT_CPU1_P3_ADDR1
  R949    1      A Q_RES_0201LF-1K,1%,1/20W,CHIP,CS21001FE07    I83 @T6G_MB_LIB.T6G(SCH_1):PAGE462
  R927    2      B Q_RES_0201LF-1K,1%,1/20W,EMPTY,CS21001FE07    I84 @T6G_MB_LIB.T6G(SCH_1):PAGE462
 U6017  F34 SMB_ADDR1 PT5161LRS-PT5161LRS,SMLF,IC,AJ051610U03    I97 @T6G_MB_LIB.T6G(SCH_1):PAGE462

RT_CPU1_P3_ADDR2 @T6G_MB_LIB.T6G(SCH_1):RT_CPU1_P3_ADDR2
  R906    1      A Q_RES_0201LF-20K,1%,1/20W,CHIP,CS32001FE00    I81 @T6G_MB_LIB.T6G(SCH_1):PAGE462
  R904    2      B Q_RES_0201LF-1K,1%,1/20W,EMPTY,CS21001FE07    I82 @T6G_MB_LIB.T6G(SCH_1):PAGE462
 U6017  B23 SMB_ADDR2 PT5161LRS-PT5161LRS,SMLF,IC,AJ051610U03    I97 @T6G_MB_LIB.T6G(SCH_1):PAGE462

RT_CPU1_P3_ADDR3 @T6G_MB_LIB.T6G(SCH_1):RT_CPU1_P3_ADDR3
  R903    1      A Q_RES_0201LF-1K,1%,1/20W,EMPTY,CS21001FE07    I79 @T6G_MB_LIB.T6G(SCH_1):PAGE462
  R902    2      B Q_RES_0201LF-1K,1%,1/20W,CHIP,CS21001FE07    I80 @T6G_MB_LIB.T6G(SCH_1):PAGE462
 U6017  B25 SMB_ADDR3 PT5161LRS-PT5161LRS,SMLF,IC,AJ051610U03    I97 @T6G_MB_LIB.T6G(SCH_1):PAGE462

RT_CPU1_P3_SCAN_MODE @T6G_MB_LIB.T6G(SCH_1):RT_CPU1_P3_SCAN_MODE
  R909    2      B Q_RES_0201LF-4.7K,5%,1/20W,EMPTY,CS24701JE04    I17 @T6G_MB_LIB.T6G(SCH_1):PAGE462
 U6017 FF33 SCAN_MODE PT5161LRS-PT5161LRS,SMLF,IC,AJ051610U03    I97 @T6G_MB_LIB.T6G(SCH_1):PAGE462
  R910    1      A Q_RES_0201LF-200,1%,1/20W,CHIP,CS12001FE12   I119 @T6G_MB_LIB.T6G(SCH_1):PAGE462

RT_CPU1_P3_VQPS @T6G_MB_LIB.T6G(SCH_1):RT_CPU1_P3_VQPS
 U6017   G1   VQPS PT5161LRS-PT5161LRS,SMLF,IC,AJ051610U03     I5 @T6G_MB_LIB.T6G(SCH_1):PAGE463
 R6901    1      A Q_RES_0201LF-200,1%,1/20W,CHIP,CS12001FE12    I18 @T6G_MB_LIB.T6G(SCH_1):PAGE463
 R6900    2      B Q_RES_0201LF-1K,1%,1/20W,EMPTY,CS21001FE07    I19 @T6G_MB_LIB.T6G(SCH_1):PAGE463

RT_ROM_MUX1_OE_N @T6G_MB_LIB.T6G(SCH_1):RT_ROM_MUX1_OE_N
   U45    6    OE# PI3CSW12ZUAEX-PI3CSW12ZUAEX,SMLF,IC,AL3CSW12000    I22 @T6G_MB_LIB.T6G(SCH_1):PAGE376
 R1215    2      B Q_RES_0201LF-1K,1%,1/20W,CHIP,CS21001FE07    I28 @T6G_MB_LIB.T6G(SCH_1):PAGE376

RT_ROM_MUX2_OE_N @T6G_MB_LIB.T6G(SCH_1):RT_ROM_MUX2_OE_N
   U42    6    OE# PI3CSW12ZUAEX-PI3CSW12ZUAEX,SMLF,IC,AL3CSW12000    I31 @T6G_MB_LIB.T6G(SCH_1):PAGE376
 R1213    2      B Q_RES_0201LF-1K,1%,1/20W,CHIP,CS21001FE07    I41 @T6G_MB_LIB.T6G(SCH_1):PAGE376

RT_ROM_MUX3_OE_N @T6G_MB_LIB.T6G(SCH_1):RT_ROM_MUX3_OE_N
   U41    6    OE# PI3CSW12ZUAEX-PI3CSW12ZUAEX,SMLF,IC,AL3CSW12000    I46 @T6G_MB_LIB.T6G(SCH_1):PAGE376
 R1212    2      B Q_RES_0201LF-1K,1%,1/20W,CHIP,CS21001FE07    I54 @T6G_MB_LIB.T6G(SCH_1):PAGE376

RT_ROM_MUX4_OE_N @T6G_MB_LIB.T6G(SCH_1):RT_ROM_MUX4_OE_N
   U43    6    OE# PI3CSW12ZUAEX-PI3CSW12ZUAEX,SMLF,IC,AL3CSW12000    I61 @T6G_MB_LIB.T6G(SCH_1):PAGE376
 R1214    2      B Q_RES_0201LF-1K,1%,1/20W,CHIP,CS21001FE07    I69 @T6G_MB_LIB.T6G(SCH_1):PAGE376

RT_ROM_MUX5_OE_N @T6G_MB_LIB.T6G(SCH_1):RT_ROM_MUX5_OE_N
   U49    6    OE# PI3CSW12ZUAEX-PI3CSW12ZUAEX,SMLF,IC,AL3CSW12000    I85 @T6G_MB_LIB.T6G(SCH_1):PAGE376
 R1219    2      B Q_RES_0201LF-1K,1%,1/20W,CHIP,CS21001FE07    I87 @T6G_MB_LIB.T6G(SCH_1):PAGE376

RT_ROM_MUX6_OE_N @T6G_MB_LIB.T6G(SCH_1):RT_ROM_MUX6_OE_N
   U48    6    OE# PI3CSW12ZUAEX-PI3CSW12ZUAEX,SMLF,IC,AL3CSW12000    I76 @T6G_MB_LIB.T6G(SCH_1):PAGE376
 R1218    2      B Q_RES_0201LF-1K,1%,1/20W,CHIP,CS21001FE07   I110 @T6G_MB_LIB.T6G(SCH_1):PAGE376

RT_ROM_MUX7_OE_N @T6G_MB_LIB.T6G(SCH_1):RT_ROM_MUX7_OE_N
   U46    6    OE# PI3CSW12ZUAEX-PI3CSW12ZUAEX,SMLF,IC,AL3CSW12000   I108 @T6G_MB_LIB.T6G(SCH_1):PAGE376
 R1216    2      B Q_RES_0201LF-1K,1%,1/20W,CHIP,CS21001FE07   I116 @T6G_MB_LIB.T6G(SCH_1):PAGE376

RT_ROM_MUX8_OE_N @T6G_MB_LIB.T6G(SCH_1):RT_ROM_MUX8_OE_N
   U47    6    OE# PI3CSW12ZUAEX-PI3CSW12ZUAEX,SMLF,IC,AL3CSW12000   I121 @T6G_MB_LIB.T6G(SCH_1):PAGE376
 R1217    2      B Q_RES_0201LF-1K,1%,1/20W,CHIP,CS21001FE07   I122 @T6G_MB_LIB.T6G(SCH_1):PAGE376

RT_ROM_SMB_MUX_ADDR0 @T6G_MB_LIB.T6G(SCH_1):RT_ROM_SMB_MUX_ADDR0
  R847    1      A Q_RES_0201LF-4.7K,5%,1/20W,CHIP,CS24701JE04     I8 @T6G_MB_LIB.T6G(SCH_1):PAGE377
  R844    2      B Q_RES_0201LF-4.7K,5%,1/20W,EMPTY,CS24701JE04     I9 @T6G_MB_LIB.T6G(SCH_1):PAGE377
   U22    1     A0 TCA9548APWR-TCA9548APWR,SMLF,IC,AL009548K02    I94 @T6G_MB_LIB.T6G(SCH_1):PAGE377

RT_ROM_SMB_MUX_ADDR1 @T6G_MB_LIB.T6G(SCH_1):RT_ROM_SMB_MUX_ADDR1
  R846    1      A Q_RES_0201LF-4.7K,5%,1/20W,CHIP,CS24701JE04     I3 @T6G_MB_LIB.T6G(SCH_1):PAGE377
  R843    2      B Q_RES_0201LF-4.7K,5%,1/20W,EMPTY,CS24701JE04     I5 @T6G_MB_LIB.T6G(SCH_1):PAGE377
   U22    2     A1 TCA9548APWR-TCA9548APWR,SMLF,IC,AL009548K02    I94 @T6G_MB_LIB.T6G(SCH_1):PAGE377

RT_ROM_SMB_MUX_ADDR2 @T6G_MB_LIB.T6G(SCH_1):RT_ROM_SMB_MUX_ADDR2
  R845    1      A Q_RES_0201LF-4.7K,5%,1/20W,CHIP,CS24701JE04     I2 @T6G_MB_LIB.T6G(SCH_1):PAGE377
  R842    2      B Q_RES_0201LF-4.7K,5%,1/20W,EMPTY,CS24701JE04     I4 @T6G_MB_LIB.T6G(SCH_1):PAGE377
   U22   21     A2 TCA9548APWR-TCA9548APWR,SMLF,IC,AL009548K02    I94 @T6G_MB_LIB.T6G(SCH_1):PAGE377

RT_SMB_MUX_ADDR0 @T6G_MB_LIB.T6G(SCH_1):RT_SMB_MUX_ADDR0
 U6020    1     A0 TCA9548APWR-TCA9548APWR,SMLF,IC,AL009548K02     I1 @T6G_MB_LIB.T6G(SCH_1):PAGE378
 R6775    1      A Q_RES_0201LF-4.7K,5%,1/20W,CHIP,CS24701JE04    I97 @T6G_MB_LIB.T6G(SCH_1):PAGE378
 R6772    2      B Q_RES_0201LF-4.7K,5%,1/20W,EMPTY,CS24701JE04    I98 @T6G_MB_LIB.T6G(SCH_1):PAGE378

RT_SMB_MUX_ADDR1 @T6G_MB_LIB.T6G(SCH_1):RT_SMB_MUX_ADDR1
 U6020    2     A1 TCA9548APWR-TCA9548APWR,SMLF,IC,AL009548K02     I1 @T6G_MB_LIB.T6G(SCH_1):PAGE378
 R6774    1      A Q_RES_0201LF-4.7K,5%,1/20W,CHIP,CS24701JE04    I95 @T6G_MB_LIB.T6G(SCH_1):PAGE378
 R6771    2      B Q_RES_0201LF-4.7K,5%,1/20W,EMPTY,CS24701JE04   I100 @T6G_MB_LIB.T6G(SCH_1):PAGE378

RT_SMB_MUX_ADDR2 @T6G_MB_LIB.T6G(SCH_1):RT_SMB_MUX_ADDR2
 U6020   21     A2 TCA9548APWR-TCA9548APWR,SMLF,IC,AL009548K02     I1 @T6G_MB_LIB.T6G(SCH_1):PAGE378
 R6773    1      A Q_RES_0201LF-4.7K,5%,1/20W,CHIP,CS24701JE04    I94 @T6G_MB_LIB.T6G(SCH_1):PAGE378
 R6770    2      B Q_RES_0201LF-4.7K,5%,1/20W,EMPTY,CS24701JE04    I96 @T6G_MB_LIB.T6G(SCH_1):PAGE378

RXDET_BYP_RT_CPU0_P0 @T6G_MB_LIB.T6G(SCH_1):RXDET_BYP_RT_CPU0_P0
 U6010  E11 RXDET_BYP PT5161LRS-PT5161LRS,SMLF,IC,AJ051610U03    I53 @T6G_MB_LIB.T6G(SCH_1):PAGE385
 R1370    1      A Q_RES_0201LF-10K,1%,1/20W,CHIP,CS31001FE17   I114 @T6G_MB_LIB.T6G(SCH_1):PAGE385
 R1369    2      B Q_RES_0201LF-1K,1%,1/20W,EMPTY,CS21001FE07   I116 @T6G_MB_LIB.T6G(SCH_1):PAGE385

RXDET_BYP_RT_CPU0_P1 @T6G_MB_LIB.T6G(SCH_1):RXDET_BYP_RT_CPU0_P1
 U6011  E11 RXDET_BYP PT5161LRS-PT5161LRS,SMLF,IC,AJ051610U03    I83 @T6G_MB_LIB.T6G(SCH_1):PAGE408
 R1398    1      A Q_RES_0201LF-10K,1%,1/20W,CHIP,CS31001FE17    I98 @T6G_MB_LIB.T6G(SCH_1):PAGE408
 R1397    2      B Q_RES_0201LF-1K,1%,1/20W,EMPTY,CS21001FE07    I99 @T6G_MB_LIB.T6G(SCH_1):PAGE408

RXDET_BYP_RT_CPU0_P2 @T6G_MB_LIB.T6G(SCH_1):RXDET_BYP_RT_CPU0_P2
 U6012  E11 RXDET_BYP PT5161LRS-PT5161LRS,SMLF,IC,AJ051610U03    I83 @T6G_MB_LIB.T6G(SCH_1):PAGE419
 R1406    1      A Q_RES_0201LF-10K,1%,1/20W,CHIP,CS31001FE17    I95 @T6G_MB_LIB.T6G(SCH_1):PAGE419
 R1405    2      B Q_RES_0201LF-1K,1%,1/20W,EMPTY,CS21001FE07    I96 @T6G_MB_LIB.T6G(SCH_1):PAGE419

RXDET_BYP_RT_CPU0_P3 @T6G_MB_LIB.T6G(SCH_1):RXDET_BYP_RT_CPU0_P3
 U6013  E11 RXDET_BYP PT5161LRS-PT5161LRS,SMLF,IC,AJ051610U03    I83 @T6G_MB_LIB.T6G(SCH_1):PAGE430
 R1414    1      A Q_RES_0201LF-10K,1%,1/20W,CHIP,CS31001FE17    I96 @T6G_MB_LIB.T6G(SCH_1):PAGE430
 R1413    2      B Q_RES_0201LF-1K,1%,1/20W,EMPTY,CS21001FE07    I97 @T6G_MB_LIB.T6G(SCH_1):PAGE430

RXDET_BYP_RT_CPU1_P0 @T6G_MB_LIB.T6G(SCH_1):RXDET_BYP_RT_CPU1_P0
 U6014  E11 RXDET_BYP PT5161LRS-PT5161LRS,SMLF,IC,AJ051610U03     I1 @T6G_MB_LIB.T6G(SCH_1):PAGE401
 R1389    1      A Q_RES_0201LF-10K,1%,1/20W,CHIP,CS31001FE17   I124 @T6G_MB_LIB.T6G(SCH_1):PAGE401
 R1388    2      B Q_RES_0201LF-1K,1%,1/20W,EMPTY,CS21001FE07   I125 @T6G_MB_LIB.T6G(SCH_1):PAGE401

RXDET_BYP_RT_CPU1_P1 @T6G_MB_LIB.T6G(SCH_1):RXDET_BYP_RT_CPU1_P1
 U6015  E11 RXDET_BYP PT5161LRS-PT5161LRS,SMLF,IC,AJ051610U03    I47 @T6G_MB_LIB.T6G(SCH_1):PAGE392
 R1377    2      B Q_RES_0201LF-1K,1%,1/20W,EMPTY,CS21001FE07   I125 @T6G_MB_LIB.T6G(SCH_1):PAGE392
 R1378    1      A Q_RES_0201LF-10K,1%,1/20W,CHIP,CS31001FE17   I126 @T6G_MB_LIB.T6G(SCH_1):PAGE392

RXDET_BYP_RT_CPU1_P2 @T6G_MB_LIB.T6G(SCH_1):RXDET_BYP_RT_CPU1_P2
 U6016  E11 RXDET_BYP PT5161LRS-PT5161LRS,SMLF,IC,AJ051610U03    I97 @T6G_MB_LIB.T6G(SCH_1):PAGE451
 R1427    1      A Q_RES_0201LF-10K,1%,1/20W,CHIP,CS31001FE17   I113 @T6G_MB_LIB.T6G(SCH_1):PAGE451
 R1426    2      B Q_RES_0201LF-1K,1%,1/20W,EMPTY,CS21001FE07   I114 @T6G_MB_LIB.T6G(SCH_1):PAGE451

RXDET_BYP_RT_CPU1_P3 @T6G_MB_LIB.T6G(SCH_1):RXDET_BYP_RT_CPU1_P3
 U6017  E11 RXDET_BYP PT5161LRS-PT5161LRS,SMLF,IC,AJ051610U03    I97 @T6G_MB_LIB.T6G(SCH_1):PAGE462
 R1435    1      A Q_RES_0201LF-10K,1%,1/20W,CHIP,CS31001FE17   I114 @T6G_MB_LIB.T6G(SCH_1):PAGE462
 R1434    2      B Q_RES_0201LF-1K,1%,1/20W,EMPTY,CS21001FE07   I115 @T6G_MB_LIB.T6G(SCH_1):PAGE462

SCM_HDT_DBREQ_N @T6G_MB_LIB.T6G(SCH_1):SCM_HDT_DBREQ_N
 R6032    2      B Q_RES_0402LF-0,5%,1/16W,CHIP,CS00002JB13    I28 @T6G_MB_LIB.T6G(SCH_1):PAGE348
   J41  A49 GND_A49 SCONN168_ME1016810202011-SCONN168_ME1016810202011,A   I176 @T6G_MB_LIB.T6G(SCH_1):PAGE348

SCM_IRQ_1V8_N @T6G_MB_LIB.T6G(SCH_1):SCM_IRQ_1V8_N
  R174    2      B Q_RES_0402LF-33,5%,1/16W,CHIP,CS03302JB10   I160 @T6G_MB_LIB.T6G(SCH_1):PAGE80
  R996    2      B Q_RES_0402LF-4.7K,5%,1/16W,CHIP,CS24702JB10    I22 @T6G_MB_LIB.T6G(SCH_1):PAGE83
   U92    2      A SN74LVC1G07DBVR_SMLF-SN74LVC1G07DBVR,IC,AL1G0007024    I26 @T6G_MB_LIB.T6G(SCH_1):PAGE83

SCM_IRQ_1V8_R_N @T6G_MB_LIB.T6G(SCH_1):SCM_IRQ_1V8_R_N
  R174    1      A Q_RES_0402LF-33,5%,1/16W,CHIP,CS03302JB10   I160 @T6G_MB_LIB.T6G(SCH_1):PAGE80
   U18  T20  PR26D LCMXO3LF9400C5BG484C-LCMXO3LF-9400C-5BG484C,SMLF,IA   I217 @T6G_MB_LIB.T6G(SCH_1):PAGE80

SCM_IRQ_N @T6G_MB_LIB.T6G(SCH_1):SCM_IRQ_N
  R321    1      A Q_RES_0402LF-0,5%,1/16W,CHIP,CS00002JB13    I24 @T6G_MB_LIB.T6G(SCH_1):PAGE348
   R71    2      B Q_RES_0402LF-33,5%,1/16W,CHIP,CS03302JB10    I27 @T6G_MB_LIB.T6G(SCH_1):PAGE83
 R1338    2      B Q_RES_0402LF-4.7K,5%,1/16W,CHIP,CS24702JB10    I29 @T6G_MB_LIB.T6G(SCH_1):PAGE83

SCM_IRQ_R_N @T6G_MB_LIB.T6G(SCH_1):SCM_IRQ_R_N
   U92    4      Y SN74LVC1G07DBVR_SMLF-SN74LVC1G07DBVR,IC,AL1G0007024    I26 @T6G_MB_LIB.T6G(SCH_1):PAGE83
   R71    1      A Q_RES_0402LF-33,5%,1/16W,CHIP,CS03302JB10    I27 @T6G_MB_LIB.T6G(SCH_1):PAGE83

SCM_JTAG_MUX_R_S0 @T6G_MB_LIB.T6G(SCH_1):SCM_JTAG_MUX_R_S0
   R49    1      A Q_RES_0402LF-33,5%,1/16W,CHIP,CS03302JB10    I46 @T6G_MB_LIB.T6G(SCH_1):PAGE79
   U18   B3  PT11A LCMXO3LF9400C5BG484C-LCMXO3LF-9400C-5BG484C,SMLF,IA    I94 @T6G_MB_LIB.T6G(SCH_1):PAGE79

SCM_JTAG_MUX_R_S1 @T6G_MB_LIB.T6G(SCH_1):SCM_JTAG_MUX_R_S1
   R50    1      A Q_RES_0402LF-33,5%,1/16W,CHIP,CS03302JB10    I49 @T6G_MB_LIB.T6G(SCH_1):PAGE79
   U18   A3  PT10B LCMXO3LF9400C5BG484C-LCMXO3LF-9400C-5BG484C,SMLF,IA    I94 @T6G_MB_LIB.T6G(SCH_1):PAGE79

SCM_JTAG_MUX_S0 @T6G_MB_LIB.T6G(SCH_1):SCM_JTAG_MUX_S0
 R1659    2      B Q_RES_0402LF-4.7K,5%,1/16W,EMPTY,CS24702JB10   I309 @T6G_MB_LIB.T6G(SCH_1):PAGE148
 R1658    1      A Q_RES_0402LF-4.7K,5%,1/16W,CHIP,CS24702JB10   I310 @T6G_MB_LIB.T6G(SCH_1):PAGE148
   R49    2      B Q_RES_0402LF-33,5%,1/16W,CHIP,CS03302JB10    I46 @T6G_MB_LIB.T6G(SCH_1):PAGE79
 R6101    1      A Q_RES_0402LF-0,5%,1/16W,CHIP,CS00002JB13   I375 @T6G_MB_LIB.T6G(SCH_1):PAGE148
 R6102    1      A Q_RES_0402LF-0,5%,1/16W,CHIP,CS00002JB13   I376 @T6G_MB_LIB.T6G(SCH_1):PAGE148

SCM_JTAG_MUX_S0_R1 @T6G_MB_LIB.T6G(SCH_1):SCM_JTAG_MUX_S0_R1
  U160   10     S0 74LV4052PW-74LV4052PW,SMLF,IC,ALLV4052K19   I266 @T6G_MB_LIB.T6G(SCH_1):PAGE148
 R6101    2      B Q_RES_0402LF-0,5%,1/16W,CHIP,CS00002JB13   I375 @T6G_MB_LIB.T6G(SCH_1):PAGE148

SCM_JTAG_MUX_S0_R2 @T6G_MB_LIB.T6G(SCH_1):SCM_JTAG_MUX_S0_R2
  U212   10     S0 74LV4052PW-74LV4052PW,SMLF,IC,ALLV4052K19   I302 @T6G_MB_LIB.T6G(SCH_1):PAGE148
 R6102    2      B Q_RES_0402LF-0,5%,1/16W,CHIP,CS00002JB13   I376 @T6G_MB_LIB.T6G(SCH_1):PAGE148

SCM_JTAG_MUX_S1 @T6G_MB_LIB.T6G(SCH_1):SCM_JTAG_MUX_S1
  U160    9     S1 74LV4052PW-74LV4052PW,SMLF,IC,ALLV4052K19   I266 @T6G_MB_LIB.T6G(SCH_1):PAGE148
  U212    9     S1 74LV4052PW-74LV4052PW,SMLF,IC,ALLV4052K19   I302 @T6G_MB_LIB.T6G(SCH_1):PAGE148
 R1730    2      B Q_RES_0402LF-4.7K,5%,1/16W,EMPTY,CS24702JB10   I305 @T6G_MB_LIB.T6G(SCH_1):PAGE148
 R1729    1      A Q_RES_0402LF-4.7K,5%,1/16W,CHIP,CS24702JB10   I306 @T6G_MB_LIB.T6G(SCH_1):PAGE148
 R1343    2      B Q_RES_0402LF-4.7K,5%,1/16W,EMPTY,CS24702JB10   I339 @T6G_MB_LIB.T6G(SCH_1):PAGE148
   U99    4      Y SN74LVC1G07DBVR_SMLF-SN74LVC1G07DBVR,EMPTY,AL1G000A   I340 @T6G_MB_LIB.T6G(SCH_1):PAGE148
   R50    2      B Q_RES_0402LF-33,5%,1/16W,CHIP,CS03302JB10    I49 @T6G_MB_LIB.T6G(SCH_1):PAGE79

SCM_ROT_CPU_RST_N @T6G_MB_LIB.T6G(SCH_1):SCM_ROT_CPU_RST_N
 R1798    2      B Q_RES_0402LF-0,5%,1/16W,CHIP,CS00002JB13    I26 @T6G_MB_LIB.T6G(SCH_1):PAGE348
   J41  A53 PERN11 SCONN168_ME1016810202011-SCONN168_ME1016810202011,A   I176 @T6G_MB_LIB.T6G(SCH_1):PAGE348

SCM_ROT_CPU_RST_R_N @T6G_MB_LIB.T6G(SCH_1):SCM_ROT_CPU_RST_R_N
 R6035    1      A Q_RES_0402LF-4.7K,5%,1/16W,EMPTY,CS24702JB10    I17 @T6G_MB_LIB.T6G(SCH_1):PAGE348
 R6034    2      B Q_RES_0402LF-1K,1%,1/16W,CHIP,CS21002FB06    I18 @T6G_MB_LIB.T6G(SCH_1):PAGE348
 R1798    1      A Q_RES_0402LF-0,5%,1/16W,CHIP,CS00002JB13    I26 @T6G_MB_LIB.T6G(SCH_1):PAGE348
   U18  C13  PT29C LCMXO3LF9400C5BG484C-LCMXO3LF-9400C-5BG484C,SMLF,IA    I94 @T6G_MB_LIB.T6G(SCH_1):PAGE79

SCM_SPARE_0 @T6G_MB_LIB.T6G(SCH_1):SCM_SPARE_0
  R888    2      B Q_RES_0402LF-10K,5%,1/16W,EMPTY,CS31002JB08   I145 @T6G_MB_LIB.T6G(SCH_1):PAGE349
   U18  G14  PT31A LCMXO3LF9400C5BG484C-LCMXO3LF-9400C-5BG484C,SMLF,IA    I94 @T6G_MB_LIB.T6G(SCH_1):PAGE79
  R889    1      A Q_RES_0402LF-10K,5%,1/16W,EMPTY,CS31002JB08   I142 @T6G_MB_LIB.T6G(SCH_1):PAGE349

SCM_SPARE_1 @T6G_MB_LIB.T6G(SCH_1):SCM_SPARE_1
  R890    2      B Q_RES_0402LF-10K,5%,1/16W,EMPTY,CS31002JB08   I147 @T6G_MB_LIB.T6G(SCH_1):PAGE349
   U18  F14  PT31B LCMXO3LF9400C5BG484C-LCMXO3LF-9400C-5BG484C,SMLF,IA    I94 @T6G_MB_LIB.T6G(SCH_1):PAGE79
  R891    1      A Q_RES_0402LF-10K,5%,1/16W,EMPTY,CS31002JB08   I144 @T6G_MB_LIB.T6G(SCH_1):PAGE349

SCM_SYS_PWRBTN_N @T6G_MB_LIB.T6G(SCH_1):SCM_SYS_PWRBTN_N
 R1815    1      A Q_RES_0402LF-0,5%,1/16W,CHIP,CS00002JB13    I29 @T6G_MB_LIB.T6G(SCH_1):PAGE348
   U18  E12  PT27B LCMXO3LF9400C5BG484C-LCMXO3LF-9400C-5BG484C,SMLF,IA    I94 @T6G_MB_LIB.T6G(SCH_1):PAGE79
   R64    1      A Q_RES_0402LF-1K,1%,1/16W,EMPTY,CS21002FB06   I166 @T6G_MB_LIB.T6G(SCH_1):PAGE82

SCM_SYS_PWRBTN_R_N @T6G_MB_LIB.T6G(SCH_1):SCM_SYS_PWRBTN_R_N
 R1815    2      B Q_RES_0402LF-0,5%,1/16W,CHIP,CS00002JB13    I29 @T6G_MB_LIB.T6G(SCH_1):PAGE348
   J41  A47  PERN9 SCONN168_ME1016810202011-SCONN168_ME1016810202011,A   I176 @T6G_MB_LIB.T6G(SCH_1):PAGE348

SCM_SYS_PWROK @T6G_MB_LIB.T6G(SCH_1):SCM_SYS_PWROK
   R63    2      B Q_RES_0402LF-33,5%,1/16W,CHIP,CS03302JB10    I79 @T6G_MB_LIB.T6G(SCH_1):PAGE79
   U18  A15  PT38A LCMXO3LF9400C5BG484C-LCMXO3LF-9400C-5BG484C,SMLF,IA    I94 @T6G_MB_LIB.T6G(SCH_1):PAGE79

SCM_SYS_PWROK_R @T6G_MB_LIB.T6G(SCH_1):SCM_SYS_PWROK_R
   R63    1      A Q_RES_0402LF-33,5%,1/16W,CHIP,CS03302JB10    I79 @T6G_MB_LIB.T6G(SCH_1):PAGE79
 R6092    1      A Q_RES_0402LF-0,5%,1/16W,CHIP,CS00002JB13    I82 @T6G_MB_LIB.T6G(SCH_1):PAGE84
 R6093    1      A Q_RES_0402LF-0,5%,1/16W,CHIP,CS00002JB13    I84 @T6G_MB_LIB.T6G(SCH_1):PAGE84

SCM_SYS_PWROK_R1 @T6G_MB_LIB.T6G(SCH_1):SCM_SYS_PWROK_R1
   J41  A48  PERP9 SCONN168_ME1016810202011-SCONN168_ME1016810202011,A   I176 @T6G_MB_LIB.T6G(SCH_1):PAGE348
 R6092    2      B Q_RES_0402LF-0,5%,1/16W,CHIP,CS00002JB13    I82 @T6G_MB_LIB.T6G(SCH_1):PAGE84

SCM_SYS_PWROK_R2 @T6G_MB_LIB.T6G(SCH_1):SCM_SYS_PWROK_R2
 R6093    2      B Q_RES_0402LF-0,5%,1/16W,CHIP,CS00002JB13    I84 @T6G_MB_LIB.T6G(SCH_1):PAGE84
   Q87    5     G2 MOSFET_NCH_DUAL-PJT138K,SMLF,IC,BAM138K0003    I35 @T6G_MB_LIB.T6G(SCH_1):PAGE254
 C1209    1      A Q_CAP_0402-100PF,50V,5%,NPO,CH11006JB00    I88 @T6G_MB_LIB.T6G(SCH_1):PAGE84

SCM_USB_OC_BUF_N @T6G_MB_LIB.T6G(SCH_1):SCM_USB_OC_BUF_N
   U25  E23 USB00_OC_L||AGPIO264 GENOA_SP5-SOCKET6096_13568-001,SMLF,IO,DGA^6000030   I287 @T6G_MB_LIB.T6G(SCH_1):PAGE29
  R589    2      B Q_RES_0402LF-0,5%,1/16W,CHIP,CS00002JB13   I377 @T6G_MB_LIB.T6G(SCH_1):PAGE29
  R454    2      B Q_RES_0402LF-10K,5%,1/16W,CHIP,CS31002JB08   I383 @T6G_MB_LIB.T6G(SCH_1):PAGE29

SCM_USB_OC_BU_R_N @T6G_MB_LIB.T6G(SCH_1):SCM_USB_OC_BU_R_N
    U3    4      Y SN74LVC1G07DBVR_SMLF-SN74LVC1G07DBVR,IC,AL1G0007024   I373 @T6G_MB_LIB.T6G(SCH_1):PAGE29
  R589    1      A Q_RES_0402LF-0,5%,1/16W,CHIP,CS00002JB13   I377 @T6G_MB_LIB.T6G(SCH_1):PAGE29

SCM_USB_OC_N @T6G_MB_LIB.T6G(SCH_1):SCM_USB_OC_N
    U3    2      A SN74LVC1G07DBVR_SMLF-SN74LVC1G07DBVR,IC,AL1G0007024   I373 @T6G_MB_LIB.T6G(SCH_1):PAGE29
  R588    2      B Q_RES_0402LF-33,5%,1/16W,CHIP,CS03302JB10   I164 @T6G_MB_LIB.T6G(SCH_1):PAGE80
  R654    1      A Q_RES_0402LF-4.7K,5%,1/16W,CHIP,CS24702JB10    I64 @T6G_MB_LIB.T6G(SCH_1):PAGE82

SCM_USB_OC_R_N @T6G_MB_LIB.T6G(SCH_1):SCM_USB_OC_R_N
  R588    1      A Q_RES_0402LF-33,5%,1/16W,CHIP,CS03302JB10   I164 @T6G_MB_LIB.T6G(SCH_1):PAGE80
   U18  R19  PR25D LCMXO3LF9400C5BG484C-LCMXO3LF-9400C-5BG484C,SMLF,IA   I217 @T6G_MB_LIB.T6G(SCH_1):PAGE80

SCM_VDD_RTC @T6G_MB_LIB.T6G(SCH_1):SCM_VDD_RTC
   J41  B41 GND_B41 SCONN168_ME1016810202011-SCONN168_ME1016810202011,A   I176 @T6G_MB_LIB.T6G(SCH_1):PAGE348
  R364    2      B Q_RES_0402LF-0,5%,1/16W,CHIP,CS00002JB13   I231 @T6G_MB_LIB.T6G(SCH_1):PAGE349
 C6000    1      A Q_CAP_0402-0.1UF,25V,10%,X7R,CH4104K1B00   I219 @T6G_MB_LIB.T6G(SCH_1):PAGE348

SGPIO_OCP_SFF_CLK @T6G_MB_LIB.T6G(SCH_1):SGPIO_OCP_SFF_CLK
   J38  OB6    CLK SCONN168_ME1016810202011-SCONN168_ME1016810202011,A   I168 @T6G_MB_LIB.T6G(SCH_1):PAGE335
 R8423    1      A Q_RES_0402LF-1K,1%,1/16W,CHIP,CS21002FB06    I20 @T6G_MB_LIB.T6G(SCH_1):PAGE335
   U18   C9  PT20C LCMXO3LF9400C5BG484C-LCMXO3LF-9400C-5BG484C,SMLF,IA    I94 @T6G_MB_LIB.T6G(SCH_1):PAGE79

SGPIO_OCP_SFF_DATAIN @T6G_MB_LIB.T6G(SCH_1):SGPIO_OCP_SFF_DATAIN
   J38  OB4 DATA_IN SCONN168_ME1016810202011-SCONN168_ME1016810202011,A   I168 @T6G_MB_LIB.T6G(SCH_1):PAGE335
 R8421    1      A Q_RES_0402LF-10K,1%,1/16W,CHIP,CS31002FB08    I21 @T6G_MB_LIB.T6G(SCH_1):PAGE335
   U18   B8  PT20A LCMXO3LF9400C5BG484C-LCMXO3LF-9400C-5BG484C,SMLF,IA    I94 @T6G_MB_LIB.T6G(SCH_1):PAGE79

SGPIO_OCP_SFF_DATAOUT @T6G_MB_LIB.T6G(SCH_1):SGPIO_OCP_SFF_DATAOUT
   J38  OB5 DATA_OUT SCONN168_ME1016810202011-SCONN168_ME1016810202011,A   I168 @T6G_MB_LIB.T6G(SCH_1):PAGE335
 R8422    1      A Q_RES_0402LF-10K,1%,1/16W,CHIP,CS31002FB08    I19 @T6G_MB_LIB.T6G(SCH_1):PAGE335
   U18   A8  PT20B LCMXO3LF9400C5BG484C-LCMXO3LF-9400C-5BG484C,SMLF,IA    I94 @T6G_MB_LIB.T6G(SCH_1):PAGE79

SGPIO_OCP_SFF_LD_N @T6G_MB_LIB.T6G(SCH_1):SGPIO_OCP_SFF_LD_N
   J38  OB3    LD# SCONN168_ME1016810202011-SCONN168_ME1016810202011,A   I168 @T6G_MB_LIB.T6G(SCH_1):PAGE335
 R8420    1      A Q_RES_0402LF-1K,1%,1/16W,CHIP,CS21002FB06    I22 @T6G_MB_LIB.T6G(SCH_1):PAGE335
   U18   D8  PT15B LCMXO3LF9400C5BG484C-LCMXO3LF-9400C-5BG484C,SMLF,IA    I94 @T6G_MB_LIB.T6G(SCH_1):PAGE79

SGPIO_OCP_V3_2_CLK @T6G_MB_LIB.T6G(SCH_1):SGPIO_OCP_V3_2_CLK
   J35  OB6    CLK SCONN168_ME1016810202011-SCONN168_ME1016810202011,A   I168 @T6G_MB_LIB.T6G(SCH_1):PAGE341
 R3176    1      A Q_RES_0402LF-1K,1%,1/16W,CHIP,CS21002FB06    I12 @T6G_MB_LIB.T6G(SCH_1):PAGE341
   U18  D14  PT30D LCMXO3LF9400C5BG484C-LCMXO3LF-9400C-5BG484C,SMLF,IA    I94 @T6G_MB_LIB.T6G(SCH_1):PAGE79

SGPIO_OCP_V3_2_DATAIN @T6G_MB_LIB.T6G(SCH_1):SGPIO_OCP_V3_2_DATAIN
   J35  OB4 DATA_IN SCONN168_ME1016810202011-SCONN168_ME1016810202011,A   I168 @T6G_MB_LIB.T6G(SCH_1):PAGE341
 R3174    1      A Q_RES_0402LF-10K,1%,1/16W,CHIP,CS31002FB08     I9 @T6G_MB_LIB.T6G(SCH_1):PAGE341
   U18  B14  PT30B LCMXO3LF9400C5BG484C-LCMXO3LF-9400C-5BG484C,SMLF,IA    I94 @T6G_MB_LIB.T6G(SCH_1):PAGE79

SGPIO_OCP_V3_2_DATAOUT @T6G_MB_LIB.T6G(SCH_1):SGPIO_OCP_V3_2_DATAOUT
   J35  OB5 DATA_OUT SCONN168_ME1016810202011-SCONN168_ME1016810202011,A   I168 @T6G_MB_LIB.T6G(SCH_1):PAGE341
 R3175    1      A Q_RES_0402LF-10K,1%,1/16W,CHIP,CS31002FB08    I11 @T6G_MB_LIB.T6G(SCH_1):PAGE341
   U18  C14  PT30C LCMXO3LF9400C5BG484C-LCMXO3LF-9400C-5BG484C,SMLF,IA    I94 @T6G_MB_LIB.T6G(SCH_1):PAGE79

SGPIO_OCP_V3_2_LD_N @T6G_MB_LIB.T6G(SCH_1):SGPIO_OCP_V3_2_LD_N
   J35  OB3    LD# SCONN168_ME1016810202011-SCONN168_ME1016810202011,A   I168 @T6G_MB_LIB.T6G(SCH_1):PAGE341
 R3173    1      A Q_RES_0402LF-1K,1%,1/16W,CHIP,CS21002FB06    I10 @T6G_MB_LIB.T6G(SCH_1):PAGE341
   U18  A14  PT30A LCMXO3LF9400C5BG484C-LCMXO3LF-9400C-5BG484C,SMLF,IA    I94 @T6G_MB_LIB.T6G(SCH_1):PAGE79

SGPIO_SCM_CLK_<0> @T6G_MB_LIB.T6G(SCH_1):SGPIO_SCM_CLK_(0)
 R6017    2      B Q_RES_0402LF-2K,5%,1/16W,EMPTY,TMP_QCS22002JB29    I28 @T6G_MB_LIB.T6G(SCH_1):PAGE349
   U18   D6  PT13C LCMXO3LF9400C5BG484C-LCMXO3LF-9400C-5BG484C,SMLF,IA    I94 @T6G_MB_LIB.T6G(SCH_1):PAGE79
 R6009    1      A Q_RES_0402LF-0,5%,1/16W,CHIP,CS00002JB13   I134 @T6G_MB_LIB.T6G(SCH_1):PAGE348

SGPIO_SCM_CLK_<1> @T6G_MB_LIB.T6G(SCH_1):SGPIO_SCM_CLK_(1)
 R6013    1      A Q_RES_0402LF-0,5%,1/16W,CHIP,CS00002JB13   I130 @T6G_MB_LIB.T6G(SCH_1):PAGE348
   U18  D18  PT41D LCMXO3LF9400C5BG484C-LCMXO3LF-9400C-5BG484C,SMLF,IA    I94 @T6G_MB_LIB.T6G(SCH_1):PAGE79
 R6021    2      B Q_RES_0402LF-2K,5%,1/16W,EMPTY,TMP_QCS22002JB29    I22 @T6G_MB_LIB.T6G(SCH_1):PAGE349

SGPIO_SCM_CLK_R_<0> @T6G_MB_LIB.T6G(SCH_1):SGPIO_SCM_CLK_R_(0)
   J41  B30  PETN4 SCONN168_ME1016810202011-SCONN168_ME1016810202011,A   I176 @T6G_MB_LIB.T6G(SCH_1):PAGE348
 R6009    2      B Q_RES_0402LF-0,5%,1/16W,CHIP,CS00002JB13   I134 @T6G_MB_LIB.T6G(SCH_1):PAGE348

SGPIO_SCM_CLK_R_<1> @T6G_MB_LIB.T6G(SCH_1):SGPIO_SCM_CLK_R_(1)
 R6013    2      B Q_RES_0402LF-0,5%,1/16W,CHIP,CS00002JB13   I130 @T6G_MB_LIB.T6G(SCH_1):PAGE348
   J41  B35 GND_B35 SCONN168_ME1016810202011-SCONN168_ME1016810202011,A   I176 @T6G_MB_LIB.T6G(SCH_1):PAGE348

SGPIO_SCM_DI_<0> @T6G_MB_LIB.T6G(SCH_1):SGPIO_SCM_DI_(0)
  R167    2      B Q_RES_0402LF-0,5%,1/16W,CHIP,CS00002JB13    I45 @T6G_MB_LIB.T6G(SCH_1):PAGE79
 R6010    1      A Q_RES_0402LF-0,5%,1/16W,CHIP,CS00002JB13   I133 @T6G_MB_LIB.T6G(SCH_1):PAGE348
 R6018    2      B Q_RES_0402LF-2K,5%,1/16W,EMPTY,TMP_QCS22002JB29    I27 @T6G_MB_LIB.T6G(SCH_1):PAGE349

SGPIO_SCM_DI_<1> @T6G_MB_LIB.T6G(SCH_1):SGPIO_SCM_DI_(1)
 R6014    1      A Q_RES_0402LF-0,5%,1/16W,CHIP,CS00002JB13   I128 @T6G_MB_LIB.T6G(SCH_1):PAGE348
  R168    2      B Q_RES_0402LF-0,5%,1/16W,CHIP,CS00002JB13    I24 @T6G_MB_LIB.T6G(SCH_1):PAGE79
 R6022    2      B Q_RES_0402LF-2K,5%,1/16W,EMPTY,TMP_QCS22002JB29    I23 @T6G_MB_LIB.T6G(SCH_1):PAGE349

SGPIO_SCM_DI_R<0> @T6G_MB_LIB.T6G(SCH_1):SGPIO_SCM_DI_R(0)
  R167    1      A Q_RES_0402LF-0,5%,1/16W,CHIP,CS00002JB13    I45 @T6G_MB_LIB.T6G(SCH_1):PAGE79
   U18   A4  PT11B LCMXO3LF9400C5BG484C-LCMXO3LF-9400C-5BG484C,SMLF,IA    I94 @T6G_MB_LIB.T6G(SCH_1):PAGE79

SGPIO_SCM_DI_R<1> @T6G_MB_LIB.T6G(SCH_1):SGPIO_SCM_DI_R(1)
  R168    1      A Q_RES_0402LF-0,5%,1/16W,CHIP,CS00002JB13    I24 @T6G_MB_LIB.T6G(SCH_1):PAGE79
   U18   C6  PT14C LCMXO3LF9400C5BG484C-LCMXO3LF-9400C-5BG484C,SMLF,IA    I94 @T6G_MB_LIB.T6G(SCH_1):PAGE79

SGPIO_SCM_DI_R_<0> @T6G_MB_LIB.T6G(SCH_1):SGPIO_SCM_DI_R_(0)
   J41  B31  PETP4 SCONN168_ME1016810202011-SCONN168_ME1016810202011,A   I176 @T6G_MB_LIB.T6G(SCH_1):PAGE348
 R6010    2      B Q_RES_0402LF-0,5%,1/16W,CHIP,CS00002JB13   I133 @T6G_MB_LIB.T6G(SCH_1):PAGE348

SGPIO_SCM_DI_R_<1> @T6G_MB_LIB.T6G(SCH_1):SGPIO_SCM_DI_R_(1)
 R6014    2      B Q_RES_0402LF-0,5%,1/16W,CHIP,CS00002JB13   I128 @T6G_MB_LIB.T6G(SCH_1):PAGE348
   J41  B36  PETN6 SCONN168_ME1016810202011-SCONN168_ME1016810202011,A   I176 @T6G_MB_LIB.T6G(SCH_1):PAGE348

SGPIO_SCM_DO_<0> @T6G_MB_LIB.T6G(SCH_1):SGPIO_SCM_DO_(0)
 R6016    2      B Q_RES_0402LF-2K,5%,1/16W,EMPTY,TMP_QCS22002JB29    I29 @T6G_MB_LIB.T6G(SCH_1):PAGE349
   U18   E7  PT13D LCMXO3LF9400C5BG484C-LCMXO3LF-9400C-5BG484C,SMLF,IA    I94 @T6G_MB_LIB.T6G(SCH_1):PAGE79
 R6008    1      A Q_RES_0402LF-0,5%,1/16W,CHIP,CS00002JB13   I135 @T6G_MB_LIB.T6G(SCH_1):PAGE348

SGPIO_SCM_DO_<1> @T6G_MB_LIB.T6G(SCH_1):SGPIO_SCM_DO_(1)
   U18   B4  PT12A LCMXO3LF9400C5BG484C-LCMXO3LF-9400C-5BG484C,SMLF,IA    I94 @T6G_MB_LIB.T6G(SCH_1):PAGE79
 R6012    1      A Q_RES_0402LF-0,5%,1/16W,CHIP,CS00002JB13   I131 @T6G_MB_LIB.T6G(SCH_1):PAGE348
 R6020    2      B Q_RES_0402LF-2K,5%,1/16W,EMPTY,TMP_QCS22002JB29    I24 @T6G_MB_LIB.T6G(SCH_1):PAGE349

SGPIO_SCM_DO_R_<0> @T6G_MB_LIB.T6G(SCH_1):SGPIO_SCM_DO_R_(0)
   J41  B29 GND_B29 SCONN168_ME1016810202011-SCONN168_ME1016810202011,A   I176 @T6G_MB_LIB.T6G(SCH_1):PAGE348
 R6008    2      B Q_RES_0402LF-0,5%,1/16W,CHIP,CS00002JB13   I135 @T6G_MB_LIB.T6G(SCH_1):PAGE348

SGPIO_SCM_DO_R_<1> @T6G_MB_LIB.T6G(SCH_1):SGPIO_SCM_DO_R_(1)
   J41  B34  PETP5 SCONN168_ME1016810202011-SCONN168_ME1016810202011,A   I176 @T6G_MB_LIB.T6G(SCH_1):PAGE348
 R6012    2      B Q_RES_0402LF-0,5%,1/16W,CHIP,CS00002JB13   I131 @T6G_MB_LIB.T6G(SCH_1):PAGE348

SGPIO_SCM_INTR_N @T6G_MB_LIB.T6G(SCH_1):SGPIO_SCM_INTR_N
   R58    2      B Q_RES_0402LF-33,5%,1/16W,CHIP,CS03302JB10    I44 @T6G_MB_LIB.T6G(SCH_1):PAGE79
 R6026    1      A Q_RES_0402LF-0,5%,1/16W,CHIP,CS00002JB13    I42 @T6G_MB_LIB.T6G(SCH_1):PAGE348
 R6024    2      B Q_RES_0402LF-4.7K,5%,1/16W,EMPTY,CS24702JB10    I20 @T6G_MB_LIB.T6G(SCH_1):PAGE349

SGPIO_SCM_INTR_R1_N @T6G_MB_LIB.T6G(SCH_1):SGPIO_SCM_INTR_R1_N
   J41  B40  PETP7 SCONN168_ME1016810202011-SCONN168_ME1016810202011,A   I176 @T6G_MB_LIB.T6G(SCH_1):PAGE348
 R6026    2      B Q_RES_0402LF-0,5%,1/16W,CHIP,CS00002JB13    I42 @T6G_MB_LIB.T6G(SCH_1):PAGE348

SGPIO_SCM_INTR_R_N @T6G_MB_LIB.T6G(SCH_1):SGPIO_SCM_INTR_R_N
   R58    1      A Q_RES_0402LF-33,5%,1/16W,CHIP,CS03302JB10    I44 @T6G_MB_LIB.T6G(SCH_1):PAGE79
   U18   G8  PT11D LCMXO3LF9400C5BG484C-LCMXO3LF-9400C-5BG484C,SMLF,IA    I94 @T6G_MB_LIB.T6G(SCH_1):PAGE79

SGPIO_SCM_LD_<0> @T6G_MB_LIB.T6G(SCH_1):SGPIO_SCM_LD_(0)
   U18   D7  PT14D LCMXO3LF9400C5BG484C-LCMXO3LF-9400C-5BG484C,SMLF,IA    I94 @T6G_MB_LIB.T6G(SCH_1):PAGE79
 R6011    1      A Q_RES_0402LF-0,5%,1/16W,CHIP,CS00002JB13   I132 @T6G_MB_LIB.T6G(SCH_1):PAGE348
 R6019    2      B Q_RES_0402LF-2K,5%,1/16W,EMPTY,TMP_QCS22002JB29    I25 @T6G_MB_LIB.T6G(SCH_1):PAGE349

SGPIO_SCM_LD_<1> @T6G_MB_LIB.T6G(SCH_1):SGPIO_SCM_LD_(1)
 R6015    1      A Q_RES_0402LF-0,5%,1/16W,CHIP,CS00002JB13   I129 @T6G_MB_LIB.T6G(SCH_1):PAGE348
   U18   B5  PT13A LCMXO3LF9400C5BG484C-LCMXO3LF-9400C-5BG484C,SMLF,IA    I94 @T6G_MB_LIB.T6G(SCH_1):PAGE79
 R6023    2      B Q_RES_0402LF-2K,5%,1/16W,EMPTY,TMP_QCS22002JB29    I21 @T6G_MB_LIB.T6G(SCH_1):PAGE349

SGPIO_SCM_LD_R_<0> @T6G_MB_LIB.T6G(SCH_1):SGPIO_SCM_LD_R_(0)
   J41  B32 GND_B32 SCONN168_ME1016810202011-SCONN168_ME1016810202011,A   I176 @T6G_MB_LIB.T6G(SCH_1):PAGE348
 R6011    2      B Q_RES_0402LF-0,5%,1/16W,CHIP,CS00002JB13   I132 @T6G_MB_LIB.T6G(SCH_1):PAGE348

SGPIO_SCM_LD_R_<1> @T6G_MB_LIB.T6G(SCH_1):SGPIO_SCM_LD_R_(1)
 R6015    2      B Q_RES_0402LF-0,5%,1/16W,CHIP,CS00002JB13   I129 @T6G_MB_LIB.T6G(SCH_1):PAGE348
   J41  B37  PETP6 SCONN168_ME1016810202011-SCONN168_ME1016810202011,A   I176 @T6G_MB_LIB.T6G(SCH_1):PAGE348

SGPIO_SCM_RESET_N @T6G_MB_LIB.T6G(SCH_1):SGPIO_SCM_RESET_N
 R6025    1      A Q_RES_0402LF-0,5%,1/16W,CHIP,CS00002JB13    I43 @T6G_MB_LIB.T6G(SCH_1):PAGE348
 R6027    1      A Q_RES_0402LF-4.7K,5%,1/16W,EMPTY,CS24702JB10    I32 @T6G_MB_LIB.T6G(SCH_1):PAGE349
   U18   A5  PT12B LCMXO3LF9400C5BG484C-LCMXO3LF-9400C-5BG484C,SMLF,IA    I94 @T6G_MB_LIB.T6G(SCH_1):PAGE79

SGPIO_SCM_RESET_R_N @T6G_MB_LIB.T6G(SCH_1):SGPIO_SCM_RESET_R_N
 R6025    2      B Q_RES_0402LF-0,5%,1/16W,CHIP,CS00002JB13    I43 @T6G_MB_LIB.T6G(SCH_1):PAGE348
   J41  B39  PETN7 SCONN168_ME1016810202011-SCONN168_ME1016810202011,A   I176 @T6G_MB_LIB.T6G(SCH_1):PAGE348

SMB_1_BMC_GPU_BUF_R_SCL @T6G_MB_LIB.T6G(SCH_1):SMB_1_BMC_GPU_BUF_R_SCL
  U194    2 SCL_OUT LTC4307CMS8-LTC4307CMS8,SMLF,IC,AL004307000    I42 @T6G_MB_LIB.T6G(SCH_1):PAGE249
 R2893    2      B Q_RES_0402LF-0,5%,1/16W,EMPTY,CS00002JB13    I68 @T6G_MB_LIB.T6G(SCH_1):PAGE249
 R2897    1      A Q_RES_0402LF-33.2,1%,1/16W,CHIP,CS03322FB03    I74 @T6G_MB_LIB.T6G(SCH_1):PAGE249
 R3523    2      B Q_RES_0402LF-54.9K,1%,1/16W,CHIP,CS35492FB03    I80 @T6G_MB_LIB.T6G(SCH_1):PAGE249

SMB_1_BMC_GPU_BUF_R_SDA @T6G_MB_LIB.T6G(SCH_1):SMB_1_BMC_GPU_BUF_R_SDA
  U194    7 SDA_OUT LTC4307CMS8-LTC4307CMS8,SMLF,IC,AL004307000    I42 @T6G_MB_LIB.T6G(SCH_1):PAGE249
 R2894    2      B Q_RES_0402LF-0,5%,1/16W,EMPTY,CS00002JB13    I67 @T6G_MB_LIB.T6G(SCH_1):PAGE249
 R2898    1      A Q_RES_0402LF-33.2,1%,1/16W,CHIP,CS03322FB03    I73 @T6G_MB_LIB.T6G(SCH_1):PAGE249
 R3524    2      B Q_RES_0402LF-54.9K,1%,1/16W,CHIP,CS35492FB03    I81 @T6G_MB_LIB.T6G(SCH_1):PAGE249

SMB_1_BMC_GPU_BUF_SCL @T6G_MB_LIB.T6G(SCH_1):SMB_1_BMC_GPU_BUF_SCL
 R2897    2      B Q_RES_0402LF-33.2,1%,1/16W,CHIP,CS03322FB03    I74 @T6G_MB_LIB.T6G(SCH_1):PAGE249
  J112   Q4     Q4 CONN160_10131762101LF-CONN160_10131762-101LF,THLF,A   I102 @T6G_MB_LIB.T6G(SCH_1):PAGE329

SMB_1_BMC_GPU_BUF_SDA @T6G_MB_LIB.T6G(SCH_1):SMB_1_BMC_GPU_BUF_SDA
 R2898    2      B Q_RES_0402LF-33.2,1%,1/16W,CHIP,CS03322FB03    I73 @T6G_MB_LIB.T6G(SCH_1):PAGE249
  J112   R4     R4 CONN160_10131762101LF-CONN160_10131762-101LF,THLF,A   I102 @T6G_MB_LIB.T6G(SCH_1):PAGE329

SMB_1_BMC_GPU_R_SCL @T6G_MB_LIB.T6G(SCH_1):SMB_1_BMC_GPU_R_SCL
 R3109    2      B Q_RES_0402LF-0,5%,1/16W,CHIP,CS00002JB13    I35 @T6G_MB_LIB.T6G(SCH_1):PAGE249
  U194    3 SCL_IN LTC4307CMS8-LTC4307CMS8,SMLF,IC,AL004307000    I42 @T6G_MB_LIB.T6G(SCH_1):PAGE249
 R2893    1      A Q_RES_0402LF-0,5%,1/16W,EMPTY,CS00002JB13    I68 @T6G_MB_LIB.T6G(SCH_1):PAGE249

SMB_1_BMC_GPU_R_SDA @T6G_MB_LIB.T6G(SCH_1):SMB_1_BMC_GPU_R_SDA
 R3110    2      B Q_RES_0402LF-0,5%,1/16W,CHIP,CS00002JB13    I34 @T6G_MB_LIB.T6G(SCH_1):PAGE249
  U194    6 SDA_IN LTC4307CMS8-LTC4307CMS8,SMLF,IC,AL004307000    I42 @T6G_MB_LIB.T6G(SCH_1):PAGE249
 R2894    1      A Q_RES_0402LF-0,5%,1/16W,EMPTY,CS00002JB13    I67 @T6G_MB_LIB.T6G(SCH_1):PAGE249

SMB_1_BMC_GPU_SCL @T6G_MB_LIB.T6G(SCH_1):SMB_1_BMC_GPU_SCL
 R3226    1      A Q_RES_0402LF-2.2K,5%,1/16W,EMPTY,CS22202JB07   I122 @T6G_MB_LIB.T6G(SCH_1):PAGE349
 R3109    1      A Q_RES_0402LF-0,5%,1/16W,CHIP,CS00002JB13    I35 @T6G_MB_LIB.T6G(SCH_1):PAGE249
 R2415    1      A Q_RES_0402LF-33.2,1%,1/16W,CHIP,CS03322FB03    I60 @T6G_MB_LIB.T6G(SCH_1):PAGE348

SMB_1_BMC_GPU_SDA @T6G_MB_LIB.T6G(SCH_1):SMB_1_BMC_GPU_SDA
 R3227    1      A Q_RES_0402LF-2.2K,5%,1/16W,EMPTY,CS22202JB07   I121 @T6G_MB_LIB.T6G(SCH_1):PAGE349
 R3110    1      A Q_RES_0402LF-0,5%,1/16W,CHIP,CS00002JB13    I34 @T6G_MB_LIB.T6G(SCH_1):PAGE249
 R2416    1      A Q_RES_0402LF-33.2,1%,1/16W,CHIP,CS03322FB03    I33 @T6G_MB_LIB.T6G(SCH_1):PAGE348

SMB_1_PLD_3V3AUX_SCL @T6G_MB_LIB.T6G(SCH_1):SMB_1_PLD_3V3AUX_SCL
 R4508    1      A Q_RES_0402LF-33.2,1%,1/16W,CHIP,CS03322FB03    I88 @T6G_MB_LIB.T6G(SCH_1):PAGE348
 R6036    1      A Q_RES_0402LF-2K,1%,1/16W,EMPTY,CS22002FB07   I131 @T6G_MB_LIB.T6G(SCH_1):PAGE349
 R4151    1      A Q_RES_0402LF-33.2,1%,1/16W,CHIP,CS03322FB03    I83 @T6G_MB_LIB.T6G(SCH_1):PAGE349
 R4149    1      A Q_RES_0402LF-33.2,1%,1/16W,CHIP,CS03322FB03    I89 @T6G_MB_LIB.T6G(SCH_1):PAGE349

SMB_1_PLD_3V3AUX_SCL_R1 @T6G_MB_LIB.T6G(SCH_1):SMB_1_PLD_3V3AUX_SCL_R1
   R51    1      A Q_RES_0402LF-0,5%,1/16W,CHIP,CS00002JB13    I83 @T6G_MB_LIB.T6G(SCH_1):PAGE79
 R4149    2      B Q_RES_0402LF-33.2,1%,1/16W,CHIP,CS03322FB03    I89 @T6G_MB_LIB.T6G(SCH_1):PAGE349

SMB_1_PLD_3V3AUX_SCL_R2 @T6G_MB_LIB.T6G(SCH_1):SMB_1_PLD_3V3AUX_SCL_R2
   R51    2      B Q_RES_0402LF-0,5%,1/16W,CHIP,CS00002JB13    I83 @T6G_MB_LIB.T6G(SCH_1):PAGE79
   U18  B12 PT27C||SCL||PCLKT0_0 LCMXO3LF9400C5BG484C-LCMXO3LF-9400C-5BG484C,SMLF,IA    I94 @T6G_MB_LIB.T6G(SCH_1):PAGE79

SMB_1_PLD_3V3AUX_SCL_R3 @T6G_MB_LIB.T6G(SCH_1):SMB_1_PLD_3V3AUX_SCL_R3
 R4508    2      B Q_RES_0402LF-33.2,1%,1/16W,CHIP,CS03322FB03    I88 @T6G_MB_LIB.T6G(SCH_1):PAGE348
   J41  A27  PERP3 SCONN168_ME1016810202011-SCONN168_ME1016810202011,A   I176 @T6G_MB_LIB.T6G(SCH_1):PAGE348

SMB_1_PLD_3V3AUX_SDA @T6G_MB_LIB.T6G(SCH_1):SMB_1_PLD_3V3AUX_SDA
 R4509    1      A Q_RES_0402LF-33.2,1%,1/16W,CHIP,CS03322FB03    I87 @T6G_MB_LIB.T6G(SCH_1):PAGE348
 R4152    1      A Q_RES_0402LF-33.2,1%,1/16W,CHIP,CS03322FB03    I84 @T6G_MB_LIB.T6G(SCH_1):PAGE349
 R6037    1      A Q_RES_0402LF-2K,1%,1/16W,EMPTY,CS22002FB07   I132 @T6G_MB_LIB.T6G(SCH_1):PAGE349
 R4150    1      A Q_RES_0402LF-33.2,1%,1/16W,CHIP,CS03322FB03    I90 @T6G_MB_LIB.T6G(SCH_1):PAGE349

SMB_1_PLD_3V3AUX_SDA_R1 @T6G_MB_LIB.T6G(SCH_1):SMB_1_PLD_3V3AUX_SDA_R1
   R56    1      A Q_RES_0402LF-0,5%,1/16W,CHIP,CS00002JB13    I82 @T6G_MB_LIB.T6G(SCH_1):PAGE79
 R4150    2      B Q_RES_0402LF-33.2,1%,1/16W,CHIP,CS03322FB03    I90 @T6G_MB_LIB.T6G(SCH_1):PAGE349

SMB_1_PLD_3V3AUX_SDA_R2 @T6G_MB_LIB.T6G(SCH_1):SMB_1_PLD_3V3AUX_SDA_R2
   R56    2      B Q_RES_0402LF-0,5%,1/16W,CHIP,CS00002JB13    I82 @T6G_MB_LIB.T6G(SCH_1):PAGE79
   U18  A12 PT27D||SDA||PCLKC0_0 LCMXO3LF9400C5BG484C-LCMXO3LF-9400C-5BG484C,SMLF,IA    I94 @T6G_MB_LIB.T6G(SCH_1):PAGE79

SMB_1_PLD_3V3AUX_SDA_R3 @T6G_MB_LIB.T6G(SCH_1):SMB_1_PLD_3V3AUX_SDA_R3
 R4509    2      B Q_RES_0402LF-33.2,1%,1/16W,CHIP,CS03322FB03    I87 @T6G_MB_LIB.T6G(SCH_1):PAGE348
   J41  A28 GND_A28 SCONN168_ME1016810202011-SCONN168_ME1016810202011,A   I176 @T6G_MB_LIB.T6G(SCH_1):PAGE348

SMB_2_BMC_GPU_BUF_R_SCL @T6G_MB_LIB.T6G(SCH_1):SMB_2_BMC_GPU_BUF_R_SCL
  U200    2 SCL_OUT LTC4307CMS8-LTC4307CMS8,SMLF,IC,AL004307000    I15 @T6G_MB_LIB.T6G(SCH_1):PAGE249
 R2986    2      B Q_RES_0402LF-0,5%,1/16W,EMPTY,CS00002JB13    I18 @T6G_MB_LIB.T6G(SCH_1):PAGE249
 R3521    2      B Q_RES_0402LF-54.9K,1%,1/16W,CHIP,CS35492FB03    I36 @T6G_MB_LIB.T6G(SCH_1):PAGE249
 R2990    1      A Q_RES_0402LF-33.2,1%,1/16W,CHIP,CS03322FB03    I38 @T6G_MB_LIB.T6G(SCH_1):PAGE249

SMB_2_BMC_GPU_BUF_R_SDA @T6G_MB_LIB.T6G(SCH_1):SMB_2_BMC_GPU_BUF_R_SDA
  U200    7 SDA_OUT LTC4307CMS8-LTC4307CMS8,SMLF,IC,AL004307000    I15 @T6G_MB_LIB.T6G(SCH_1):PAGE249
 R2987    2      B Q_RES_0402LF-0,5%,1/16W,EMPTY,CS00002JB13    I17 @T6G_MB_LIB.T6G(SCH_1):PAGE249
 R3522    2      B Q_RES_0402LF-54.9K,1%,1/16W,CHIP,CS35492FB03    I37 @T6G_MB_LIB.T6G(SCH_1):PAGE249
 R2991    1      A Q_RES_0402LF-33.2,1%,1/16W,CHIP,CS03322FB03    I39 @T6G_MB_LIB.T6G(SCH_1):PAGE249

SMB_2_BMC_GPU_BUF_SCL @T6G_MB_LIB.T6G(SCH_1):SMB_2_BMC_GPU_BUF_SCL
 R2990    2      B Q_RES_0402LF-33.2,1%,1/16W,CHIP,CS03322FB03    I38 @T6G_MB_LIB.T6G(SCH_1):PAGE249
  J112   R3     R3 CONN160_10131762101LF-CONN160_10131762-101LF,THLF,A   I102 @T6G_MB_LIB.T6G(SCH_1):PAGE329

SMB_2_BMC_GPU_BUF_SDA @T6G_MB_LIB.T6G(SCH_1):SMB_2_BMC_GPU_BUF_SDA
 R2991    2      B Q_RES_0402LF-33.2,1%,1/16W,CHIP,CS03322FB03    I39 @T6G_MB_LIB.T6G(SCH_1):PAGE249
  J112   S3     S3 CONN160_10131762101LF-CONN160_10131762-101LF,THLF,A   I102 @T6G_MB_LIB.T6G(SCH_1):PAGE329

SMB_2_BMC_GPU_R_SCL @T6G_MB_LIB.T6G(SCH_1):SMB_2_BMC_GPU_R_SCL
 R3107    2      B Q_RES_0402LF-0,5%,1/16W,CHIP,CS00002JB13    I13 @T6G_MB_LIB.T6G(SCH_1):PAGE249
  U200    3 SCL_IN LTC4307CMS8-LTC4307CMS8,SMLF,IC,AL004307000    I15 @T6G_MB_LIB.T6G(SCH_1):PAGE249
 R2986    1      A Q_RES_0402LF-0,5%,1/16W,EMPTY,CS00002JB13    I18 @T6G_MB_LIB.T6G(SCH_1):PAGE249

SMB_2_BMC_GPU_R_SDA @T6G_MB_LIB.T6G(SCH_1):SMB_2_BMC_GPU_R_SDA
 R3108    2      B Q_RES_0402LF-0,5%,1/16W,CHIP,CS00002JB13    I14 @T6G_MB_LIB.T6G(SCH_1):PAGE249
  U200    6 SDA_IN LTC4307CMS8-LTC4307CMS8,SMLF,IC,AL004307000    I15 @T6G_MB_LIB.T6G(SCH_1):PAGE249
 R2987    1      A Q_RES_0402LF-0,5%,1/16W,EMPTY,CS00002JB13    I17 @T6G_MB_LIB.T6G(SCH_1):PAGE249

SMB_2_BMC_GPU_SCL @T6G_MB_LIB.T6G(SCH_1):SMB_2_BMC_GPU_SCL
 R2413    1      A Q_RES_0402LF-33.2,1%,1/16W,CHIP,CS03322FB03    I86 @T6G_MB_LIB.T6G(SCH_1):PAGE348
 R2999    1      A Q_RES_0402LF-2.2K,5%,1/16W,EMPTY,CS22202JB07   I124 @T6G_MB_LIB.T6G(SCH_1):PAGE349
 R3107    1      A Q_RES_0402LF-0,5%,1/16W,CHIP,CS00002JB13    I13 @T6G_MB_LIB.T6G(SCH_1):PAGE249

SMB_2_BMC_GPU_SDA @T6G_MB_LIB.T6G(SCH_1):SMB_2_BMC_GPU_SDA
 R2414    1      A Q_RES_0402LF-33.2,1%,1/16W,CHIP,CS03322FB03    I85 @T6G_MB_LIB.T6G(SCH_1):PAGE348
 R3004    1      A Q_RES_0402LF-2.2K,5%,1/16W,EMPTY,CS22202JB07   I123 @T6G_MB_LIB.T6G(SCH_1):PAGE349
 R3108    1      A Q_RES_0402LF-0,5%,1/16W,CHIP,CS00002JB13    I14 @T6G_MB_LIB.T6G(SCH_1):PAGE249

SMB_2_PLD_3V3AUX_SCL_R1 @T6G_MB_LIB.T6G(SCH_1):SMB_2_PLD_3V3AUX_SCL_R1
  R210    1      A Q_RES_0402LF-0,5%,1/16W,CHIP,CS00002JB13    I81 @T6G_MB_LIB.T6G(SCH_1):PAGE79
 R4151    2      B Q_RES_0402LF-33.2,1%,1/16W,CHIP,CS03322FB03    I83 @T6G_MB_LIB.T6G(SCH_1):PAGE349

SMB_2_PLD_3V3AUX_SCL_R2 @T6G_MB_LIB.T6G(SCH_1):SMB_2_PLD_3V3AUX_SCL_R2
  R210    2      B Q_RES_0402LF-0,5%,1/16W,CHIP,CS00002JB13    I81 @T6G_MB_LIB.T6G(SCH_1):PAGE79
   U18  A13  PT29A LCMXO3LF9400C5BG484C-LCMXO3LF-9400C-5BG484C,SMLF,IA    I94 @T6G_MB_LIB.T6G(SCH_1):PAGE79

SMB_2_PLD_3V3AUX_SDA_R1 @T6G_MB_LIB.T6G(SCH_1):SMB_2_PLD_3V3AUX_SDA_R1
 R4152    2      B Q_RES_0402LF-33.2,1%,1/16W,CHIP,CS03322FB03    I84 @T6G_MB_LIB.T6G(SCH_1):PAGE349
  R211    1      A Q_RES_0402LF-0,5%,1/16W,CHIP,CS00002JB13    I80 @T6G_MB_LIB.T6G(SCH_1):PAGE79

SMB_2_PLD_3V3AUX_SDA_R2 @T6G_MB_LIB.T6G(SCH_1):SMB_2_PLD_3V3AUX_SDA_R2
  R211    2      B Q_RES_0402LF-0,5%,1/16W,CHIP,CS00002JB13    I80 @T6G_MB_LIB.T6G(SCH_1):PAGE79
   U18  B13  PT29B LCMXO3LF9400C5BG484C-LCMXO3LF-9400C-5BG484C,SMLF,IA    I94 @T6G_MB_LIB.T6G(SCH_1):PAGE79

SMB_9ZXL045_P0_SCL @T6G_MB_LIB.T6G(SCH_1):SMB_9ZXL045_P0_SCL
  U314    7 SMBCLK 9ZXL0451EKILFT-9ZXL0451EKILFT,SMLF,IC,AL000451003    I63 @T6G_MB_LIB.T6G(SCH_1):PAGE160
 R6864    2      B Q_RES_0402LF-33,5%,1/16W,CHIP,CS03302JB10   I220 @T6G_MB_LIB.T6G(SCH_1):PAGE349

SMB_9ZXL045_P0_SDA @T6G_MB_LIB.T6G(SCH_1):SMB_9ZXL045_P0_SDA
  U314    6 SMBDAT 9ZXL0451EKILFT-9ZXL0451EKILFT,SMLF,IC,AL000451003    I63 @T6G_MB_LIB.T6G(SCH_1):PAGE160
 R6865    2      B Q_RES_0402LF-33,5%,1/16W,CHIP,CS03302JB10   I221 @T6G_MB_LIB.T6G(SCH_1):PAGE349

SMB_9ZXL045_P1_SCL @T6G_MB_LIB.T6G(SCH_1):SMB_9ZXL045_P1_SCL
   U10    7 SMBCLK 9ZXL0451EKILFT-9ZXL0451EKILFT,SMLF,IC,AL000451003    I63 @T6G_MB_LIB.T6G(SCH_1):PAGE379
 R6862    2      B Q_RES_0402LF-33,5%,1/16W,CHIP,CS03302JB10   I218 @T6G_MB_LIB.T6G(SCH_1):PAGE349

SMB_9ZXL045_P1_SDA @T6G_MB_LIB.T6G(SCH_1):SMB_9ZXL045_P1_SDA
   U10    6 SMBDAT 9ZXL0451EKILFT-9ZXL0451EKILFT,SMLF,IC,AL000451003    I63 @T6G_MB_LIB.T6G(SCH_1):PAGE379
 R6863    2      B Q_RES_0402LF-33,5%,1/16W,CHIP,CS03302JB10   I219 @T6G_MB_LIB.T6G(SCH_1):PAGE349

SMB_ADC_SCL @T6G_MB_LIB.T6G(SCH_1):SMB_ADC_SCL
   U39   18    SC6 TCA9548APWR-TCA9548APWR,SMLF,IC,AL009548K02    I74 @T6G_MB_LIB.T6G(SCH_1):PAGE251
 R1315    1      A Q_RES_0402LF-0,5%,1/16W,CHIP,CS00002JB13    I80 @T6G_MB_LIB.T6G(SCH_1):PAGE251

SMB_ADC_SCL_R @T6G_MB_LIB.T6G(SCH_1):SMB_ADC_SCL_R
 R1228    1      A Q_RES_0402LF-0,5%,1/16W,EMPTY,CS00002JB13   I139 @T6G_MB_LIB.T6G(SCH_1):PAGE263
 R1244    1      A Q_RES_0402LF-0,5%,1/16W,CHIP,CS00002JB13   I140 @T6G_MB_LIB.T6G(SCH_1):PAGE263
 R1315    2      B Q_RES_0402LF-0,5%,1/16W,CHIP,CS00002JB13    I80 @T6G_MB_LIB.T6G(SCH_1):PAGE251
 R1316    2      B Q_RES_0402LF-2.2K,5%,1/16W,CHIP,CS22202JB07    I83 @T6G_MB_LIB.T6G(SCH_1):PAGE251

SMB_ADC_SDA @T6G_MB_LIB.T6G(SCH_1):SMB_ADC_SDA
   U39   17    SD6 TCA9548APWR-TCA9548APWR,SMLF,IC,AL009548K02    I74 @T6G_MB_LIB.T6G(SCH_1):PAGE251
 R1312    1      A Q_RES_0402LF-0,5%,1/16W,CHIP,CS00002JB13    I79 @T6G_MB_LIB.T6G(SCH_1):PAGE251

SMB_ADC_SDA_R @T6G_MB_LIB.T6G(SCH_1):SMB_ADC_SDA_R
 R1227    1      A Q_RES_0402LF-0,5%,1/16W,EMPTY,CS00002JB13   I138 @T6G_MB_LIB.T6G(SCH_1):PAGE263
 R1243    1      A Q_RES_0402LF-0,5%,1/16W,CHIP,CS00002JB13   I141 @T6G_MB_LIB.T6G(SCH_1):PAGE263
 R1312    2      B Q_RES_0402LF-0,5%,1/16W,CHIP,CS00002JB13    I79 @T6G_MB_LIB.T6G(SCH_1):PAGE251
 R1341    2      B Q_RES_0402LF-2.2K,5%,1/16W,CHIP,CS22202JB07    I84 @T6G_MB_LIB.T6G(SCH_1):PAGE251

SMB_APML_CPU0_MUX2_SCL @T6G_MB_LIB.T6G(SCH_1):SMB_APML_CPU0_MUX2_SCL
  R327    1      A Q_RES_0402LF-0,5%,1/16W,CHIP,CS00002JB13    I91 @T6G_MB_LIB.T6G(SCH_1):PAGE138
    U4    1    1D+ PI3CSW12ZUAEX-PI3CSW12ZUAEX,SMLF,IC,AL3CSW12000   I114 @T6G_MB_LIB.T6G(SCH_1):PAGE138

SMB_APML_CPU0_MUX2_SDA @T6G_MB_LIB.T6G(SCH_1):SMB_APML_CPU0_MUX2_SDA
  R328    1      A Q_RES_0402LF-0,5%,1/16W,CHIP,CS00002JB13    I92 @T6G_MB_LIB.T6G(SCH_1):PAGE138
    U4    2    1D- PI3CSW12ZUAEX-PI3CSW12ZUAEX,SMLF,IC,AL3CSW12000   I114 @T6G_MB_LIB.T6G(SCH_1):PAGE138

SMB_APML_CPU0_R_SCL @T6G_MB_LIB.T6G(SCH_1):SMB_APML_CPU0_R_SCL
  R142    2      B Q_RES_0402LF-0,5%,1/16W,EMPTY,CS00002JB13    I35 @T6G_MB_LIB.T6G(SCH_1):PAGE138
 R1156    1      A Q_RES_0402LF-33,5%,1/16W,EMPTY,CS03302JB10    I38 @T6G_MB_LIB.T6G(SCH_1):PAGE138
  U213    4 LSCL_0 IML3112Y2B000NCG8-IML3112-Y2B000NCG8,SMLF,EMPTY,ALA   I111 @T6G_MB_LIB.T6G(SCH_1):PAGE138

SMB_APML_CPU0_R_SDA @T6G_MB_LIB.T6G(SCH_1):SMB_APML_CPU0_R_SDA
  R143    2      B Q_RES_0402LF-0,5%,1/16W,EMPTY,CS00002JB13    I34 @T6G_MB_LIB.T6G(SCH_1):PAGE138
 R1155    1      A Q_RES_0402LF-33,5%,1/16W,EMPTY,CS03302JB10    I39 @T6G_MB_LIB.T6G(SCH_1):PAGE138
  U213    1 LSDA_0 IML3112Y2B000NCG8-IML3112-Y2B000NCG8,SMLF,EMPTY,ALA   I111 @T6G_MB_LIB.T6G(SCH_1):PAGE138

SMB_APML_CPU0_SCL @T6G_MB_LIB.T6G(SCH_1):SMB_APML_CPU0_SCL
   U25 DJ71    SIC GENOA_SP5-SOCKET6096_13568-001,SMLF,IO,DGA^6000030   I227 @T6G_MB_LIB.T6G(SCH_1):PAGE27
 R1156    2      B Q_RES_0402LF-33,5%,1/16W,EMPTY,CS03302JB10    I38 @T6G_MB_LIB.T6G(SCH_1):PAGE138
  R363    2      B Q_RES_0402LF-1K,1%,1/16W,CHIP,CS21002FB06    I56 @T6G_MB_LIB.T6G(SCH_1):PAGE138
  R327    2      B Q_RES_0402LF-0,5%,1/16W,CHIP,CS00002JB13    I91 @T6G_MB_LIB.T6G(SCH_1):PAGE138

SMB_APML_CPU0_SDA @T6G_MB_LIB.T6G(SCH_1):SMB_APML_CPU0_SDA
   U25 DH71    SID GENOA_SP5-SOCKET6096_13568-001,SMLF,IO,DGA^6000030   I227 @T6G_MB_LIB.T6G(SCH_1):PAGE27
 R1155    2      B Q_RES_0402LF-33,5%,1/16W,EMPTY,CS03302JB10    I39 @T6G_MB_LIB.T6G(SCH_1):PAGE138
  R360    2      B Q_RES_0402LF-1K,1%,1/16W,CHIP,CS21002FB06    I55 @T6G_MB_LIB.T6G(SCH_1):PAGE138
  R328    2      B Q_RES_0402LF-0,5%,1/16W,CHIP,CS00002JB13    I92 @T6G_MB_LIB.T6G(SCH_1):PAGE138

SMB_APML_CPU1_MUX2_SCL @T6G_MB_LIB.T6G(SCH_1):SMB_APML_CPU1_MUX2_SCL
  R337    1      A Q_RES_0402LF-0,5%,1/16W,CHIP,CS00002JB13    I93 @T6G_MB_LIB.T6G(SCH_1):PAGE138
    U4    3    2D+ PI3CSW12ZUAEX-PI3CSW12ZUAEX,SMLF,IC,AL3CSW12000   I114 @T6G_MB_LIB.T6G(SCH_1):PAGE138

SMB_APML_CPU1_MUX2_SDA @T6G_MB_LIB.T6G(SCH_1):SMB_APML_CPU1_MUX2_SDA
  R338    1      A Q_RES_0402LF-0,5%,1/16W,CHIP,CS00002JB13    I94 @T6G_MB_LIB.T6G(SCH_1):PAGE138
    U4    4    2D- PI3CSW12ZUAEX-PI3CSW12ZUAEX,SMLF,IC,AL3CSW12000   I114 @T6G_MB_LIB.T6G(SCH_1):PAGE138

SMB_APML_CPU1_R_SCL @T6G_MB_LIB.T6G(SCH_1):SMB_APML_CPU1_R_SCL
  R146    2      B Q_RES_0402LF-0,5%,1/16W,EMPTY,CS00002JB13    I17 @T6G_MB_LIB.T6G(SCH_1):PAGE138
 R1157    1      A Q_RES_0402LF-33,5%,1/16W,EMPTY,CS03302JB10    I74 @T6G_MB_LIB.T6G(SCH_1):PAGE138
  U213    6 LSCL_1 IML3112Y2B000NCG8-IML3112-Y2B000NCG8,SMLF,EMPTY,ALA   I111 @T6G_MB_LIB.T6G(SCH_1):PAGE138

SMB_APML_CPU1_R_SDA @T6G_MB_LIB.T6G(SCH_1):SMB_APML_CPU1_R_SDA
 R5004    1      A Q_RES_0402LF-10K,1%,1/16W,CHIP,CS31002FB08    I27 @T6G_MB_LIB.T6G(SCH_1):PAGE138
  R147    2      B Q_RES_0402LF-0,5%,1/16W,EMPTY,CS00002JB13    I16 @T6G_MB_LIB.T6G(SCH_1):PAGE138
 R1158    1      A Q_RES_0402LF-33,5%,1/16W,EMPTY,CS03302JB10    I73 @T6G_MB_LIB.T6G(SCH_1):PAGE138
  U213    8 LSDA_1||HSA IML3112Y2B000NCG8-IML3112-Y2B000NCG8,SMLF,EMPTY,ALA   I111 @T6G_MB_LIB.T6G(SCH_1):PAGE138

SMB_APML_CPU1_SCL @T6G_MB_LIB.T6G(SCH_1):SMB_APML_CPU1_SCL
   U26 DJ71    SIC GENOA_SP5-SOCKET6096_13568-001,SMLF,IO,DGA^6000030   I190 @T6G_MB_LIB.T6G(SCH_1):PAGE54
  R362    2      B Q_RES_0402LF-1K,1%,1/16W,CHIP,CS21002FB06    I53 @T6G_MB_LIB.T6G(SCH_1):PAGE138
 R1157    2      B Q_RES_0402LF-33,5%,1/16W,EMPTY,CS03302JB10    I74 @T6G_MB_LIB.T6G(SCH_1):PAGE138
  R337    2      B Q_RES_0402LF-0,5%,1/16W,CHIP,CS00002JB13    I93 @T6G_MB_LIB.T6G(SCH_1):PAGE138

SMB_APML_CPU1_SDA @T6G_MB_LIB.T6G(SCH_1):SMB_APML_CPU1_SDA
   U26 DH71    SID GENOA_SP5-SOCKET6096_13568-001,SMLF,IO,DGA^6000030   I190 @T6G_MB_LIB.T6G(SCH_1):PAGE54
  R359    2      B Q_RES_0402LF-1K,1%,1/16W,CHIP,CS21002FB06    I52 @T6G_MB_LIB.T6G(SCH_1):PAGE138
 R1158    2      B Q_RES_0402LF-33,5%,1/16W,EMPTY,CS03302JB10    I73 @T6G_MB_LIB.T6G(SCH_1):PAGE138
  R338    2      B Q_RES_0402LF-0,5%,1/16W,CHIP,CS00002JB13    I94 @T6G_MB_LIB.T6G(SCH_1):PAGE138

SMB_BMC_GPU_EN @T6G_MB_LIB.T6G(SCH_1):SMB_BMC_GPU_EN
 R2992    1      A Q_RES_0402LF-0,5%,1/16W,CHIP,CS00002JB13    I12 @T6G_MB_LIB.T6G(SCH_1):PAGE249
 R4603    1      A Q_RES_0402LF-10K,1%,1/16W,CHIP,CS31002FB08    I23 @T6G_MB_LIB.T6G(SCH_1):PAGE249
 R2899    1      A Q_RES_0402LF-0,5%,1/16W,CHIP,CS00002JB13    I50 @T6G_MB_LIB.T6G(SCH_1):PAGE249
   U18   L4  PL16D LCMXO3LF9400C5BG484C-LCMXO3LF-9400C-5BG484C,SMLF,IA   I143 @T6G_MB_LIB.T6G(SCH_1):PAGE81

SMB_BMC_GPU_EN_R1 @T6G_MB_LIB.T6G(SCH_1):SMB_BMC_GPU_EN_R1
  U194    1 ENABLE LTC4307CMS8-LTC4307CMS8,SMLF,IC,AL004307000    I42 @T6G_MB_LIB.T6G(SCH_1):PAGE249
 R2899    2      B Q_RES_0402LF-0,5%,1/16W,CHIP,CS00002JB13    I50 @T6G_MB_LIB.T6G(SCH_1):PAGE249

SMB_BMC_GPU_EN_R3 @T6G_MB_LIB.T6G(SCH_1):SMB_BMC_GPU_EN_R3
 R2992    2      B Q_RES_0402LF-0,5%,1/16W,CHIP,CS00002JB13    I12 @T6G_MB_LIB.T6G(SCH_1):PAGE249
  U200    1 ENABLE LTC4307CMS8-LTC4307CMS8,SMLF,IC,AL004307000    I15 @T6G_MB_LIB.T6G(SCH_1):PAGE249

SMB_BMC_SWB_BUF_R_SCL @T6G_MB_LIB.T6G(SCH_1):SMB_BMC_SWB_BUF_R_SCL
 R2705    2      B Q_RES_0402LF-0,5%,1/16W,EMPTY,CS00002JB13    I47 @T6G_MB_LIB.T6G(SCH_1):PAGE249
  U175    2 SCL_OUT LTC4307CMS8-LTC4307CMS8,SMLF,IC,AL004307000    I49 @T6G_MB_LIB.T6G(SCH_1):PAGE249
 R2667    2      B Q_RES_0402LF-2.2K,5%,1/16W,CHIP,CS22202JB07    I54 @T6G_MB_LIB.T6G(SCH_1):PAGE249
 R2671    1      A Q_RES_0402LF-33.2,1%,1/16W,CHIP,CS03322FB03    I58 @T6G_MB_LIB.T6G(SCH_1):PAGE249

SMB_BMC_SWB_BUF_R_SDA @T6G_MB_LIB.T6G(SCH_1):SMB_BMC_SWB_BUF_R_SDA
 R2724    2      B Q_RES_0402LF-0,5%,1/16W,EMPTY,CS00002JB13    I48 @T6G_MB_LIB.T6G(SCH_1):PAGE249
  U175    7 SDA_OUT LTC4307CMS8-LTC4307CMS8,SMLF,IC,AL004307000    I49 @T6G_MB_LIB.T6G(SCH_1):PAGE249
 R2672    1      A Q_RES_0402LF-33.2,1%,1/16W,CHIP,CS03322FB03    I56 @T6G_MB_LIB.T6G(SCH_1):PAGE249
 R2669    2      B Q_RES_0402LF-2.2K,5%,1/16W,CHIP,CS22202JB07    I57 @T6G_MB_LIB.T6G(SCH_1):PAGE249

SMB_BMC_SWB_BUF_SCL @T6G_MB_LIB.T6G(SCH_1):SMB_BMC_SWB_BUF_SCL
 R2671    2      B Q_RES_0402LF-33.2,1%,1/16W,CHIP,CS03322FB03    I58 @T6G_MB_LIB.T6G(SCH_1):PAGE249
  J109   A5     A5 CONN112_10137002101LF-CONN112_10137002-101LF,THLF,A    I16 @T6G_MB_LIB.T6G(SCH_1):PAGE319

SMB_BMC_SWB_BUF_SDA @T6G_MB_LIB.T6G(SCH_1):SMB_BMC_SWB_BUF_SDA
 R2672    2      B Q_RES_0402LF-33.2,1%,1/16W,CHIP,CS03322FB03    I56 @T6G_MB_LIB.T6G(SCH_1):PAGE249
  J109   A7     A7 CONN112_10137002101LF-CONN112_10137002-101LF,THLF,A    I16 @T6G_MB_LIB.T6G(SCH_1):PAGE319

SMB_BMC_SWB_EN @T6G_MB_LIB.T6G(SCH_1):SMB_BMC_SWB_EN
 R2666    1      A Q_RES_0402LF-10K,1%,1/16W,CHIP,CS31002FB08     I8 @T6G_MB_LIB.T6G(SCH_1):PAGE249
 R2676    1      A Q_RES_0402LF-0,5%,1/16W,CHIP,CS00002JB13    I26 @T6G_MB_LIB.T6G(SCH_1):PAGE249
 R2707    1      A Q_RES_0402LF-0,5%,1/16W,CHIP,CS00002JB13    I45 @T6G_MB_LIB.T6G(SCH_1):PAGE249
   U18  A21 PT44A||R_GPLLT LCMXO3LF9400C5BG484C-LCMXO3LF-9400C-5BG484C,SMLF,IA    I94 @T6G_MB_LIB.T6G(SCH_1):PAGE79

SMB_BMC_SWB_EN_R @T6G_MB_LIB.T6G(SCH_1):SMB_BMC_SWB_EN_R
 R2707    2      B Q_RES_0402LF-0,5%,1/16W,CHIP,CS00002JB13    I45 @T6G_MB_LIB.T6G(SCH_1):PAGE249
  U175    1 ENABLE LTC4307CMS8-LTC4307CMS8,SMLF,IC,AL004307000    I49 @T6G_MB_LIB.T6G(SCH_1):PAGE249

SMB_BMC_SWB_EN_R2 @T6G_MB_LIB.T6G(SCH_1):SMB_BMC_SWB_EN_R2
 R2676    2      B Q_RES_0402LF-0,5%,1/16W,CHIP,CS00002JB13    I26 @T6G_MB_LIB.T6G(SCH_1):PAGE249
  U176    1 ENABLE LTC4307CMS8-LTC4307CMS8,SMLF,EMPTY,AL004307000    I30 @T6G_MB_LIB.T6G(SCH_1):PAGE249

SMB_BMC_SWB_R_SCL @T6G_MB_LIB.T6G(SCH_1):SMB_BMC_SWB_R_SCL
 R3105    2      B Q_RES_0402LF-0,5%,1/16W,CHIP,CS00002JB13    I44 @T6G_MB_LIB.T6G(SCH_1):PAGE249
 R2705    1      A Q_RES_0402LF-0,5%,1/16W,EMPTY,CS00002JB13    I47 @T6G_MB_LIB.T6G(SCH_1):PAGE249
  U175    3 SCL_IN LTC4307CMS8-LTC4307CMS8,SMLF,IC,AL004307000    I49 @T6G_MB_LIB.T6G(SCH_1):PAGE249

SMB_BMC_SWB_R_SDA @T6G_MB_LIB.T6G(SCH_1):SMB_BMC_SWB_R_SDA
 R3106    2      B Q_RES_0402LF-0,5%,1/16W,CHIP,CS00002JB13    I43 @T6G_MB_LIB.T6G(SCH_1):PAGE249
 R2724    1      A Q_RES_0402LF-0,5%,1/16W,EMPTY,CS00002JB13    I48 @T6G_MB_LIB.T6G(SCH_1):PAGE249
  U175    6 SDA_IN LTC4307CMS8-LTC4307CMS8,SMLF,IC,AL004307000    I49 @T6G_MB_LIB.T6G(SCH_1):PAGE249

SMB_BMC_SWB_SCL @T6G_MB_LIB.T6G(SCH_1):SMB_BMC_SWB_SCL
 R3105    1      A Q_RES_0402LF-0,5%,1/16W,CHIP,CS00002JB13    I44 @T6G_MB_LIB.T6G(SCH_1):PAGE249
 R2984    2      B Q_RES_0402LF-2.2K,5%,1/16W,CHIP,CS22202JB07    I41 @T6G_MB_LIB.T6G(SCH_1):PAGE252
 R2703    2      B Q_RES_0402LF-0,5%,1/16W,CHIP,CS00002JB13    I71 @T6G_MB_LIB.T6G(SCH_1):PAGE252

SMB_BMC_SWB_SCL_R4 @T6G_MB_LIB.T6G(SCH_1):SMB_BMC_SWB_SCL_R4
   U36   14    SC4 TCA9548APWR-TCA9548APWR,SMLF,IC,AL009548K02    I33 @T6G_MB_LIB.T6G(SCH_1):PAGE252
 R2703    1      A Q_RES_0402LF-0,5%,1/16W,CHIP,CS00002JB13    I71 @T6G_MB_LIB.T6G(SCH_1):PAGE252

SMB_BMC_SWB_SDA @T6G_MB_LIB.T6G(SCH_1):SMB_BMC_SWB_SDA
 R3106    1      A Q_RES_0402LF-0,5%,1/16W,CHIP,CS00002JB13    I43 @T6G_MB_LIB.T6G(SCH_1):PAGE249
 R2985    2      B Q_RES_0402LF-2.2K,5%,1/16W,CHIP,CS22202JB07    I42 @T6G_MB_LIB.T6G(SCH_1):PAGE252
 R2704    2      B Q_RES_0402LF-0,5%,1/16W,CHIP,CS00002JB13    I70 @T6G_MB_LIB.T6G(SCH_1):PAGE252

SMB_BMC_SWB_SDA_R4 @T6G_MB_LIB.T6G(SCH_1):SMB_BMC_SWB_SDA_R4
   U36   13    SD4 TCA9548APWR-TCA9548APWR,SMLF,IC,AL009548K02    I33 @T6G_MB_LIB.T6G(SCH_1):PAGE252
 R2704    1      A Q_RES_0402LF-0,5%,1/16W,CHIP,CS00002JB13    I70 @T6G_MB_LIB.T6G(SCH_1):PAGE252

SMB_CLK_PVDDCR_CPU1_P0_R @T6G_MB_LIB.T6G(SCH_1):SMB_CLK_PVDDCR_CPU1_P0_R
 R8071    2      B Q_RES_0402LF-0,5%,1/16W,CHIP,CS00002JB13    I85 @T6G_MB_LIB.T6G(SCH_1):PAGE175
  PU12   14  PMSCL RAA229620GNPHA0-RAA229620GNP#HA0,SMLF,IC,ARF0TGP40A   I128 @T6G_MB_LIB.T6G(SCH_1):PAGE175

SMB_CLK_PVDDCR_CPU1_P1_R @T6G_MB_LIB.T6G(SCH_1):SMB_CLK_PVDDCR_CPU1_P1_R
 R8248    2      B Q_RES_0402LF-0,5%,1/16W,CHIP,CS00002JB13    I84 @T6G_MB_LIB.T6G(SCH_1):PAGE192
  PU34   14  PMSCL RAA229620GNPHA0-RAA229620GNP#HA0,SMLF,IC,ARF0TGP40A   I128 @T6G_MB_LIB.T6G(SCH_1):PAGE192

SMB_CPU0_2_R_SCL @T6G_MB_LIB.T6G(SCH_1):SMB_CPU0_2_R_SCL
   U25  C72 I3C2_SCL||I2C2_SCL||SPD2_SCL||AGPIO149 GENOA_SP5-SOCKET6096_13568-001,SMLF,IO,DGA^6000030   I188 @T6G_MB_LIB.T6G(SCH_1):PAGE28
   R27    1      A Q_RES_0402LF-0,5%,1/16W,CHIP,CS00002JB13   I206 @T6G_MB_LIB.T6G(SCH_1):PAGE28

SMB_CPU0_2_R_SDA @T6G_MB_LIB.T6G(SCH_1):SMB_CPU0_2_R_SDA
   U25  B72 I3C2_SDA||I2C2_SDA||SPD2_SDA||AGPIO150 GENOA_SP5-SOCKET6096_13568-001,SMLF,IO,DGA^6000030   I188 @T6G_MB_LIB.T6G(SCH_1):PAGE28
   R28    1      A Q_RES_0402LF-0,5%,1/16W,CHIP,CS00002JB13   I207 @T6G_MB_LIB.T6G(SCH_1):PAGE28

SMB_CPU0_2_SCL @T6G_MB_LIB.T6G(SCH_1):SMB_CPU0_2_SCL
   R27    2      B Q_RES_0402LF-0,5%,1/16W,CHIP,CS00002JB13   I206 @T6G_MB_LIB.T6G(SCH_1):PAGE28
 R6081    2      B Q_RES_0402LF-4.7K,5%,1/16W,CHIP,CS24702JB10   I210 @T6G_MB_LIB.T6G(SCH_1):PAGE28

SMB_CPU0_2_SDA @T6G_MB_LIB.T6G(SCH_1):SMB_CPU0_2_SDA
   R28    2      B Q_RES_0402LF-0,5%,1/16W,CHIP,CS00002JB13   I207 @T6G_MB_LIB.T6G(SCH_1):PAGE28
 R6082    2      B Q_RES_0402LF-4.7K,5%,1/16W,CHIP,CS24702JB10   I212 @T6G_MB_LIB.T6G(SCH_1):PAGE28

SMB_CPU0_3_R_SCL @T6G_MB_LIB.T6G(SCH_1):SMB_CPU0_3_R_SCL
   U25   A4 I3C3_SCL||I2C3_SCL||SPD3_SCL||AGPIO151 GENOA_SP5-SOCKET6096_13568-001,SMLF,IO,DGA^6000030   I188 @T6G_MB_LIB.T6G(SCH_1):PAGE28
   R29    1      A Q_RES_0402LF-0,5%,1/16W,CHIP,CS00002JB13   I208 @T6G_MB_LIB.T6G(SCH_1):PAGE28

SMB_CPU0_3_R_SDA @T6G_MB_LIB.T6G(SCH_1):SMB_CPU0_3_R_SDA
   U25   B4 I3C3_SDA||I2C3_SDA||SPD3_SDA||AGPIO152 GENOA_SP5-SOCKET6096_13568-001,SMLF,IO,DGA^6000030   I188 @T6G_MB_LIB.T6G(SCH_1):PAGE28
   R30    1      A Q_RES_0402LF-0,5%,1/16W,CHIP,CS00002JB13   I209 @T6G_MB_LIB.T6G(SCH_1):PAGE28

SMB_CPU0_3_SCL @T6G_MB_LIB.T6G(SCH_1):SMB_CPU0_3_SCL
   R29    2      B Q_RES_0402LF-0,5%,1/16W,CHIP,CS00002JB13   I208 @T6G_MB_LIB.T6G(SCH_1):PAGE28
 R6083    2      B Q_RES_0402LF-4.7K,5%,1/16W,CHIP,CS24702JB10   I213 @T6G_MB_LIB.T6G(SCH_1):PAGE28

SMB_CPU0_3_SDA @T6G_MB_LIB.T6G(SCH_1):SMB_CPU0_3_SDA
   R30    2      B Q_RES_0402LF-0,5%,1/16W,CHIP,CS00002JB13   I209 @T6G_MB_LIB.T6G(SCH_1):PAGE28
 R6084    2      B Q_RES_0402LF-4.7K,5%,1/16W,CHIP,CS24702JB10   I214 @T6G_MB_LIB.T6G(SCH_1):PAGE28

SMB_CPU0_4_R_SCL @T6G_MB_LIB.T6G(SCH_1):SMB_CPU0_4_R_SCL
  R430    1      A Q_RES_0402LF-0,5%,1/16W,CHIP,CS00002JB13    I98 @T6G_MB_LIB.T6G(SCH_1):PAGE28
   U25 DG12 I2C4_SCL||HP_SCL||UBM_SCL||AGPIO13 GENOA_SP5-SOCKET6096_13568-001,SMLF,IO,DGA^6000030   I188 @T6G_MB_LIB.T6G(SCH_1):PAGE28

SMB_CPU0_4_R_SDA @T6G_MB_LIB.T6G(SCH_1):SMB_CPU0_4_R_SDA
  R431    1      A Q_RES_0402LF-0,5%,1/16W,CHIP,CS00002JB13    I97 @T6G_MB_LIB.T6G(SCH_1):PAGE28
   U25 DH12 I2C4_SDA||HP_SDA||UBM_SDA||AGPIO14 GENOA_SP5-SOCKET6096_13568-001,SMLF,IO,DGA^6000030   I188 @T6G_MB_LIB.T6G(SCH_1):PAGE28

SMB_CPU0_4_SCL @T6G_MB_LIB.T6G(SCH_1):SMB_CPU0_4_SCL
   U27    2   SCLA PCA9617ADP-PCA9617ADP,SMLF,IC,AL009617K02    I18 @T6G_MB_LIB.T6G(SCH_1):PAGE34
  R495    2      B Q_RES_0402LF-4.7K,5%,1/16W,CHIP,CS24702JB10   I106 @T6G_MB_LIB.T6G(SCH_1):PAGE34
  R430    2      B Q_RES_0402LF-0,5%,1/16W,CHIP,CS00002JB13    I98 @T6G_MB_LIB.T6G(SCH_1):PAGE28

SMB_CPU0_4_SDA @T6G_MB_LIB.T6G(SCH_1):SMB_CPU0_4_SDA
   U27    3   SDAA PCA9617ADP-PCA9617ADP,SMLF,IC,AL009617K02    I18 @T6G_MB_LIB.T6G(SCH_1):PAGE34
  R498    2      B Q_RES_0402LF-2.2K,5%,1/16W,CHIP,CS22202JB07   I107 @T6G_MB_LIB.T6G(SCH_1):PAGE34
  R431    2      B Q_RES_0402LF-0,5%,1/16W,CHIP,CS00002JB13    I97 @T6G_MB_LIB.T6G(SCH_1):PAGE28

SMB_CPU0_4_XLTR_R_SCL @T6G_MB_LIB.T6G(SCH_1):SMB_CPU0_4_XLTR_R_SCL
   R70    1      A Q_RES_0402LF-0,5%,1/16W,CHIP,CS00002JB13    I19 @T6G_MB_LIB.T6G(SCH_1):PAGE79
   U18  G11  PT23C LCMXO3LF9400C5BG484C-LCMXO3LF-9400C-5BG484C,SMLF,IA    I94 @T6G_MB_LIB.T6G(SCH_1):PAGE79

SMB_CPU0_4_XLTR_R_SDA @T6G_MB_LIB.T6G(SCH_1):SMB_CPU0_4_XLTR_R_SDA
  R493    1      A Q_RES_0402LF-0,5%,1/16W,CHIP,CS00002JB13    I18 @T6G_MB_LIB.T6G(SCH_1):PAGE79
   U18  F11  PT23D LCMXO3LF9400C5BG484C-LCMXO3LF-9400C-5BG484C,SMLF,IA    I94 @T6G_MB_LIB.T6G(SCH_1):PAGE79

SMB_CPU0_4_XLTR_SCL @T6G_MB_LIB.T6G(SCH_1):SMB_CPU0_4_XLTR_SCL
  R499    2      B Q_RES_0402LF-4.7K,5%,1/16W,CHIP,CS24702JB10     I4 @T6G_MB_LIB.T6G(SCH_1):PAGE34
   U27    7   SCLB PCA9617ADP-PCA9617ADP,SMLF,IC,AL009617K02    I18 @T6G_MB_LIB.T6G(SCH_1):PAGE34
   R70    2      B Q_RES_0402LF-0,5%,1/16W,CHIP,CS00002JB13    I19 @T6G_MB_LIB.T6G(SCH_1):PAGE79

SMB_CPU0_4_XLTR_SDA @T6G_MB_LIB.T6G(SCH_1):SMB_CPU0_4_XLTR_SDA
  R590    2      B Q_RES_0402LF-4.7K,5%,1/16W,CHIP,CS24702JB10     I5 @T6G_MB_LIB.T6G(SCH_1):PAGE34
   U27    6   SDAB PCA9617ADP-PCA9617ADP,SMLF,IC,AL009617K02    I18 @T6G_MB_LIB.T6G(SCH_1):PAGE34
  R493    2      B Q_RES_0402LF-0,5%,1/16W,CHIP,CS00002JB13    I18 @T6G_MB_LIB.T6G(SCH_1):PAGE79

SMB_CPU0_CPU1_APML_BUF1_SCL @T6G_MB_LIB.T6G(SCH_1):SMB_CPU0_CPU1_APML_BUF1_SCL
    U5    2   SCLA PCA9617ADP-PCA9617ADP,SMLF,EMPTY,AL009617K02    I48 @T6G_MB_LIB.T6G(SCH_1):PAGE137
  R789    1      A Q_RES_0402LF-0,5%,1/16W,EMPTY,CS00002JB13    I96 @T6G_MB_LIB.T6G(SCH_1):PAGE137
  R140    2      B Q_RES_0402LF-0,5%,1/16W,EMPTY,CS00002JB13    I98 @T6G_MB_LIB.T6G(SCH_1):PAGE137

SMB_CPU0_CPU1_APML_BUF1_SCL_R1 @T6G_MB_LIB.T6G(SCH_1):SMB_CPU0_CPU1_APML_BUF1_SCL_R1
    U5    7   SCLB PCA9617ADP-PCA9617ADP,SMLF,EMPTY,AL009617K02    I48 @T6G_MB_LIB.T6G(SCH_1):PAGE137
 R1151    1      A Q_RES_0402LF-0,5%,1/16W,EMPTY,CS00002JB13    I93 @T6G_MB_LIB.T6G(SCH_1):PAGE137
  R789    2      B Q_RES_0402LF-0,5%,1/16W,EMPTY,CS00002JB13    I96 @T6G_MB_LIB.T6G(SCH_1):PAGE137

SMB_CPU0_CPU1_APML_BUF1_SCL_R2 @T6G_MB_LIB.T6G(SCH_1):SMB_CPU0_CPU1_APML_BUF1_SCL_R2
  R361    2      B Q_RES_0402LF-4.7K,5%,1/16W,EMPTY,CS24702JB10    I40 @T6G_MB_LIB.T6G(SCH_1):PAGE137
  R256    1      A Q_RES_0402LF-0,5%,1/16W,EMPTY,CS00002JB13    I92 @T6G_MB_LIB.T6G(SCH_1):PAGE137
 R1151    2      B Q_RES_0402LF-0,5%,1/16W,EMPTY,CS00002JB13    I93 @T6G_MB_LIB.T6G(SCH_1):PAGE137

SMB_CPU0_CPU1_APML_BUF1_SDA @T6G_MB_LIB.T6G(SCH_1):SMB_CPU0_CPU1_APML_BUF1_SDA
    U5    3   SDAA PCA9617ADP-PCA9617ADP,SMLF,EMPTY,AL009617K02    I48 @T6G_MB_LIB.T6G(SCH_1):PAGE137
  R790    1      A Q_RES_0402LF-0,5%,1/16W,EMPTY,CS00002JB13    I95 @T6G_MB_LIB.T6G(SCH_1):PAGE137
  R150    2      B Q_RES_0402LF-0,5%,1/16W,EMPTY,CS00002JB13    I97 @T6G_MB_LIB.T6G(SCH_1):PAGE137

SMB_CPU0_CPU1_APML_BUF1_SDA_R1 @T6G_MB_LIB.T6G(SCH_1):SMB_CPU0_CPU1_APML_BUF1_SDA_R1
    U5    6   SDAB PCA9617ADP-PCA9617ADP,SMLF,EMPTY,AL009617K02    I48 @T6G_MB_LIB.T6G(SCH_1):PAGE137
 R1152    1      A Q_RES_0402LF-0,5%,1/16W,EMPTY,CS00002JB13    I94 @T6G_MB_LIB.T6G(SCH_1):PAGE137
  R790    2      B Q_RES_0402LF-0,5%,1/16W,EMPTY,CS00002JB13    I95 @T6G_MB_LIB.T6G(SCH_1):PAGE137

SMB_CPU0_CPU1_APML_BUF1_SDA_R2 @T6G_MB_LIB.T6G(SCH_1):SMB_CPU0_CPU1_APML_BUF1_SDA_R2
  R365    2      B Q_RES_0402LF-4.7K,5%,1/16W,EMPTY,CS24702JB10    I41 @T6G_MB_LIB.T6G(SCH_1):PAGE137
  R257    1      A Q_RES_0402LF-0,5%,1/16W,EMPTY,CS00002JB13    I91 @T6G_MB_LIB.T6G(SCH_1):PAGE137
 R1152    2      B Q_RES_0402LF-0,5%,1/16W,EMPTY,CS00002JB13    I94 @T6G_MB_LIB.T6G(SCH_1):PAGE137

SMB_CPU0_CPU1_APML_BUF2_SCL @T6G_MB_LIB.T6G(SCH_1):SMB_CPU0_CPU1_APML_BUF2_SCL
  R151    2      B Q_RES_0402LF-0,5%,1/16W,CHIP,CS00002JB13    I79 @T6G_MB_LIB.T6G(SCH_1):PAGE137
    U2    7   SCLB PCA9617ADP-PCA9617ADP,SMLF,IC,AL009617K02    I99 @T6G_MB_LIB.T6G(SCH_1):PAGE137

SMB_CPU0_CPU1_APML_BUF2_SCL_R1 @T6G_MB_LIB.T6G(SCH_1):SMB_CPU0_CPU1_APML_BUF2_SCL_R1
  R202    1      A Q_RES_0402LF-0,5%,1/16W,CHIP,CS00002JB13    I67 @T6G_MB_LIB.T6G(SCH_1):PAGE137
    U2    2   SCLA PCA9617ADP-PCA9617ADP,SMLF,IC,AL009617K02    I99 @T6G_MB_LIB.T6G(SCH_1):PAGE137

SMB_CPU0_CPU1_APML_BUF2_SCL_R2 @T6G_MB_LIB.T6G(SCH_1):SMB_CPU0_CPU1_APML_BUF2_SCL_R2
  R202    2      B Q_RES_0402LF-0,5%,1/16W,CHIP,CS00002JB13    I67 @T6G_MB_LIB.T6G(SCH_1):PAGE137
  R274    1      A Q_RES_0402LF-0,5%,1/16W,CHIP,CS00002JB13    I71 @T6G_MB_LIB.T6G(SCH_1):PAGE137
  R322    2      B Q_RES_0402LF-1K,1%,1/16W,EMPTY,CS21002FB06    I73 @T6G_MB_LIB.T6G(SCH_1):PAGE137

SMB_CPU0_CPU1_APML_BUF2_SDA @T6G_MB_LIB.T6G(SCH_1):SMB_CPU0_CPU1_APML_BUF2_SDA
  R162    2      B Q_RES_0402LF-0,5%,1/16W,CHIP,CS00002JB13    I80 @T6G_MB_LIB.T6G(SCH_1):PAGE137
    U2    6   SDAB PCA9617ADP-PCA9617ADP,SMLF,IC,AL009617K02    I99 @T6G_MB_LIB.T6G(SCH_1):PAGE137

SMB_CPU0_CPU1_APML_BUF2_SDA_R1 @T6G_MB_LIB.T6G(SCH_1):SMB_CPU0_CPU1_APML_BUF2_SDA_R1
  R206    1      A Q_RES_0402LF-0,5%,1/16W,CHIP,CS00002JB13    I68 @T6G_MB_LIB.T6G(SCH_1):PAGE137
    U2    3   SDAA PCA9617ADP-PCA9617ADP,SMLF,IC,AL009617K02    I99 @T6G_MB_LIB.T6G(SCH_1):PAGE137

SMB_CPU0_CPU1_APML_BUF2_SDA_R2 @T6G_MB_LIB.T6G(SCH_1):SMB_CPU0_CPU1_APML_BUF2_SDA_R2
  R206    2      B Q_RES_0402LF-0,5%,1/16W,CHIP,CS00002JB13    I68 @T6G_MB_LIB.T6G(SCH_1):PAGE137
  R281    1      A Q_RES_0402LF-0,5%,1/16W,CHIP,CS00002JB13    I72 @T6G_MB_LIB.T6G(SCH_1):PAGE137
  R290    2      B Q_RES_0402LF-1K,1%,1/16W,EMPTY,CS21002FB06    I78 @T6G_MB_LIB.T6G(SCH_1):PAGE137

SMB_CPU0_CPU1_APML_MUX1_SCL @T6G_MB_LIB.T6G(SCH_1):SMB_CPU0_CPU1_APML_MUX1_SCL
  R146    1      A Q_RES_0402LF-0,5%,1/16W,EMPTY,CS00002JB13    I17 @T6G_MB_LIB.T6G(SCH_1):PAGE138
  R142    1      A Q_RES_0402LF-0,5%,1/16W,EMPTY,CS00002JB13    I35 @T6G_MB_LIB.T6G(SCH_1):PAGE138
  R324    2      B Q_RES_0402LF-0,5%,1/16W,EMPTY,CS00002JB13   I110 @T6G_MB_LIB.T6G(SCH_1):PAGE138
  U213    3   HSCL IML3112Y2B000NCG8-IML3112-Y2B000NCG8,SMLF,EMPTY,ALA   I111 @T6G_MB_LIB.T6G(SCH_1):PAGE138

SMB_CPU0_CPU1_APML_MUX1_SDA @T6G_MB_LIB.T6G(SCH_1):SMB_CPU0_CPU1_APML_MUX1_SDA
  R147    1      A Q_RES_0402LF-0,5%,1/16W,EMPTY,CS00002JB13    I16 @T6G_MB_LIB.T6G(SCH_1):PAGE138
  R143    1      A Q_RES_0402LF-0,5%,1/16W,EMPTY,CS00002JB13    I34 @T6G_MB_LIB.T6G(SCH_1):PAGE138
  R323    2      B Q_RES_0402LF-0,5%,1/16W,EMPTY,CS00002JB13   I109 @T6G_MB_LIB.T6G(SCH_1):PAGE138
  U213    2   HSDA IML3112Y2B000NCG8-IML3112-Y2B000NCG8,SMLF,EMPTY,ALA   I111 @T6G_MB_LIB.T6G(SCH_1):PAGE138

SMB_CPU0_CPU1_APML_MUX2_SCL @T6G_MB_LIB.T6G(SCH_1):SMB_CPU0_CPU1_APML_MUX2_SCL
  R325    2      B Q_RES_0402LF-0,5%,1/16W,CHIP,CS00002JB13    I99 @T6G_MB_LIB.T6G(SCH_1):PAGE138
    U4    8     D+ PI3CSW12ZUAEX-PI3CSW12ZUAEX,SMLF,IC,AL3CSW12000   I114 @T6G_MB_LIB.T6G(SCH_1):PAGE138

SMB_CPU0_CPU1_APML_MUX2_SDA @T6G_MB_LIB.T6G(SCH_1):SMB_CPU0_CPU1_APML_MUX2_SDA
  R326    2      B Q_RES_0402LF-0,5%,1/16W,CHIP,CS00002JB13   I100 @T6G_MB_LIB.T6G(SCH_1):PAGE138
    U4    7     D- PI3CSW12ZUAEX-PI3CSW12ZUAEX,SMLF,IC,AL3CSW12000   I114 @T6G_MB_LIB.T6G(SCH_1):PAGE138

SMB_CPU0_CPU1_APML_SCL @T6G_MB_LIB.T6G(SCH_1):SMB_CPU0_CPU1_APML_SCL
 R1319    1      A Q_RES_0402LF-2K,1%,1/16W,EMPTY,CS22002FB07   I138 @T6G_MB_LIB.T6G(SCH_1):PAGE349
 R2419    1      A Q_RES_0402LF-33.2,1%,1/16W,CHIP,CS03322FB03   I104 @T6G_MB_LIB.T6G(SCH_1):PAGE348
  R151    1      A Q_RES_0402LF-0,5%,1/16W,CHIP,CS00002JB13    I79 @T6G_MB_LIB.T6G(SCH_1):PAGE137
  R140    1      A Q_RES_0402LF-0,5%,1/16W,EMPTY,CS00002JB13    I98 @T6G_MB_LIB.T6G(SCH_1):PAGE137

SMB_CPU0_CPU1_APML_SCL_R @T6G_MB_LIB.T6G(SCH_1):SMB_CPU0_CPU1_APML_SCL_R
   J41   A3 GND_A3 SCONN168_ME1016810202011-SCONN168_ME1016810202011,A   I176 @T6G_MB_LIB.T6G(SCH_1):PAGE348
 R2419    2      B Q_RES_0402LF-33.2,1%,1/16W,CHIP,CS03322FB03   I104 @T6G_MB_LIB.T6G(SCH_1):PAGE348

SMB_CPU0_CPU1_APML_SCL_R2 @T6G_MB_LIB.T6G(SCH_1):SMB_CPU0_CPU1_APML_SCL_R2
  R325    1      A Q_RES_0402LF-0,5%,1/16W,CHIP,CS00002JB13    I99 @T6G_MB_LIB.T6G(SCH_1):PAGE138
  R274    2      B Q_RES_0402LF-0,5%,1/16W,CHIP,CS00002JB13    I71 @T6G_MB_LIB.T6G(SCH_1):PAGE137
  R324    1      A Q_RES_0402LF-0,5%,1/16W,EMPTY,CS00002JB13   I110 @T6G_MB_LIB.T6G(SCH_1):PAGE138
  R256    2      B Q_RES_0402LF-0,5%,1/16W,EMPTY,CS00002JB13    I92 @T6G_MB_LIB.T6G(SCH_1):PAGE137

SMB_CPU0_CPU1_APML_SDA @T6G_MB_LIB.T6G(SCH_1):SMB_CPU0_CPU1_APML_SDA
 R3062    1      A Q_RES_0402LF-2K,1%,1/16W,EMPTY,CS22002FB07   I137 @T6G_MB_LIB.T6G(SCH_1):PAGE349
 R2420    1      A Q_RES_0402LF-33.2,1%,1/16W,CHIP,CS03322FB03   I105 @T6G_MB_LIB.T6G(SCH_1):PAGE348
  R162    1      A Q_RES_0402LF-0,5%,1/16W,CHIP,CS00002JB13    I80 @T6G_MB_LIB.T6G(SCH_1):PAGE137
  R150    1      A Q_RES_0402LF-0,5%,1/16W,EMPTY,CS00002JB13    I97 @T6G_MB_LIB.T6G(SCH_1):PAGE137

SMB_CPU0_CPU1_APML_SDA_R @T6G_MB_LIB.T6G(SCH_1):SMB_CPU0_CPU1_APML_SDA_R
   J41   A4 GND_A4 SCONN168_ME1016810202011-SCONN168_ME1016810202011,A   I176 @T6G_MB_LIB.T6G(SCH_1):PAGE348
 R2420    2      B Q_RES_0402LF-33.2,1%,1/16W,CHIP,CS03322FB03   I105 @T6G_MB_LIB.T6G(SCH_1):PAGE348

SMB_CPU0_CPU1_APML_SDA_R2 @T6G_MB_LIB.T6G(SCH_1):SMB_CPU0_CPU1_APML_SDA_R2
  R326    1      A Q_RES_0402LF-0,5%,1/16W,CHIP,CS00002JB13   I100 @T6G_MB_LIB.T6G(SCH_1):PAGE138
  R281    2      B Q_RES_0402LF-0,5%,1/16W,CHIP,CS00002JB13    I72 @T6G_MB_LIB.T6G(SCH_1):PAGE137
  R323    1      A Q_RES_0402LF-0,5%,1/16W,EMPTY,CS00002JB13   I109 @T6G_MB_LIB.T6G(SCH_1):PAGE138
  R257    2      B Q_RES_0402LF-0,5%,1/16W,EMPTY,CS00002JB13    I91 @T6G_MB_LIB.T6G(SCH_1):PAGE137

SMB_CPU0_CPU1_SEC_SCL @T6G_MB_LIB.T6G(SCH_1):SMB_CPU0_CPU1_SEC_SCL
 R1384    1      A Q_RES_0402LF-2K,1%,1/16W,EMPTY,CS22002FB07   I136 @T6G_MB_LIB.T6G(SCH_1):PAGE349
 R4506    1      A Q_RES_0402LF-33.2,1%,1/16W,CHIP,CS03322FB03   I191 @T6G_MB_LIB.T6G(SCH_1):PAGE348
   U96    7   SCLB PCA9617ADP-PCA9617ADP,SMLF,IC,AL009617K02    I51 @T6G_MB_LIB.T6G(SCH_1):PAGE137

SMB_CPU0_CPU1_SEC_SCL_R @T6G_MB_LIB.T6G(SCH_1):SMB_CPU0_CPU1_SEC_SCL_R
   J41   A7  SMCLK SCONN168_ME1016810202011-SCONN168_ME1016810202011,A   I176 @T6G_MB_LIB.T6G(SCH_1):PAGE348
 R4506    2      B Q_RES_0402LF-33.2,1%,1/16W,CHIP,CS03322FB03   I191 @T6G_MB_LIB.T6G(SCH_1):PAGE348

SMB_CPU0_CPU1_SEC_SCL_R1 @T6G_MB_LIB.T6G(SCH_1):SMB_CPU0_CPU1_SEC_SCL_R1
 R1153    1      A Q_RES_0402LF-0,5%,1/16W,CHIP,CS00002JB13    I16 @T6G_MB_LIB.T6G(SCH_1):PAGE137
   U96    2   SCLA PCA9617ADP-PCA9617ADP,SMLF,IC,AL009617K02    I51 @T6G_MB_LIB.T6G(SCH_1):PAGE137

SMB_CPU0_CPU1_SEC_SCL_R2 @T6G_MB_LIB.T6G(SCH_1):SMB_CPU0_CPU1_SEC_SCL_R2
  R358    1      A Q_RES_0402LF-0,5%,1/16W,EMPTY,CS00002JB13     I5 @T6G_MB_LIB.T6G(SCH_1):PAGE138
  R145    1      A Q_RES_0402LF-0,5%,1/16W,EMPTY,CS00002JB13    I14 @T6G_MB_LIB.T6G(SCH_1):PAGE138
 R1153    2      B Q_RES_0402LF-0,5%,1/16W,CHIP,CS00002JB13    I16 @T6G_MB_LIB.T6G(SCH_1):PAGE137
  R368    2      B Q_RES_0402LF-4.7K,5%,1/16W,EMPTY,CS24702JB10    I44 @T6G_MB_LIB.T6G(SCH_1):PAGE137
    U6    8     D+ PI3CSW12ZUAEX-PI3CSW12ZUAEX,SMLF,IC,AL3CSW12000    I67 @T6G_MB_LIB.T6G(SCH_1):PAGE138

SMB_CPU0_CPU1_SEC_SDA @T6G_MB_LIB.T6G(SCH_1):SMB_CPU0_CPU1_SEC_SDA
 R1385    1      A Q_RES_0402LF-2K,1%,1/16W,EMPTY,CS22002FB07   I135 @T6G_MB_LIB.T6G(SCH_1):PAGE349
 R4507    1      A Q_RES_0402LF-33.2,1%,1/16W,CHIP,CS03322FB03   I190 @T6G_MB_LIB.T6G(SCH_1):PAGE348
   U96    6   SDAB PCA9617ADP-PCA9617ADP,SMLF,IC,AL009617K02    I51 @T6G_MB_LIB.T6G(SCH_1):PAGE137

SMB_CPU0_CPU1_SEC_SDA_R @T6G_MB_LIB.T6G(SCH_1):SMB_CPU0_CPU1_SEC_SDA_R
   J41   A8  SMDAT SCONN168_ME1016810202011-SCONN168_ME1016810202011,A   I176 @T6G_MB_LIB.T6G(SCH_1):PAGE348
 R4507    2      B Q_RES_0402LF-33.2,1%,1/16W,CHIP,CS03322FB03   I190 @T6G_MB_LIB.T6G(SCH_1):PAGE348

SMB_CPU0_CPU1_SEC_SDA_R1 @T6G_MB_LIB.T6G(SCH_1):SMB_CPU0_CPU1_SEC_SDA_R1
 R1154    1      A Q_RES_0402LF-0,5%,1/16W,CHIP,CS00002JB13    I15 @T6G_MB_LIB.T6G(SCH_1):PAGE137
   U96    3   SDAA PCA9617ADP-PCA9617ADP,SMLF,IC,AL009617K02    I51 @T6G_MB_LIB.T6G(SCH_1):PAGE137

SMB_CPU0_CPU1_SEC_SDA_R2 @T6G_MB_LIB.T6G(SCH_1):SMB_CPU0_CPU1_SEC_SDA_R2
  R148    1      A Q_RES_0402LF-0,5%,1/16W,EMPTY,CS00002JB13     I6 @T6G_MB_LIB.T6G(SCH_1):PAGE138
  R144    1      A Q_RES_0402LF-0,5%,1/16W,EMPTY,CS00002JB13    I15 @T6G_MB_LIB.T6G(SCH_1):PAGE138
 R1154    2      B Q_RES_0402LF-0,5%,1/16W,CHIP,CS00002JB13    I15 @T6G_MB_LIB.T6G(SCH_1):PAGE137
  R406    2      B Q_RES_0402LF-4.7K,5%,1/16W,EMPTY,CS24702JB10    I46 @T6G_MB_LIB.T6G(SCH_1):PAGE137
    U6    7     D- PI3CSW12ZUAEX-PI3CSW12ZUAEX,SMLF,IC,AL3CSW12000    I67 @T6G_MB_LIB.T6G(SCH_1):PAGE138

SMB_CPU0_SEC_R_SCL @T6G_MB_LIB.T6G(SCH_1):SMB_CPU0_SEC_R_SCL
  R145    2      B Q_RES_0402LF-0,5%,1/16W,EMPTY,CS00002JB13    I14 @T6G_MB_LIB.T6G(SCH_1):PAGE138
    U6    1    1D+ PI3CSW12ZUAEX-PI3CSW12ZUAEX,SMLF,IC,AL3CSW12000    I67 @T6G_MB_LIB.T6G(SCH_1):PAGE138
 R1159    1      A Q_RES_0402LF-0,5%,1/16W,CHIP,CS00002JB13    I76 @T6G_MB_LIB.T6G(SCH_1):PAGE138

SMB_CPU0_SEC_R_SDA @T6G_MB_LIB.T6G(SCH_1):SMB_CPU0_SEC_R_SDA
  R144    2      B Q_RES_0402LF-0,5%,1/16W,EMPTY,CS00002JB13    I15 @T6G_MB_LIB.T6G(SCH_1):PAGE138
    U6    2    1D- PI3CSW12ZUAEX-PI3CSW12ZUAEX,SMLF,IC,AL3CSW12000    I67 @T6G_MB_LIB.T6G(SCH_1):PAGE138
 R1160    1      A Q_RES_0402LF-0,5%,1/16W,CHIP,CS00002JB13    I75 @T6G_MB_LIB.T6G(SCH_1):PAGE138

SMB_CPU0_SEC_SCL @T6G_MB_LIB.T6G(SCH_1):SMB_CPU0_SEC_SCL
  R367    2      B Q_RES_0402LF-1K,1%,1/16W,CHIP,CS21002FB06    I57 @T6G_MB_LIB.T6G(SCH_1):PAGE138
   U25  B14 SEC_SCL||AGPIO262 GENOA_SP5-SOCKET6096_13568-001,SMLF,IO,DGA^6000030   I188 @T6G_MB_LIB.T6G(SCH_1):PAGE28
 R1159    2      B Q_RES_0402LF-0,5%,1/16W,CHIP,CS00002JB13    I76 @T6G_MB_LIB.T6G(SCH_1):PAGE138

SMB_CPU0_SEC_SDA @T6G_MB_LIB.T6G(SCH_1):SMB_CPU0_SEC_SDA
  R370    2      B Q_RES_0402LF-1K,1%,1/16W,CHIP,CS21002FB06    I60 @T6G_MB_LIB.T6G(SCH_1):PAGE138
   U25  D14 SEC_SDA||AGPIO263 GENOA_SP5-SOCKET6096_13568-001,SMLF,IO,DGA^6000030   I188 @T6G_MB_LIB.T6G(SCH_1):PAGE28
 R1160    2      B Q_RES_0402LF-0,5%,1/16W,CHIP,CS00002JB13    I75 @T6G_MB_LIB.T6G(SCH_1):PAGE138

SMB_CPU1_SEC_R_SCL @T6G_MB_LIB.T6G(SCH_1):SMB_CPU1_SEC_R_SCL
  R358    2      B Q_RES_0402LF-0,5%,1/16W,EMPTY,CS00002JB13     I5 @T6G_MB_LIB.T6G(SCH_1):PAGE138
 R1161    1      A Q_RES_0402LF-0,5%,1/16W,CHIP,CS00002JB13    I23 @T6G_MB_LIB.T6G(SCH_1):PAGE138
    U6    3    2D+ PI3CSW12ZUAEX-PI3CSW12ZUAEX,SMLF,IC,AL3CSW12000    I67 @T6G_MB_LIB.T6G(SCH_1):PAGE138

SMB_CPU1_SEC_R_SDA @T6G_MB_LIB.T6G(SCH_1):SMB_CPU1_SEC_R_SDA
  R148    2      B Q_RES_0402LF-0,5%,1/16W,EMPTY,CS00002JB13     I6 @T6G_MB_LIB.T6G(SCH_1):PAGE138
 R1162    1      A Q_RES_0402LF-0,5%,1/16W,CHIP,CS00002JB13    I22 @T6G_MB_LIB.T6G(SCH_1):PAGE138
    U6    4    2D- PI3CSW12ZUAEX-PI3CSW12ZUAEX,SMLF,IC,AL3CSW12000    I67 @T6G_MB_LIB.T6G(SCH_1):PAGE138

SMB_CPU1_SEC_SCL @T6G_MB_LIB.T6G(SCH_1):SMB_CPU1_SEC_SCL
   U26  B14 SEC_SCL||AGPIO262 GENOA_SP5-SOCKET6096_13568-001,SMLF,IO,DGA^6000030   I182 @T6G_MB_LIB.T6G(SCH_1):PAGE55
  R366    2      B Q_RES_0402LF-1K,1%,1/16W,CHIP,CS21002FB06    I54 @T6G_MB_LIB.T6G(SCH_1):PAGE138
 R1161    2      B Q_RES_0402LF-0,5%,1/16W,CHIP,CS00002JB13    I23 @T6G_MB_LIB.T6G(SCH_1):PAGE138

SMB_CPU1_SEC_SDA @T6G_MB_LIB.T6G(SCH_1):SMB_CPU1_SEC_SDA
   U26  D14 SEC_SDA||AGPIO263 GENOA_SP5-SOCKET6096_13568-001,SMLF,IO,DGA^6000030   I182 @T6G_MB_LIB.T6G(SCH_1):PAGE55
  R369    2      B Q_RES_0402LF-1K,1%,1/16W,CHIP,CS21002FB06    I58 @T6G_MB_LIB.T6G(SCH_1):PAGE138
 R1162    2      B Q_RES_0402LF-0,5%,1/16W,CHIP,CS00002JB13    I22 @T6G_MB_LIB.T6G(SCH_1):PAGE138

SMB_CPU_5_R1_SCL @T6G_MB_LIB.T6G(SCH_1):SMB_CPU_5_R1_SCL
 R1447    2      B Q_RES_0402LF-0,5%,1/16W,CHIP,CS00002JB13    I57 @T6G_MB_LIB.T6G(SCH_1):PAGE349
   U18  M20  PR17C LCMXO3LF9400C5BG484C-LCMXO3LF-9400C-5BG484C,SMLF,IA   I217 @T6G_MB_LIB.T6G(SCH_1):PAGE80

SMB_CPU_5_R1_SDA @T6G_MB_LIB.T6G(SCH_1):SMB_CPU_5_R1_SDA
   U18  M19  PR17D LCMXO3LF9400C5BG484C-LCMXO3LF-9400C-5BG484C,SMLF,IA   I217 @T6G_MB_LIB.T6G(SCH_1):PAGE80
 R1453    2      B Q_RES_0402LF-0,5%,1/16W,CHIP,CS00002JB13    I56 @T6G_MB_LIB.T6G(SCH_1):PAGE349

SMB_CPU_5_R_SCL @T6G_MB_LIB.T6G(SCH_1):SMB_CPU_5_R_SCL
  R212    1      A Q_RES_0402LF-33,5%,1/16W,CHIP,CS03302JB10    I96 @T6G_MB_LIB.T6G(SCH_1):PAGE28
   U25 DJ21 I2C5_SCL||BMC_SCL||SMBUS1_SCL||AGPIO19 GENOA_SP5-SOCKET6096_13568-001,SMLF,IO,DGA^6000030   I188 @T6G_MB_LIB.T6G(SCH_1):PAGE28

SMB_CPU_5_R_SDA @T6G_MB_LIB.T6G(SCH_1):SMB_CPU_5_R_SDA
  R213    1      A Q_RES_0402LF-0,5%,1/16W,CHIP,CS00002JB13    I95 @T6G_MB_LIB.T6G(SCH_1):PAGE28
   U25 DJ20 I2C5_SDA||BMC_SDA||SMBUS1_SDA||AGPIO20 GENOA_SP5-SOCKET6096_13568-001,SMLF,IO,DGA^6000030   I188 @T6G_MB_LIB.T6G(SCH_1):PAGE28

SMB_CPU_5_SCL @T6G_MB_LIB.T6G(SCH_1):SMB_CPU_5_SCL
 R1447    1      A Q_RES_0402LF-0,5%,1/16W,CHIP,CS00002JB13    I57 @T6G_MB_LIB.T6G(SCH_1):PAGE349
  R212    2      B Q_RES_0402LF-33,5%,1/16W,CHIP,CS03302JB10    I96 @T6G_MB_LIB.T6G(SCH_1):PAGE28
  R632    2      B Q_RES_0402LF-2.2K,5%,1/16W,CHIP,CS22202JB07    I18 @T6G_MB_LIB.T6G(SCH_1):PAGE349

SMB_CPU_5_SDA @T6G_MB_LIB.T6G(SCH_1):SMB_CPU_5_SDA
  R633    2      B Q_RES_0402LF-2.2K,5%,1/16W,CHIP,CS22202JB07    I17 @T6G_MB_LIB.T6G(SCH_1):PAGE349
 R1453    1      A Q_RES_0402LF-0,5%,1/16W,CHIP,CS00002JB13    I56 @T6G_MB_LIB.T6G(SCH_1):PAGE349
  R213    2      B Q_RES_0402LF-0,5%,1/16W,CHIP,CS00002JB13    I95 @T6G_MB_LIB.T6G(SCH_1):PAGE28

SMB_CPU_FRU_3V3AUX_SCL @T6G_MB_LIB.T6G(SCH_1):SMB_CPU_FRU_3V3AUX_SCL
    R4    2      B Q_RES_0402LF-4.7K,5%,1/16W,EMPTY,CS24702JB10   I114 @T6G_MB_LIB.T6G(SCH_1):PAGE361
    U1    6    SCL M24128BWMN6TP-M24128-BWMN6TP,SMLF,IC,AKE30Z00613    I97 @T6G_MB_LIB.T6G(SCH_1):PAGE361
  R121    2      B Q_RES_0402LF-0,5%,1/16W,CHIP,CS00002JB13   I122 @T6G_MB_LIB.T6G(SCH_1):PAGE361

SMB_CPU_FRU_3V3AUX_SDA @T6G_MB_LIB.T6G(SCH_1):SMB_CPU_FRU_3V3AUX_SDA
   R24    2      B Q_RES_0402LF-4.7K,5%,1/16W,EMPTY,CS24702JB10   I113 @T6G_MB_LIB.T6G(SCH_1):PAGE361
    U1    5    SDA M24128BWMN6TP-M24128-BWMN6TP,SMLF,IC,AKE30Z00613    I97 @T6G_MB_LIB.T6G(SCH_1):PAGE361
  R125    2      B Q_RES_0402LF-0,5%,1/16W,CHIP,CS00002JB13   I123 @T6G_MB_LIB.T6G(SCH_1):PAGE361

SMB_DIO_PVDDCR_CPU1_P0_R @T6G_MB_LIB.T6G(SCH_1):SMB_DIO_PVDDCR_CPU1_P0_R
 R8072    2      B Q_RES_0402LF-0,5%,1/16W,CHIP,CS00002JB13    I82 @T6G_MB_LIB.T6G(SCH_1):PAGE175
  PU12   13  PMSDA RAA229620GNPHA0-RAA229620GNP#HA0,SMLF,IC,ARF0TGP40A   I128 @T6G_MB_LIB.T6G(SCH_1):PAGE175

SMB_DIO_PVDDCR_CPU1_P1_R @T6G_MB_LIB.T6G(SCH_1):SMB_DIO_PVDDCR_CPU1_P1_R
 R8249    2      B Q_RES_0402LF-0,5%,1/16W,CHIP,CS00002JB13    I81 @T6G_MB_LIB.T6G(SCH_1):PAGE192
  PU34   13  PMSDA RAA229620GNPHA0-RAA229620GNP#HA0,SMLF,IC,ARF0TGP40A   I128 @T6G_MB_LIB.T6G(SCH_1):PAGE192

SMB_E1S_3V3AUX_ISO_SCL @T6G_MB_LIB.T6G(SCH_1):SMB_E1S_3V3AUX_ISO_SCL
 R3533    2      B Q_RES_0402LF-33.2,1%,1/16W,CHIP,CS03322FB03    I76 @T6G_MB_LIB.T6G(SCH_1):PAGE346
   J90   A7 SMBCLK SCONN56_123276793-SCONN56_1-2327679-3,SMLF,IO,DFHSA    I90 @T6G_MB_LIB.T6G(SCH_1):PAGE297

SMB_E1S_3V3AUX_ISO_SCL_R @T6G_MB_LIB.T6G(SCH_1):SMB_E1S_3V3AUX_ISO_SCL_R
 R3533    1      A Q_RES_0402LF-33.2,1%,1/16W,CHIP,CS03322FB03    I76 @T6G_MB_LIB.T6G(SCH_1):PAGE346
 R3530    2      B Q_RES_0402LF-4.7K,5%,1/16W,CHIP,CS24702JB10    I80 @T6G_MB_LIB.T6G(SCH_1):PAGE346
  U279    2   SCLA PCA9617ADP-PCA9617ADP,SMLF,IC,AL009617K02    I93 @T6G_MB_LIB.T6G(SCH_1):PAGE346

SMB_E1S_3V3AUX_ISO_SDA @T6G_MB_LIB.T6G(SCH_1):SMB_E1S_3V3AUX_ISO_SDA
 R3534    2      B Q_RES_0402LF-33.2,1%,1/16W,CHIP,CS03322FB03    I77 @T6G_MB_LIB.T6G(SCH_1):PAGE346
   J90   A8 SMBDAT SCONN56_123276793-SCONN56_1-2327679-3,SMLF,IO,DFHSA    I90 @T6G_MB_LIB.T6G(SCH_1):PAGE297

SMB_E1S_3V3AUX_ISO_SDA_R @T6G_MB_LIB.T6G(SCH_1):SMB_E1S_3V3AUX_ISO_SDA_R
 R3534    1      A Q_RES_0402LF-33.2,1%,1/16W,CHIP,CS03322FB03    I77 @T6G_MB_LIB.T6G(SCH_1):PAGE346
 R3532    2      B Q_RES_0402LF-4.7K,5%,1/16W,CHIP,CS24702JB10    I78 @T6G_MB_LIB.T6G(SCH_1):PAGE346
  U279    3   SDAA PCA9617ADP-PCA9617ADP,SMLF,IC,AL009617K02    I93 @T6G_MB_LIB.T6G(SCH_1):PAGE346

SMB_FAN_3V3AUX_BUF_R_SCL @T6G_MB_LIB.T6G(SCH_1):SMB_FAN_3V3AUX_BUF_R_SCL
 R2811    2      B Q_RES_0402LF-33.2,1%,1/16W,CHIP,CS03322FB03   I425 @T6G_MB_LIB.T6G(SCH_1):PAGE363
   J45   C1     C1 CONN60_101062636003K02LF-CONN60_10106263-6003K02LFA   I466 @T6G_MB_LIB.T6G(SCH_1):PAGE363

SMB_FAN_3V3AUX_BUF_R_SDA @T6G_MB_LIB.T6G(SCH_1):SMB_FAN_3V3AUX_BUF_R_SDA
 R2812    2      B Q_RES_0402LF-33.2,1%,1/16W,CHIP,CS03322FB03   I426 @T6G_MB_LIB.T6G(SCH_1):PAGE363
   J45   C2     C2 CONN60_101062636003K02LF-CONN60_10106263-6003K02LFA   I466 @T6G_MB_LIB.T6G(SCH_1):PAGE363

SMB_FAN_3V3AUX_BUF_SCL @T6G_MB_LIB.T6G(SCH_1):SMB_FAN_3V3AUX_BUF_SCL
  U192    2 SCL_OUT LTC4307CMS8-LTC4307CMS8,SMLF,IC,AL004307000   I398 @T6G_MB_LIB.T6G(SCH_1):PAGE363
 R2811    1      A Q_RES_0402LF-33.2,1%,1/16W,CHIP,CS03322FB03   I425 @T6G_MB_LIB.T6G(SCH_1):PAGE363
 R2800    2      B Q_RES_0402LF-0,5%,1/16W,EMPTY,CS00002JB13   I429 @T6G_MB_LIB.T6G(SCH_1):PAGE363
 R2805    2      B Q_RES_0402LF-4.7K,5%,1/16W,EMPTY,CS24702JB10   I436 @T6G_MB_LIB.T6G(SCH_1):PAGE363

SMB_FAN_3V3AUX_BUF_SDA @T6G_MB_LIB.T6G(SCH_1):SMB_FAN_3V3AUX_BUF_SDA
  U192    7 SDA_OUT LTC4307CMS8-LTC4307CMS8,SMLF,IC,AL004307000   I398 @T6G_MB_LIB.T6G(SCH_1):PAGE363
 R2812    1      A Q_RES_0402LF-33.2,1%,1/16W,CHIP,CS03322FB03   I426 @T6G_MB_LIB.T6G(SCH_1):PAGE363
 R2801    2      B Q_RES_0402LF-0,5%,1/16W,EMPTY,CS00002JB13   I430 @T6G_MB_LIB.T6G(SCH_1):PAGE363
 R2807    2      B Q_RES_0402LF-4.7K,5%,1/16W,EMPTY,CS24702JB10   I438 @T6G_MB_LIB.T6G(SCH_1):PAGE363

SMB_FAN_3V3AUX_R_SCL @T6G_MB_LIB.T6G(SCH_1):SMB_FAN_3V3AUX_R_SCL
  U192    3 SCL_IN LTC4307CMS8-LTC4307CMS8,SMLF,IC,AL004307000   I398 @T6G_MB_LIB.T6G(SCH_1):PAGE363
 R2800    1      A Q_RES_0402LF-0,5%,1/16W,EMPTY,CS00002JB13   I429 @T6G_MB_LIB.T6G(SCH_1):PAGE363
 R3113    2      B Q_RES_0402LF-33.2,1%,1/16W,CHIP,CS03322FB03   I463 @T6G_MB_LIB.T6G(SCH_1):PAGE363

SMB_FAN_3V3AUX_R_SDA @T6G_MB_LIB.T6G(SCH_1):SMB_FAN_3V3AUX_R_SDA
  U192    6 SDA_IN LTC4307CMS8-LTC4307CMS8,SMLF,IC,AL004307000   I398 @T6G_MB_LIB.T6G(SCH_1):PAGE363
 R2801    1      A Q_RES_0402LF-0,5%,1/16W,EMPTY,CS00002JB13   I430 @T6G_MB_LIB.T6G(SCH_1):PAGE363
 R3114    2      B Q_RES_0402LF-33.2,1%,1/16W,CHIP,CS03322FB03   I464 @T6G_MB_LIB.T6G(SCH_1):PAGE363

SMB_FAN_3V3AUX_SCL @T6G_MB_LIB.T6G(SCH_1):SMB_FAN_3V3AUX_SCL
 R3113    1      A Q_RES_0402LF-33.2,1%,1/16W,CHIP,CS03322FB03   I463 @T6G_MB_LIB.T6G(SCH_1):PAGE363
   J41  A29 GND_A29 SCONN168_ME1016810202011-SCONN168_ME1016810202011,A   I176 @T6G_MB_LIB.T6G(SCH_1):PAGE348
  R330    1      A Q_RES_0402LF-2.2K,5%,1/16W,EMPTY,CS22202JB07   I130 @T6G_MB_LIB.T6G(SCH_1):PAGE349

SMB_FAN_3V3AUX_SDA @T6G_MB_LIB.T6G(SCH_1):SMB_FAN_3V3AUX_SDA
 R3114    1      A Q_RES_0402LF-33.2,1%,1/16W,CHIP,CS03322FB03   I464 @T6G_MB_LIB.T6G(SCH_1):PAGE363
   J41  A30  PERN4 SCONN168_ME1016810202011-SCONN168_ME1016810202011,A   I176 @T6G_MB_LIB.T6G(SCH_1):PAGE348
  R331    1      A Q_RES_0402LF-2.2K,5%,1/16W,EMPTY,CS22202JB07   I129 @T6G_MB_LIB.T6G(SCH_1):PAGE349

SMB_FRU_3V3AUX_R1_SCL @T6G_MB_LIB.T6G(SCH_1):SMB_FRU_3V3AUX_R1_SCL
   U64    6    SCL M24128BWMN6TP-M24128-BWMN6TP,SMLF,IC,AKE30Z00613    I35 @T6G_MB_LIB.T6G(SCH_1):PAGE361
   R26    2      B Q_RES_0402LF-4.7K,5%,1/16W,EMPTY,CS24702JB10    I95 @T6G_MB_LIB.T6G(SCH_1):PAGE361
   R85    2      B Q_RES_0402LF-0,5%,1/16W,CHIP,CS00002JB13   I124 @T6G_MB_LIB.T6G(SCH_1):PAGE361

SMB_FRU_3V3AUX_R1_SDA @T6G_MB_LIB.T6G(SCH_1):SMB_FRU_3V3AUX_R1_SDA
   U64    5    SDA M24128BWMN6TP-M24128-BWMN6TP,SMLF,IC,AKE30Z00613    I35 @T6G_MB_LIB.T6G(SCH_1):PAGE361
   R43    2      B Q_RES_0402LF-4.7K,5%,1/16W,EMPTY,CS24702JB10    I93 @T6G_MB_LIB.T6G(SCH_1):PAGE361
   R86    2      B Q_RES_0402LF-0,5%,1/16W,CHIP,CS00002JB13   I125 @T6G_MB_LIB.T6G(SCH_1):PAGE361

SMB_FRU_3V3AUX_SCL @T6G_MB_LIB.T6G(SCH_1):SMB_FRU_3V3AUX_SCL
   R66    2      B Q_RES_0402LF-2.2K,5%,1/16W,CHIP,CS22202JB07    I40 @T6G_MB_LIB.T6G(SCH_1):PAGE252
 R2565    2      B Q_RES_0402LF-0,5%,1/16W,CHIP,CS00002JB13    I67 @T6G_MB_LIB.T6G(SCH_1):PAGE252
  R121    1      A Q_RES_0402LF-0,5%,1/16W,CHIP,CS00002JB13   I122 @T6G_MB_LIB.T6G(SCH_1):PAGE361
   R85    1      A Q_RES_0402LF-0,5%,1/16W,CHIP,CS00002JB13   I124 @T6G_MB_LIB.T6G(SCH_1):PAGE361

SMB_FRU_3V3AUX_SCL_R @T6G_MB_LIB.T6G(SCH_1):SMB_FRU_3V3AUX_SCL_R
   U36   16    SC5 TCA9548APWR-TCA9548APWR,SMLF,IC,AL009548K02    I33 @T6G_MB_LIB.T6G(SCH_1):PAGE252
 R2565    1      A Q_RES_0402LF-0,5%,1/16W,CHIP,CS00002JB13    I67 @T6G_MB_LIB.T6G(SCH_1):PAGE252

SMB_FRU_3V3AUX_SDA @T6G_MB_LIB.T6G(SCH_1):SMB_FRU_3V3AUX_SDA
   R67    2      B Q_RES_0402LF-2.2K,5%,1/16W,CHIP,CS22202JB07    I39 @T6G_MB_LIB.T6G(SCH_1):PAGE252
 R2566    2      B Q_RES_0402LF-0,5%,1/16W,CHIP,CS00002JB13    I72 @T6G_MB_LIB.T6G(SCH_1):PAGE252
  R125    1      A Q_RES_0402LF-0,5%,1/16W,CHIP,CS00002JB13   I123 @T6G_MB_LIB.T6G(SCH_1):PAGE361
   R86    1      A Q_RES_0402LF-0,5%,1/16W,CHIP,CS00002JB13   I125 @T6G_MB_LIB.T6G(SCH_1):PAGE361

SMB_FRU_3V3AUX_SDA_R @T6G_MB_LIB.T6G(SCH_1):SMB_FRU_3V3AUX_SDA_R
   U36   15    SD5 TCA9548APWR-TCA9548APWR,SMLF,IC,AL009548K02    I33 @T6G_MB_LIB.T6G(SCH_1):PAGE252
 R2566    1      A Q_RES_0402LF-0,5%,1/16W,CHIP,CS00002JB13    I72 @T6G_MB_LIB.T6G(SCH_1):PAGE252

SMB_HOST_CLK_3V3AUX_SCL @T6G_MB_LIB.T6G(SCH_1):SMB_HOST_CLK_3V3AUX_SCL
 R2212    1      A Q_RES_0402LF-2.2K,5%,1/16W,EMPTY,CS22202JB07   I126 @T6G_MB_LIB.T6G(SCH_1):PAGE349
 R2417    1      A Q_RES_0402LF-33.2,1%,1/16W,CHIP,CS03322FB03    I35 @T6G_MB_LIB.T6G(SCH_1):PAGE348
 R3340    1      A Q_RES_0402LF-33.2,1%,1/16W,CHIP,CS03322FB03    I81 @T6G_MB_LIB.T6G(SCH_1):PAGE349
 R1516    1      A Q_RES_0402LF-33.2,1%,1/16W,CHIP,CS03322FB03   I222 @T6G_MB_LIB.T6G(SCH_1):PAGE349

SMB_HOST_CLK_3V3AUX_SCL_R0 @T6G_MB_LIB.T6G(SCH_1):SMB_HOST_CLK_3V3AUX_SCL_R0
   J41  A40  PERP7 SCONN168_ME1016810202011-SCONN168_ME1016810202011,A   I176 @T6G_MB_LIB.T6G(SCH_1):PAGE348
 R2417    2      B Q_RES_0402LF-33.2,1%,1/16W,CHIP,CS03322FB03    I35 @T6G_MB_LIB.T6G(SCH_1):PAGE348

SMB_HOST_CLK_3V3AUX_SCL_R1 @T6G_MB_LIB.T6G(SCH_1):SMB_HOST_CLK_3V3AUX_SCL_R1
 R6862    1      A Q_RES_0402LF-33,5%,1/16W,CHIP,CS03302JB10   I218 @T6G_MB_LIB.T6G(SCH_1):PAGE349
 R6864    1      A Q_RES_0402LF-33,5%,1/16W,CHIP,CS03302JB10   I220 @T6G_MB_LIB.T6G(SCH_1):PAGE349
 R1516    2      B Q_RES_0402LF-33.2,1%,1/16W,CHIP,CS03322FB03   I222 @T6G_MB_LIB.T6G(SCH_1):PAGE349
 R6782    2      B Q_RES_0402LF-33,5%,1/16W,CHIP,CS03302JB10   I228 @T6G_MB_LIB.T6G(SCH_1):PAGE349

SMB_HOST_CLK_3V3AUX_SDA @T6G_MB_LIB.T6G(SCH_1):SMB_HOST_CLK_3V3AUX_SDA
 R2213    1      A Q_RES_0402LF-2.2K,5%,1/16W,EMPTY,CS22202JB07   I125 @T6G_MB_LIB.T6G(SCH_1):PAGE349
 R2418    1      A Q_RES_0402LF-33.2,1%,1/16W,CHIP,CS03322FB03    I34 @T6G_MB_LIB.T6G(SCH_1):PAGE348
 R3341    1      A Q_RES_0402LF-33.2,1%,1/16W,CHIP,CS03322FB03    I82 @T6G_MB_LIB.T6G(SCH_1):PAGE349
 R1517    1      A Q_RES_0402LF-33.2,1%,1/16W,CHIP,CS03322FB03   I223 @T6G_MB_LIB.T6G(SCH_1):PAGE349

SMB_HOST_CLK_3V3AUX_SDA_R0 @T6G_MB_LIB.T6G(SCH_1):SMB_HOST_CLK_3V3AUX_SDA_R0
   J41  A41 GND_A41 SCONN168_ME1016810202011-SCONN168_ME1016810202011,A   I176 @T6G_MB_LIB.T6G(SCH_1):PAGE348
 R2418    2      B Q_RES_0402LF-33.2,1%,1/16W,CHIP,CS03322FB03    I34 @T6G_MB_LIB.T6G(SCH_1):PAGE348

SMB_HOST_CLK_3V3AUX_SDA_R1 @T6G_MB_LIB.T6G(SCH_1):SMB_HOST_CLK_3V3AUX_SDA_R1
 R6863    1      A Q_RES_0402LF-33,5%,1/16W,CHIP,CS03302JB10   I219 @T6G_MB_LIB.T6G(SCH_1):PAGE349
 R6865    1      A Q_RES_0402LF-33,5%,1/16W,CHIP,CS03302JB10   I221 @T6G_MB_LIB.T6G(SCH_1):PAGE349
 R1517    2      B Q_RES_0402LF-33.2,1%,1/16W,CHIP,CS03322FB03   I223 @T6G_MB_LIB.T6G(SCH_1):PAGE349
 R6783    2      B Q_RES_0402LF-33,5%,1/16W,CHIP,CS03302JB10   I229 @T6G_MB_LIB.T6G(SCH_1):PAGE349

SMB_HOST_CLK_GEN2_3V3AUX_SCL @T6G_MB_LIB.T6G(SCH_1):SMB_HOST_CLK_GEN2_3V3AUX_SCL
 R3340    2      B Q_RES_0402LF-33.2,1%,1/16W,CHIP,CS03322FB03    I81 @T6G_MB_LIB.T6G(SCH_1):PAGE349
  U247    8 SCLK_3.3 9FGL0251DKILFT-9FGL0251DKILFT,SMLF,IC,AL000251002    I77 @T6G_MB_LIB.T6G(SCH_1):PAGE232

SMB_HOST_CLK_GEN2_3V3AUX_SDA @T6G_MB_LIB.T6G(SCH_1):SMB_HOST_CLK_GEN2_3V3AUX_SDA
 R3341    2      B Q_RES_0402LF-33.2,1%,1/16W,CHIP,CS03322FB03    I82 @T6G_MB_LIB.T6G(SCH_1):PAGE349
  U247    9 SDATA_3.3 9FGL0251DKILFT-9FGL0251DKILFT,SMLF,IC,AL000251002    I77 @T6G_MB_LIB.T6G(SCH_1):PAGE232

SMB_HSC_TYPE_ADC_SCL @T6G_MB_LIB.T6G(SCH_1):SMB_HSC_TYPE_ADC_SCL
 R6252    2      B Q_RES_0402LF-33.2,1%,1/16W,CHIP,CS03322FB03     I9 @T6G_MB_LIB.T6G(SCH_1):PAGE271
 U6005    5 SCL|||SMBCLK ISL28022FRZT-ISL28022FRZ-T,SMLF,IC,AL028022003    I28 @T6G_MB_LIB.T6G(SCH_1):PAGE271

SMB_HSC_TYPE_ADC_SDA @T6G_MB_LIB.T6G(SCH_1):SMB_HSC_TYPE_ADC_SDA
 R6253    2      B Q_RES_0402LF-33.2,1%,1/16W,CHIP,CS03322FB03    I10 @T6G_MB_LIB.T6G(SCH_1):PAGE271
 U6005    4 SDA||SMBDAT ISL28022FRZT-ISL28022FRZ-T,SMLF,IC,AL028022003    I28 @T6G_MB_LIB.T6G(SCH_1):PAGE271
 R6254    2      B Q_RES_0402LF-0,5%,1/16W,CHIP,CS00002JB13    I29 @T6G_MB_LIB.T6G(SCH_1):PAGE271

SMB_INA230_1_3V3AUX_SCL_R @T6G_MB_LIB.T6G(SCH_1):SMB_INA230_1_3V3AUX_SCL_R
 R3586    2      B Q_RES_0402LF-33.2,1%,1/16W,CHIP,CS03322FB03    I12 @T6G_MB_LIB.T6G(SCH_1):PAGE253
 R3600    1      A Q_RES_0402LF-0,5%,1/16W,CHIP,CS00002JB13   I152 @T6G_MB_LIB.T6G(SCH_1):PAGE295

SMB_INA230_1_3V3AUX_SCL_R1 @T6G_MB_LIB.T6G(SCH_1):SMB_INA230_1_3V3AUX_SCL_R1
  U266    5 SCL|||SMBCLK ISL28022FRZT-ISL28022FRZ-T,SMLF,IC,AL028022003    I30 @T6G_MB_LIB.T6G(SCH_1):PAGE295
 R3600    2      B Q_RES_0402LF-0,5%,1/16W,CHIP,CS00002JB13   I152 @T6G_MB_LIB.T6G(SCH_1):PAGE295

SMB_INA230_1_3V3AUX_SDA_R @T6G_MB_LIB.T6G(SCH_1):SMB_INA230_1_3V3AUX_SDA_R
 R3587    2      B Q_RES_0402LF-33.2,1%,1/16W,CHIP,CS03322FB03    I11 @T6G_MB_LIB.T6G(SCH_1):PAGE253
 R3601    1      A Q_RES_0402LF-0,5%,1/16W,CHIP,CS00002JB13   I153 @T6G_MB_LIB.T6G(SCH_1):PAGE295

SMB_INA230_1_3V3AUX_SDA_R1 @T6G_MB_LIB.T6G(SCH_1):SMB_INA230_1_3V3AUX_SDA_R1
  U266    4 SDA||SMBDAT ISL28022FRZT-ISL28022FRZ-T,SMLF,IC,AL028022003    I30 @T6G_MB_LIB.T6G(SCH_1):PAGE295
 R3601    2      B Q_RES_0402LF-0,5%,1/16W,CHIP,CS00002JB13   I153 @T6G_MB_LIB.T6G(SCH_1):PAGE295

SMB_INA230_2_3V3AUX_SCL_R @T6G_MB_LIB.T6G(SCH_1):SMB_INA230_2_3V3AUX_SCL_R
 R3588    2      B Q_RES_0402LF-33.2,1%,1/16W,CHIP,CS03322FB03    I10 @T6G_MB_LIB.T6G(SCH_1):PAGE253
 R3754    1      A Q_RES_0402LF-0,5%,1/16W,CHIP,CS00002JB13   I155 @T6G_MB_LIB.T6G(SCH_1):PAGE295

SMB_INA230_2_3V3AUX_SCL_R1 @T6G_MB_LIB.T6G(SCH_1):SMB_INA230_2_3V3AUX_SCL_R1
  U276    5 SCL|||SMBCLK ISL28022FRZT-ISL28022FRZ-T,SMLF,IC,AL028022003   I129 @T6G_MB_LIB.T6G(SCH_1):PAGE295
 R3754    2      B Q_RES_0402LF-0,5%,1/16W,CHIP,CS00002JB13   I155 @T6G_MB_LIB.T6G(SCH_1):PAGE295

SMB_INA230_2_3V3AUX_SDA_R @T6G_MB_LIB.T6G(SCH_1):SMB_INA230_2_3V3AUX_SDA_R
 R3589    2      B Q_RES_0402LF-33.2,1%,1/16W,CHIP,CS03322FB03     I9 @T6G_MB_LIB.T6G(SCH_1):PAGE253
 R3756    1      A Q_RES_0402LF-0,5%,1/16W,CHIP,CS00002JB13   I154 @T6G_MB_LIB.T6G(SCH_1):PAGE295

SMB_INA230_2_3V3AUX_SDA_R1 @T6G_MB_LIB.T6G(SCH_1):SMB_INA230_2_3V3AUX_SDA_R1
  U276    4 SDA||SMBDAT ISL28022FRZT-ISL28022FRZ-T,SMLF,IC,AL028022003   I129 @T6G_MB_LIB.T6G(SCH_1):PAGE295
 R3751    2      B Q_RES_0402LF-0,5%,1/16W,CHIP,CS00002JB13   I146 @T6G_MB_LIB.T6G(SCH_1):PAGE295
 R3756    2      B Q_RES_0402LF-0,5%,1/16W,CHIP,CS00002JB13   I154 @T6G_MB_LIB.T6G(SCH_1):PAGE295

SMB_INA230_3V3AUX_SCL @T6G_MB_LIB.T6G(SCH_1):SMB_INA230_3V3AUX_SCL
 R3395    2      B Q_RES_0402LF-2.2K,5%,1/16W,CHIP,CS22202JB07    I47 @T6G_MB_LIB.T6G(SCH_1):PAGE252
 R3580    2      B Q_RES_0402LF-0,5%,1/16W,CHIP,CS00002JB13    I69 @T6G_MB_LIB.T6G(SCH_1):PAGE252
 R3592    1      A Q_RES_0402LF-33.2,1%,1/16W,CHIP,CS03322FB03     I4 @T6G_MB_LIB.T6G(SCH_1):PAGE253
 R3594    1      A Q_RES_0402LF-33.2,1%,1/16W,CHIP,CS03322FB03     I6 @T6G_MB_LIB.T6G(SCH_1):PAGE253
 R3590    1      A Q_RES_0402LF-33.2,1%,1/16W,CHIP,CS03322FB03     I8 @T6G_MB_LIB.T6G(SCH_1):PAGE253
 R3588    1      A Q_RES_0402LF-33.2,1%,1/16W,CHIP,CS03322FB03    I10 @T6G_MB_LIB.T6G(SCH_1):PAGE253
 R3586    1      A Q_RES_0402LF-33.2,1%,1/16W,CHIP,CS03322FB03    I12 @T6G_MB_LIB.T6G(SCH_1):PAGE253
 R1344    1      A Q_RES_0402LF-33.2,1%,1/16W,CHIP,CS03322FB03    I23 @T6G_MB_LIB.T6G(SCH_1):PAGE253
 R1346    1      A Q_RES_0402LF-33.2,1%,1/16W,CHIP,CS03322FB03    I25 @T6G_MB_LIB.T6G(SCH_1):PAGE253
 R1348    1      A Q_RES_0402LF-33.2,1%,1/16W,CHIP,CS03322FB03    I27 @T6G_MB_LIB.T6G(SCH_1):PAGE253

SMB_INA230_3V3AUX_SCL_R @T6G_MB_LIB.T6G(SCH_1):SMB_INA230_3V3AUX_SCL_R
   U36   18    SC6 TCA9548APWR-TCA9548APWR,SMLF,IC,AL009548K02    I33 @T6G_MB_LIB.T6G(SCH_1):PAGE252
 R3580    1      A Q_RES_0402LF-0,5%,1/16W,CHIP,CS00002JB13    I69 @T6G_MB_LIB.T6G(SCH_1):PAGE252

SMB_INA230_3V3AUX_SDA @T6G_MB_LIB.T6G(SCH_1):SMB_INA230_3V3AUX_SDA
 R3396    2      B Q_RES_0402LF-2.2K,5%,1/16W,CHIP,CS22202JB07    I48 @T6G_MB_LIB.T6G(SCH_1):PAGE252
 R3581    2      B Q_RES_0402LF-0,5%,1/16W,CHIP,CS00002JB13    I68 @T6G_MB_LIB.T6G(SCH_1):PAGE252
 R3593    1      A Q_RES_0402LF-33.2,1%,1/16W,CHIP,CS03322FB03     I3 @T6G_MB_LIB.T6G(SCH_1):PAGE253
 R3595    1      A Q_RES_0402LF-33.2,1%,1/16W,CHIP,CS03322FB03     I5 @T6G_MB_LIB.T6G(SCH_1):PAGE253
 R3591    1      A Q_RES_0402LF-33.2,1%,1/16W,CHIP,CS03322FB03     I7 @T6G_MB_LIB.T6G(SCH_1):PAGE253
 R3589    1      A Q_RES_0402LF-33.2,1%,1/16W,CHIP,CS03322FB03     I9 @T6G_MB_LIB.T6G(SCH_1):PAGE253
 R3587    1      A Q_RES_0402LF-33.2,1%,1/16W,CHIP,CS03322FB03    I11 @T6G_MB_LIB.T6G(SCH_1):PAGE253
 R1345    1      A Q_RES_0402LF-33.2,1%,1/16W,CHIP,CS03322FB03    I24 @T6G_MB_LIB.T6G(SCH_1):PAGE253
 R1347    1      A Q_RES_0402LF-33.2,1%,1/16W,CHIP,CS03322FB03    I26 @T6G_MB_LIB.T6G(SCH_1):PAGE253
 R1349    1      A Q_RES_0402LF-33.2,1%,1/16W,CHIP,CS03322FB03    I28 @T6G_MB_LIB.T6G(SCH_1):PAGE253

SMB_INA230_3V3AUX_SDA_R @T6G_MB_LIB.T6G(SCH_1):SMB_INA230_3V3AUX_SDA_R
   U36   17    SD6 TCA9548APWR-TCA9548APWR,SMLF,IC,AL009548K02    I33 @T6G_MB_LIB.T6G(SCH_1):PAGE252
 R3581    1      A Q_RES_0402LF-0,5%,1/16W,CHIP,CS00002JB13    I68 @T6G_MB_LIB.T6G(SCH_1):PAGE252

SMB_INA230_3_3V3AUX_SCL_R @T6G_MB_LIB.T6G(SCH_1):SMB_INA230_3_3V3AUX_SCL_R
 R3590    2      B Q_RES_0402LF-33.2,1%,1/16W,CHIP,CS03322FB03     I8 @T6G_MB_LIB.T6G(SCH_1):PAGE253
 R3568    1      A Q_RES_0402LF-0,5%,1/16W,CHIP,CS00002JB13   I128 @T6G_MB_LIB.T6G(SCH_1):PAGE360

SMB_INA230_3_3V3AUX_SCL_R1 @T6G_MB_LIB.T6G(SCH_1):SMB_INA230_3_3V3AUX_SCL_R1
  U263    5 SCL|||SMBCLK ISL28022FRZT-ISL28022FRZ-T,SMLF,IC,AL028022003    I94 @T6G_MB_LIB.T6G(SCH_1):PAGE360
 R3620    2      B Q_RES_0402LF-0,5%,1/16W,CHIP,CS00002JB13   I100 @T6G_MB_LIB.T6G(SCH_1):PAGE360
 R3568    2      B Q_RES_0402LF-0,5%,1/16W,CHIP,CS00002JB13   I128 @T6G_MB_LIB.T6G(SCH_1):PAGE360

SMB_INA230_3_3V3AUX_SDA_R @T6G_MB_LIB.T6G(SCH_1):SMB_INA230_3_3V3AUX_SDA_R
 R3591    2      B Q_RES_0402LF-33.2,1%,1/16W,CHIP,CS03322FB03     I7 @T6G_MB_LIB.T6G(SCH_1):PAGE253
 R3569    1      A Q_RES_0402LF-0,5%,1/16W,CHIP,CS00002JB13   I127 @T6G_MB_LIB.T6G(SCH_1):PAGE360

SMB_INA230_3_3V3AUX_SDA_R1 @T6G_MB_LIB.T6G(SCH_1):SMB_INA230_3_3V3AUX_SDA_R1
  U263    4 SDA||SMBDAT ISL28022FRZT-ISL28022FRZ-T,SMLF,IC,AL028022003    I94 @T6G_MB_LIB.T6G(SCH_1):PAGE360
 R3569    2      B Q_RES_0402LF-0,5%,1/16W,CHIP,CS00002JB13   I127 @T6G_MB_LIB.T6G(SCH_1):PAGE360

SMB_INA230_4_3V3AUX_SCL_R @T6G_MB_LIB.T6G(SCH_1):SMB_INA230_4_3V3AUX_SCL_R
 R3594    2      B Q_RES_0402LF-33.2,1%,1/16W,CHIP,CS03322FB03     I6 @T6G_MB_LIB.T6G(SCH_1):PAGE253
 R3572    1      A Q_RES_0402LF-0,5%,1/16W,CHIP,CS00002JB13   I130 @T6G_MB_LIB.T6G(SCH_1):PAGE360

SMB_INA230_4_3V3AUX_SCL_R1 @T6G_MB_LIB.T6G(SCH_1):SMB_INA230_4_3V3AUX_SCL_R1
  U264    5 SCL|||SMBCLK ISL28022FRZT-ISL28022FRZ-T,SMLF,IC,AL028022003    I46 @T6G_MB_LIB.T6G(SCH_1):PAGE360
 R3572    2      B Q_RES_0402LF-0,5%,1/16W,CHIP,CS00002JB13   I130 @T6G_MB_LIB.T6G(SCH_1):PAGE360

SMB_INA230_4_3V3AUX_SDA_R @T6G_MB_LIB.T6G(SCH_1):SMB_INA230_4_3V3AUX_SDA_R
 R3595    2      B Q_RES_0402LF-33.2,1%,1/16W,CHIP,CS03322FB03     I5 @T6G_MB_LIB.T6G(SCH_1):PAGE253
 R3573    1      A Q_RES_0402LF-0,5%,1/16W,CHIP,CS00002JB13   I129 @T6G_MB_LIB.T6G(SCH_1):PAGE360

SMB_INA230_4_3V3AUX_SDA_R1 @T6G_MB_LIB.T6G(SCH_1):SMB_INA230_4_3V3AUX_SDA_R1
  U264    4 SDA||SMBDAT ISL28022FRZT-ISL28022FRZ-T,SMLF,IC,AL028022003    I46 @T6G_MB_LIB.T6G(SCH_1):PAGE360
 R3573    2      B Q_RES_0402LF-0,5%,1/16W,CHIP,CS00002JB13   I129 @T6G_MB_LIB.T6G(SCH_1):PAGE360

SMB_INA230_5_3V3AUX_SCL_R @T6G_MB_LIB.T6G(SCH_1):SMB_INA230_5_3V3AUX_SCL_R
 R3592    2      B Q_RES_0402LF-33.2,1%,1/16W,CHIP,CS03322FB03     I4 @T6G_MB_LIB.T6G(SCH_1):PAGE253
 R3576    1      A Q_RES_0402LF-0,5%,1/16W,CHIP,CS00002JB13   I131 @T6G_MB_LIB.T6G(SCH_1):PAGE360

SMB_INA230_5_3V3AUX_SCL_R1 @T6G_MB_LIB.T6G(SCH_1):SMB_INA230_5_3V3AUX_SCL_R1
  U265    5 SCL|||SMBCLK ISL28022FRZT-ISL28022FRZ-T,SMLF,IC,AL028022003    I69 @T6G_MB_LIB.T6G(SCH_1):PAGE360
 R3576    2      B Q_RES_0402LF-0,5%,1/16W,CHIP,CS00002JB13   I131 @T6G_MB_LIB.T6G(SCH_1):PAGE360

SMB_INA230_5_3V3AUX_SDA_R @T6G_MB_LIB.T6G(SCH_1):SMB_INA230_5_3V3AUX_SDA_R
 R3593    2      B Q_RES_0402LF-33.2,1%,1/16W,CHIP,CS03322FB03     I3 @T6G_MB_LIB.T6G(SCH_1):PAGE253
 R3577    1      A Q_RES_0402LF-0,5%,1/16W,CHIP,CS00002JB13   I132 @T6G_MB_LIB.T6G(SCH_1):PAGE360

SMB_INA230_5_3V3AUX_SDA_R1 @T6G_MB_LIB.T6G(SCH_1):SMB_INA230_5_3V3AUX_SDA_R1
  U265    4 SDA||SMBDAT ISL28022FRZT-ISL28022FRZ-T,SMLF,IC,AL028022003    I69 @T6G_MB_LIB.T6G(SCH_1):PAGE360
 R3577    2      B Q_RES_0402LF-0,5%,1/16W,CHIP,CS00002JB13   I132 @T6G_MB_LIB.T6G(SCH_1):PAGE360

SMB_INA230_6_3V3AUX_SCL_R @T6G_MB_LIB.T6G(SCH_1):SMB_INA230_6_3V3AUX_SCL_R
 R1273    1      A Q_RES_0402LF-0,5%,1/16W,CHIP,CS00002JB13    I27 @T6G_MB_LIB.T6G(SCH_1):PAGE466
 R1344    2      B Q_RES_0402LF-33.2,1%,1/16W,CHIP,CS03322FB03    I23 @T6G_MB_LIB.T6G(SCH_1):PAGE253

SMB_INA230_6_3V3AUX_SCL_R1 @T6G_MB_LIB.T6G(SCH_1):SMB_INA230_6_3V3AUX_SCL_R1
 R1273    2      B Q_RES_0402LF-0,5%,1/16W,CHIP,CS00002JB13    I27 @T6G_MB_LIB.T6G(SCH_1):PAGE466
   U55    5 SCL|||SMBCLK ISL28022FRZT-ISL28022FRZ-T,SMLF,IC,AL028022003    I28 @T6G_MB_LIB.T6G(SCH_1):PAGE466

SMB_INA230_6_3V3AUX_SDA_R @T6G_MB_LIB.T6G(SCH_1):SMB_INA230_6_3V3AUX_SDA_R
 R1276    1      A Q_RES_0402LF-0,5%,1/16W,CHIP,CS00002JB13    I14 @T6G_MB_LIB.T6G(SCH_1):PAGE466
 R1345    2      B Q_RES_0402LF-33.2,1%,1/16W,CHIP,CS03322FB03    I24 @T6G_MB_LIB.T6G(SCH_1):PAGE253

SMB_INA230_6_3V3AUX_SDA_R1 @T6G_MB_LIB.T6G(SCH_1):SMB_INA230_6_3V3AUX_SDA_R1
 R1276    2      B Q_RES_0402LF-0,5%,1/16W,CHIP,CS00002JB13    I14 @T6G_MB_LIB.T6G(SCH_1):PAGE466
   U55    4 SDA||SMBDAT ISL28022FRZT-ISL28022FRZ-T,SMLF,IC,AL028022003    I28 @T6G_MB_LIB.T6G(SCH_1):PAGE466
 R1355    2      B Q_RES_0402LF-0,5%,1/16W,CHIP,CS00002JB13    I92 @T6G_MB_LIB.T6G(SCH_1):PAGE466

SMB_INA230_7_3V3AUX_SCL_R @T6G_MB_LIB.T6G(SCH_1):SMB_INA230_7_3V3AUX_SCL_R
 R1274    1      A Q_RES_0402LF-0,5%,1/16W,CHIP,CS00002JB13    I42 @T6G_MB_LIB.T6G(SCH_1):PAGE466
 R1346    2      B Q_RES_0402LF-33.2,1%,1/16W,CHIP,CS03322FB03    I25 @T6G_MB_LIB.T6G(SCH_1):PAGE253

SMB_INA230_7_3V3AUX_SCL_R1 @T6G_MB_LIB.T6G(SCH_1):SMB_INA230_7_3V3AUX_SCL_R1
   U56    5 SCL|||SMBCLK ISL28022FRZT-ISL28022FRZ-T,SMLF,IC,AL028022003    I29 @T6G_MB_LIB.T6G(SCH_1):PAGE466
 R1274    2      B Q_RES_0402LF-0,5%,1/16W,CHIP,CS00002JB13    I42 @T6G_MB_LIB.T6G(SCH_1):PAGE466
 R1360    2      B Q_RES_0402LF-0,5%,1/16W,CHIP,CS00002JB13    I93 @T6G_MB_LIB.T6G(SCH_1):PAGE466

SMB_INA230_7_3V3AUX_SDA_R @T6G_MB_LIB.T6G(SCH_1):SMB_INA230_7_3V3AUX_SDA_R
 R1277    1      A Q_RES_0402LF-0,5%,1/16W,CHIP,CS00002JB13    I41 @T6G_MB_LIB.T6G(SCH_1):PAGE466
 R1347    2      B Q_RES_0402LF-33.2,1%,1/16W,CHIP,CS03322FB03    I26 @T6G_MB_LIB.T6G(SCH_1):PAGE253

SMB_INA230_7_3V3AUX_SDA_R1 @T6G_MB_LIB.T6G(SCH_1):SMB_INA230_7_3V3AUX_SDA_R1
   U56    4 SDA||SMBDAT ISL28022FRZT-ISL28022FRZ-T,SMLF,IC,AL028022003    I29 @T6G_MB_LIB.T6G(SCH_1):PAGE466
 R1277    2      B Q_RES_0402LF-0,5%,1/16W,CHIP,CS00002JB13    I41 @T6G_MB_LIB.T6G(SCH_1):PAGE466

SMB_INA230_8_3V3AUX_SCL_R @T6G_MB_LIB.T6G(SCH_1):SMB_INA230_8_3V3AUX_SCL_R
 R1272    1      A Q_RES_0402LF-0,5%,1/16W,CHIP,CS00002JB13    I71 @T6G_MB_LIB.T6G(SCH_1):PAGE466
 R1348    2      B Q_RES_0402LF-33.2,1%,1/16W,CHIP,CS03322FB03    I27 @T6G_MB_LIB.T6G(SCH_1):PAGE253

SMB_INA230_8_3V3AUX_SCL_R1 @T6G_MB_LIB.T6G(SCH_1):SMB_INA230_8_3V3AUX_SCL_R1
   U52    5 SCL|||SMBCLK ISL28022FRZT-ISL28022FRZ-T,SMLF,IC,AL028022003    I57 @T6G_MB_LIB.T6G(SCH_1):PAGE466
 R1272    2      B Q_RES_0402LF-0,5%,1/16W,CHIP,CS00002JB13    I71 @T6G_MB_LIB.T6G(SCH_1):PAGE466

SMB_INA230_8_3V3AUX_SDA_R @T6G_MB_LIB.T6G(SCH_1):SMB_INA230_8_3V3AUX_SDA_R
 R1275    1      A Q_RES_0402LF-0,5%,1/16W,CHIP,CS00002JB13    I70 @T6G_MB_LIB.T6G(SCH_1):PAGE466
 R1349    2      B Q_RES_0402LF-33.2,1%,1/16W,CHIP,CS03322FB03    I28 @T6G_MB_LIB.T6G(SCH_1):PAGE253

SMB_INA230_8_3V3AUX_SDA_R1 @T6G_MB_LIB.T6G(SCH_1):SMB_INA230_8_3V3AUX_SDA_R1
   U52    4 SDA||SMBDAT ISL28022FRZT-ISL28022FRZ-T,SMLF,IC,AL028022003    I57 @T6G_MB_LIB.T6G(SCH_1):PAGE466
 R1275    2      B Q_RES_0402LF-0,5%,1/16W,CHIP,CS00002JB13    I70 @T6G_MB_LIB.T6G(SCH_1):PAGE466
 R1350    2      B Q_RES_0402LF-0,5%,1/16W,CHIP,CS00002JB13    I94 @T6G_MB_LIB.T6G(SCH_1):PAGE466

SMB_IOEXP_3V3AUX_SCL @T6G_MB_LIB.T6G(SCH_1):SMB_IOEXP_3V3AUX_SCL
 R3393    2      B Q_RES_0402LF-0,5%,1/16W,CHIP,CS00002JB13    I27 @T6G_MB_LIB.T6G(SCH_1):PAGE252
 R3582    2      B Q_RES_0402LF-2.2K,5%,1/16W,CHIP,CS22202JB07    I46 @T6G_MB_LIB.T6G(SCH_1):PAGE252
 R2982    1      A Q_RES_0402LF-0,5%,1/16W,CHIP,CS00002JB13    I82 @T6G_MB_LIB.T6G(SCH_1):PAGE246

SMB_IOEXP_3V3AUX_SCL_R @T6G_MB_LIB.T6G(SCH_1):SMB_IOEXP_3V3AUX_SCL_R
 R3393    1      A Q_RES_0402LF-0,5%,1/16W,CHIP,CS00002JB13    I27 @T6G_MB_LIB.T6G(SCH_1):PAGE252
   U36    7    SC1 TCA9548APWR-TCA9548APWR,SMLF,IC,AL009548K02    I33 @T6G_MB_LIB.T6G(SCH_1):PAGE252

SMB_IOEXP_3V3AUX_SCL_R1 @T6G_MB_LIB.T6G(SCH_1):SMB_IOEXP_3V3AUX_SCL_R1
 R2982    2      B Q_RES_0402LF-0,5%,1/16W,CHIP,CS00002JB13    I82 @T6G_MB_LIB.T6G(SCH_1):PAGE246
  U181   22    SCL PCA9539RPW-PCA9539RPW,SMLF,IC,AL009539K07    I83 @T6G_MB_LIB.T6G(SCH_1):PAGE246

SMB_IOEXP_3V3AUX_SDA @T6G_MB_LIB.T6G(SCH_1):SMB_IOEXP_3V3AUX_SDA
 R3394    2      B Q_RES_0402LF-0,5%,1/16W,CHIP,CS00002JB13    I29 @T6G_MB_LIB.T6G(SCH_1):PAGE252
 R3583    2      B Q_RES_0402LF-2.2K,5%,1/16W,CHIP,CS22202JB07    I45 @T6G_MB_LIB.T6G(SCH_1):PAGE252
 R2983    1      A Q_RES_0402LF-0,5%,1/16W,CHIP,CS00002JB13    I58 @T6G_MB_LIB.T6G(SCH_1):PAGE246

SMB_IOEXP_3V3AUX_SDA_R @T6G_MB_LIB.T6G(SCH_1):SMB_IOEXP_3V3AUX_SDA_R
 R3394    1      A Q_RES_0402LF-0,5%,1/16W,CHIP,CS00002JB13    I29 @T6G_MB_LIB.T6G(SCH_1):PAGE252
   U36    6    SD1 TCA9548APWR-TCA9548APWR,SMLF,IC,AL009548K02    I33 @T6G_MB_LIB.T6G(SCH_1):PAGE252

SMB_IOEXP_3V3AUX_SDA_R1 @T6G_MB_LIB.T6G(SCH_1):SMB_IOEXP_3V3AUX_SDA_R1
 R2983    2      B Q_RES_0402LF-0,5%,1/16W,CHIP,CS00002JB13    I58 @T6G_MB_LIB.T6G(SCH_1):PAGE246
  U181   23    SDA PCA9539RPW-PCA9539RPW,SMLF,IC,AL009539K07    I83 @T6G_MB_LIB.T6G(SCH_1):PAGE246

SMB_LM75_0_3V3AUX_SCL @T6G_MB_LIB.T6G(SCH_1):SMB_LM75_0_3V3AUX_SCL
 R4180    1      A Q_RES_0402LF-33.2,1%,1/16W,CHIP,CS03322FB03    I77 @T6G_MB_LIB.T6G(SCH_1):PAGE359
 R3715    2      B Q_RES_0402LF-0,5%,1/16W,CHIP,CS00002JB13    I31 @T6G_MB_LIB.T6G(SCH_1):PAGE251
 R3725    2      B Q_RES_0402LF-2.2K,5%,1/16W,CHIP,CS22202JB07    I50 @T6G_MB_LIB.T6G(SCH_1):PAGE251
 R6252    1      A Q_RES_0402LF-33.2,1%,1/16W,CHIP,CS03322FB03     I9 @T6G_MB_LIB.T6G(SCH_1):PAGE271

SMB_LM75_0_3V3AUX_SCL_R @T6G_MB_LIB.T6G(SCH_1):SMB_LM75_0_3V3AUX_SCL_R
 R3715    1      A Q_RES_0402LF-0,5%,1/16W,CHIP,CS00002JB13    I31 @T6G_MB_LIB.T6G(SCH_1):PAGE251
   U39    7    SC1 TCA9548APWR-TCA9548APWR,SMLF,IC,AL009548K02    I74 @T6G_MB_LIB.T6G(SCH_1):PAGE251

SMB_LM75_0_3V3AUX_SCL_R1 @T6G_MB_LIB.T6G(SCH_1):SMB_LM75_0_3V3AUX_SCL_R1
 R4180    2      B Q_RES_0402LF-33.2,1%,1/16W,CHIP,CS03322FB03    I77 @T6G_MB_LIB.T6G(SCH_1):PAGE359
  U270    2    SCL LM75BD-LM75BD,SMLF,IC,AL0075BD000   I164 @T6G_MB_LIB.T6G(SCH_1):PAGE359

SMB_LM75_0_3V3AUX_SDA @T6G_MB_LIB.T6G(SCH_1):SMB_LM75_0_3V3AUX_SDA
 R4183    1      A Q_RES_0402LF-33.2,1%,1/16W,CHIP,CS03322FB03    I78 @T6G_MB_LIB.T6G(SCH_1):PAGE359
 R3716    2      B Q_RES_0402LF-0,5%,1/16W,CHIP,CS00002JB13    I30 @T6G_MB_LIB.T6G(SCH_1):PAGE251
 R3726    2      B Q_RES_0402LF-2.2K,5%,1/16W,CHIP,CS22202JB07    I49 @T6G_MB_LIB.T6G(SCH_1):PAGE251
 R6253    1      A Q_RES_0402LF-33.2,1%,1/16W,CHIP,CS03322FB03    I10 @T6G_MB_LIB.T6G(SCH_1):PAGE271

SMB_LM75_0_3V3AUX_SDA_R @T6G_MB_LIB.T6G(SCH_1):SMB_LM75_0_3V3AUX_SDA_R
 R3716    1      A Q_RES_0402LF-0,5%,1/16W,CHIP,CS00002JB13    I30 @T6G_MB_LIB.T6G(SCH_1):PAGE251
   U39    6    SD1 TCA9548APWR-TCA9548APWR,SMLF,IC,AL009548K02    I74 @T6G_MB_LIB.T6G(SCH_1):PAGE251

SMB_LM75_0_3V3AUX_SDA_R1 @T6G_MB_LIB.T6G(SCH_1):SMB_LM75_0_3V3AUX_SDA_R1
 R4183    2      B Q_RES_0402LF-33.2,1%,1/16W,CHIP,CS03322FB03    I78 @T6G_MB_LIB.T6G(SCH_1):PAGE359
  U270    1    SDA LM75BD-LM75BD,SMLF,IC,AL0075BD000   I164 @T6G_MB_LIB.T6G(SCH_1):PAGE359

SMB_LM75_1_3V3AUX_SCL @T6G_MB_LIB.T6G(SCH_1):SMB_LM75_1_3V3AUX_SCL
 R4179    1      A Q_RES_0402LF-33.2,1%,1/16W,CHIP,CS03322FB03   I109 @T6G_MB_LIB.T6G(SCH_1):PAGE359
 R3717    2      B Q_RES_0402LF-0,5%,1/16W,CHIP,CS00002JB13    I20 @T6G_MB_LIB.T6G(SCH_1):PAGE251
 R3727    2      B Q_RES_0402LF-2.2K,5%,1/16W,CHIP,CS22202JB07    I48 @T6G_MB_LIB.T6G(SCH_1):PAGE251

SMB_LM75_1_3V3AUX_SCL_R @T6G_MB_LIB.T6G(SCH_1):SMB_LM75_1_3V3AUX_SCL_R
 R3717    1      A Q_RES_0402LF-0,5%,1/16W,CHIP,CS00002JB13    I20 @T6G_MB_LIB.T6G(SCH_1):PAGE251
   U39    9    SC2 TCA9548APWR-TCA9548APWR,SMLF,IC,AL009548K02    I74 @T6G_MB_LIB.T6G(SCH_1):PAGE251

SMB_LM75_1_3V3AUX_SCL_R1 @T6G_MB_LIB.T6G(SCH_1):SMB_LM75_1_3V3AUX_SCL_R1
 R4179    2      B Q_RES_0402LF-33.2,1%,1/16W,CHIP,CS03322FB03   I109 @T6G_MB_LIB.T6G(SCH_1):PAGE359
  U271    2    SCL LM75BD-LM75BD,SMLF,IC,AL0075BD000   I165 @T6G_MB_LIB.T6G(SCH_1):PAGE359

SMB_LM75_1_3V3AUX_SDA @T6G_MB_LIB.T6G(SCH_1):SMB_LM75_1_3V3AUX_SDA
 R4182    1      A Q_RES_0402LF-33.2,1%,1/16W,CHIP,CS03322FB03   I107 @T6G_MB_LIB.T6G(SCH_1):PAGE359
 R3718    2      B Q_RES_0402LF-0,5%,1/16W,CHIP,CS00002JB13    I21 @T6G_MB_LIB.T6G(SCH_1):PAGE251
 R3728    2      B Q_RES_0402LF-2.2K,5%,1/16W,CHIP,CS22202JB07    I47 @T6G_MB_LIB.T6G(SCH_1):PAGE251

SMB_LM75_1_3V3AUX_SDA_R @T6G_MB_LIB.T6G(SCH_1):SMB_LM75_1_3V3AUX_SDA_R
 R3718    1      A Q_RES_0402LF-0,5%,1/16W,CHIP,CS00002JB13    I21 @T6G_MB_LIB.T6G(SCH_1):PAGE251
   U39    8    SD2 TCA9548APWR-TCA9548APWR,SMLF,IC,AL009548K02    I74 @T6G_MB_LIB.T6G(SCH_1):PAGE251

SMB_LM75_1_3V3AUX_SDA_R1 @T6G_MB_LIB.T6G(SCH_1):SMB_LM75_1_3V3AUX_SDA_R1
 R4182    2      B Q_RES_0402LF-33.2,1%,1/16W,CHIP,CS03322FB03   I107 @T6G_MB_LIB.T6G(SCH_1):PAGE359
  U271    1    SDA LM75BD-LM75BD,SMLF,IC,AL0075BD000   I165 @T6G_MB_LIB.T6G(SCH_1):PAGE359

SMB_LM75_2_3V3AUX_SCL @T6G_MB_LIB.T6G(SCH_1):SMB_LM75_2_3V3AUX_SCL
 R4178    1      A Q_RES_0402LF-33.2,1%,1/16W,CHIP,CS03322FB03   I114 @T6G_MB_LIB.T6G(SCH_1):PAGE359
 R3719    2      B Q_RES_0402LF-0,5%,1/16W,CHIP,CS00002JB13    I18 @T6G_MB_LIB.T6G(SCH_1):PAGE251
 R3729    2      B Q_RES_0402LF-2.2K,5%,1/16W,CHIP,CS22202JB07    I44 @T6G_MB_LIB.T6G(SCH_1):PAGE251

SMB_LM75_2_3V3AUX_SCL_R @T6G_MB_LIB.T6G(SCH_1):SMB_LM75_2_3V3AUX_SCL_R
 R3719    1      A Q_RES_0402LF-0,5%,1/16W,CHIP,CS00002JB13    I18 @T6G_MB_LIB.T6G(SCH_1):PAGE251
   U39   11    SC3 TCA9548APWR-TCA9548APWR,SMLF,IC,AL009548K02    I74 @T6G_MB_LIB.T6G(SCH_1):PAGE251

SMB_LM75_2_3V3AUX_SCL_R1 @T6G_MB_LIB.T6G(SCH_1):SMB_LM75_2_3V3AUX_SCL_R1
 R4178    2      B Q_RES_0402LF-33.2,1%,1/16W,CHIP,CS03322FB03   I114 @T6G_MB_LIB.T6G(SCH_1):PAGE359
  U272    2    SCL LM75BD-LM75BD,SMLF,IC,AL0075BD000   I166 @T6G_MB_LIB.T6G(SCH_1):PAGE359

SMB_LM75_2_3V3AUX_SDA @T6G_MB_LIB.T6G(SCH_1):SMB_LM75_2_3V3AUX_SDA
 R4181    1      A Q_RES_0402LF-33.2,1%,1/16W,CHIP,CS03322FB03   I116 @T6G_MB_LIB.T6G(SCH_1):PAGE359
 R3720    2      B Q_RES_0402LF-0,5%,1/16W,CHIP,CS00002JB13    I19 @T6G_MB_LIB.T6G(SCH_1):PAGE251
 R3730    2      B Q_RES_0402LF-2.2K,5%,1/16W,CHIP,CS22202JB07    I45 @T6G_MB_LIB.T6G(SCH_1):PAGE251

SMB_LM75_2_3V3AUX_SDA_R @T6G_MB_LIB.T6G(SCH_1):SMB_LM75_2_3V3AUX_SDA_R
 R3720    1      A Q_RES_0402LF-0,5%,1/16W,CHIP,CS00002JB13    I19 @T6G_MB_LIB.T6G(SCH_1):PAGE251
   U39   10    SD3 TCA9548APWR-TCA9548APWR,SMLF,IC,AL009548K02    I74 @T6G_MB_LIB.T6G(SCH_1):PAGE251

SMB_LM75_2_3V3AUX_SDA_R1 @T6G_MB_LIB.T6G(SCH_1):SMB_LM75_2_3V3AUX_SDA_R1
 R4181    2      B Q_RES_0402LF-33.2,1%,1/16W,CHIP,CS03322FB03   I116 @T6G_MB_LIB.T6G(SCH_1):PAGE359
  U272    1    SDA LM75BD-LM75BD,SMLF,IC,AL0075BD000   I166 @T6G_MB_LIB.T6G(SCH_1):PAGE359

SMB_LM75_3_3V3AUX_SCL @T6G_MB_LIB.T6G(SCH_1):SMB_LM75_3_3V3AUX_SCL
 R3553    1      A Q_RES_0402LF-33.2,1%,1/16W,CHIP,CS03322FB03   I134 @T6G_MB_LIB.T6G(SCH_1):PAGE359
 R3731    2      B Q_RES_0402LF-2.2K,5%,1/16W,CHIP,CS22202JB07    I43 @T6G_MB_LIB.T6G(SCH_1):PAGE251
 R3721    2      B Q_RES_0402LF-0,5%,1/16W,CHIP,CS00002JB13    I67 @T6G_MB_LIB.T6G(SCH_1):PAGE251

SMB_LM75_3_3V3AUX_SCL_R @T6G_MB_LIB.T6G(SCH_1):SMB_LM75_3_3V3AUX_SCL_R
 R3721    1      A Q_RES_0402LF-0,5%,1/16W,CHIP,CS00002JB13    I67 @T6G_MB_LIB.T6G(SCH_1):PAGE251
   U39   14    SC4 TCA9548APWR-TCA9548APWR,SMLF,IC,AL009548K02    I74 @T6G_MB_LIB.T6G(SCH_1):PAGE251

SMB_LM75_3_3V3AUX_SCL_R1 @T6G_MB_LIB.T6G(SCH_1):SMB_LM75_3_3V3AUX_SCL_R1
 R3553    2      B Q_RES_0402LF-33.2,1%,1/16W,CHIP,CS03322FB03   I134 @T6G_MB_LIB.T6G(SCH_1):PAGE359
  U273    2    SCL LM75BD-LM75BD,SMLF,IC,AL0075BD000   I167 @T6G_MB_LIB.T6G(SCH_1):PAGE359

SMB_LM75_3_3V3AUX_SDA @T6G_MB_LIB.T6G(SCH_1):SMB_LM75_3_3V3AUX_SDA
 R3554    1      A Q_RES_0402LF-33.2,1%,1/16W,CHIP,CS03322FB03   I136 @T6G_MB_LIB.T6G(SCH_1):PAGE359
 R3732    2      B Q_RES_0402LF-2.2K,5%,1/16W,CHIP,CS22202JB07    I42 @T6G_MB_LIB.T6G(SCH_1):PAGE251
 R3722    2      B Q_RES_0402LF-0,5%,1/16W,CHIP,CS00002JB13    I66 @T6G_MB_LIB.T6G(SCH_1):PAGE251

SMB_LM75_3_3V3AUX_SDA_R @T6G_MB_LIB.T6G(SCH_1):SMB_LM75_3_3V3AUX_SDA_R
 R3722    1      A Q_RES_0402LF-0,5%,1/16W,CHIP,CS00002JB13    I66 @T6G_MB_LIB.T6G(SCH_1):PAGE251
   U39   13    SD4 TCA9548APWR-TCA9548APWR,SMLF,IC,AL009548K02    I74 @T6G_MB_LIB.T6G(SCH_1):PAGE251

SMB_LM75_3_3V3AUX_SDA_R1 @T6G_MB_LIB.T6G(SCH_1):SMB_LM75_3_3V3AUX_SDA_R1
 R3554    2      B Q_RES_0402LF-33.2,1%,1/16W,CHIP,CS03322FB03   I136 @T6G_MB_LIB.T6G(SCH_1):PAGE359
  U273    1    SDA LM75BD-LM75BD,SMLF,IC,AL0075BD000   I167 @T6G_MB_LIB.T6G(SCH_1):PAGE359

SMB_M2_P1_1V8AUX_SCL @T6G_MB_LIB.T6G(SCH_1):SMB_M2_P1_1V8AUX_SCL
   J59   40   NC12 SCONN75K_APCI0155P004A-SCONN75K_APCI0155-P004A,SMLA    I88 @T6G_MB_LIB.T6G(SCH_1):PAGE345
 R2411    2      B Q_RES_0402LF-33.2,1%,1/16W,CHIP,CS03322FB03    I66 @T6G_MB_LIB.T6G(SCH_1):PAGE346

SMB_M2_P1_1V8AUX_SCL_R @T6G_MB_LIB.T6G(SCH_1):SMB_M2_P1_1V8AUX_SCL_R
   U98    3   SCL1 PCA9306DP1-PCA9306DP1,SMLF,IC,AL009306K04    I27 @T6G_MB_LIB.T6G(SCH_1):PAGE346
 R1703    2      B Q_RES_0402LF-4.7K,5%,1/16W,CHIP,CS24702JB10    I45 @T6G_MB_LIB.T6G(SCH_1):PAGE346
 R2411    1      A Q_RES_0402LF-33.2,1%,1/16W,CHIP,CS03322FB03    I66 @T6G_MB_LIB.T6G(SCH_1):PAGE346

SMB_M2_P1_1V8AUX_SDA @T6G_MB_LIB.T6G(SCH_1):SMB_M2_P1_1V8AUX_SDA
   J59   42   NC13 SCONN75K_APCI0155P004A-SCONN75K_APCI0155-P004A,SMLA    I88 @T6G_MB_LIB.T6G(SCH_1):PAGE345
 R2410    2      B Q_RES_0402LF-33.2,1%,1/16W,CHIP,CS03322FB03    I65 @T6G_MB_LIB.T6G(SCH_1):PAGE346

SMB_M2_P1_1V8AUX_SDA_R @T6G_MB_LIB.T6G(SCH_1):SMB_M2_P1_1V8AUX_SDA_R
   U98    4   SDA1 PCA9306DP1-PCA9306DP1,SMLF,IC,AL009306K04    I27 @T6G_MB_LIB.T6G(SCH_1):PAGE346
 R1702    2      B Q_RES_0402LF-4.7K,5%,1/16W,CHIP,CS24702JB10    I43 @T6G_MB_LIB.T6G(SCH_1):PAGE346
 R2410    1      A Q_RES_0402LF-33.2,1%,1/16W,CHIP,CS03322FB03    I65 @T6G_MB_LIB.T6G(SCH_1):PAGE346

SMB_MUX_RT_R1_SCL @T6G_MB_LIB.T6G(SCH_1):SMB_MUX_RT_R1_SCL
 R6784    1      A Q_RES_0402LF-0,5%,1/16W,CHIP,CS00002JB13   I198 @T6G_MB_LIB.T6G(SCH_1):PAGE349
 R1514    1      A Q_RES_0201LF-0,5%,1/20W,CHIP,CS00001JE10   I118 @T6G_MB_LIB.T6G(SCH_1):PAGE378
 R6780    2      B Q_RES_0201LF-33.2,1%,1/20W,CHIP,CS03321FE09   I120 @T6G_MB_LIB.T6G(SCH_1):PAGE378

SMB_MUX_RT_R1_SDA @T6G_MB_LIB.T6G(SCH_1):SMB_MUX_RT_R1_SDA
 R6785    1      A Q_RES_0402LF-0,5%,1/16W,CHIP,CS00002JB13   I199 @T6G_MB_LIB.T6G(SCH_1):PAGE349
 R1515    1      A Q_RES_0201LF-0,5%,1/20W,CHIP,CS00001JE10   I117 @T6G_MB_LIB.T6G(SCH_1):PAGE378
 R6779    2      B Q_RES_0201LF-33.2,1%,1/20W,CHIP,CS03321FE09   I119 @T6G_MB_LIB.T6G(SCH_1):PAGE378

SMB_MUX_RT_R2_SCL @T6G_MB_LIB.T6G(SCH_1):SMB_MUX_RT_R2_SCL
JP6500    1      1 CONN3_210HP1030BR1-CONN3_210-HP1-030BR1,THLF,IO,DFA   I116 @T6G_MB_LIB.T6G(SCH_1):PAGE378
 R1514    2      B Q_RES_0201LF-0,5%,1/20W,CHIP,CS00001JE10   I118 @T6G_MB_LIB.T6G(SCH_1):PAGE378

SMB_MUX_RT_R2_SDA @T6G_MB_LIB.T6G(SCH_1):SMB_MUX_RT_R2_SDA
JP6500    2      2 CONN3_210HP1030BR1-CONN3_210-HP1-030BR1,THLF,IO,DFA   I116 @T6G_MB_LIB.T6G(SCH_1):PAGE378
 R1515    2      B Q_RES_0201LF-0,5%,1/20W,CHIP,CS00001JE10   I117 @T6G_MB_LIB.T6G(SCH_1):PAGE378

SMB_MUX_RT_ROM_R1_SCL @T6G_MB_LIB.T6G(SCH_1):SMB_MUX_RT_ROM_R1_SCL
  R851    2      B Q_RES_0201LF-0,5%,1/20W,CHIP,CS00001JE10    I82 @T6G_MB_LIB.T6G(SCH_1):PAGE377
 R6782    1      A Q_RES_0402LF-33,5%,1/16W,CHIP,CS03302JB10   I228 @T6G_MB_LIB.T6G(SCH_1):PAGE349

SMB_MUX_RT_ROM_R1_SDA @T6G_MB_LIB.T6G(SCH_1):SMB_MUX_RT_ROM_R1_SDA
  R850    2      B Q_RES_0201LF-0,5%,1/20W,CHIP,CS00001JE10    I81 @T6G_MB_LIB.T6G(SCH_1):PAGE377
 R6783    1      A Q_RES_0402LF-33,5%,1/16W,CHIP,CS03302JB10   I229 @T6G_MB_LIB.T6G(SCH_1):PAGE349

SMB_MUX_RT_ROM_SCL @T6G_MB_LIB.T6G(SCH_1):SMB_MUX_RT_ROM_SCL
  R851    1      A Q_RES_0201LF-0,5%,1/20W,CHIP,CS00001JE10    I82 @T6G_MB_LIB.T6G(SCH_1):PAGE377
   U22   22    SCL TCA9548APWR-TCA9548APWR,SMLF,IC,AL009548K02    I94 @T6G_MB_LIB.T6G(SCH_1):PAGE377

SMB_MUX_RT_ROM_SDA @T6G_MB_LIB.T6G(SCH_1):SMB_MUX_RT_ROM_SDA
  R850    1      A Q_RES_0201LF-0,5%,1/20W,CHIP,CS00001JE10    I81 @T6G_MB_LIB.T6G(SCH_1):PAGE377
   U22   23    SDA TCA9548APWR-TCA9548APWR,SMLF,IC,AL009548K02    I94 @T6G_MB_LIB.T6G(SCH_1):PAGE377

SMB_MUX_RT_SCL @T6G_MB_LIB.T6G(SCH_1):SMB_MUX_RT_SCL
 U6020   22    SCL TCA9548APWR-TCA9548APWR,SMLF,IC,AL009548K02     I1 @T6G_MB_LIB.T6G(SCH_1):PAGE378
 R6780    1      A Q_RES_0201LF-33.2,1%,1/20W,CHIP,CS03321FE09   I120 @T6G_MB_LIB.T6G(SCH_1):PAGE378

SMB_MUX_RT_SDA @T6G_MB_LIB.T6G(SCH_1):SMB_MUX_RT_SDA
 U6020   23    SDA TCA9548APWR-TCA9548APWR,SMLF,IC,AL009548K02     I1 @T6G_MB_LIB.T6G(SCH_1):PAGE378
 R6779    1      A Q_RES_0201LF-33.2,1%,1/20W,CHIP,CS03321FE09   I119 @T6G_MB_LIB.T6G(SCH_1):PAGE378

SMB_OCP_SFF_3V3AUX_BUF_R_SCL @T6G_MB_LIB.T6G(SCH_1):SMB_OCP_SFF_3V3AUX_BUF_R_SCL
   J38   A7  SMCLK SCONN168_ME1016810202011-SCONN168_ME1016810202011,A   I168 @T6G_MB_LIB.T6G(SCH_1):PAGE335
   R47    1      A Q_RES_0402LF-200,1%,1/16W,CHIP,CS12002FB06   I171 @T6G_MB_LIB.T6G(SCH_1):PAGE335

SMB_OCP_SFF_3V3AUX_BUF_R_SDA @T6G_MB_LIB.T6G(SCH_1):SMB_OCP_SFF_3V3AUX_BUF_R_SDA
   J38   A8  SMDAT SCONN168_ME1016810202011-SCONN168_ME1016810202011,A   I168 @T6G_MB_LIB.T6G(SCH_1):PAGE335
   R48    1      A Q_RES_0402LF-200,1%,1/16W,CHIP,CS12002FB06   I170 @T6G_MB_LIB.T6G(SCH_1):PAGE335

SMB_OCP_SFF_3V3AUX_BUF_SCL @T6G_MB_LIB.T6G(SCH_1):SMB_OCP_SFF_3V3AUX_BUF_SCL
  U236    7   SCLB PCA9617ADP-PCA9617ADP,SMLF,IC,AL009617K02    I14 @T6G_MB_LIB.T6G(SCH_1):PAGE248
 R3500    2      B Q_RES_0402LF-4.7K,5%,1/16W,CHIP,CS24702JB10    I27 @T6G_MB_LIB.T6G(SCH_1):PAGE248
   R47    2      B Q_RES_0402LF-200,1%,1/16W,CHIP,CS12002FB06   I171 @T6G_MB_LIB.T6G(SCH_1):PAGE335

SMB_OCP_SFF_3V3AUX_BUF_SDA @T6G_MB_LIB.T6G(SCH_1):SMB_OCP_SFF_3V3AUX_BUF_SDA
  U236    6   SDAB PCA9617ADP-PCA9617ADP,SMLF,IC,AL009617K02    I14 @T6G_MB_LIB.T6G(SCH_1):PAGE248
 R3501    2      B Q_RES_0402LF-4.7K,5%,1/16W,CHIP,CS24702JB10    I31 @T6G_MB_LIB.T6G(SCH_1):PAGE248
   R48    2      B Q_RES_0402LF-200,1%,1/16W,CHIP,CS12002FB06   I170 @T6G_MB_LIB.T6G(SCH_1):PAGE335

SMB_OCP_SFF_3V3AUX_SCL @T6G_MB_LIB.T6G(SCH_1):SMB_OCP_SFF_3V3AUX_SCL
 R3240    1      A Q_RES_0402LF-2.2K,5%,1/16W,EMPTY,CS22202JB07   I120 @T6G_MB_LIB.T6G(SCH_1):PAGE349
  U236    2   SCLA PCA9617ADP-PCA9617ADP,SMLF,IC,AL009617K02    I14 @T6G_MB_LIB.T6G(SCH_1):PAGE248
 R3238    1      A Q_RES_0402LF-33.2,1%,1/16W,CHIP,CS03322FB03   I103 @T6G_MB_LIB.T6G(SCH_1):PAGE348

SMB_OCP_SFF_3V3AUX_SCL_R0 @T6G_MB_LIB.T6G(SCH_1):SMB_OCP_SFF_3V3AUX_SCL_R0
   J41   A1 GND_A1 SCONN168_ME1016810202011-SCONN168_ME1016810202011,A   I176 @T6G_MB_LIB.T6G(SCH_1):PAGE348
 R3238    2      B Q_RES_0402LF-33.2,1%,1/16W,CHIP,CS03322FB03   I103 @T6G_MB_LIB.T6G(SCH_1):PAGE348

SMB_OCP_SFF_3V3AUX_SDA @T6G_MB_LIB.T6G(SCH_1):SMB_OCP_SFF_3V3AUX_SDA
  U236    3   SDAA PCA9617ADP-PCA9617ADP,SMLF,IC,AL009617K02    I14 @T6G_MB_LIB.T6G(SCH_1):PAGE248
 R3239    1      A Q_RES_0402LF-33.2,1%,1/16W,CHIP,CS03322FB03   I102 @T6G_MB_LIB.T6G(SCH_1):PAGE348
 R3241    1      A Q_RES_0402LF-2.2K,5%,1/16W,EMPTY,CS22202JB07   I149 @T6G_MB_LIB.T6G(SCH_1):PAGE349

SMB_OCP_SFF_3V3AUX_SDA_R0 @T6G_MB_LIB.T6G(SCH_1):SMB_OCP_SFF_3V3AUX_SDA_R0
   J41   A2 GND_A2 SCONN168_ME1016810202011-SCONN168_ME1016810202011,A   I176 @T6G_MB_LIB.T6G(SCH_1):PAGE348
 R3239    2      B Q_RES_0402LF-33.2,1%,1/16W,CHIP,CS03322FB03   I102 @T6G_MB_LIB.T6G(SCH_1):PAGE348

SMB_OCP_V3_2_3V3AUX_BUF_R_SCL @T6G_MB_LIB.T6G(SCH_1):SMB_OCP_V3_2_3V3AUX_BUF_R_SCL
   J35   A7  SMCLK SCONN168_ME1016810202011-SCONN168_ME1016810202011,A   I168 @T6G_MB_LIB.T6G(SCH_1):PAGE341
 R3228    1      A Q_RES_0402LF-200,1%,1/16W,CHIP,CS12002FB06   I171 @T6G_MB_LIB.T6G(SCH_1):PAGE341

SMB_OCP_V3_2_3V3AUX_BUF_R_SDA @T6G_MB_LIB.T6G(SCH_1):SMB_OCP_V3_2_3V3AUX_BUF_R_SDA
   J35   A8  SMDAT SCONN168_ME1016810202011-SCONN168_ME1016810202011,A   I168 @T6G_MB_LIB.T6G(SCH_1):PAGE341
 R3229    1      A Q_RES_0402LF-200,1%,1/16W,CHIP,CS12002FB06   I170 @T6G_MB_LIB.T6G(SCH_1):PAGE341

SMB_OCP_V3_2_3V3AUX_BUF_SCL @T6G_MB_LIB.T6G(SCH_1):SMB_OCP_V3_2_3V3AUX_BUF_SCL
  U235    7   SCLB PCA9617ADP-PCA9617ADP,SMLF,IC,AL009617K02     I6 @T6G_MB_LIB.T6G(SCH_1):PAGE248
 R3519    2      B Q_RES_0402LF-4.7K,5%,1/16W,CHIP,CS24702JB10    I34 @T6G_MB_LIB.T6G(SCH_1):PAGE248
 R3228    2      B Q_RES_0402LF-200,1%,1/16W,CHIP,CS12002FB06   I171 @T6G_MB_LIB.T6G(SCH_1):PAGE341

SMB_OCP_V3_2_3V3AUX_BUF_SDA @T6G_MB_LIB.T6G(SCH_1):SMB_OCP_V3_2_3V3AUX_BUF_SDA
  U235    6   SDAB PCA9617ADP-PCA9617ADP,SMLF,IC,AL009617K02     I6 @T6G_MB_LIB.T6G(SCH_1):PAGE248
 R3520    2      B Q_RES_0402LF-4.7K,5%,1/16W,CHIP,CS24702JB10    I23 @T6G_MB_LIB.T6G(SCH_1):PAGE248
 R3229    2      B Q_RES_0402LF-200,1%,1/16W,CHIP,CS12002FB06   I170 @T6G_MB_LIB.T6G(SCH_1):PAGE341

SMB_OCP_V3_2_3V3AUX_SCL @T6G_MB_LIB.T6G(SCH_1):SMB_OCP_V3_2_3V3AUX_SCL
 R2425    1      A Q_RES_0402LF-33.2,1%,1/16W,CHIP,CS03322FB03    I97 @T6G_MB_LIB.T6G(SCH_1):PAGE348
  U235    2   SCLA PCA9617ADP-PCA9617ADP,SMLF,IC,AL009617K02     I6 @T6G_MB_LIB.T6G(SCH_1):PAGE248
 R3242    1      A Q_RES_0402LF-2.2K,5%,1/16W,EMPTY,CS22202JB07   I119 @T6G_MB_LIB.T6G(SCH_1):PAGE349

SMB_OCP_V3_2_3V3AUX_SCL_R0 @T6G_MB_LIB.T6G(SCH_1):SMB_OCP_V3_2_3V3AUX_SCL_R0
 R2425    2      B Q_RES_0402LF-33.2,1%,1/16W,CHIP,CS03322FB03    I97 @T6G_MB_LIB.T6G(SCH_1):PAGE348
   J41  A11 PERST1# SCONN168_ME1016810202011-SCONN168_ME1016810202011,A   I176 @T6G_MB_LIB.T6G(SCH_1):PAGE348

SMB_OCP_V3_2_3V3AUX_SDA @T6G_MB_LIB.T6G(SCH_1):SMB_OCP_V3_2_3V3AUX_SDA
 R3858    1      A Q_RES_0402LF-33.2,1%,1/16W,CHIP,CS03322FB03    I96 @T6G_MB_LIB.T6G(SCH_1):PAGE348
 R3243    1      A Q_RES_0402LF-2.2K,5%,1/16W,EMPTY,CS22202JB07   I115 @T6G_MB_LIB.T6G(SCH_1):PAGE349
  U235    3   SDAA PCA9617ADP-PCA9617ADP,SMLF,IC,AL009617K02     I6 @T6G_MB_LIB.T6G(SCH_1):PAGE248

SMB_OCP_V3_2_3V3AUX_SDA_R0 @T6G_MB_LIB.T6G(SCH_1):SMB_OCP_V3_2_3V3AUX_SDA_R0
 R3858    2      B Q_RES_0402LF-33.2,1%,1/16W,CHIP,CS03322FB03    I96 @T6G_MB_LIB.T6G(SCH_1):PAGE348
   J41  A12 PRSNTB2# SCONN168_ME1016810202011-SCONN168_ME1016810202011,A   I176 @T6G_MB_LIB.T6G(SCH_1):PAGE348

SMB_P12V_HSC_SCL @T6G_MB_LIB.T6G(SCH_1):SMB_P12V_HSC_SCL
 R2626    2      B Q_RES_0402LF-0,5%,1/16W,CHIP,CS00002JB13    I40 @T6G_MB_LIB.T6G(SCH_1):PAGE371
 R6229    2      B Q_RES_0402LF-0,5%,1/16W,CHIP,CS00002JB13    I76 @T6G_MB_LIB.T6G(SCH_1):PAGE251
 R6231    2      B Q_RES_0402LF-2.2K,5%,1/16W,CHIP,CS22202JB07    I46 @T6G_MB_LIB.T6G(SCH_1):PAGE371

SMB_P12V_HSC_SCL_R @T6G_MB_LIB.T6G(SCH_1):SMB_P12V_HSC_SCL_R
   U39   16    SC5 TCA9548APWR-TCA9548APWR,SMLF,IC,AL009548K02    I74 @T6G_MB_LIB.T6G(SCH_1):PAGE251
 R6229    1      A Q_RES_0402LF-0,5%,1/16W,CHIP,CS00002JB13    I76 @T6G_MB_LIB.T6G(SCH_1):PAGE251

SMB_P12V_HSC_SDA @T6G_MB_LIB.T6G(SCH_1):SMB_P12V_HSC_SDA
 R2627    2      B Q_RES_0402LF-0,5%,1/16W,CHIP,CS00002JB13    I39 @T6G_MB_LIB.T6G(SCH_1):PAGE371
 R6228    2      B Q_RES_0402LF-0,5%,1/16W,CHIP,CS00002JB13    I75 @T6G_MB_LIB.T6G(SCH_1):PAGE251
 R6230    2      B Q_RES_0402LF-2.2K,5%,1/16W,CHIP,CS22202JB07    I45 @T6G_MB_LIB.T6G(SCH_1):PAGE371

SMB_P12V_HSC_SDA_R @T6G_MB_LIB.T6G(SCH_1):SMB_P12V_HSC_SDA_R
   U39   15    SD5 TCA9548APWR-TCA9548APWR,SMLF,IC,AL009548K02    I74 @T6G_MB_LIB.T6G(SCH_1):PAGE251
 R6228    1      A Q_RES_0402LF-0,5%,1/16W,CHIP,CS00002JB13    I75 @T6G_MB_LIB.T6G(SCH_1):PAGE251

SMB_P12V_HSC_TEMP_SCL @T6G_MB_LIB.T6G(SCH_1):SMB_P12V_HSC_TEMP_SCL
  U143    8    SCL NCT7718W-NCT7718W,SMLF,IC,AL007718001     I8 @T6G_MB_LIB.T6G(SCH_1):PAGE371
 R2626    1      A Q_RES_0402LF-0,5%,1/16W,CHIP,CS00002JB13    I40 @T6G_MB_LIB.T6G(SCH_1):PAGE371

SMB_P12V_HSC_TEMP_SDA @T6G_MB_LIB.T6G(SCH_1):SMB_P12V_HSC_TEMP_SDA
  U143    7    SDA NCT7718W-NCT7718W,SMLF,IC,AL007718001     I8 @T6G_MB_LIB.T6G(SCH_1):PAGE371
 R2627    1      A Q_RES_0402LF-0,5%,1/16W,CHIP,CS00002JB13    I39 @T6G_MB_LIB.T6G(SCH_1):PAGE371

SMB_PCIE0_3V3AUX_SCL @T6G_MB_LIB.T6G(SCH_1):SMB_PCIE0_3V3AUX_SCL
   J41  A23  PERN2 SCONN168_ME1016810202011-SCONN168_ME1016810202011,A   I176 @T6G_MB_LIB.T6G(SCH_1):PAGE348
 R2204    2      B Q_RES_0402LF-2.2K,5%,1/16W,EMPTY,CS22202JB07    I50 @T6G_MB_LIB.T6G(SCH_1):PAGE252
   R65    1      A Q_RES_0402LF-33.2,1%,1/16W,CHIP,CS03322FB03    I74 @T6G_MB_LIB.T6G(SCH_1):PAGE252

SMB_PCIE0_3V3AUX_SCL_R @T6G_MB_LIB.T6G(SCH_1):SMB_PCIE0_3V3AUX_SCL_R
   U36   22    SCL TCA9548APWR-TCA9548APWR,SMLF,IC,AL009548K02    I33 @T6G_MB_LIB.T6G(SCH_1):PAGE252
   R65    2      B Q_RES_0402LF-33.2,1%,1/16W,CHIP,CS03322FB03    I74 @T6G_MB_LIB.T6G(SCH_1):PAGE252

SMB_PCIE0_3V3AUX_SCL_R3 @T6G_MB_LIB.T6G(SCH_1):SMB_PCIE0_3V3AUX_SCL_R3
 R2967    1      A Q_RES_0402LF-0,5%,1/16W,CHIP,CS00002JB13    I25 @T6G_MB_LIB.T6G(SCH_1):PAGE252
   U36    9    SC2 TCA9548APWR-TCA9548APWR,SMLF,IC,AL009548K02    I33 @T6G_MB_LIB.T6G(SCH_1):PAGE252

SMB_PCIE0_3V3AUX_SCL_R5 @T6G_MB_LIB.T6G(SCH_1):SMB_PCIE0_3V3AUX_SCL_R5
 R3526    1      A Q_RES_0402LF-0,5%,1/16W,CHIP,CS00002JB13    I23 @T6G_MB_LIB.T6G(SCH_1):PAGE252
   U36   11    SC3 TCA9548APWR-TCA9548APWR,SMLF,IC,AL009548K02    I33 @T6G_MB_LIB.T6G(SCH_1):PAGE252

SMB_PCIE0_3V3AUX_SDA @T6G_MB_LIB.T6G(SCH_1):SMB_PCIE0_3V3AUX_SDA
   J41  A24  PERP2 SCONN168_ME1016810202011-SCONN168_ME1016810202011,A   I176 @T6G_MB_LIB.T6G(SCH_1):PAGE348
 R2205    2      B Q_RES_0402LF-2.2K,5%,1/16W,EMPTY,CS22202JB07    I49 @T6G_MB_LIB.T6G(SCH_1):PAGE252
   R55    1      A Q_RES_0402LF-33.2,1%,1/16W,CHIP,CS03322FB03    I73 @T6G_MB_LIB.T6G(SCH_1):PAGE252

SMB_PCIE0_3V3AUX_SDA_R @T6G_MB_LIB.T6G(SCH_1):SMB_PCIE0_3V3AUX_SDA_R
   U36   23    SDA TCA9548APWR-TCA9548APWR,SMLF,IC,AL009548K02    I33 @T6G_MB_LIB.T6G(SCH_1):PAGE252
   R55    2      B Q_RES_0402LF-33.2,1%,1/16W,CHIP,CS03322FB03    I73 @T6G_MB_LIB.T6G(SCH_1):PAGE252

SMB_PCIE0_3V3AUX_SDA_R3 @T6G_MB_LIB.T6G(SCH_1):SMB_PCIE0_3V3AUX_SDA_R3
 R2968    1      A Q_RES_0402LF-0,5%,1/16W,CHIP,CS00002JB13    I26 @T6G_MB_LIB.T6G(SCH_1):PAGE252
   U36    8    SD2 TCA9548APWR-TCA9548APWR,SMLF,IC,AL009548K02    I33 @T6G_MB_LIB.T6G(SCH_1):PAGE252

SMB_PCIE0_3V3AUX_SDA_R5 @T6G_MB_LIB.T6G(SCH_1):SMB_PCIE0_3V3AUX_SDA_R5
 R3527    1      A Q_RES_0402LF-0,5%,1/16W,CHIP,CS00002JB13    I24 @T6G_MB_LIB.T6G(SCH_1):PAGE252
   U36   10    SD3 TCA9548APWR-TCA9548APWR,SMLF,IC,AL009548K02    I33 @T6G_MB_LIB.T6G(SCH_1):PAGE252

SMB_PCIE2_3V3AUX_SCL_R0 @T6G_MB_LIB.T6G(SCH_1):SMB_PCIE2_3V3AUX_SCL_R0
 R2413    2      B Q_RES_0402LF-33.2,1%,1/16W,CHIP,CS03322FB03    I86 @T6G_MB_LIB.T6G(SCH_1):PAGE348
   J41  A31  PERP4 SCONN168_ME1016810202011-SCONN168_ME1016810202011,A   I176 @T6G_MB_LIB.T6G(SCH_1):PAGE348

SMB_PCIE2_3V3AUX_SDA_R0 @T6G_MB_LIB.T6G(SCH_1):SMB_PCIE2_3V3AUX_SDA_R0
 R2414    2      B Q_RES_0402LF-33.2,1%,1/16W,CHIP,CS03322FB03    I85 @T6G_MB_LIB.T6G(SCH_1):PAGE348
   J41  A32 GND_A32 SCONN168_ME1016810202011-SCONN168_ME1016810202011,A   I176 @T6G_MB_LIB.T6G(SCH_1):PAGE348

SMB_PCIE3_3V3AUX_SCL_R @T6G_MB_LIB.T6G(SCH_1):SMB_PCIE3_3V3AUX_SCL_R
   J41  A38 GND_A38 SCONN168_ME1016810202011-SCONN168_ME1016810202011,A   I176 @T6G_MB_LIB.T6G(SCH_1):PAGE348
 R2415    2      B Q_RES_0402LF-33.2,1%,1/16W,CHIP,CS03322FB03    I60 @T6G_MB_LIB.T6G(SCH_1):PAGE348

SMB_PCIE3_3V3AUX_SDA_R @T6G_MB_LIB.T6G(SCH_1):SMB_PCIE3_3V3AUX_SDA_R
   J41  A39  PERN7 SCONN168_ME1016810202011-SCONN168_ME1016810202011,A   I176 @T6G_MB_LIB.T6G(SCH_1):PAGE348
 R2416    2      B Q_RES_0402LF-33.2,1%,1/16W,CHIP,CS03322FB03    I33 @T6G_MB_LIB.T6G(SCH_1):PAGE348

SMB_PCIE_E1S_ISO_EN @T6G_MB_LIB.T6G(SCH_1):SMB_PCIE_E1S_ISO_EN
 R3531    1      A Q_RES_0402LF-200K,1%,1/16W,EMPTY,CS42002FB05    I96 @T6G_MB_LIB.T6G(SCH_1):PAGE346
 R2114    2      B Q_RES_0402LF-0,5%,1/16W,CHIP,CS00002JB13    I37 @T6G_MB_LIB.T6G(SCH_1):PAGE297
 R2125    2      B Q_RES_0402LF-4.7K,5%,1/16W,CHIP,CS24702JB10    I40 @T6G_MB_LIB.T6G(SCH_1):PAGE297

SMB_PCIE_E1S_ISO_EN_R @T6G_MB_LIB.T6G(SCH_1):SMB_PCIE_E1S_ISO_EN_R
  U279    5     EN PCA9617ADP-PCA9617ADP,SMLF,IC,AL009617K02    I93 @T6G_MB_LIB.T6G(SCH_1):PAGE346
 R3531    2      B Q_RES_0402LF-200K,1%,1/16W,EMPTY,CS42002FB05    I96 @T6G_MB_LIB.T6G(SCH_1):PAGE346
 R3529    2      B Q_RES_0402LF-10K,1%,1/16W,CHIP,CS31002FB08    I99 @T6G_MB_LIB.T6G(SCH_1):PAGE346

SMB_PCIE_E1S_ISO_EN_R2 @T6G_MB_LIB.T6G(SCH_1):SMB_PCIE_E1S_ISO_EN_R2
  U134    4     2Y 74LVC2G07DW7-74LVC2G07DW-7,SMLF,IC,AL002G07003     I4 @T6G_MB_LIB.T6G(SCH_1):PAGE297
 R2114    1      A Q_RES_0402LF-0,5%,1/16W,CHIP,CS00002JB13    I37 @T6G_MB_LIB.T6G(SCH_1):PAGE297

SMB_PCIE_M2_0_EN @T6G_MB_LIB.T6G(SCH_1):SMB_PCIE_M2_0_EN
   U98    8     EN PCA9306DP1-PCA9306DP1,SMLF,IC,AL009306K04    I27 @T6G_MB_LIB.T6G(SCH_1):PAGE346
   U98    7  VREF2 PCA9306DP1-PCA9306DP1,SMLF,IC,AL009306K04    I27 @T6G_MB_LIB.T6G(SCH_1):PAGE346
 R2476    1      A Q_RES_0402LF-200K,1%,1/16W,EMPTY,CS42002FB05    I70 @T6G_MB_LIB.T6G(SCH_1):PAGE346
 R1700    2      B Q_RES_0402LF-200K,1%,1/16W,CHIP,CS42002FB05    I72 @T6G_MB_LIB.T6G(SCH_1):PAGE346

SMB_PMBUS_3V3AUX_SCL @T6G_MB_LIB.T6G(SCH_1):SMB_PMBUS_3V3AUX_SCL
 R1386    1      A Q_RES_0402LF-2K,1%,1/16W,EMPTY,CS22002FB07   I134 @T6G_MB_LIB.T6G(SCH_1):PAGE349
 R2995    1      A Q_RES_0402LF-33.2,1%,1/16W,CHIP,CS03322FB03    I91 @T6G_MB_LIB.T6G(SCH_1):PAGE349
 R2423    1      A Q_RES_0402LF-33.2,1%,1/16W,CHIP,CS03322FB03   I196 @T6G_MB_LIB.T6G(SCH_1):PAGE348

SMB_PMBUS_3V3AUX_SCL_R0 @T6G_MB_LIB.T6G(SCH_1):SMB_PMBUS_3V3AUX_SCL_R0
   J41  A25 GND_A25 SCONN168_ME1016810202011-SCONN168_ME1016810202011,A   I176 @T6G_MB_LIB.T6G(SCH_1):PAGE348
 R2423    2      B Q_RES_0402LF-33.2,1%,1/16W,CHIP,CS03322FB03   I196 @T6G_MB_LIB.T6G(SCH_1):PAGE348

SMB_PMBUS_3V3AUX_SDA @T6G_MB_LIB.T6G(SCH_1):SMB_PMBUS_3V3AUX_SDA
  R329    1      A Q_RES_0402LF-2K,1%,1/16W,EMPTY,CS22002FB07   I133 @T6G_MB_LIB.T6G(SCH_1):PAGE349
 R2996    1      A Q_RES_0402LF-33.2,1%,1/16W,CHIP,CS03322FB03    I92 @T6G_MB_LIB.T6G(SCH_1):PAGE349
 R2424    1      A Q_RES_0402LF-33.2,1%,1/16W,CHIP,CS03322FB03   I195 @T6G_MB_LIB.T6G(SCH_1):PAGE348

SMB_PMBUS_3V3AUX_SDA_R0 @T6G_MB_LIB.T6G(SCH_1):SMB_PMBUS_3V3AUX_SDA_R0
   J41  A26  PERN3 SCONN168_ME1016810202011-SCONN168_ME1016810202011,A   I176 @T6G_MB_LIB.T6G(SCH_1):PAGE348
 R2424    2      B Q_RES_0402LF-33.2,1%,1/16W,CHIP,CS03322FB03   I195 @T6G_MB_LIB.T6G(SCH_1):PAGE348

SMB_RT_CPU0_P0_R2_SCL @T6G_MB_LIB.T6G(SCH_1):SMB_RT_CPU0_P0_R2_SCL
  R976    2      B Q_RES_0201LF-0,5%,1/20W,CHIP,CS00001JE10    I50 @T6G_MB_LIB.T6G(SCH_1):PAGE385
 U6010  B31 SMBCLK PT5161LRS-PT5161LRS,SMLF,IC,AJ051610U03    I53 @T6G_MB_LIB.T6G(SCH_1):PAGE385

SMB_RT_CPU0_P0_R2_SDA @T6G_MB_LIB.T6G(SCH_1):SMB_RT_CPU0_P0_R2_SDA
  R977    2      B Q_RES_0201LF-0,5%,1/20W,CHIP,CS00001JE10    I49 @T6G_MB_LIB.T6G(SCH_1):PAGE385
 U6010  B28 SMBDAT PT5161LRS-PT5161LRS,SMLF,IC,AJ051610U03    I53 @T6G_MB_LIB.T6G(SCH_1):PAGE385

SMB_RT_CPU0_P0_ROM_MUX_1D_R_SCL @T6G_MB_LIB.T6G(SCH_1):SMB_RT_CPU0_P0_ROM_MUX_1D_R_SCL
  R666    2      B Q_RES_0201LF-49.9,1%,1/20W,CHIP,CS04991FE06    I42 @T6G_MB_LIB.T6G(SCH_1):PAGE385
 U6010  FF5 EE_CLK PT5161LRS-PT5161LRS,SMLF,IC,AJ051610U03    I53 @T6G_MB_LIB.T6G(SCH_1):PAGE385

SMB_RT_CPU0_P0_ROM_MUX_1D_R_SDA @T6G_MB_LIB.T6G(SCH_1):SMB_RT_CPU0_P0_ROM_MUX_1D_R_SDA
  R667    2      B Q_RES_0201LF-49.9,1%,1/20W,CHIP,CS04991FE06    I41 @T6G_MB_LIB.T6G(SCH_1):PAGE385
 U6010  FJ3 EE_DAT PT5161LRS-PT5161LRS,SMLF,IC,AJ051610U03    I53 @T6G_MB_LIB.T6G(SCH_1):PAGE385

SMB_RT_CPU0_P0_ROM_MUX_1D_SCL @T6G_MB_LIB.T6G(SCH_1):SMB_RT_CPU0_P0_ROM_MUX_1D_SCL
  R666    1      A Q_RES_0201LF-49.9,1%,1/20W,CHIP,CS04991FE06    I42 @T6G_MB_LIB.T6G(SCH_1):PAGE385
   U49    1    1D+ PI3CSW12ZUAEX-PI3CSW12ZUAEX,SMLF,IC,AL3CSW12000    I85 @T6G_MB_LIB.T6G(SCH_1):PAGE376
 R1411    2      B Q_RES_0201LF-1K,1%,1/20W,CHIP,CS21001FE07   I165 @T6G_MB_LIB.T6G(SCH_1):PAGE377

SMB_RT_CPU0_P0_ROM_MUX_1D_SDA @T6G_MB_LIB.T6G(SCH_1):SMB_RT_CPU0_P0_ROM_MUX_1D_SDA
  R667    1      A Q_RES_0201LF-49.9,1%,1/20W,CHIP,CS04991FE06    I41 @T6G_MB_LIB.T6G(SCH_1):PAGE385
   U49    2    1D- PI3CSW12ZUAEX-PI3CSW12ZUAEX,SMLF,IC,AL3CSW12000    I85 @T6G_MB_LIB.T6G(SCH_1):PAGE376
 R1410    2      B Q_RES_0201LF-1K,1%,1/20W,CHIP,CS21001FE07   I164 @T6G_MB_LIB.T6G(SCH_1):PAGE377

SMB_RT_CPU0_P0_ROM_MUX_2D_R_SCL @T6G_MB_LIB.T6G(SCH_1):SMB_RT_CPU0_P0_ROM_MUX_2D_R_SCL
  R799    1      A Q_RES_0201LF-0,5%,1/20W,CHIP,CS00001JE10    I79 @T6G_MB_LIB.T6G(SCH_1):PAGE377
   U22   14    SC4 TCA9548APWR-TCA9548APWR,SMLF,IC,AL009548K02    I94 @T6G_MB_LIB.T6G(SCH_1):PAGE377
 R1367    2      B Q_RES_0201LF-4.7K,5%,1/20W,CHIP,CS24701JE04   I121 @T6G_MB_LIB.T6G(SCH_1):PAGE377

SMB_RT_CPU0_P0_ROM_MUX_2D_R_SDA @T6G_MB_LIB.T6G(SCH_1):SMB_RT_CPU0_P0_ROM_MUX_2D_R_SDA
  R797    1      A Q_RES_0201LF-0,5%,1/20W,CHIP,CS00001JE10    I80 @T6G_MB_LIB.T6G(SCH_1):PAGE377
   U22   13    SD4 TCA9548APWR-TCA9548APWR,SMLF,IC,AL009548K02    I94 @T6G_MB_LIB.T6G(SCH_1):PAGE377
 R1366    2      B Q_RES_0201LF-4.7K,5%,1/20W,CHIP,CS24701JE04   I122 @T6G_MB_LIB.T6G(SCH_1):PAGE377

SMB_RT_CPU0_P0_ROM_MUX_2D_SCL @T6G_MB_LIB.T6G(SCH_1):SMB_RT_CPU0_P0_ROM_MUX_2D_SCL
  R799    2      B Q_RES_0201LF-0,5%,1/20W,CHIP,CS00001JE10    I79 @T6G_MB_LIB.T6G(SCH_1):PAGE377
   U49    3    2D+ PI3CSW12ZUAEX-PI3CSW12ZUAEX,SMLF,IC,AL3CSW12000    I85 @T6G_MB_LIB.T6G(SCH_1):PAGE376

SMB_RT_CPU0_P0_ROM_MUX_2D_SDA @T6G_MB_LIB.T6G(SCH_1):SMB_RT_CPU0_P0_ROM_MUX_2D_SDA
  R797    2      B Q_RES_0201LF-0,5%,1/20W,CHIP,CS00001JE10    I80 @T6G_MB_LIB.T6G(SCH_1):PAGE377
   U49    4    2D- PI3CSW12ZUAEX-PI3CSW12ZUAEX,SMLF,IC,AL3CSW12000    I85 @T6G_MB_LIB.T6G(SCH_1):PAGE376

SMB_RT_CPU0_P0_ROM_R_SCL @T6G_MB_LIB.T6G(SCH_1):SMB_RT_CPU0_P0_ROM_R_SCL
  R668    1      A Q_RES_0201LF-33.2,1%,1/20W,CHIP,CS03321FE09     I6 @T6G_MB_LIB.T6G(SCH_1):PAGE387
  R835    2      B Q_RES_0201LF-1K,1%,1/20W,CHIP,CS21001FE07    I23 @T6G_MB_LIB.T6G(SCH_1):PAGE377
   U49    8     D+ PI3CSW12ZUAEX-PI3CSW12ZUAEX,SMLF,IC,AL3CSW12000    I85 @T6G_MB_LIB.T6G(SCH_1):PAGE376

SMB_RT_CPU0_P0_ROM_R_SDA @T6G_MB_LIB.T6G(SCH_1):SMB_RT_CPU0_P0_ROM_R_SDA
  R669    1      A Q_RES_0201LF-33.2,1%,1/20W,CHIP,CS03321FE09     I7 @T6G_MB_LIB.T6G(SCH_1):PAGE387
  R834    2      B Q_RES_0201LF-1K,1%,1/20W,CHIP,CS21001FE07    I24 @T6G_MB_LIB.T6G(SCH_1):PAGE377
   U49    7     D- PI3CSW12ZUAEX-PI3CSW12ZUAEX,SMLF,IC,AL3CSW12000    I85 @T6G_MB_LIB.T6G(SCH_1):PAGE376

SMB_RT_CPU0_P0_ROM_SCL @T6G_MB_LIB.T6G(SCH_1):SMB_RT_CPU0_P0_ROM_SCL
   U11    6    SCL M24M02DRMN6TP-M24M02-DRMN6TP,SMLF,IC,AKE33Z00600     I3 @T6G_MB_LIB.T6G(SCH_1):PAGE387
  R668    2      B Q_RES_0201LF-33.2,1%,1/20W,CHIP,CS03321FE09     I6 @T6G_MB_LIB.T6G(SCH_1):PAGE387

SMB_RT_CPU0_P0_ROM_SDA @T6G_MB_LIB.T6G(SCH_1):SMB_RT_CPU0_P0_ROM_SDA
   U11    5    SDA M24M02DRMN6TP-M24M02-DRMN6TP,SMLF,IC,AKE33Z00600     I3 @T6G_MB_LIB.T6G(SCH_1):PAGE387
  R669    2      B Q_RES_0201LF-33.2,1%,1/20W,CHIP,CS03321FE09     I7 @T6G_MB_LIB.T6G(SCH_1):PAGE387

SMB_RT_CPU0_P0_R_SCL @T6G_MB_LIB.T6G(SCH_1):SMB_RT_CPU0_P0_R_SCL
 R6755    2      B Q_RES_0201LF-0,5%,1/20W,CHIP,CS00001JE10    I54 @T6G_MB_LIB.T6G(SCH_1):PAGE378
 R6763    2      B Q_RES_0201LF-1K,1%,1/20W,CHIP,CS21001FE07    I78 @T6G_MB_LIB.T6G(SCH_1):PAGE378
  R976    1      A Q_RES_0201LF-0,5%,1/20W,CHIP,CS00001JE10    I50 @T6G_MB_LIB.T6G(SCH_1):PAGE385

SMB_RT_CPU0_P0_R_SDA @T6G_MB_LIB.T6G(SCH_1):SMB_RT_CPU0_P0_R_SDA
 R6754    2      B Q_RES_0201LF-0,5%,1/20W,CHIP,CS00001JE10    I53 @T6G_MB_LIB.T6G(SCH_1):PAGE378
 R6762    2      B Q_RES_0201LF-1K,1%,1/20W,CHIP,CS21001FE07    I77 @T6G_MB_LIB.T6G(SCH_1):PAGE378
  R977    1      A Q_RES_0201LF-0,5%,1/20W,CHIP,CS00001JE10    I49 @T6G_MB_LIB.T6G(SCH_1):PAGE385

SMB_RT_CPU0_P0_SCL @T6G_MB_LIB.T6G(SCH_1):SMB_RT_CPU0_P0_SCL
 U6020   14    SC4 TCA9548APWR-TCA9548APWR,SMLF,IC,AL009548K02     I1 @T6G_MB_LIB.T6G(SCH_1):PAGE378
 R6755    1      A Q_RES_0201LF-0,5%,1/20W,CHIP,CS00001JE10    I54 @T6G_MB_LIB.T6G(SCH_1):PAGE378

SMB_RT_CPU0_P0_SDA @T6G_MB_LIB.T6G(SCH_1):SMB_RT_CPU0_P0_SDA
 U6020   13    SD4 TCA9548APWR-TCA9548APWR,SMLF,IC,AL009548K02     I1 @T6G_MB_LIB.T6G(SCH_1):PAGE378
 R6754    1      A Q_RES_0201LF-0,5%,1/20W,CHIP,CS00001JE10    I53 @T6G_MB_LIB.T6G(SCH_1):PAGE378

SMB_RT_CPU0_P1_R2_SCL @T6G_MB_LIB.T6G(SCH_1):SMB_RT_CPU0_P1_R2_SCL
 R1025    2      B Q_RES_0201LF-0,5%,1/20W,CHIP,CS00001JE10    I30 @T6G_MB_LIB.T6G(SCH_1):PAGE408
 U6011  B31 SMBCLK PT5161LRS-PT5161LRS,SMLF,IC,AJ051610U03    I83 @T6G_MB_LIB.T6G(SCH_1):PAGE408

SMB_RT_CPU0_P1_R2_SDA @T6G_MB_LIB.T6G(SCH_1):SMB_RT_CPU0_P1_R2_SDA
 R1026    2      B Q_RES_0201LF-0,5%,1/20W,CHIP,CS00001JE10    I29 @T6G_MB_LIB.T6G(SCH_1):PAGE408
 U6011  B28 SMBDAT PT5161LRS-PT5161LRS,SMLF,IC,AJ051610U03    I83 @T6G_MB_LIB.T6G(SCH_1):PAGE408

SMB_RT_CPU0_P1_ROM_MUX_1D_R_SCL @T6G_MB_LIB.T6G(SCH_1):SMB_RT_CPU0_P1_ROM_MUX_1D_R_SCL
  R676    2      B Q_RES_0201LF-49.9,1%,1/20W,CHIP,CS04991FE06    I22 @T6G_MB_LIB.T6G(SCH_1):PAGE408
 U6011  FF5 EE_CLK PT5161LRS-PT5161LRS,SMLF,IC,AJ051610U03    I83 @T6G_MB_LIB.T6G(SCH_1):PAGE408

SMB_RT_CPU0_P1_ROM_MUX_1D_R_SDA @T6G_MB_LIB.T6G(SCH_1):SMB_RT_CPU0_P1_ROM_MUX_1D_R_SDA
  R677    2      B Q_RES_0201LF-49.9,1%,1/20W,CHIP,CS04991FE06    I21 @T6G_MB_LIB.T6G(SCH_1):PAGE408
 U6011  FJ3 EE_DAT PT5161LRS-PT5161LRS,SMLF,IC,AJ051610U03    I83 @T6G_MB_LIB.T6G(SCH_1):PAGE408

SMB_RT_CPU0_P1_ROM_MUX_1D_SCL @T6G_MB_LIB.T6G(SCH_1):SMB_RT_CPU0_P1_ROM_MUX_1D_SCL
  R676    1      A Q_RES_0201LF-49.9,1%,1/20W,CHIP,CS04991FE06    I22 @T6G_MB_LIB.T6G(SCH_1):PAGE408
   U48    1    1D+ PI3CSW12ZUAEX-PI3CSW12ZUAEX,SMLF,IC,AL3CSW12000    I76 @T6G_MB_LIB.T6G(SCH_1):PAGE376
 R1418    2      B Q_RES_0201LF-1K,1%,1/20W,CHIP,CS21001FE07   I167 @T6G_MB_LIB.T6G(SCH_1):PAGE377

SMB_RT_CPU0_P1_ROM_MUX_1D_SDA @T6G_MB_LIB.T6G(SCH_1):SMB_RT_CPU0_P1_ROM_MUX_1D_SDA
  R677    1      A Q_RES_0201LF-49.9,1%,1/20W,CHIP,CS04991FE06    I21 @T6G_MB_LIB.T6G(SCH_1):PAGE408
   U48    2    1D- PI3CSW12ZUAEX-PI3CSW12ZUAEX,SMLF,IC,AL3CSW12000    I76 @T6G_MB_LIB.T6G(SCH_1):PAGE376
 R1415    2      B Q_RES_0201LF-1K,1%,1/20W,CHIP,CS21001FE07   I166 @T6G_MB_LIB.T6G(SCH_1):PAGE377

SMB_RT_CPU0_P1_ROM_MUX_2D_R_SCL @T6G_MB_LIB.T6G(SCH_1):SMB_RT_CPU0_P1_ROM_MUX_2D_R_SCL
  R829    1      A Q_RES_0201LF-0,5%,1/20W,CHIP,CS00001JE10    I77 @T6G_MB_LIB.T6G(SCH_1):PAGE377
   U22   16    SC5 TCA9548APWR-TCA9548APWR,SMLF,IC,AL009548K02    I94 @T6G_MB_LIB.T6G(SCH_1):PAGE377
 R1374    2      B Q_RES_0201LF-4.7K,5%,1/20W,CHIP,CS24701JE04   I123 @T6G_MB_LIB.T6G(SCH_1):PAGE377

SMB_RT_CPU0_P1_ROM_MUX_2D_R_SDA @T6G_MB_LIB.T6G(SCH_1):SMB_RT_CPU0_P1_ROM_MUX_2D_R_SDA
  R828    1      A Q_RES_0201LF-0,5%,1/20W,CHIP,CS00001JE10    I76 @T6G_MB_LIB.T6G(SCH_1):PAGE377
   U22   15    SD5 TCA9548APWR-TCA9548APWR,SMLF,IC,AL009548K02    I94 @T6G_MB_LIB.T6G(SCH_1):PAGE377
 R1371    2      B Q_RES_0201LF-4.7K,5%,1/20W,CHIP,CS24701JE04   I124 @T6G_MB_LIB.T6G(SCH_1):PAGE377

SMB_RT_CPU0_P1_ROM_MUX_2D_SCL @T6G_MB_LIB.T6G(SCH_1):SMB_RT_CPU0_P1_ROM_MUX_2D_SCL
  R829    2      B Q_RES_0201LF-0,5%,1/20W,CHIP,CS00001JE10    I77 @T6G_MB_LIB.T6G(SCH_1):PAGE377
   U48    3    2D+ PI3CSW12ZUAEX-PI3CSW12ZUAEX,SMLF,IC,AL3CSW12000    I76 @T6G_MB_LIB.T6G(SCH_1):PAGE376

SMB_RT_CPU0_P1_ROM_MUX_2D_SDA @T6G_MB_LIB.T6G(SCH_1):SMB_RT_CPU0_P1_ROM_MUX_2D_SDA
  R828    2      B Q_RES_0201LF-0,5%,1/20W,CHIP,CS00001JE10    I76 @T6G_MB_LIB.T6G(SCH_1):PAGE377
   U48    4    2D- PI3CSW12ZUAEX-PI3CSW12ZUAEX,SMLF,IC,AL3CSW12000    I76 @T6G_MB_LIB.T6G(SCH_1):PAGE376

SMB_RT_CPU0_P1_ROM_R_SCL @T6G_MB_LIB.T6G(SCH_1):SMB_RT_CPU0_P1_ROM_R_SCL
  R678    1      A Q_RES_0201LF-33.2,1%,1/20W,CHIP,CS03321FE09     I6 @T6G_MB_LIB.T6G(SCH_1):PAGE410
  R837    2      B Q_RES_0201LF-1K,1%,1/20W,CHIP,CS21001FE07    I21 @T6G_MB_LIB.T6G(SCH_1):PAGE377
   U48    8     D+ PI3CSW12ZUAEX-PI3CSW12ZUAEX,SMLF,IC,AL3CSW12000    I76 @T6G_MB_LIB.T6G(SCH_1):PAGE376

SMB_RT_CPU0_P1_ROM_R_SDA @T6G_MB_LIB.T6G(SCH_1):SMB_RT_CPU0_P1_ROM_R_SDA
  R679    1      A Q_RES_0201LF-33.2,1%,1/20W,CHIP,CS03321FE09     I7 @T6G_MB_LIB.T6G(SCH_1):PAGE410
  R836    2      B Q_RES_0201LF-1K,1%,1/20W,CHIP,CS21001FE07    I22 @T6G_MB_LIB.T6G(SCH_1):PAGE377
   U48    7     D- PI3CSW12ZUAEX-PI3CSW12ZUAEX,SMLF,IC,AL3CSW12000    I76 @T6G_MB_LIB.T6G(SCH_1):PAGE376

SMB_RT_CPU0_P1_ROM_SCL @T6G_MB_LIB.T6G(SCH_1):SMB_RT_CPU0_P1_ROM_SCL
   U15    6    SCL M24M02DRMN6TP-M24M02-DRMN6TP,SMLF,IC,AKE33Z00600     I5 @T6G_MB_LIB.T6G(SCH_1):PAGE410
  R678    2      B Q_RES_0201LF-33.2,1%,1/20W,CHIP,CS03321FE09     I6 @T6G_MB_LIB.T6G(SCH_1):PAGE410

SMB_RT_CPU0_P1_ROM_SDA @T6G_MB_LIB.T6G(SCH_1):SMB_RT_CPU0_P1_ROM_SDA
   U15    5    SDA M24M02DRMN6TP-M24M02-DRMN6TP,SMLF,IC,AKE33Z00600     I5 @T6G_MB_LIB.T6G(SCH_1):PAGE410
  R679    2      B Q_RES_0201LF-33.2,1%,1/20W,CHIP,CS03321FE09     I7 @T6G_MB_LIB.T6G(SCH_1):PAGE410

SMB_RT_CPU0_P1_R_SCL @T6G_MB_LIB.T6G(SCH_1):SMB_RT_CPU0_P1_R_SCL
 R6757    2      B Q_RES_0201LF-0,5%,1/20W,CHIP,CS00001JE10    I57 @T6G_MB_LIB.T6G(SCH_1):PAGE378
 R6765    2      B Q_RES_0201LF-1K,1%,1/20W,CHIP,CS21001FE07    I80 @T6G_MB_LIB.T6G(SCH_1):PAGE378
 R1025    1      A Q_RES_0201LF-0,5%,1/20W,CHIP,CS00001JE10    I30 @T6G_MB_LIB.T6G(SCH_1):PAGE408

SMB_RT_CPU0_P1_R_SDA @T6G_MB_LIB.T6G(SCH_1):SMB_RT_CPU0_P1_R_SDA
 R6756    2      B Q_RES_0201LF-0,5%,1/20W,CHIP,CS00001JE10    I56 @T6G_MB_LIB.T6G(SCH_1):PAGE378
 R6764    2      B Q_RES_0201LF-1K,1%,1/20W,CHIP,CS21001FE07    I79 @T6G_MB_LIB.T6G(SCH_1):PAGE378
 R1026    1      A Q_RES_0201LF-0,5%,1/20W,CHIP,CS00001JE10    I29 @T6G_MB_LIB.T6G(SCH_1):PAGE408

SMB_RT_CPU0_P1_SCL @T6G_MB_LIB.T6G(SCH_1):SMB_RT_CPU0_P1_SCL
 U6020   16    SC5 TCA9548APWR-TCA9548APWR,SMLF,IC,AL009548K02     I1 @T6G_MB_LIB.T6G(SCH_1):PAGE378
 R6757    1      A Q_RES_0201LF-0,5%,1/20W,CHIP,CS00001JE10    I57 @T6G_MB_LIB.T6G(SCH_1):PAGE378

SMB_RT_CPU0_P1_SDA @T6G_MB_LIB.T6G(SCH_1):SMB_RT_CPU0_P1_SDA
 U6020   15    SD5 TCA9548APWR-TCA9548APWR,SMLF,IC,AL009548K02     I1 @T6G_MB_LIB.T6G(SCH_1):PAGE378
 R6756    1      A Q_RES_0201LF-0,5%,1/20W,CHIP,CS00001JE10    I56 @T6G_MB_LIB.T6G(SCH_1):PAGE378

SMB_RT_CPU0_P2_R2_SCL @T6G_MB_LIB.T6G(SCH_1):SMB_RT_CPU0_P2_R2_SCL
 R1067    2      B Q_RES_0201LF-0,5%,1/20W,CHIP,CS00001JE10    I29 @T6G_MB_LIB.T6G(SCH_1):PAGE419
 U6012  B31 SMBCLK PT5161LRS-PT5161LRS,SMLF,IC,AJ051610U03    I83 @T6G_MB_LIB.T6G(SCH_1):PAGE419

SMB_RT_CPU0_P2_R2_SDA @T6G_MB_LIB.T6G(SCH_1):SMB_RT_CPU0_P2_R2_SDA
 R1068    2      B Q_RES_0201LF-0,5%,1/20W,CHIP,CS00001JE10    I30 @T6G_MB_LIB.T6G(SCH_1):PAGE419
 U6012  B28 SMBDAT PT5161LRS-PT5161LRS,SMLF,IC,AJ051610U03    I83 @T6G_MB_LIB.T6G(SCH_1):PAGE419

SMB_RT_CPU0_P2_ROM_MUX_1D_R_SCL @T6G_MB_LIB.T6G(SCH_1):SMB_RT_CPU0_P2_ROM_MUX_1D_R_SCL
  R680    2      B Q_RES_0201LF-49.9,1%,1/20W,CHIP,CS04991FE06    I22 @T6G_MB_LIB.T6G(SCH_1):PAGE419
 U6012  FF5 EE_CLK PT5161LRS-PT5161LRS,SMLF,IC,AJ051610U03    I83 @T6G_MB_LIB.T6G(SCH_1):PAGE419

SMB_RT_CPU0_P2_ROM_MUX_1D_R_SDA @T6G_MB_LIB.T6G(SCH_1):SMB_RT_CPU0_P2_ROM_MUX_1D_R_SDA
  R681    2      B Q_RES_0201LF-49.9,1%,1/20W,CHIP,CS04991FE06    I21 @T6G_MB_LIB.T6G(SCH_1):PAGE419
 U6012  FJ3 EE_DAT PT5161LRS-PT5161LRS,SMLF,IC,AJ051610U03    I83 @T6G_MB_LIB.T6G(SCH_1):PAGE419

SMB_RT_CPU0_P2_ROM_MUX_1D_SCL @T6G_MB_LIB.T6G(SCH_1):SMB_RT_CPU0_P2_ROM_MUX_1D_SCL
  R680    1      A Q_RES_0201LF-49.9,1%,1/20W,CHIP,CS04991FE06    I22 @T6G_MB_LIB.T6G(SCH_1):PAGE419
   U47    1    1D+ PI3CSW12ZUAEX-PI3CSW12ZUAEX,SMLF,IC,AL3CSW12000   I121 @T6G_MB_LIB.T6G(SCH_1):PAGE376
 R1432    2      B Q_RES_0201LF-1K,1%,1/20W,CHIP,CS21001FE07   I171 @T6G_MB_LIB.T6G(SCH_1):PAGE377

SMB_RT_CPU0_P2_ROM_MUX_1D_SDA @T6G_MB_LIB.T6G(SCH_1):SMB_RT_CPU0_P2_ROM_MUX_1D_SDA
  R681    1      A Q_RES_0201LF-49.9,1%,1/20W,CHIP,CS04991FE06    I21 @T6G_MB_LIB.T6G(SCH_1):PAGE419
   U47    2    1D- PI3CSW12ZUAEX-PI3CSW12ZUAEX,SMLF,IC,AL3CSW12000   I121 @T6G_MB_LIB.T6G(SCH_1):PAGE376
 R1431    2      B Q_RES_0201LF-1K,1%,1/20W,CHIP,CS21001FE07   I170 @T6G_MB_LIB.T6G(SCH_1):PAGE377

SMB_RT_CPU0_P2_ROM_MUX_2D_R_SCL @T6G_MB_LIB.T6G(SCH_1):SMB_RT_CPU0_P2_ROM_MUX_2D_R_SCL
  R833    1      A Q_RES_0201LF-0,5%,1/20W,CHIP,CS00001JE10    I73 @T6G_MB_LIB.T6G(SCH_1):PAGE377
   U22   20    SC7 TCA9548APWR-TCA9548APWR,SMLF,IC,AL009548K02    I94 @T6G_MB_LIB.T6G(SCH_1):PAGE377
 R1383    2      B Q_RES_0201LF-4.7K,5%,1/20W,CHIP,CS24701JE04   I128 @T6G_MB_LIB.T6G(SCH_1):PAGE377

SMB_RT_CPU0_P2_ROM_MUX_2D_R_SDA @T6G_MB_LIB.T6G(SCH_1):SMB_RT_CPU0_P2_ROM_MUX_2D_R_SDA
  R832    1      A Q_RES_0201LF-0,5%,1/20W,CHIP,CS00001JE10    I75 @T6G_MB_LIB.T6G(SCH_1):PAGE377
   U22   19    SD7 TCA9548APWR-TCA9548APWR,SMLF,IC,AL009548K02    I94 @T6G_MB_LIB.T6G(SCH_1):PAGE377
 R1382    2      B Q_RES_0201LF-4.7K,5%,1/20W,CHIP,CS24701JE04   I127 @T6G_MB_LIB.T6G(SCH_1):PAGE377

SMB_RT_CPU0_P2_ROM_MUX_2D_SCL @T6G_MB_LIB.T6G(SCH_1):SMB_RT_CPU0_P2_ROM_MUX_2D_SCL
  R833    2      B Q_RES_0201LF-0,5%,1/20W,CHIP,CS00001JE10    I73 @T6G_MB_LIB.T6G(SCH_1):PAGE377
   U47    3    2D+ PI3CSW12ZUAEX-PI3CSW12ZUAEX,SMLF,IC,AL3CSW12000   I121 @T6G_MB_LIB.T6G(SCH_1):PAGE376

SMB_RT_CPU0_P2_ROM_MUX_2D_SDA @T6G_MB_LIB.T6G(SCH_1):SMB_RT_CPU0_P2_ROM_MUX_2D_SDA
  R832    2      B Q_RES_0201LF-0,5%,1/20W,CHIP,CS00001JE10    I75 @T6G_MB_LIB.T6G(SCH_1):PAGE377
   U47    4    2D- PI3CSW12ZUAEX-PI3CSW12ZUAEX,SMLF,IC,AL3CSW12000   I121 @T6G_MB_LIB.T6G(SCH_1):PAGE376

SMB_RT_CPU0_P2_ROM_R_SCL @T6G_MB_LIB.T6G(SCH_1):SMB_RT_CPU0_P2_ROM_R_SCL
  R682    1      A Q_RES_0201LF-33.2,1%,1/20W,CHIP,CS03321FE09     I3 @T6G_MB_LIB.T6G(SCH_1):PAGE421
  R841    2      B Q_RES_0201LF-1K,1%,1/20W,CHIP,CS21001FE07    I17 @T6G_MB_LIB.T6G(SCH_1):PAGE377
   U47    8     D+ PI3CSW12ZUAEX-PI3CSW12ZUAEX,SMLF,IC,AL3CSW12000   I121 @T6G_MB_LIB.T6G(SCH_1):PAGE376

SMB_RT_CPU0_P2_ROM_R_SDA @T6G_MB_LIB.T6G(SCH_1):SMB_RT_CPU0_P2_ROM_R_SDA
  R683    1      A Q_RES_0201LF-33.2,1%,1/20W,CHIP,CS03321FE09     I4 @T6G_MB_LIB.T6G(SCH_1):PAGE421
  R840    2      B Q_RES_0201LF-1K,1%,1/20W,CHIP,CS21001FE07    I18 @T6G_MB_LIB.T6G(SCH_1):PAGE377
   U47    7     D- PI3CSW12ZUAEX-PI3CSW12ZUAEX,SMLF,IC,AL3CSW12000   I121 @T6G_MB_LIB.T6G(SCH_1):PAGE376

SMB_RT_CPU0_P2_ROM_SCL @T6G_MB_LIB.T6G(SCH_1):SMB_RT_CPU0_P2_ROM_SCL
  R682    2      B Q_RES_0201LF-33.2,1%,1/20W,CHIP,CS03321FE09     I3 @T6G_MB_LIB.T6G(SCH_1):PAGE421
   U16    6    SCL M24M02DRMN6TP-M24M02-DRMN6TP,SMLF,IC,AKE33Z00600     I5 @T6G_MB_LIB.T6G(SCH_1):PAGE421

SMB_RT_CPU0_P2_ROM_SDA @T6G_MB_LIB.T6G(SCH_1):SMB_RT_CPU0_P2_ROM_SDA
  R683    2      B Q_RES_0201LF-33.2,1%,1/20W,CHIP,CS03321FE09     I4 @T6G_MB_LIB.T6G(SCH_1):PAGE421
   U16    5    SDA M24M02DRMN6TP-M24M02-DRMN6TP,SMLF,IC,AKE33Z00600     I5 @T6G_MB_LIB.T6G(SCH_1):PAGE421

SMB_RT_CPU0_P2_R_SCL @T6G_MB_LIB.T6G(SCH_1):SMB_RT_CPU0_P2_R_SCL
 R6761    2      B Q_RES_0201LF-0,5%,1/20W,CHIP,CS00001JE10    I60 @T6G_MB_LIB.T6G(SCH_1):PAGE378
 R6769    2      B Q_RES_0201LF-1K,1%,1/20W,CHIP,CS21001FE07    I85 @T6G_MB_LIB.T6G(SCH_1):PAGE378
 R1067    1      A Q_RES_0201LF-0,5%,1/20W,CHIP,CS00001JE10    I29 @T6G_MB_LIB.T6G(SCH_1):PAGE419

SMB_RT_CPU0_P2_R_SDA @T6G_MB_LIB.T6G(SCH_1):SMB_RT_CPU0_P2_R_SDA
 R6760    2      B Q_RES_0201LF-0,5%,1/20W,CHIP,CS00001JE10    I58 @T6G_MB_LIB.T6G(SCH_1):PAGE378
 R6768    2      B Q_RES_0201LF-1K,1%,1/20W,CHIP,CS21001FE07    I84 @T6G_MB_LIB.T6G(SCH_1):PAGE378
 R1068    1      A Q_RES_0201LF-0,5%,1/20W,CHIP,CS00001JE10    I30 @T6G_MB_LIB.T6G(SCH_1):PAGE419

SMB_RT_CPU0_P2_SCL @T6G_MB_LIB.T6G(SCH_1):SMB_RT_CPU0_P2_SCL
 U6020   20    SC7 TCA9548APWR-TCA9548APWR,SMLF,IC,AL009548K02     I1 @T6G_MB_LIB.T6G(SCH_1):PAGE378
 R6761    1      A Q_RES_0201LF-0,5%,1/20W,CHIP,CS00001JE10    I60 @T6G_MB_LIB.T6G(SCH_1):PAGE378

SMB_RT_CPU0_P2_SDA @T6G_MB_LIB.T6G(SCH_1):SMB_RT_CPU0_P2_SDA
 U6020   19    SD7 TCA9548APWR-TCA9548APWR,SMLF,IC,AL009548K02     I1 @T6G_MB_LIB.T6G(SCH_1):PAGE378
 R6760    1      A Q_RES_0201LF-0,5%,1/20W,CHIP,CS00001JE10    I58 @T6G_MB_LIB.T6G(SCH_1):PAGE378

SMB_RT_CPU0_P3_R2_SCL @T6G_MB_LIB.T6G(SCH_1):SMB_RT_CPU0_P3_R2_SCL
 R1109    2      B Q_RES_0201LF-0,5%,1/20W,CHIP,CS00001JE10    I32 @T6G_MB_LIB.T6G(SCH_1):PAGE430
 U6013  B31 SMBCLK PT5161LRS-PT5161LRS,SMLF,IC,AJ051610U03    I83 @T6G_MB_LIB.T6G(SCH_1):PAGE430

SMB_RT_CPU0_P3_R2_SDA @T6G_MB_LIB.T6G(SCH_1):SMB_RT_CPU0_P3_R2_SDA
 R1110    2      B Q_RES_0201LF-0,5%,1/20W,CHIP,CS00001JE10    I33 @T6G_MB_LIB.T6G(SCH_1):PAGE430
 U6013  B28 SMBDAT PT5161LRS-PT5161LRS,SMLF,IC,AJ051610U03    I83 @T6G_MB_LIB.T6G(SCH_1):PAGE430

SMB_RT_CPU0_P3_ROM_MUX_1D_R_SCL @T6G_MB_LIB.T6G(SCH_1):SMB_RT_CPU0_P3_ROM_MUX_1D_R_SCL
  R684    2      B Q_RES_0201LF-49.9,1%,1/20W,CHIP,CS04991FE06    I22 @T6G_MB_LIB.T6G(SCH_1):PAGE430
 U6013  FF5 EE_CLK PT5161LRS-PT5161LRS,SMLF,IC,AJ051610U03    I83 @T6G_MB_LIB.T6G(SCH_1):PAGE430

SMB_RT_CPU0_P3_ROM_MUX_1D_R_SDA @T6G_MB_LIB.T6G(SCH_1):SMB_RT_CPU0_P3_ROM_MUX_1D_R_SDA
  R686    2      B Q_RES_0201LF-49.9,1%,1/20W,CHIP,CS04991FE06    I21 @T6G_MB_LIB.T6G(SCH_1):PAGE430
 U6013  FJ3 EE_DAT PT5161LRS-PT5161LRS,SMLF,IC,AJ051610U03    I83 @T6G_MB_LIB.T6G(SCH_1):PAGE430

SMB_RT_CPU0_P3_ROM_MUX_1D_SCL @T6G_MB_LIB.T6G(SCH_1):SMB_RT_CPU0_P3_ROM_MUX_1D_SCL
  R684    1      A Q_RES_0201LF-49.9,1%,1/20W,CHIP,CS04991FE06    I22 @T6G_MB_LIB.T6G(SCH_1):PAGE430
   U46    1    1D+ PI3CSW12ZUAEX-PI3CSW12ZUAEX,SMLF,IC,AL3CSW12000   I108 @T6G_MB_LIB.T6G(SCH_1):PAGE376
 R1428    2      B Q_RES_0201LF-1K,1%,1/20W,CHIP,CS21001FE07   I169 @T6G_MB_LIB.T6G(SCH_1):PAGE377

SMB_RT_CPU0_P3_ROM_MUX_1D_SDA @T6G_MB_LIB.T6G(SCH_1):SMB_RT_CPU0_P3_ROM_MUX_1D_SDA
  R686    1      A Q_RES_0201LF-49.9,1%,1/20W,CHIP,CS04991FE06    I21 @T6G_MB_LIB.T6G(SCH_1):PAGE430
   U46    2    1D- PI3CSW12ZUAEX-PI3CSW12ZUAEX,SMLF,IC,AL3CSW12000   I108 @T6G_MB_LIB.T6G(SCH_1):PAGE376
 R1420    2      B Q_RES_0201LF-1K,1%,1/20W,CHIP,CS21001FE07   I168 @T6G_MB_LIB.T6G(SCH_1):PAGE377

SMB_RT_CPU0_P3_ROM_MUX_2D_R_SCL @T6G_MB_LIB.T6G(SCH_1):SMB_RT_CPU0_P3_ROM_MUX_2D_R_SCL
  R831    1      A Q_RES_0201LF-0,5%,1/20W,CHIP,CS00001JE10    I74 @T6G_MB_LIB.T6G(SCH_1):PAGE377
   U22   18    SC6 TCA9548APWR-TCA9548APWR,SMLF,IC,AL009548K02    I94 @T6G_MB_LIB.T6G(SCH_1):PAGE377
 R1379    2      B Q_RES_0201LF-4.7K,5%,1/20W,CHIP,CS24701JE04   I126 @T6G_MB_LIB.T6G(SCH_1):PAGE377

SMB_RT_CPU0_P3_ROM_MUX_2D_R_SDA @T6G_MB_LIB.T6G(SCH_1):SMB_RT_CPU0_P3_ROM_MUX_2D_R_SDA
  R830    1      A Q_RES_0201LF-0,5%,1/20W,CHIP,CS00001JE10    I78 @T6G_MB_LIB.T6G(SCH_1):PAGE377
   U22   17    SD6 TCA9548APWR-TCA9548APWR,SMLF,IC,AL009548K02    I94 @T6G_MB_LIB.T6G(SCH_1):PAGE377
 R1375    2      B Q_RES_0201LF-4.7K,5%,1/20W,CHIP,CS24701JE04   I125 @T6G_MB_LIB.T6G(SCH_1):PAGE377

SMB_RT_CPU0_P3_ROM_MUX_2D_SCL @T6G_MB_LIB.T6G(SCH_1):SMB_RT_CPU0_P3_ROM_MUX_2D_SCL
  R831    2      B Q_RES_0201LF-0,5%,1/20W,CHIP,CS00001JE10    I74 @T6G_MB_LIB.T6G(SCH_1):PAGE377
   U46    3    2D+ PI3CSW12ZUAEX-PI3CSW12ZUAEX,SMLF,IC,AL3CSW12000   I108 @T6G_MB_LIB.T6G(SCH_1):PAGE376

SMB_RT_CPU0_P3_ROM_MUX_2D_SDA @T6G_MB_LIB.T6G(SCH_1):SMB_RT_CPU0_P3_ROM_MUX_2D_SDA
  R830    2      B Q_RES_0201LF-0,5%,1/20W,CHIP,CS00001JE10    I78 @T6G_MB_LIB.T6G(SCH_1):PAGE377
   U46    4    2D- PI3CSW12ZUAEX-PI3CSW12ZUAEX,SMLF,IC,AL3CSW12000   I108 @T6G_MB_LIB.T6G(SCH_1):PAGE376

SMB_RT_CPU0_P3_ROM_R_SCL @T6G_MB_LIB.T6G(SCH_1):SMB_RT_CPU0_P3_ROM_R_SCL
  R687    1      A Q_RES_0201LF-33.2,1%,1/20W,CHIP,CS03321FE09     I3 @T6G_MB_LIB.T6G(SCH_1):PAGE432
  R839    2      B Q_RES_0201LF-1K,1%,1/20W,CHIP,CS21001FE07    I20 @T6G_MB_LIB.T6G(SCH_1):PAGE377
   U46    8     D+ PI3CSW12ZUAEX-PI3CSW12ZUAEX,SMLF,IC,AL3CSW12000   I108 @T6G_MB_LIB.T6G(SCH_1):PAGE376

SMB_RT_CPU0_P3_ROM_R_SDA @T6G_MB_LIB.T6G(SCH_1):SMB_RT_CPU0_P3_ROM_R_SDA
  R688    1      A Q_RES_0201LF-33.2,1%,1/20W,CHIP,CS03321FE09     I4 @T6G_MB_LIB.T6G(SCH_1):PAGE432
  R838    2      B Q_RES_0201LF-1K,1%,1/20W,CHIP,CS21001FE07    I19 @T6G_MB_LIB.T6G(SCH_1):PAGE377
   U46    7     D- PI3CSW12ZUAEX-PI3CSW12ZUAEX,SMLF,IC,AL3CSW12000   I108 @T6G_MB_LIB.T6G(SCH_1):PAGE376

SMB_RT_CPU0_P3_ROM_SCL @T6G_MB_LIB.T6G(SCH_1):SMB_RT_CPU0_P3_ROM_SCL
  R687    2      B Q_RES_0201LF-33.2,1%,1/20W,CHIP,CS03321FE09     I3 @T6G_MB_LIB.T6G(SCH_1):PAGE432
   U17    6    SCL M24M02DRMN6TP-M24M02-DRMN6TP,SMLF,IC,AKE33Z00600     I5 @T6G_MB_LIB.T6G(SCH_1):PAGE432

SMB_RT_CPU0_P3_ROM_SDA @T6G_MB_LIB.T6G(SCH_1):SMB_RT_CPU0_P3_ROM_SDA
  R688    2      B Q_RES_0201LF-33.2,1%,1/20W,CHIP,CS03321FE09     I4 @T6G_MB_LIB.T6G(SCH_1):PAGE432
   U17    5    SDA M24M02DRMN6TP-M24M02-DRMN6TP,SMLF,IC,AKE33Z00600     I5 @T6G_MB_LIB.T6G(SCH_1):PAGE432

SMB_RT_CPU0_P3_R_SCL @T6G_MB_LIB.T6G(SCH_1):SMB_RT_CPU0_P3_R_SCL
 R6759    2      B Q_RES_0201LF-0,5%,1/20W,CHIP,CS00001JE10    I59 @T6G_MB_LIB.T6G(SCH_1):PAGE378
 R6767    2      B Q_RES_0201LF-1K,1%,1/20W,CHIP,CS21001FE07    I82 @T6G_MB_LIB.T6G(SCH_1):PAGE378
 R1109    1      A Q_RES_0201LF-0,5%,1/20W,CHIP,CS00001JE10    I32 @T6G_MB_LIB.T6G(SCH_1):PAGE430

SMB_RT_CPU0_P3_R_SDA @T6G_MB_LIB.T6G(SCH_1):SMB_RT_CPU0_P3_R_SDA
 R6758    2      B Q_RES_0201LF-0,5%,1/20W,CHIP,CS00001JE10    I55 @T6G_MB_LIB.T6G(SCH_1):PAGE378
 R6766    2      B Q_RES_0201LF-1K,1%,1/20W,CHIP,CS21001FE07    I83 @T6G_MB_LIB.T6G(SCH_1):PAGE378
 R1110    1      A Q_RES_0201LF-0,5%,1/20W,CHIP,CS00001JE10    I33 @T6G_MB_LIB.T6G(SCH_1):PAGE430

SMB_RT_CPU0_P3_SCL @T6G_MB_LIB.T6G(SCH_1):SMB_RT_CPU0_P3_SCL
 U6020   18    SC6 TCA9548APWR-TCA9548APWR,SMLF,IC,AL009548K02     I1 @T6G_MB_LIB.T6G(SCH_1):PAGE378
 R6759    1      A Q_RES_0201LF-0,5%,1/20W,CHIP,CS00001JE10    I59 @T6G_MB_LIB.T6G(SCH_1):PAGE378

SMB_RT_CPU0_P3_SDA @T6G_MB_LIB.T6G(SCH_1):SMB_RT_CPU0_P3_SDA
 U6020   17    SD6 TCA9548APWR-TCA9548APWR,SMLF,IC,AL009548K02     I1 @T6G_MB_LIB.T6G(SCH_1):PAGE378
 R6758    1      A Q_RES_0201LF-0,5%,1/20W,CHIP,CS00001JE10    I55 @T6G_MB_LIB.T6G(SCH_1):PAGE378

SMB_RT_CPU1_P0_R2_SCL @T6G_MB_LIB.T6G(SCH_1):SMB_RT_CPU1_P0_R2_SCL
 U6014  B31 SMBCLK PT5161LRS-PT5161LRS,SMLF,IC,AJ051610U03     I1 @T6G_MB_LIB.T6G(SCH_1):PAGE401
 R6812    2      B Q_RES_0201LF-0,5%,1/20W,CHIP,CS00001JE10    I19 @T6G_MB_LIB.T6G(SCH_1):PAGE401

SMB_RT_CPU1_P0_R2_SDA @T6G_MB_LIB.T6G(SCH_1):SMB_RT_CPU1_P0_R2_SDA
 U6014  B28 SMBDAT PT5161LRS-PT5161LRS,SMLF,IC,AJ051610U03     I1 @T6G_MB_LIB.T6G(SCH_1):PAGE401
 R6813    2      B Q_RES_0201LF-0,5%,1/20W,CHIP,CS00001JE10    I20 @T6G_MB_LIB.T6G(SCH_1):PAGE401

SMB_RT_CPU1_P0_ROM_MUX_1D_R_SCL @T6G_MB_LIB.T6G(SCH_1):SMB_RT_CPU1_P0_ROM_MUX_1D_R_SCL
 U6014  FF5 EE_CLK PT5161LRS-PT5161LRS,SMLF,IC,AJ051610U03     I1 @T6G_MB_LIB.T6G(SCH_1):PAGE401
  R674    2      B Q_RES_0201LF-22,1%,1/20W,CHIP,CS02201FE11   I155 @T6G_MB_LIB.T6G(SCH_1):PAGE401

SMB_RT_CPU1_P0_ROM_MUX_1D_R_SDA @T6G_MB_LIB.T6G(SCH_1):SMB_RT_CPU1_P0_ROM_MUX_1D_R_SDA
 U6014  FJ3 EE_DAT PT5161LRS-PT5161LRS,SMLF,IC,AJ051610U03     I1 @T6G_MB_LIB.T6G(SCH_1):PAGE401
  R675    2      B Q_RES_0201LF-49.9,1%,1/20W,CHIP,CS04991FE06    I13 @T6G_MB_LIB.T6G(SCH_1):PAGE401

SMB_RT_CPU1_P0_ROM_MUX_1D_SCL @T6G_MB_LIB.T6G(SCH_1):SMB_RT_CPU1_P0_ROM_MUX_1D_SCL
   U45    1    1D+ PI3CSW12ZUAEX-PI3CSW12ZUAEX,SMLF,IC,AL3CSW12000    I22 @T6G_MB_LIB.T6G(SCH_1):PAGE376
 R1437    2      B Q_RES_0201LF-1K,1%,1/20W,CHIP,CS21001FE07   I172 @T6G_MB_LIB.T6G(SCH_1):PAGE377
  R674    1      A Q_RES_0201LF-22,1%,1/20W,CHIP,CS02201FE11   I155 @T6G_MB_LIB.T6G(SCH_1):PAGE401

SMB_RT_CPU1_P0_ROM_MUX_1D_SDA @T6G_MB_LIB.T6G(SCH_1):SMB_RT_CPU1_P0_ROM_MUX_1D_SDA
  R675    1      A Q_RES_0201LF-49.9,1%,1/20W,CHIP,CS04991FE06    I13 @T6G_MB_LIB.T6G(SCH_1):PAGE401
   U45    2    1D- PI3CSW12ZUAEX-PI3CSW12ZUAEX,SMLF,IC,AL3CSW12000    I22 @T6G_MB_LIB.T6G(SCH_1):PAGE376
 R1436    2      B Q_RES_0201LF-1K,1%,1/20W,CHIP,CS21001FE07   I173 @T6G_MB_LIB.T6G(SCH_1):PAGE377

SMB_RT_CPU1_P0_ROM_MUX_2D_R_SCL @T6G_MB_LIB.T6G(SCH_1):SMB_RT_CPU1_P0_ROM_MUX_2D_R_SCL
  R802    2      B Q_RES_0201LF-0,5%,1/20W,CHIP,CS00001JE10    I50 @T6G_MB_LIB.T6G(SCH_1):PAGE377
   U22    5    SC0 TCA9548APWR-TCA9548APWR,SMLF,IC,AL009548K02    I94 @T6G_MB_LIB.T6G(SCH_1):PAGE377
 R1390    2      B Q_RES_0201LF-4.7K,5%,1/20W,CHIP,CS24701JE04   I105 @T6G_MB_LIB.T6G(SCH_1):PAGE377

SMB_RT_CPU1_P0_ROM_MUX_2D_R_SDA @T6G_MB_LIB.T6G(SCH_1):SMB_RT_CPU1_P0_ROM_MUX_2D_R_SDA
  R801    2      B Q_RES_0201LF-0,5%,1/20W,CHIP,CS00001JE10    I49 @T6G_MB_LIB.T6G(SCH_1):PAGE377
   U22    4    SD0 TCA9548APWR-TCA9548APWR,SMLF,IC,AL009548K02    I94 @T6G_MB_LIB.T6G(SCH_1):PAGE377
 R1361    2      B Q_RES_0201LF-4.7K,5%,1/20W,CHIP,CS24701JE04   I104 @T6G_MB_LIB.T6G(SCH_1):PAGE377

SMB_RT_CPU1_P0_ROM_MUX_2D_SCL @T6G_MB_LIB.T6G(SCH_1):SMB_RT_CPU1_P0_ROM_MUX_2D_SCL
  R802    1      A Q_RES_0201LF-0,5%,1/20W,CHIP,CS00001JE10    I50 @T6G_MB_LIB.T6G(SCH_1):PAGE377
   U45    3    2D+ PI3CSW12ZUAEX-PI3CSW12ZUAEX,SMLF,IC,AL3CSW12000    I22 @T6G_MB_LIB.T6G(SCH_1):PAGE376

SMB_RT_CPU1_P0_ROM_MUX_2D_SDA @T6G_MB_LIB.T6G(SCH_1):SMB_RT_CPU1_P0_ROM_MUX_2D_SDA
  R801    1      A Q_RES_0201LF-0,5%,1/20W,CHIP,CS00001JE10    I49 @T6G_MB_LIB.T6G(SCH_1):PAGE377
   U45    4    2D- PI3CSW12ZUAEX-PI3CSW12ZUAEX,SMLF,IC,AL3CSW12000    I22 @T6G_MB_LIB.T6G(SCH_1):PAGE376

SMB_RT_CPU1_P0_ROM_R_SCL @T6G_MB_LIB.T6G(SCH_1):SMB_RT_CPU1_P0_ROM_R_SCL
  R672    1      A Q_RES_0201LF-33.2,1%,1/20W,CHIP,CS03321FE09     I3 @T6G_MB_LIB.T6G(SCH_1):PAGE399
 R6706    2      B Q_RES_0201LF-1K,1%,1/20W,CHIP,CS21001FE07    I65 @T6G_MB_LIB.T6G(SCH_1):PAGE377
   U45    8     D+ PI3CSW12ZUAEX-PI3CSW12ZUAEX,SMLF,IC,AL3CSW12000    I22 @T6G_MB_LIB.T6G(SCH_1):PAGE376

SMB_RT_CPU1_P0_ROM_R_SDA @T6G_MB_LIB.T6G(SCH_1):SMB_RT_CPU1_P0_ROM_R_SDA
  R673    1      A Q_RES_0201LF-33.2,1%,1/20W,CHIP,CS03321FE09     I4 @T6G_MB_LIB.T6G(SCH_1):PAGE399
 R6707    2      B Q_RES_0201LF-1K,1%,1/20W,CHIP,CS21001FE07    I64 @T6G_MB_LIB.T6G(SCH_1):PAGE377
   U45    7     D- PI3CSW12ZUAEX-PI3CSW12ZUAEX,SMLF,IC,AL3CSW12000    I22 @T6G_MB_LIB.T6G(SCH_1):PAGE376

SMB_RT_CPU1_P0_ROM_SCL @T6G_MB_LIB.T6G(SCH_1):SMB_RT_CPU1_P0_ROM_SCL
  R672    2      B Q_RES_0201LF-33.2,1%,1/20W,CHIP,CS03321FE09     I3 @T6G_MB_LIB.T6G(SCH_1):PAGE399
   U12    6    SCL M24M02DRMN6TP-M24M02-DRMN6TP,SMLF,IC,AKE33Z00600     I5 @T6G_MB_LIB.T6G(SCH_1):PAGE399

SMB_RT_CPU1_P0_ROM_SDA @T6G_MB_LIB.T6G(SCH_1):SMB_RT_CPU1_P0_ROM_SDA
  R673    2      B Q_RES_0201LF-33.2,1%,1/20W,CHIP,CS03321FE09     I4 @T6G_MB_LIB.T6G(SCH_1):PAGE399
   U12    5    SDA M24M02DRMN6TP-M24M02-DRMN6TP,SMLF,IC,AKE33Z00600     I5 @T6G_MB_LIB.T6G(SCH_1):PAGE399

SMB_RT_CPU1_P0_R_SCL @T6G_MB_LIB.T6G(SCH_1):SMB_RT_CPU1_P0_R_SCL
 R6812    1      A Q_RES_0201LF-0,5%,1/20W,CHIP,CS00001JE10    I19 @T6G_MB_LIB.T6G(SCH_1):PAGE401
 R6811    1      A Q_RES_0201LF-0,5%,1/20W,CHIP,CS00001JE10     I7 @T6G_MB_LIB.T6G(SCH_1):PAGE378
 R6719    2      B Q_RES_0201LF-1K,1%,1/20W,CHIP,CS21001FE07    I11 @T6G_MB_LIB.T6G(SCH_1):PAGE378

SMB_RT_CPU1_P0_R_SDA @T6G_MB_LIB.T6G(SCH_1):SMB_RT_CPU1_P0_R_SDA
 R6813    1      A Q_RES_0201LF-0,5%,1/20W,CHIP,CS00001JE10    I20 @T6G_MB_LIB.T6G(SCH_1):PAGE401
 R6810    1      A Q_RES_0201LF-0,5%,1/20W,CHIP,CS00001JE10     I6 @T6G_MB_LIB.T6G(SCH_1):PAGE378
 R6718    2      B Q_RES_0201LF-1K,1%,1/20W,CHIP,CS21001FE07     I9 @T6G_MB_LIB.T6G(SCH_1):PAGE378

SMB_RT_CPU1_P0_SCL @T6G_MB_LIB.T6G(SCH_1):SMB_RT_CPU1_P0_SCL
 U6020    5    SC0 TCA9548APWR-TCA9548APWR,SMLF,IC,AL009548K02     I1 @T6G_MB_LIB.T6G(SCH_1):PAGE378
 R6811    2      B Q_RES_0201LF-0,5%,1/20W,CHIP,CS00001JE10     I7 @T6G_MB_LIB.T6G(SCH_1):PAGE378

SMB_RT_CPU1_P0_SDA @T6G_MB_LIB.T6G(SCH_1):SMB_RT_CPU1_P0_SDA
 U6020    4    SD0 TCA9548APWR-TCA9548APWR,SMLF,IC,AL009548K02     I1 @T6G_MB_LIB.T6G(SCH_1):PAGE378
 R6810    2      B Q_RES_0201LF-0,5%,1/20W,CHIP,CS00001JE10     I6 @T6G_MB_LIB.T6G(SCH_1):PAGE378

SMB_RT_CPU1_P1_R2_SCL @T6G_MB_LIB.T6G(SCH_1):SMB_RT_CPU1_P1_R2_SCL
  R779    2      B Q_RES_0201LF-0,5%,1/20W,CHIP,CS00001JE10    I44 @T6G_MB_LIB.T6G(SCH_1):PAGE392
 U6015  B31 SMBCLK PT5161LRS-PT5161LRS,SMLF,IC,AJ051610U03    I47 @T6G_MB_LIB.T6G(SCH_1):PAGE392

SMB_RT_CPU1_P1_R2_SDA @T6G_MB_LIB.T6G(SCH_1):SMB_RT_CPU1_P1_R2_SDA
  R780    2      B Q_RES_0201LF-0,5%,1/20W,CHIP,CS00001JE10    I43 @T6G_MB_LIB.T6G(SCH_1):PAGE392
 U6015  B28 SMBDAT PT5161LRS-PT5161LRS,SMLF,IC,AJ051610U03    I47 @T6G_MB_LIB.T6G(SCH_1):PAGE392

SMB_RT_CPU1_P1_ROM_MUX_1D_R_SCL @T6G_MB_LIB.T6G(SCH_1):SMB_RT_CPU1_P1_ROM_MUX_1D_R_SCL
  R670    2      B Q_RES_0201LF-49.9,1%,1/20W,CHIP,CS04991FE06    I36 @T6G_MB_LIB.T6G(SCH_1):PAGE392
 U6015  FF5 EE_CLK PT5161LRS-PT5161LRS,SMLF,IC,AJ051610U03    I47 @T6G_MB_LIB.T6G(SCH_1):PAGE392

SMB_RT_CPU1_P1_ROM_MUX_1D_R_SDA @T6G_MB_LIB.T6G(SCH_1):SMB_RT_CPU1_P1_ROM_MUX_1D_R_SDA
  R671    2      B Q_RES_0201LF-49.9,1%,1/20W,CHIP,CS04991FE06    I35 @T6G_MB_LIB.T6G(SCH_1):PAGE392
 U6015  FJ3 EE_DAT PT5161LRS-PT5161LRS,SMLF,IC,AJ051610U03    I47 @T6G_MB_LIB.T6G(SCH_1):PAGE392

SMB_RT_CPU1_P1_ROM_MUX_1D_SCL @T6G_MB_LIB.T6G(SCH_1):SMB_RT_CPU1_P1_ROM_MUX_1D_SCL
  R670    1      A Q_RES_0201LF-49.9,1%,1/20W,CHIP,CS04991FE06    I36 @T6G_MB_LIB.T6G(SCH_1):PAGE392
   U42    1    1D+ PI3CSW12ZUAEX-PI3CSW12ZUAEX,SMLF,IC,AL3CSW12000    I31 @T6G_MB_LIB.T6G(SCH_1):PAGE376
 R1451    2      B Q_RES_0201LF-1K,1%,1/20W,CHIP,CS21001FE07   I175 @T6G_MB_LIB.T6G(SCH_1):PAGE377

SMB_RT_CPU1_P1_ROM_MUX_1D_SDA @T6G_MB_LIB.T6G(SCH_1):SMB_RT_CPU1_P1_ROM_MUX_1D_SDA
  R671    1      A Q_RES_0201LF-49.9,1%,1/20W,CHIP,CS04991FE06    I35 @T6G_MB_LIB.T6G(SCH_1):PAGE392
   U42    2    1D- PI3CSW12ZUAEX-PI3CSW12ZUAEX,SMLF,IC,AL3CSW12000    I31 @T6G_MB_LIB.T6G(SCH_1):PAGE376
 R1448    2      B Q_RES_0201LF-1K,1%,1/20W,CHIP,CS21001FE07   I174 @T6G_MB_LIB.T6G(SCH_1):PAGE377

SMB_RT_CPU1_P1_ROM_MUX_2D_R_SCL @T6G_MB_LIB.T6G(SCH_1):SMB_RT_CPU1_P1_ROM_MUX_2D_R_SCL
  R805    2      B Q_RES_0201LF-0,5%,1/20W,CHIP,CS00001JE10    I46 @T6G_MB_LIB.T6G(SCH_1):PAGE377
   U22    7    SC1 TCA9548APWR-TCA9548APWR,SMLF,IC,AL009548K02    I94 @T6G_MB_LIB.T6G(SCH_1):PAGE377
 R1394    2      B Q_RES_0201LF-4.7K,5%,1/20W,CHIP,CS24701JE04   I107 @T6G_MB_LIB.T6G(SCH_1):PAGE377

SMB_RT_CPU1_P1_ROM_MUX_2D_R_SDA @T6G_MB_LIB.T6G(SCH_1):SMB_RT_CPU1_P1_ROM_MUX_2D_R_SDA
  R803    2      B Q_RES_0201LF-0,5%,1/20W,CHIP,CS00001JE10    I48 @T6G_MB_LIB.T6G(SCH_1):PAGE377
   U22    6    SD1 TCA9548APWR-TCA9548APWR,SMLF,IC,AL009548K02    I94 @T6G_MB_LIB.T6G(SCH_1):PAGE377
 R1393    2      B Q_RES_0201LF-4.7K,5%,1/20W,CHIP,CS24701JE04   I106 @T6G_MB_LIB.T6G(SCH_1):PAGE377

SMB_RT_CPU1_P1_ROM_MUX_2D_SCL @T6G_MB_LIB.T6G(SCH_1):SMB_RT_CPU1_P1_ROM_MUX_2D_SCL
  R805    1      A Q_RES_0201LF-0,5%,1/20W,CHIP,CS00001JE10    I46 @T6G_MB_LIB.T6G(SCH_1):PAGE377
   U42    3    2D+ PI3CSW12ZUAEX-PI3CSW12ZUAEX,SMLF,IC,AL3CSW12000    I31 @T6G_MB_LIB.T6G(SCH_1):PAGE376

SMB_RT_CPU1_P1_ROM_MUX_2D_SDA @T6G_MB_LIB.T6G(SCH_1):SMB_RT_CPU1_P1_ROM_MUX_2D_SDA
  R803    1      A Q_RES_0201LF-0,5%,1/20W,CHIP,CS00001JE10    I48 @T6G_MB_LIB.T6G(SCH_1):PAGE377
   U42    4    2D- PI3CSW12ZUAEX-PI3CSW12ZUAEX,SMLF,IC,AL3CSW12000    I31 @T6G_MB_LIB.T6G(SCH_1):PAGE376

SMB_RT_CPU1_P1_ROM_R_SCL @T6G_MB_LIB.T6G(SCH_1):SMB_RT_CPU1_P1_ROM_R_SCL
  R689    1      A Q_RES_0201LF-33.2,1%,1/20W,CHIP,CS03321FE09     I4 @T6G_MB_LIB.T6G(SCH_1):PAGE442
 R6734    2      B Q_RES_0201LF-1K,1%,1/20W,CHIP,CS21001FE07    I62 @T6G_MB_LIB.T6G(SCH_1):PAGE377
   U42    8     D+ PI3CSW12ZUAEX-PI3CSW12ZUAEX,SMLF,IC,AL3CSW12000    I31 @T6G_MB_LIB.T6G(SCH_1):PAGE376

SMB_RT_CPU1_P1_ROM_R_SDA @T6G_MB_LIB.T6G(SCH_1):SMB_RT_CPU1_P1_ROM_R_SDA
  R690    1      A Q_RES_0201LF-33.2,1%,1/20W,CHIP,CS03321FE09     I3 @T6G_MB_LIB.T6G(SCH_1):PAGE442
 R6735    2      B Q_RES_0201LF-1K,1%,1/20W,CHIP,CS21001FE07    I63 @T6G_MB_LIB.T6G(SCH_1):PAGE377
   U42    7     D- PI3CSW12ZUAEX-PI3CSW12ZUAEX,SMLF,IC,AL3CSW12000    I31 @T6G_MB_LIB.T6G(SCH_1):PAGE376

SMB_RT_CPU1_P1_ROM_SCL @T6G_MB_LIB.T6G(SCH_1):SMB_RT_CPU1_P1_ROM_SCL
  R689    2      B Q_RES_0201LF-33.2,1%,1/20W,CHIP,CS03321FE09     I4 @T6G_MB_LIB.T6G(SCH_1):PAGE442
   U19    6    SCL M24M02DRMN6TP-M24M02-DRMN6TP,SMLF,IC,AKE33Z00600     I5 @T6G_MB_LIB.T6G(SCH_1):PAGE442

SMB_RT_CPU1_P1_ROM_SDA @T6G_MB_LIB.T6G(SCH_1):SMB_RT_CPU1_P1_ROM_SDA
  R690    2      B Q_RES_0201LF-33.2,1%,1/20W,CHIP,CS03321FE09     I3 @T6G_MB_LIB.T6G(SCH_1):PAGE442
   U19    5    SDA M24M02DRMN6TP-M24M02-DRMN6TP,SMLF,IC,AKE33Z00600     I5 @T6G_MB_LIB.T6G(SCH_1):PAGE442

SMB_RT_CPU1_P1_R_SCL @T6G_MB_LIB.T6G(SCH_1):SMB_RT_CPU1_P1_R_SCL
  R779    1      A Q_RES_0201LF-0,5%,1/20W,CHIP,CS00001JE10    I44 @T6G_MB_LIB.T6G(SCH_1):PAGE392
 R6737    1      A Q_RES_0201LF-0,5%,1/20W,CHIP,CS00001JE10    I14 @T6G_MB_LIB.T6G(SCH_1):PAGE378
 R6739    2      B Q_RES_0201LF-1K,1%,1/20W,CHIP,CS21001FE07    I18 @T6G_MB_LIB.T6G(SCH_1):PAGE378

SMB_RT_CPU1_P1_R_SDA @T6G_MB_LIB.T6G(SCH_1):SMB_RT_CPU1_P1_R_SDA
  R780    1      A Q_RES_0201LF-0,5%,1/20W,CHIP,CS00001JE10    I43 @T6G_MB_LIB.T6G(SCH_1):PAGE392
 R6736    1      A Q_RES_0201LF-0,5%,1/20W,CHIP,CS00001JE10    I13 @T6G_MB_LIB.T6G(SCH_1):PAGE378
 R6738    2      B Q_RES_0201LF-1K,1%,1/20W,CHIP,CS21001FE07    I17 @T6G_MB_LIB.T6G(SCH_1):PAGE378

SMB_RT_CPU1_P1_SCL @T6G_MB_LIB.T6G(SCH_1):SMB_RT_CPU1_P1_SCL
 U6020    7    SC1 TCA9548APWR-TCA9548APWR,SMLF,IC,AL009548K02     I1 @T6G_MB_LIB.T6G(SCH_1):PAGE378
 R6737    2      B Q_RES_0201LF-0,5%,1/20W,CHIP,CS00001JE10    I14 @T6G_MB_LIB.T6G(SCH_1):PAGE378

SMB_RT_CPU1_P1_SDA @T6G_MB_LIB.T6G(SCH_1):SMB_RT_CPU1_P1_SDA
 U6020    6    SD1 TCA9548APWR-TCA9548APWR,SMLF,IC,AL009548K02     I1 @T6G_MB_LIB.T6G(SCH_1):PAGE378
 R6736    2      B Q_RES_0201LF-0,5%,1/20W,CHIP,CS00001JE10    I13 @T6G_MB_LIB.T6G(SCH_1):PAGE378

SMB_RT_CPU1_P2_R2_SCL @T6G_MB_LIB.T6G(SCH_1):SMB_RT_CPU1_P2_R2_SCL
  R872    2      B Q_RES_0201LF-0,5%,1/20W,CHIP,CS00001JE10    I34 @T6G_MB_LIB.T6G(SCH_1):PAGE451
 U6016  B31 SMBCLK PT5161LRS-PT5161LRS,SMLF,IC,AJ051610U03    I97 @T6G_MB_LIB.T6G(SCH_1):PAGE451

SMB_RT_CPU1_P2_R2_SDA @T6G_MB_LIB.T6G(SCH_1):SMB_RT_CPU1_P2_R2_SDA
  R873    2      B Q_RES_0201LF-0,5%,1/20W,CHIP,CS00001JE10    I35 @T6G_MB_LIB.T6G(SCH_1):PAGE451
 U6016  B28 SMBDAT PT5161LRS-PT5161LRS,SMLF,IC,AJ051610U03    I97 @T6G_MB_LIB.T6G(SCH_1):PAGE451

SMB_RT_CPU1_P2_ROM_MUX_1D_R_SCL @T6G_MB_LIB.T6G(SCH_1):SMB_RT_CPU1_P2_ROM_MUX_1D_R_SCL
  R691    2      B Q_RES_0201LF-49.9,1%,1/20W,CHIP,CS04991FE06    I30 @T6G_MB_LIB.T6G(SCH_1):PAGE451
 U6016  FF5 EE_CLK PT5161LRS-PT5161LRS,SMLF,IC,AJ051610U03    I97 @T6G_MB_LIB.T6G(SCH_1):PAGE451

SMB_RT_CPU1_P2_ROM_MUX_1D_R_SDA @T6G_MB_LIB.T6G(SCH_1):SMB_RT_CPU1_P2_ROM_MUX_1D_R_SDA
  R692    2      B Q_RES_0201LF-49.9,1%,1/20W,CHIP,CS04991FE06    I29 @T6G_MB_LIB.T6G(SCH_1):PAGE451
 U6016  FJ3 EE_DAT PT5161LRS-PT5161LRS,SMLF,IC,AJ051610U03    I97 @T6G_MB_LIB.T6G(SCH_1):PAGE451

SMB_RT_CPU1_P2_ROM_MUX_1D_SCL @T6G_MB_LIB.T6G(SCH_1):SMB_RT_CPU1_P2_ROM_MUX_1D_SCL
  R691    1      A Q_RES_0201LF-49.9,1%,1/20W,CHIP,CS04991FE06    I30 @T6G_MB_LIB.T6G(SCH_1):PAGE451
   U43    1    1D+ PI3CSW12ZUAEX-PI3CSW12ZUAEX,SMLF,IC,AL3CSW12000    I61 @T6G_MB_LIB.T6G(SCH_1):PAGE376
 R1469    2      B Q_RES_0201LF-1K,1%,1/20W,CHIP,CS21001FE07   I179 @T6G_MB_LIB.T6G(SCH_1):PAGE377

SMB_RT_CPU1_P2_ROM_MUX_1D_SDA @T6G_MB_LIB.T6G(SCH_1):SMB_RT_CPU1_P2_ROM_MUX_1D_SDA
  R692    1      A Q_RES_0201LF-49.9,1%,1/20W,CHIP,CS04991FE06    I29 @T6G_MB_LIB.T6G(SCH_1):PAGE451
   U43    2    1D- PI3CSW12ZUAEX-PI3CSW12ZUAEX,SMLF,IC,AL3CSW12000    I61 @T6G_MB_LIB.T6G(SCH_1):PAGE376
 R1468    2      B Q_RES_0201LF-1K,1%,1/20W,CHIP,CS21001FE07   I178 @T6G_MB_LIB.T6G(SCH_1):PAGE377

SMB_RT_CPU1_P2_ROM_MUX_2D_R_SCL @T6G_MB_LIB.T6G(SCH_1):SMB_RT_CPU1_P2_ROM_MUX_2D_R_SCL
  R809    2      B Q_RES_0201LF-0,5%,1/20W,CHIP,CS00001JE10    I44 @T6G_MB_LIB.T6G(SCH_1):PAGE377
   U22   11    SC3 TCA9548APWR-TCA9548APWR,SMLF,IC,AL009548K02    I94 @T6G_MB_LIB.T6G(SCH_1):PAGE377
 R1407    2      B Q_RES_0201LF-4.7K,5%,1/20W,CHIP,CS24701JE04   I111 @T6G_MB_LIB.T6G(SCH_1):PAGE377

SMB_RT_CPU1_P2_ROM_MUX_2D_R_SDA @T6G_MB_LIB.T6G(SCH_1):SMB_RT_CPU1_P2_ROM_MUX_2D_R_SDA
  R808    2      B Q_RES_0201LF-0,5%,1/20W,CHIP,CS00001JE10    I45 @T6G_MB_LIB.T6G(SCH_1):PAGE377
   U22   10    SD3 TCA9548APWR-TCA9548APWR,SMLF,IC,AL009548K02    I94 @T6G_MB_LIB.T6G(SCH_1):PAGE377
 R1403    2      B Q_RES_0201LF-4.7K,5%,1/20W,CHIP,CS24701JE04   I110 @T6G_MB_LIB.T6G(SCH_1):PAGE377

SMB_RT_CPU1_P2_ROM_MUX_2D_SCL @T6G_MB_LIB.T6G(SCH_1):SMB_RT_CPU1_P2_ROM_MUX_2D_SCL
  R809    1      A Q_RES_0201LF-0,5%,1/20W,CHIP,CS00001JE10    I44 @T6G_MB_LIB.T6G(SCH_1):PAGE377
   U43    3    2D+ PI3CSW12ZUAEX-PI3CSW12ZUAEX,SMLF,IC,AL3CSW12000    I61 @T6G_MB_LIB.T6G(SCH_1):PAGE376

SMB_RT_CPU1_P2_ROM_MUX_2D_SDA @T6G_MB_LIB.T6G(SCH_1):SMB_RT_CPU1_P2_ROM_MUX_2D_SDA
  R808    1      A Q_RES_0201LF-0,5%,1/20W,CHIP,CS00001JE10    I45 @T6G_MB_LIB.T6G(SCH_1):PAGE377
   U43    4    2D- PI3CSW12ZUAEX-PI3CSW12ZUAEX,SMLF,IC,AL3CSW12000    I61 @T6G_MB_LIB.T6G(SCH_1):PAGE376

SMB_RT_CPU1_P2_ROM_R_SCL @T6G_MB_LIB.T6G(SCH_1):SMB_RT_CPU1_P2_ROM_R_SCL
  R693    1      A Q_RES_0201LF-33.2,1%,1/20W,CHIP,CS03321FE09     I4 @T6G_MB_LIB.T6G(SCH_1):PAGE453
  R827    2      B Q_RES_0201LF-1K,1%,1/20W,CHIP,CS21001FE07    I58 @T6G_MB_LIB.T6G(SCH_1):PAGE377
   U43    8     D+ PI3CSW12ZUAEX-PI3CSW12ZUAEX,SMLF,IC,AL3CSW12000    I61 @T6G_MB_LIB.T6G(SCH_1):PAGE376

SMB_RT_CPU1_P2_ROM_R_SDA @T6G_MB_LIB.T6G(SCH_1):SMB_RT_CPU1_P2_ROM_R_SDA
  R694    1      A Q_RES_0201LF-33.2,1%,1/20W,CHIP,CS03321FE09     I3 @T6G_MB_LIB.T6G(SCH_1):PAGE453
  R826    2      B Q_RES_0201LF-1K,1%,1/20W,CHIP,CS21001FE07    I59 @T6G_MB_LIB.T6G(SCH_1):PAGE377
   U43    7     D- PI3CSW12ZUAEX-PI3CSW12ZUAEX,SMLF,IC,AL3CSW12000    I61 @T6G_MB_LIB.T6G(SCH_1):PAGE376

SMB_RT_CPU1_P2_ROM_SCL @T6G_MB_LIB.T6G(SCH_1):SMB_RT_CPU1_P2_ROM_SCL
  R693    2      B Q_RES_0201LF-33.2,1%,1/20W,CHIP,CS03321FE09     I4 @T6G_MB_LIB.T6G(SCH_1):PAGE453
   U20    6    SCL M24M02DRMN6TP-M24M02-DRMN6TP,SMLF,IC,AKE33Z00600     I5 @T6G_MB_LIB.T6G(SCH_1):PAGE453

SMB_RT_CPU1_P2_ROM_SDA @T6G_MB_LIB.T6G(SCH_1):SMB_RT_CPU1_P2_ROM_SDA
  R694    2      B Q_RES_0201LF-33.2,1%,1/20W,CHIP,CS03321FE09     I3 @T6G_MB_LIB.T6G(SCH_1):PAGE453
   U20    5    SDA M24M02DRMN6TP-M24M02-DRMN6TP,SMLF,IC,AKE33Z00600     I5 @T6G_MB_LIB.T6G(SCH_1):PAGE453

SMB_RT_CPU1_P2_R_SCL @T6G_MB_LIB.T6G(SCH_1):SMB_RT_CPU1_P2_R_SCL
 R6749    1      A Q_RES_0201LF-0,5%,1/20W,CHIP,CS00001JE10    I25 @T6G_MB_LIB.T6G(SCH_1):PAGE378
 R6753    2      B Q_RES_0201LF-1K,1%,1/20W,CHIP,CS21001FE07    I36 @T6G_MB_LIB.T6G(SCH_1):PAGE378
  R872    1      A Q_RES_0201LF-0,5%,1/20W,CHIP,CS00001JE10    I34 @T6G_MB_LIB.T6G(SCH_1):PAGE451

SMB_RT_CPU1_P2_R_SDA @T6G_MB_LIB.T6G(SCH_1):SMB_RT_CPU1_P2_R_SDA
 R6748    1      A Q_RES_0201LF-0,5%,1/20W,CHIP,CS00001JE10    I26 @T6G_MB_LIB.T6G(SCH_1):PAGE378
 R6752    2      B Q_RES_0201LF-1K,1%,1/20W,CHIP,CS21001FE07    I35 @T6G_MB_LIB.T6G(SCH_1):PAGE378
  R873    1      A Q_RES_0201LF-0,5%,1/20W,CHIP,CS00001JE10    I35 @T6G_MB_LIB.T6G(SCH_1):PAGE451

SMB_RT_CPU1_P2_SCL @T6G_MB_LIB.T6G(SCH_1):SMB_RT_CPU1_P2_SCL
 U6020   11    SC3 TCA9548APWR-TCA9548APWR,SMLF,IC,AL009548K02     I1 @T6G_MB_LIB.T6G(SCH_1):PAGE378
 R6749    2      B Q_RES_0201LF-0,5%,1/20W,CHIP,CS00001JE10    I25 @T6G_MB_LIB.T6G(SCH_1):PAGE378

SMB_RT_CPU1_P2_SDA @T6G_MB_LIB.T6G(SCH_1):SMB_RT_CPU1_P2_SDA
 U6020   10    SD3 TCA9548APWR-TCA9548APWR,SMLF,IC,AL009548K02     I1 @T6G_MB_LIB.T6G(SCH_1):PAGE378
 R6748    2      B Q_RES_0201LF-0,5%,1/20W,CHIP,CS00001JE10    I26 @T6G_MB_LIB.T6G(SCH_1):PAGE378

SMB_RT_CPU1_P3_R2_SCL @T6G_MB_LIB.T6G(SCH_1):SMB_RT_CPU1_P3_R2_SCL
  R913    2      B Q_RES_0201LF-0,5%,1/20W,CHIP,CS00001JE10    I42 @T6G_MB_LIB.T6G(SCH_1):PAGE462
 U6017  B31 SMBCLK PT5161LRS-PT5161LRS,SMLF,IC,AJ051610U03    I97 @T6G_MB_LIB.T6G(SCH_1):PAGE462

SMB_RT_CPU1_P3_R2_SDA @T6G_MB_LIB.T6G(SCH_1):SMB_RT_CPU1_P3_R2_SDA
  R914    2      B Q_RES_0201LF-0,5%,1/20W,CHIP,CS00001JE10    I41 @T6G_MB_LIB.T6G(SCH_1):PAGE462
 U6017  B28 SMBDAT PT5161LRS-PT5161LRS,SMLF,IC,AJ051610U03    I97 @T6G_MB_LIB.T6G(SCH_1):PAGE462

SMB_RT_CPU1_P3_ROM_MUX_1D_R_SCL @T6G_MB_LIB.T6G(SCH_1):SMB_RT_CPU1_P3_ROM_MUX_1D_R_SCL
 U6017  FF5 EE_CLK PT5161LRS-PT5161LRS,SMLF,IC,AJ051610U03    I97 @T6G_MB_LIB.T6G(SCH_1):PAGE462
  R695    2      B Q_RES_0201LF-22,1%,1/20W,CHIP,CS02201FE11   I146 @T6G_MB_LIB.T6G(SCH_1):PAGE462

SMB_RT_CPU1_P3_ROM_MUX_1D_R_SDA @T6G_MB_LIB.T6G(SCH_1):SMB_RT_CPU1_P3_ROM_MUX_1D_R_SDA
  R696    2      B Q_RES_0201LF-49.9,1%,1/20W,CHIP,CS04991FE06    I33 @T6G_MB_LIB.T6G(SCH_1):PAGE462
 U6017  FJ3 EE_DAT PT5161LRS-PT5161LRS,SMLF,IC,AJ051610U03    I97 @T6G_MB_LIB.T6G(SCH_1):PAGE462

SMB_RT_CPU1_P3_ROM_MUX_1D_SCL @T6G_MB_LIB.T6G(SCH_1):SMB_RT_CPU1_P3_ROM_MUX_1D_SCL
   U41    1    1D+ PI3CSW12ZUAEX-PI3CSW12ZUAEX,SMLF,IC,AL3CSW12000    I46 @T6G_MB_LIB.T6G(SCH_1):PAGE376
 R1463    2      B Q_RES_0201LF-1K,1%,1/20W,CHIP,CS21001FE07   I177 @T6G_MB_LIB.T6G(SCH_1):PAGE377
  R695    1      A Q_RES_0201LF-22,1%,1/20W,CHIP,CS02201FE11   I146 @T6G_MB_LIB.T6G(SCH_1):PAGE462

SMB_RT_CPU1_P3_ROM_MUX_1D_SDA @T6G_MB_LIB.T6G(SCH_1):SMB_RT_CPU1_P3_ROM_MUX_1D_SDA
  R696    1      A Q_RES_0201LF-49.9,1%,1/20W,CHIP,CS04991FE06    I33 @T6G_MB_LIB.T6G(SCH_1):PAGE462
   U41    2    1D- PI3CSW12ZUAEX-PI3CSW12ZUAEX,SMLF,IC,AL3CSW12000    I46 @T6G_MB_LIB.T6G(SCH_1):PAGE376
 R1462    2      B Q_RES_0201LF-1K,1%,1/20W,CHIP,CS21001FE07   I176 @T6G_MB_LIB.T6G(SCH_1):PAGE377

SMB_RT_CPU1_P3_ROM_MUX_2D_R_SCL @T6G_MB_LIB.T6G(SCH_1):SMB_RT_CPU1_P3_ROM_MUX_2D_R_SCL
  R807    2      B Q_RES_0201LF-0,5%,1/20W,CHIP,CS00001JE10    I43 @T6G_MB_LIB.T6G(SCH_1):PAGE377
   U22    9    SC2 TCA9548APWR-TCA9548APWR,SMLF,IC,AL009548K02    I94 @T6G_MB_LIB.T6G(SCH_1):PAGE377
 R1402    2      B Q_RES_0201LF-4.7K,5%,1/20W,CHIP,CS24701JE04   I109 @T6G_MB_LIB.T6G(SCH_1):PAGE377

SMB_RT_CPU1_P3_ROM_MUX_2D_R_SDA @T6G_MB_LIB.T6G(SCH_1):SMB_RT_CPU1_P3_ROM_MUX_2D_R_SDA
  R806    2      B Q_RES_0201LF-0,5%,1/20W,CHIP,CS00001JE10    I47 @T6G_MB_LIB.T6G(SCH_1):PAGE377
   U22    8    SD2 TCA9548APWR-TCA9548APWR,SMLF,IC,AL009548K02    I94 @T6G_MB_LIB.T6G(SCH_1):PAGE377
 R1399    2      B Q_RES_0201LF-4.7K,5%,1/20W,CHIP,CS24701JE04   I108 @T6G_MB_LIB.T6G(SCH_1):PAGE377

SMB_RT_CPU1_P3_ROM_MUX_2D_SCL @T6G_MB_LIB.T6G(SCH_1):SMB_RT_CPU1_P3_ROM_MUX_2D_SCL
  R807    1      A Q_RES_0201LF-0,5%,1/20W,CHIP,CS00001JE10    I43 @T6G_MB_LIB.T6G(SCH_1):PAGE377
   U41    3    2D+ PI3CSW12ZUAEX-PI3CSW12ZUAEX,SMLF,IC,AL3CSW12000    I46 @T6G_MB_LIB.T6G(SCH_1):PAGE376

SMB_RT_CPU1_P3_ROM_MUX_2D_SDA @T6G_MB_LIB.T6G(SCH_1):SMB_RT_CPU1_P3_ROM_MUX_2D_SDA
  R806    1      A Q_RES_0201LF-0,5%,1/20W,CHIP,CS00001JE10    I47 @T6G_MB_LIB.T6G(SCH_1):PAGE377
   U41    4    2D- PI3CSW12ZUAEX-PI3CSW12ZUAEX,SMLF,IC,AL3CSW12000    I46 @T6G_MB_LIB.T6G(SCH_1):PAGE376

SMB_RT_CPU1_P3_ROM_R_SCL @T6G_MB_LIB.T6G(SCH_1):SMB_RT_CPU1_P3_ROM_R_SCL
  R812    2      B Q_RES_0201LF-1K,1%,1/20W,CHIP,CS21001FE07    I60 @T6G_MB_LIB.T6G(SCH_1):PAGE377
   U41    8     D+ PI3CSW12ZUAEX-PI3CSW12ZUAEX,SMLF,IC,AL3CSW12000    I46 @T6G_MB_LIB.T6G(SCH_1):PAGE376
  R697    1      A Q_RES_0201LF-0,5%,1/20W,CHIP,CS00001JE10    I25 @T6G_MB_LIB.T6G(SCH_1):PAGE464

SMB_RT_CPU1_P3_ROM_R_SDA @T6G_MB_LIB.T6G(SCH_1):SMB_RT_CPU1_P3_ROM_R_SDA
  R698    1      A Q_RES_0201LF-33.2,1%,1/20W,CHIP,CS03321FE09     I4 @T6G_MB_LIB.T6G(SCH_1):PAGE464
  R810    2      B Q_RES_0201LF-1K,1%,1/20W,CHIP,CS21001FE07    I61 @T6G_MB_LIB.T6G(SCH_1):PAGE377
   U41    7     D- PI3CSW12ZUAEX-PI3CSW12ZUAEX,SMLF,IC,AL3CSW12000    I46 @T6G_MB_LIB.T6G(SCH_1):PAGE376

SMB_RT_CPU1_P3_ROM_SCL @T6G_MB_LIB.T6G(SCH_1):SMB_RT_CPU1_P3_ROM_SCL
   U21    6    SCL M24M02DRMN6TP-M24M02-DRMN6TP,SMLF,IC,AKE33Z00600     I5 @T6G_MB_LIB.T6G(SCH_1):PAGE464
  R697    2      B Q_RES_0201LF-0,5%,1/20W,CHIP,CS00001JE10    I25 @T6G_MB_LIB.T6G(SCH_1):PAGE464

SMB_RT_CPU1_P3_ROM_SDA @T6G_MB_LIB.T6G(SCH_1):SMB_RT_CPU1_P3_ROM_SDA
  R698    2      B Q_RES_0201LF-33.2,1%,1/20W,CHIP,CS03321FE09     I4 @T6G_MB_LIB.T6G(SCH_1):PAGE464
   U21    5    SDA M24M02DRMN6TP-M24M02-DRMN6TP,SMLF,IC,AKE33Z00600     I5 @T6G_MB_LIB.T6G(SCH_1):PAGE464

SMB_RT_CPU1_P3_R_SCL @T6G_MB_LIB.T6G(SCH_1):SMB_RT_CPU1_P3_R_SCL
 R6747    1      A Q_RES_0201LF-0,5%,1/20W,CHIP,CS00001JE10    I21 @T6G_MB_LIB.T6G(SCH_1):PAGE378
 R6751    2      B Q_RES_0201LF-1K,1%,1/20W,CHIP,CS21001FE07    I32 @T6G_MB_LIB.T6G(SCH_1):PAGE378
  R913    1      A Q_RES_0201LF-0,5%,1/20W,CHIP,CS00001JE10    I42 @T6G_MB_LIB.T6G(SCH_1):PAGE462

SMB_RT_CPU1_P3_R_SDA @T6G_MB_LIB.T6G(SCH_1):SMB_RT_CPU1_P3_R_SDA
 R6746    1      A Q_RES_0201LF-0,5%,1/20W,CHIP,CS00001JE10    I22 @T6G_MB_LIB.T6G(SCH_1):PAGE378
 R6750    2      B Q_RES_0201LF-1K,1%,1/20W,CHIP,CS21001FE07    I31 @T6G_MB_LIB.T6G(SCH_1):PAGE378
  R914    1      A Q_RES_0201LF-0,5%,1/20W,CHIP,CS00001JE10    I41 @T6G_MB_LIB.T6G(SCH_1):PAGE462

SMB_RT_CPU1_P3_SCL @T6G_MB_LIB.T6G(SCH_1):SMB_RT_CPU1_P3_SCL
 U6020    9    SC2 TCA9548APWR-TCA9548APWR,SMLF,IC,AL009548K02     I1 @T6G_MB_LIB.T6G(SCH_1):PAGE378
 R6747    2      B Q_RES_0201LF-0,5%,1/20W,CHIP,CS00001JE10    I21 @T6G_MB_LIB.T6G(SCH_1):PAGE378

SMB_RT_CPU1_P3_SDA @T6G_MB_LIB.T6G(SCH_1):SMB_RT_CPU1_P3_SDA
 U6020    8    SD2 TCA9548APWR-TCA9548APWR,SMLF,IC,AL009548K02     I1 @T6G_MB_LIB.T6G(SCH_1):PAGE378
 R6746    2      B Q_RES_0201LF-0,5%,1/20W,CHIP,CS00001JE10    I22 @T6G_MB_LIB.T6G(SCH_1):PAGE378

SMB_SCM_2_R1_SCL @T6G_MB_LIB.T6G(SCH_1):SMB_SCM_2_R1_SCL
 R8248    1      A Q_RES_0402LF-0,5%,1/16W,CHIP,CS00002JB13    I84 @T6G_MB_LIB.T6G(SCH_1):PAGE192
 R1321    2      B Q_RES_0402LF-33,5%,1/16W,CHIP,CS03302JB10    I10 @T6G_MB_LIB.T6G(SCH_1):PAGE349
 R1495    1      A Q_RES_0402LF-33,5%,1/16W,CHIP,CS03302JB10    I49 @T6G_MB_LIB.T6G(SCH_1):PAGE349

SMB_SCM_2_R1_SDA @T6G_MB_LIB.T6G(SCH_1):SMB_SCM_2_R1_SDA
 R8249    1      A Q_RES_0402LF-0,5%,1/16W,CHIP,CS00002JB13    I81 @T6G_MB_LIB.T6G(SCH_1):PAGE192
 R1494    2      B Q_RES_0402LF-33,5%,1/16W,CHIP,CS03302JB10     I9 @T6G_MB_LIB.T6G(SCH_1):PAGE349
 R1496    1      A Q_RES_0402LF-33,5%,1/16W,CHIP,CS03302JB10    I48 @T6G_MB_LIB.T6G(SCH_1):PAGE349

SMB_SCM_2_R2_SCL @T6G_MB_LIB.T6G(SCH_1):SMB_SCM_2_R2_SCL
 R8381    1      A Q_RES_0402LF-0,5%,1/16W,CHIP,CS00002JB13    I40 @T6G_MB_LIB.T6G(SCH_1):PAGE199
 R1495    2      B Q_RES_0402LF-33,5%,1/16W,CHIP,CS03302JB10    I49 @T6G_MB_LIB.T6G(SCH_1):PAGE349
  R349    1      A Q_RES_0402LF-33,5%,1/16W,CHIP,CS03302JB10   I185 @T6G_MB_LIB.T6G(SCH_1):PAGE349

SMB_SCM_2_R2_SDA @T6G_MB_LIB.T6G(SCH_1):SMB_SCM_2_R2_SDA
 R8382    1      A Q_RES_0402LF-0,5%,1/16W,CHIP,CS00002JB13    I39 @T6G_MB_LIB.T6G(SCH_1):PAGE199
 R1496    2      B Q_RES_0402LF-33,5%,1/16W,CHIP,CS03302JB10    I48 @T6G_MB_LIB.T6G(SCH_1):PAGE349
  R350    1      A Q_RES_0402LF-33,5%,1/16W,CHIP,CS03302JB10   I184 @T6G_MB_LIB.T6G(SCH_1):PAGE349

SMB_SCM_2_R3_SCL @T6G_MB_LIB.T6G(SCH_1):SMB_SCM_2_R3_SCL
 R8308    1      A Q_RES_0402LF-0,5%,1/16W,CHIP,CS00002JB13    I85 @T6G_MB_LIB.T6G(SCH_1):PAGE168
 R1497    2      B Q_RES_0402LF-33,5%,1/16W,CHIP,CS03302JB10   I176 @T6G_MB_LIB.T6G(SCH_1):PAGE349
 R6076    1      A Q_RES_0402LF-33,5%,1/16W,CHIP,CS03302JB10   I181 @T6G_MB_LIB.T6G(SCH_1):PAGE349
   PJ1    3      3 CONN3_210HP1030BR1-CONN3_210-HP1-030BR1,THLF,IO,DFA   I143 @T6G_MB_LIB.T6G(SCH_1):PAGE168

SMB_SCM_2_R3_SDA @T6G_MB_LIB.T6G(SCH_1):SMB_SCM_2_R3_SDA
 R8309    1      A Q_RES_0402LF-0,5%,1/16W,CHIP,CS00002JB13    I84 @T6G_MB_LIB.T6G(SCH_1):PAGE168
 R6077    1      A Q_RES_0402LF-33,5%,1/16W,CHIP,CS03302JB10   I182 @T6G_MB_LIB.T6G(SCH_1):PAGE349
 R1498    2      B Q_RES_0402LF-33,5%,1/16W,CHIP,CS03302JB10   I183 @T6G_MB_LIB.T6G(SCH_1):PAGE349
   PJ1    2      2 CONN3_210HP1030BR1-CONN3_210-HP1-030BR1,THLF,IO,DFA   I143 @T6G_MB_LIB.T6G(SCH_1):PAGE168

SMB_SCM_2_R4_SCL @T6G_MB_LIB.T6G(SCH_1):SMB_SCM_2_R4_SCL
 R1793    1      A Q_RES_0402LF-0,5%,1/16W,EMPTY,CS00002JB13   I147 @T6G_MB_LIB.T6G(SCH_1):PAGE369
 R3672    1      A Q_RES_0402LF-0,5%,1/16W,CHIP,CS00002JB13   I150 @T6G_MB_LIB.T6G(SCH_1):PAGE369
 R6076    2      B Q_RES_0402LF-33,5%,1/16W,CHIP,CS03302JB10   I181 @T6G_MB_LIB.T6G(SCH_1):PAGE349

SMB_SCM_2_R4_SDA @T6G_MB_LIB.T6G(SCH_1):SMB_SCM_2_R4_SDA
 R1792    1      A Q_RES_0402LF-0,5%,1/16W,EMPTY,CS00002JB13   I146 @T6G_MB_LIB.T6G(SCH_1):PAGE369
 R3671    1      A Q_RES_0402LF-0,5%,1/16W,CHIP,CS00002JB13   I149 @T6G_MB_LIB.T6G(SCH_1):PAGE369
 R6077    2      B Q_RES_0402LF-33,5%,1/16W,CHIP,CS03302JB10   I182 @T6G_MB_LIB.T6G(SCH_1):PAGE349

SMB_SCM_2_R5_SCL @T6G_MB_LIB.T6G(SCH_1):SMB_SCM_2_R5_SCL
 R8071    1      A Q_RES_0402LF-0,5%,1/16W,CHIP,CS00002JB13    I85 @T6G_MB_LIB.T6G(SCH_1):PAGE175
  R349    2      B Q_RES_0402LF-33,5%,1/16W,CHIP,CS03302JB10   I185 @T6G_MB_LIB.T6G(SCH_1):PAGE349
  R351    1      A Q_RES_0402LF-33,5%,1/16W,CHIP,CS03302JB10   I187 @T6G_MB_LIB.T6G(SCH_1):PAGE349

SMB_SCM_2_R5_SDA @T6G_MB_LIB.T6G(SCH_1):SMB_SCM_2_R5_SDA
 R8072    1      A Q_RES_0402LF-0,5%,1/16W,CHIP,CS00002JB13    I82 @T6G_MB_LIB.T6G(SCH_1):PAGE175
  R350    2      B Q_RES_0402LF-33,5%,1/16W,CHIP,CS03302JB10   I184 @T6G_MB_LIB.T6G(SCH_1):PAGE349
  R352    1      A Q_RES_0402LF-33,5%,1/16W,CHIP,CS03302JB10   I186 @T6G_MB_LIB.T6G(SCH_1):PAGE349

SMB_SCM_2_R6_SCL @T6G_MB_LIB.T6G(SCH_1):SMB_SCM_2_R6_SCL
  R118    1      A Q_RES_0402LF-0,5%,1/16W,CHIP,CS00002JB13    I41 @T6G_MB_LIB.T6G(SCH_1):PAGE182
  R351    2      B Q_RES_0402LF-33,5%,1/16W,CHIP,CS03302JB10   I187 @T6G_MB_LIB.T6G(SCH_1):PAGE349
 R6856    1      A Q_RES_0402LF-33,5%,1/16W,CHIP,CS03302JB10   I226 @T6G_MB_LIB.T6G(SCH_1):PAGE349

SMB_SCM_2_R6_SDA @T6G_MB_LIB.T6G(SCH_1):SMB_SCM_2_R6_SDA
  R119    1      A Q_RES_0402LF-0,5%,1/16W,CHIP,CS00002JB13    I40 @T6G_MB_LIB.T6G(SCH_1):PAGE182
  R352    2      B Q_RES_0402LF-33,5%,1/16W,CHIP,CS03302JB10   I186 @T6G_MB_LIB.T6G(SCH_1):PAGE349
 R6857    1      A Q_RES_0402LF-33,5%,1/16W,CHIP,CS03302JB10   I227 @T6G_MB_LIB.T6G(SCH_1):PAGE349

SMB_SENSOR_E1S_3V3AUX_SCL @T6G_MB_LIB.T6G(SCH_1):SMB_SENSOR_E1S_3V3AUX_SCL
  U279    7   SCLB PCA9617ADP-PCA9617ADP,SMLF,IC,AL009617K02    I93 @T6G_MB_LIB.T6G(SCH_1):PAGE346
 R3526    2      B Q_RES_0402LF-0,5%,1/16W,CHIP,CS00002JB13    I23 @T6G_MB_LIB.T6G(SCH_1):PAGE252
 R3535    2      B Q_RES_0402LF-2.2K,5%,1/16W,CHIP,CS22202JB07    I44 @T6G_MB_LIB.T6G(SCH_1):PAGE252

SMB_SENSOR_E1S_3V3AUX_SDA @T6G_MB_LIB.T6G(SCH_1):SMB_SENSOR_E1S_3V3AUX_SDA
  U279    6   SDAB PCA9617ADP-PCA9617ADP,SMLF,IC,AL009617K02    I93 @T6G_MB_LIB.T6G(SCH_1):PAGE346
 R3527    2      B Q_RES_0402LF-0,5%,1/16W,CHIP,CS00002JB13    I24 @T6G_MB_LIB.T6G(SCH_1):PAGE252
 R3536    2      B Q_RES_0402LF-2.2K,5%,1/16W,CHIP,CS22202JB07    I43 @T6G_MB_LIB.T6G(SCH_1):PAGE252

SMB_SENSOR_M2_P1_3V3AUX_SCL @T6G_MB_LIB.T6G(SCH_1):SMB_SENSOR_M2_P1_3V3AUX_SCL
   U98    6   SCL2 PCA9306DP1-PCA9306DP1,SMLF,IC,AL009306K04    I27 @T6G_MB_LIB.T6G(SCH_1):PAGE346
 R2967    2      B Q_RES_0402LF-0,5%,1/16W,CHIP,CS00002JB13    I25 @T6G_MB_LIB.T6G(SCH_1):PAGE252
 R1089    2      B Q_RES_0402LF-2.2K,5%,1/16W,CHIP,CS22202JB07    I37 @T6G_MB_LIB.T6G(SCH_1):PAGE252

SMB_SENSOR_M2_P1_3V3AUX_SDA @T6G_MB_LIB.T6G(SCH_1):SMB_SENSOR_M2_P1_3V3AUX_SDA
   U98    5   SDA2 PCA9306DP1-PCA9306DP1,SMLF,IC,AL009306K04    I27 @T6G_MB_LIB.T6G(SCH_1):PAGE346
 R2968    2      B Q_RES_0402LF-0,5%,1/16W,CHIP,CS00002JB13    I26 @T6G_MB_LIB.T6G(SCH_1):PAGE252
 R1090    2      B Q_RES_0402LF-2.2K,5%,1/16W,CHIP,CS22202JB07    I38 @T6G_MB_LIB.T6G(SCH_1):PAGE252

SMB_SEN_MAM_2_3V3AUX_SCL @T6G_MB_LIB.T6G(SCH_1):SMB_SEN_MAM_2_3V3AUX_SCL
 R1228    2      B Q_RES_0402LF-0,5%,1/16W,EMPTY,CS00002JB13   I139 @T6G_MB_LIB.T6G(SCH_1):PAGE263
   U50   13    SCL MAX11617EEET-MAX11617EEE+T,SMLF,EMPTY,AL011617W00   I156 @T6G_MB_LIB.T6G(SCH_1):PAGE263

SMB_SEN_MAM_2_3V3AUX_SDA @T6G_MB_LIB.T6G(SCH_1):SMB_SEN_MAM_2_3V3AUX_SDA
 R1227    2      B Q_RES_0402LF-0,5%,1/16W,EMPTY,CS00002JB13   I138 @T6G_MB_LIB.T6G(SCH_1):PAGE263
   U50   14    SDA MAX11617EEET-MAX11617EEE+T,SMLF,EMPTY,AL011617W00   I156 @T6G_MB_LIB.T6G(SCH_1):PAGE263

SMB_SEN_MAM_3V3AUX_SCL @T6G_MB_LIB.T6G(SCH_1):SMB_SEN_MAM_3V3AUX_SCL
 R1793    2      B Q_RES_0402LF-0,5%,1/16W,EMPTY,CS00002JB13   I147 @T6G_MB_LIB.T6G(SCH_1):PAGE369
  U193   13    SCL MAX11617EEET-MAX11617EEE+T,SMLF,EMPTY,AL011617W00   I169 @T6G_MB_LIB.T6G(SCH_1):PAGE369

SMB_SEN_MAM_3V3AUX_SDA @T6G_MB_LIB.T6G(SCH_1):SMB_SEN_MAM_3V3AUX_SDA
 R1792    2      B Q_RES_0402LF-0,5%,1/16W,EMPTY,CS00002JB13   I146 @T6G_MB_LIB.T6G(SCH_1):PAGE369
  U193   14    SDA MAX11617EEET-MAX11617EEE+T,SMLF,EMPTY,AL011617W00   I169 @T6G_MB_LIB.T6G(SCH_1):PAGE369

SMB_SEN_TIC_2_3V3AUX_SCL @T6G_MB_LIB.T6G(SCH_1):SMB_SEN_TIC_2_3V3AUX_SCL
 R1244    2      B Q_RES_0402LF-0,5%,1/16W,CHIP,CS00002JB13   I140 @T6G_MB_LIB.T6G(SCH_1):PAGE263
   U51    3    SCL ADC128D818CIMTXNOPB-ADC128D818CIMTX/NOPB,SMLF,IC,AA   I142 @T6G_MB_LIB.T6G(SCH_1):PAGE263

SMB_SEN_TIC_2_3V3AUX_SDA @T6G_MB_LIB.T6G(SCH_1):SMB_SEN_TIC_2_3V3AUX_SDA
 R1243    2      B Q_RES_0402LF-0,5%,1/16W,CHIP,CS00002JB13   I141 @T6G_MB_LIB.T6G(SCH_1):PAGE263
   U51    2    SDA ADC128D818CIMTXNOPB-ADC128D818CIMTX/NOPB,SMLF,IC,AA   I142 @T6G_MB_LIB.T6G(SCH_1):PAGE263

SMB_SEN_TIC_3V3AUX_SCL @T6G_MB_LIB.T6G(SCH_1):SMB_SEN_TIC_3V3AUX_SCL
  U269    3    SCL ADC128D818CIMTXNOPB-ADC128D818CIMTX/NOPB,SMLF,IC,AA   I142 @T6G_MB_LIB.T6G(SCH_1):PAGE369
 R3672    2      B Q_RES_0402LF-0,5%,1/16W,CHIP,CS00002JB13   I150 @T6G_MB_LIB.T6G(SCH_1):PAGE369

SMB_SEN_TIC_3V3AUX_SDA @T6G_MB_LIB.T6G(SCH_1):SMB_SEN_TIC_3V3AUX_SDA
  U269    2    SDA ADC128D818CIMTXNOPB-ADC128D818CIMTX/NOPB,SMLF,IC,AA   I142 @T6G_MB_LIB.T6G(SCH_1):PAGE369
 R3671    2      B Q_RES_0402LF-0,5%,1/16W,CHIP,CS00002JB13   I149 @T6G_MB_LIB.T6G(SCH_1):PAGE369

SMB_SML1_PMBUS_HSC_L_SCL @T6G_MB_LIB.T6G(SCH_1):SMB_SML1_PMBUS_HSC_L_SCL
 R3909    2      B Q_RES_0402LF-33.2,1%,1/16W,CHIP,CS03322FB03    I37 @T6G_MB_LIB.T6G(SCH_1):PAGE267
 PU289   11    SCL MP5990GMA1111Z-MP5990GMA-1111-Z,SMLF,IC,AR0F0TP4023    I58 @T6G_MB_LIB.T6G(SCH_1):PAGE267

SMB_SML1_PMBUS_HSC_R1_SCL @T6G_MB_LIB.T6G(SCH_1):SMB_SML1_PMBUS_HSC_R1_SCL
  PJ38   18     18 SCONN21_9193031121LF-SCONN21_91930-31121LF,SMLF,IOA    I42 @T6G_MB_LIB.T6G(SCH_1):PAGE371
  R347    2      B Q_RES_0402LF-33.2,1%,1/16W,CHIP,CS03322FB03   I173 @T6G_MB_LIB.T6G(SCH_1):PAGE349
  JP10    1      1 CONN3_210HP1030BR1-CONN3_210-HP1-030BR1,THLF,IO,DFA   I103 @T6G_MB_LIB.T6G(SCH_1):PAGE372

SMB_SML1_PMBUS_HSC_R1_SDA @T6G_MB_LIB.T6G(SCH_1):SMB_SML1_PMBUS_HSC_R1_SDA
  PJ38   19     19 SCONN21_9193031121LF-SCONN21_91930-31121LF,SMLF,IOA    I42 @T6G_MB_LIB.T6G(SCH_1):PAGE371
  R348    2      B Q_RES_0402LF-33.2,1%,1/16W,CHIP,CS03322FB03   I172 @T6G_MB_LIB.T6G(SCH_1):PAGE349
  JP10    2      2 CONN3_210HP1030BR1-CONN3_210-HP1-030BR1,THLF,IO,DFA   I103 @T6G_MB_LIB.T6G(SCH_1):PAGE372

SMB_SML1_PMBUS_HSC_R_SDA @T6G_MB_LIB.T6G(SCH_1):SMB_SML1_PMBUS_HSC_R_SDA
 R1714    2      B Q_RES_0402LF-0,5%,1/16W,CHIP,CS00002JB13    I36 @T6G_MB_LIB.T6G(SCH_1):PAGE267
 PU289   12    SDA MP5990GMA1111Z-MP5990GMA-1111-Z,SMLF,IC,AR0F0TP4023    I58 @T6G_MB_LIB.T6G(SCH_1):PAGE267

SMB_SML1_PMBUS_HSC_SCL @T6G_MB_LIB.T6G(SCH_1):SMB_SML1_PMBUS_HSC_SCL
 R2995    2      B Q_RES_0402LF-33.2,1%,1/16W,CHIP,CS03322FB03    I91 @T6G_MB_LIB.T6G(SCH_1):PAGE349
 R3909    1      A Q_RES_0402LF-33.2,1%,1/16W,CHIP,CS03322FB03    I37 @T6G_MB_LIB.T6G(SCH_1):PAGE267
  R347    1      A Q_RES_0402LF-33.2,1%,1/16W,CHIP,CS03322FB03   I173 @T6G_MB_LIB.T6G(SCH_1):PAGE349
 R6784    2      B Q_RES_0402LF-0,5%,1/16W,CHIP,CS00002JB13   I198 @T6G_MB_LIB.T6G(SCH_1):PAGE349

SMB_SML1_PMBUS_HSC_SDA @T6G_MB_LIB.T6G(SCH_1):SMB_SML1_PMBUS_HSC_SDA
 R2996    2      B Q_RES_0402LF-33.2,1%,1/16W,CHIP,CS03322FB03    I92 @T6G_MB_LIB.T6G(SCH_1):PAGE349
 R1714    1      A Q_RES_0402LF-0,5%,1/16W,CHIP,CS00002JB13    I36 @T6G_MB_LIB.T6G(SCH_1):PAGE267
  R348    1      A Q_RES_0402LF-33.2,1%,1/16W,CHIP,CS03322FB03   I172 @T6G_MB_LIB.T6G(SCH_1):PAGE349
 R6785    2      B Q_RES_0402LF-0,5%,1/16W,CHIP,CS00002JB13   I199 @T6G_MB_LIB.T6G(SCH_1):PAGE349

SMB_USB_CPU0_HUB1_SCL @T6G_MB_LIB.T6G(SCH_1):SMB_USB_CPU0_HUB1_SCL
 U6001   32 I2C_CLK CYUSB330468LTXI-CYUSB3304-68LTXI,SMLF,IC,AJ0330400A     I1 @T6G_MB_LIB.T6G(SCH_1):PAGE153
 R6201    2      B Q_RES_0402LF-0,5%,1/16W,CHIP,CS00002JB13    I84 @T6G_MB_LIB.T6G(SCH_1):PAGE252
 R6224    1      A Q_RES_0402LF-33.2,1%,1/16W,EMPTY,CS03322FB03    I84 @T6G_MB_LIB.T6G(SCH_1):PAGE153
 R6211    2      B Q_RES_0402LF-2.2K,5%,1/16W,CHIP,CS22202JB07    I89 @T6G_MB_LIB.T6G(SCH_1):PAGE252
 R6314    1      A Q_RES_0402LF-0,5%,1/16W,CHIP,CS00002JB13   I137 @T6G_MB_LIB.T6G(SCH_1):PAGE155
 R6280    1      A Q_RES_0402LF-0,5%,1/16W,CHIP,CS00002JB13   I146 @T6G_MB_LIB.T6G(SCH_1):PAGE157

SMB_USB_CPU0_HUB1_SCL_R @T6G_MB_LIB.T6G(SCH_1):SMB_USB_CPU0_HUB1_SCL_R
   U36    5    SC0 TCA9548APWR-TCA9548APWR,SMLF,IC,AL009548K02    I33 @T6G_MB_LIB.T6G(SCH_1):PAGE252
 R6201    1      A Q_RES_0402LF-0,5%,1/16W,CHIP,CS00002JB13    I84 @T6G_MB_LIB.T6G(SCH_1):PAGE252

SMB_USB_CPU0_HUB1_SCL_R2 @T6G_MB_LIB.T6G(SCH_1):SMB_USB_CPU0_HUB1_SCL_R2
 U6003    6    SCL M24128BWMN6TP-M24128-BWMN6TP,SMLF,IC,AKE30Z00613    I64 @T6G_MB_LIB.T6G(SCH_1):PAGE153
 R6224    2      B Q_RES_0402LF-33.2,1%,1/16W,EMPTY,CS03322FB03    I84 @T6G_MB_LIB.T6G(SCH_1):PAGE153
 R6226    2      B Q_RES_0402LF-10K,1%,1/16W,EMPTY,CS31002FB08    I85 @T6G_MB_LIB.T6G(SCH_1):PAGE153

SMB_USB_CPU0_HUB1_SDA @T6G_MB_LIB.T6G(SCH_1):SMB_USB_CPU0_HUB1_SDA
 U6001   33 I2C_DATA CYUSB330468LTXI-CYUSB3304-68LTXI,SMLF,IC,AJ0330400A     I1 @T6G_MB_LIB.T6G(SCH_1):PAGE153
 R6200    2      B Q_RES_0402LF-0,5%,1/16W,CHIP,CS00002JB13    I83 @T6G_MB_LIB.T6G(SCH_1):PAGE252
 R6225    1      A Q_RES_0402LF-33.2,1%,1/16W,EMPTY,CS03322FB03    I83 @T6G_MB_LIB.T6G(SCH_1):PAGE153
 R6212    2      B Q_RES_0402LF-2.2K,5%,1/16W,CHIP,CS22202JB07    I90 @T6G_MB_LIB.T6G(SCH_1):PAGE252
 R6279    1      A Q_RES_0402LF-0,5%,1/16W,CHIP,CS00002JB13   I148 @T6G_MB_LIB.T6G(SCH_1):PAGE157
 R6311    1      A Q_RES_0402LF-0,5%,1/16W,CHIP,CS00002JB13   I200 @T6G_MB_LIB.T6G(SCH_1):PAGE155

SMB_USB_CPU0_HUB1_SDA_R @T6G_MB_LIB.T6G(SCH_1):SMB_USB_CPU0_HUB1_SDA_R
   U36    4    SD0 TCA9548APWR-TCA9548APWR,SMLF,IC,AL009548K02    I33 @T6G_MB_LIB.T6G(SCH_1):PAGE252
 R6200    1      A Q_RES_0402LF-0,5%,1/16W,CHIP,CS00002JB13    I83 @T6G_MB_LIB.T6G(SCH_1):PAGE252

SMB_USB_CPU0_HUB1_SDA_R2 @T6G_MB_LIB.T6G(SCH_1):SMB_USB_CPU0_HUB1_SDA_R2
 U6003    5    SDA M24128BWMN6TP-M24128-BWMN6TP,SMLF,IC,AKE30Z00613    I64 @T6G_MB_LIB.T6G(SCH_1):PAGE153
 R6225    2      B Q_RES_0402LF-33.2,1%,1/16W,EMPTY,CS03322FB03    I83 @T6G_MB_LIB.T6G(SCH_1):PAGE153
 R6227    2      B Q_RES_0402LF-10K,1%,1/16W,EMPTY,CS31002FB08    I86 @T6G_MB_LIB.T6G(SCH_1):PAGE153

SMB_USB_HUB2_TI_SCL_MRP_PRT_CTL1 @T6G_MB_LIB.T6G(SCH_1):SMB_USB_HUB2_TI_SCL_MRP_PRT_CTL1
 U6002   38 SCL||SMBCLK TUSB8042AIRGCR-TUSB8042AIRGCR,SMLF,IC,AL008042000   I119 @T6G_MB_LIB.T6G(SCH_1):PAGE157
 R6280    2      B Q_RES_0402LF-0,5%,1/16W,CHIP,CS00002JB13   I146 @T6G_MB_LIB.T6G(SCH_1):PAGE157

SMB_USB_HUB2_TI_SDA_MRP_PRT_CTL2 @T6G_MB_LIB.T6G(SCH_1):SMB_USB_HUB2_TI_SDA_MRP_PRT_CTL2
 U6002   37 SDA||SMBDAT TUSB8042AIRGCR-TUSB8042AIRGCR,SMLF,IC,AL008042000   I119 @T6G_MB_LIB.T6G(SCH_1):PAGE157
 R6279    2      B Q_RES_0402LF-0,5%,1/16W,CHIP,CS00002JB13   I148 @T6G_MB_LIB.T6G(SCH_1):PAGE157

SMB_VR_3V3AUX_SCL @T6G_MB_LIB.T6G(SCH_1):SMB_VR_3V3AUX_SCL
 R3713    2      B Q_RES_0402LF-0,5%,1/16W,CHIP,CS00002JB13    I33 @T6G_MB_LIB.T6G(SCH_1):PAGE251
 R3723    2      B Q_RES_0402LF-2.2K,5%,1/16W,CHIP,CS22202JB07    I53 @T6G_MB_LIB.T6G(SCH_1):PAGE251
 R1497    1      A Q_RES_0402LF-33,5%,1/16W,CHIP,CS03302JB10   I176 @T6G_MB_LIB.T6G(SCH_1):PAGE349
  R308    1      A Q_RES_0402LF-33,5%,1/16W,CHIP,CS03302JB10   I224 @T6G_MB_LIB.T6G(SCH_1):PAGE349

SMB_VR_3V3AUX_SCL_R0 @T6G_MB_LIB.T6G(SCH_1):SMB_VR_3V3AUX_SCL_R0
 R2421    2      B Q_RES_0402LF-33.2,1%,1/16W,CHIP,CS03322FB03    I98 @T6G_MB_LIB.T6G(SCH_1):PAGE348
   J41   A5 GND_A5 SCONN168_ME1016810202011-SCONN168_ME1016810202011,A   I176 @T6G_MB_LIB.T6G(SCH_1):PAGE348

SMB_VR_3V3AUX_SCL_R6 @T6G_MB_LIB.T6G(SCH_1):SMB_VR_3V3AUX_SCL_R6
 R3713    1      A Q_RES_0402LF-0,5%,1/16W,CHIP,CS00002JB13    I33 @T6G_MB_LIB.T6G(SCH_1):PAGE251
   U39    5    SC0 TCA9548APWR-TCA9548APWR,SMLF,IC,AL009548K02    I74 @T6G_MB_LIB.T6G(SCH_1):PAGE251

SMB_VR_3V3AUX_SDA @T6G_MB_LIB.T6G(SCH_1):SMB_VR_3V3AUX_SDA
 R3714    2      B Q_RES_0402LF-0,5%,1/16W,CHIP,CS00002JB13    I32 @T6G_MB_LIB.T6G(SCH_1):PAGE251
 R3724    2      B Q_RES_0402LF-2.2K,5%,1/16W,CHIP,CS22202JB07    I52 @T6G_MB_LIB.T6G(SCH_1):PAGE251
 R1498    1      A Q_RES_0402LF-33,5%,1/16W,CHIP,CS03302JB10   I183 @T6G_MB_LIB.T6G(SCH_1):PAGE349
  R309    1      A Q_RES_0402LF-33,5%,1/16W,CHIP,CS03302JB10   I225 @T6G_MB_LIB.T6G(SCH_1):PAGE349

SMB_VR_3V3AUX_SDA_R0 @T6G_MB_LIB.T6G(SCH_1):SMB_VR_3V3AUX_SDA_R0
   J41   A6 GND_A6 SCONN168_ME1016810202011-SCONN168_ME1016810202011,A   I176 @T6G_MB_LIB.T6G(SCH_1):PAGE348
 R2422    2      B Q_RES_0402LF-33.2,1%,1/16W,CHIP,CS03322FB03   I101 @T6G_MB_LIB.T6G(SCH_1):PAGE348

SMB_VR_3V3AUX_SDA_R6 @T6G_MB_LIB.T6G(SCH_1):SMB_VR_3V3AUX_SDA_R6
 R3714    1      A Q_RES_0402LF-0,5%,1/16W,CHIP,CS00002JB13    I32 @T6G_MB_LIB.T6G(SCH_1):PAGE251
   U39    4    SD0 TCA9548APWR-TCA9548APWR,SMLF,IC,AL009548K02    I74 @T6G_MB_LIB.T6G(SCH_1):PAGE251

SMB_VR_3V3STBY_SCL @T6G_MB_LIB.T6G(SCH_1):SMB_VR_3V3STBY_SCL
  R175    1      A Q_RES_0402LF-0,5%,1/16W,CHIP,CS00002JB13    I81 @T6G_MB_LIB.T6G(SCH_1):PAGE185
 R1321    1      A Q_RES_0402LF-33,5%,1/16W,CHIP,CS03302JB10    I10 @T6G_MB_LIB.T6G(SCH_1):PAGE349
 R6858    1      A Q_RES_0402LF-0,5%,1/16W,CHIP,CS00002JB13   I207 @T6G_MB_LIB.T6G(SCH_1):PAGE349
  R308    2      B Q_RES_0402LF-33,5%,1/16W,CHIP,CS03302JB10   I224 @T6G_MB_LIB.T6G(SCH_1):PAGE349

SMB_VR_3V3STBY_SDA @T6G_MB_LIB.T6G(SCH_1):SMB_VR_3V3STBY_SDA
 R8176    1      A Q_RES_0402LF-0,5%,1/16W,CHIP,CS00002JB13    I80 @T6G_MB_LIB.T6G(SCH_1):PAGE185
 R1494    1      A Q_RES_0402LF-33,5%,1/16W,CHIP,CS03302JB10     I9 @T6G_MB_LIB.T6G(SCH_1):PAGE349
 R6859    1      A Q_RES_0402LF-0,5%,1/16W,CHIP,CS00002JB13   I206 @T6G_MB_LIB.T6G(SCH_1):PAGE349
  R309    2      B Q_RES_0402LF-33,5%,1/16W,CHIP,CS03302JB10   I225 @T6G_MB_LIB.T6G(SCH_1):PAGE349

SMB_VR_SENSOR_3V3AUX_SCL @T6G_MB_LIB.T6G(SCH_1):SMB_VR_SENSOR_3V3AUX_SCL
 R2421    1      A Q_RES_0402LF-33.2,1%,1/16W,CHIP,CS03322FB03    I98 @T6G_MB_LIB.T6G(SCH_1):PAGE348
 R4269    2      B Q_RES_0402LF-2.2K,5%,1/16W,EMPTY,CS22202JB07    I41 @T6G_MB_LIB.T6G(SCH_1):PAGE251
 R3711    1      A Q_RES_0402LF-33.2,1%,1/16W,CHIP,CS03322FB03    I69 @T6G_MB_LIB.T6G(SCH_1):PAGE251

SMB_VR_SENSOR_3V3AUX_SCL_R @T6G_MB_LIB.T6G(SCH_1):SMB_VR_SENSOR_3V3AUX_SCL_R
 R3711    2      B Q_RES_0402LF-33.2,1%,1/16W,CHIP,CS03322FB03    I69 @T6G_MB_LIB.T6G(SCH_1):PAGE251
   U39   22    SCL TCA9548APWR-TCA9548APWR,SMLF,IC,AL009548K02    I74 @T6G_MB_LIB.T6G(SCH_1):PAGE251

SMB_VR_SENSOR_3V3AUX_SDA @T6G_MB_LIB.T6G(SCH_1):SMB_VR_SENSOR_3V3AUX_SDA
 R4270    2      B Q_RES_0402LF-2.2K,5%,1/16W,EMPTY,CS22202JB07    I40 @T6G_MB_LIB.T6G(SCH_1):PAGE251
 R3712    1      A Q_RES_0402LF-33.2,1%,1/16W,CHIP,CS03322FB03    I68 @T6G_MB_LIB.T6G(SCH_1):PAGE251
 R2422    1      A Q_RES_0402LF-33.2,1%,1/16W,CHIP,CS03322FB03   I101 @T6G_MB_LIB.T6G(SCH_1):PAGE348

SMB_VR_SENSOR_3V3AUX_SDA_R @T6G_MB_LIB.T6G(SCH_1):SMB_VR_SENSOR_3V3AUX_SDA_R
 R3712    2      B Q_RES_0402LF-33.2,1%,1/16W,CHIP,CS03322FB03    I68 @T6G_MB_LIB.T6G(SCH_1):PAGE251
   U39   23    SDA TCA9548APWR-TCA9548APWR,SMLF,IC,AL009548K02    I74 @T6G_MB_LIB.T6G(SCH_1):PAGE251

SMERR_LED @T6G_MB_LIB.T6G(SCH_1):SMERR_LED
  R947    2      B Q_RES_0402LF-4.7K,5%,1/16W,CHIP,CS24702JB10    I11 @T6G_MB_LIB.T6G(SCH_1):PAGE143
   Q11    6     D1 MOSFET_DUAL_6P-2N7002KDW,SMLF,IC,BAM70020047    I19 @T6G_MB_LIB.T6G(SCH_1):PAGE143
   Q11    5     G2 MOSFET_DUAL_6P-2N7002KDW,SMLF,IC,BAM70020047    I19 @T6G_MB_LIB.T6G(SCH_1):PAGE143

SMERR_LED_N @T6G_MB_LIB.T6G(SCH_1):SMERR_LED_N
    D6    C      C Q_LED_SMLF-LED_YELLOW,LTST-C190KSKT-P,IC,BEYL0159ZA     I9 @T6G_MB_LIB.T6G(SCH_1):PAGE143
   Q11    3     D2 MOSFET_DUAL_6P-2N7002KDW,SMLF,IC,BAM70020047    I19 @T6G_MB_LIB.T6G(SCH_1):PAGE143

SPI_CPU0_CLK @T6G_MB_LIB.T6G(SCH_1):SPI_CPU0_CLK
   U53    4     A2 SN74AVC4T774PWR-SN74AVC4T774PWR,SMLF,IC,AL04T774K00    I63 @T6G_MB_LIB.T6G(SCH_1):PAGE76
  R461    1      A Q_RES_0402LF-33,5%,1/16W,CHIP,CS03302JB10   I409 @T6G_MB_LIB.T6G(SCH_1):PAGE29
  R743    2      B Q_RES_0402LF-10K,5%,1/16W,CHIP,CS31002JB08    I97 @T6G_MB_LIB.T6G(SCH_1):PAGE75
 R6098    2      B Q_RES_0402LF-10K,5%,1/16W,EMPTY,CS31002JB08    I99 @T6G_MB_LIB.T6G(SCH_1):PAGE75

SPI_CPU0_CS0_N @T6G_MB_LIB.T6G(SCH_1):SPI_CPU0_CS0_N
   U53    3     A1 SN74AVC4T774PWR-SN74AVC4T774PWR,SMLF,IC,AL04T774K00    I63 @T6G_MB_LIB.T6G(SCH_1):PAGE76
  R811    2      B Q_RES_0402LF-1K,1%,1/16W,CHIP,CS21002FB06   I106 @T6G_MB_LIB.T6G(SCH_1):PAGE76
  R459    1      A Q_RES_0402LF-33,5%,1/16W,CHIP,CS03302JB10   I407 @T6G_MB_LIB.T6G(SCH_1):PAGE29

SPI_CPU0_CS1_N @T6G_MB_LIB.T6G(SCH_1):SPI_CPU0_CS1_N
   U53    5     A3 SN74AVC4T774PWR-SN74AVC4T774PWR,SMLF,IC,AL04T774K00    I63 @T6G_MB_LIB.T6G(SCH_1):PAGE76
  R601    2      B Q_RES_0402LF-1K,1%,1/16W,CHIP,CS21002FB06   I108 @T6G_MB_LIB.T6G(SCH_1):PAGE76
  R460    1      A Q_RES_0402LF-33,5%,1/16W,CHIP,CS03302JB10   I408 @T6G_MB_LIB.T6G(SCH_1):PAGE29

SPI_CPU0_D0 @T6G_MB_LIB.T6G(SCH_1):SPI_CPU0_D0
  R464    1      A Q_RES_0402LF-33,5%,1/16W,CHIP,CS03302JB10   I410 @T6G_MB_LIB.T6G(SCH_1):PAGE29
 R1532    2      B Q_RES_0402LF-1K,1%,1/16W,EMPTY,CS21002FB06   I131 @T6G_MB_LIB.T6G(SCH_1):PAGE76
 R8007    1      A Q_RES_0402LF-33,5%,1/16W,CHIP,CS03302JB10   I240 @T6G_MB_LIB.T6G(SCH_1):PAGE76

SPI_CPU0_D1 @T6G_MB_LIB.T6G(SCH_1):SPI_CPU0_D1
  R465    1      A Q_RES_0402LF-49.9,1%,1/16W,CHIP,CS04992FB07   I411 @T6G_MB_LIB.T6G(SCH_1):PAGE29
 R1531    2      B Q_RES_0402LF-1K,1%,1/16W,EMPTY,CS21002FB06   I132 @T6G_MB_LIB.T6G(SCH_1):PAGE76
 R8008    1      A Q_RES_0402LF-33,5%,1/16W,CHIP,CS03302JB10   I241 @T6G_MB_LIB.T6G(SCH_1):PAGE76

SPI_CPU0_D2 @T6G_MB_LIB.T6G(SCH_1):SPI_CPU0_D2
  R466    1      A Q_RES_0402LF-33,5%,1/16W,CHIP,CS03302JB10   I412 @T6G_MB_LIB.T6G(SCH_1):PAGE29
 R1530    2      B Q_RES_0402LF-1K,1%,1/16W,EMPTY,CS21002FB06   I133 @T6G_MB_LIB.T6G(SCH_1):PAGE76
 R8006    1      A Q_RES_0402LF-33,5%,1/16W,CHIP,CS03302JB10   I239 @T6G_MB_LIB.T6G(SCH_1):PAGE76

SPI_CPU0_D3 @T6G_MB_LIB.T6G(SCH_1):SPI_CPU0_D3
  R467    1      A Q_RES_0402LF-33,5%,1/16W,CHIP,CS03302JB10   I413 @T6G_MB_LIB.T6G(SCH_1):PAGE29
 R1529    2      B Q_RES_0402LF-1K,1%,1/16W,EMPTY,CS21002FB06   I134 @T6G_MB_LIB.T6G(SCH_1):PAGE76
 R8005    1      A Q_RES_0402LF-33,5%,1/16W,CHIP,CS03302JB10   I234 @T6G_MB_LIB.T6G(SCH_1):PAGE76

SPI_CPU0_LVC3_CLK @T6G_MB_LIB.T6G(SCH_1):SPI_CPU0_LVC3_CLK
   U53   13     B2 SN74AVC4T774PWR-SN74AVC4T774PWR,SMLF,IC,AL04T774K00    I63 @T6G_MB_LIB.T6G(SCH_1):PAGE76
  R602    1      A Q_RES_0402LF-33,5%,1/16W,CHIP,CS03302JB10   I230 @T6G_MB_LIB.T6G(SCH_1):PAGE76

SPI_CPU0_LVC3_CS0_N @T6G_MB_LIB.T6G(SCH_1):SPI_CPU0_LVC3_CS0_N
   U53   14     B1 SN74AVC4T774PWR-SN74AVC4T774PWR,SMLF,IC,AL04T774K00    I63 @T6G_MB_LIB.T6G(SCH_1):PAGE76
  R603    1      A Q_RES_0402LF-0,5%,1/16W,CHIP,CS00002JB13   I228 @T6G_MB_LIB.T6G(SCH_1):PAGE76

SPI_CPU0_LVC3_CS1_N @T6G_MB_LIB.T6G(SCH_1):SPI_CPU0_LVC3_CS1_N
   U53   12     B3 SN74AVC4T774PWR-SN74AVC4T774PWR,SMLF,IC,AL04T774K00    I63 @T6G_MB_LIB.T6G(SCH_1):PAGE76
  R600    1      A Q_RES_0402LF-0,5%,1/16W,CHIP,CS00002JB13   I180 @T6G_MB_LIB.T6G(SCH_1):PAGE76

SPI_CPU0_LVC3_D0 @T6G_MB_LIB.T6G(SCH_1):SPI_CPU0_LVC3_D0
   U54    8     B3 PI4ULS3V304AZMAEX-PI4ULS3V304AZMAEX,SMLF,IC,AL0003A    I67 @T6G_MB_LIB.T6G(SCH_1):PAGE76
  R604    1      A Q_RES_0402LF-33.2,1%,1/16W,CHIP,CS03322FB03   I221 @T6G_MB_LIB.T6G(SCH_1):PAGE76

SPI_CPU0_LVC3_D1 @T6G_MB_LIB.T6G(SCH_1):SPI_CPU0_LVC3_D1
   U54    7     B4 PI4ULS3V304AZMAEX-PI4ULS3V304AZMAEX,SMLF,IC,AL0003A    I67 @T6G_MB_LIB.T6G(SCH_1):PAGE76
  R605    1      A Q_RES_0402LF-49.9,1%,1/16W,CHIP,CS04992FB07   I219 @T6G_MB_LIB.T6G(SCH_1):PAGE76

SPI_CPU0_LVC3_D2 @T6G_MB_LIB.T6G(SCH_1):SPI_CPU0_LVC3_D2
   U54    9     B2 PI4ULS3V304AZMAEX-PI4ULS3V304AZMAEX,SMLF,IC,AL0003A    I67 @T6G_MB_LIB.T6G(SCH_1):PAGE76
  R606    1      A Q_RES_0402LF-0,5%,1/16W,CHIP,CS00002JB13   I205 @T6G_MB_LIB.T6G(SCH_1):PAGE76

SPI_CPU0_LVC3_D3 @T6G_MB_LIB.T6G(SCH_1):SPI_CPU0_LVC3_D3
   U54   10     B1 PI4ULS3V304AZMAEX-PI4ULS3V304AZMAEX,SMLF,IC,AL0003A    I67 @T6G_MB_LIB.T6G(SCH_1):PAGE76
  R607    1      A Q_RES_0402LF-0,5%,1/16W,CHIP,CS00002JB13   I207 @T6G_MB_LIB.T6G(SCH_1):PAGE76

SPI_CPU0_LVC3_R_TPM_CS_N @T6G_MB_LIB.T6G(SCH_1):SPI_CPU0_LVC3_R_TPM_CS_N
   U53   11     B4 SN74AVC4T774PWR-SN74AVC4T774PWR,SMLF,IC,AL04T774K00    I63 @T6G_MB_LIB.T6G(SCH_1):PAGE76
  R608    1      A Q_RES_0402LF-33,5%,1/16W,CHIP,CS03302JB10   I242 @T6G_MB_LIB.T6G(SCH_1):PAGE76

SPI_CPU0_LVC3_SCM_CLK @T6G_MB_LIB.T6G(SCH_1):SPI_CPU0_LVC3_SCM_CLK
   R20    2      B Q_RES_0402LF-10K,1%,1/16W,CHIP,CS31002FB08   I115 @T6G_MB_LIB.T6G(SCH_1):PAGE76
  R602    2      B Q_RES_0402LF-33,5%,1/16W,CHIP,CS03302JB10   I230 @T6G_MB_LIB.T6G(SCH_1):PAGE76
   J41  B11 +3.3V_EDGE SCONN168_ME1016810202011-SCONN168_ME1016810202011,A   I176 @T6G_MB_LIB.T6G(SCH_1):PAGE348

SPI_CPU0_LVC3_SCM_CS0_N @T6G_MB_LIB.T6G(SCH_1):SPI_CPU0_LVC3_SCM_CS0_N
  R610    2      B Q_RES_0402LF-1K,1%,1/16W,EMPTY,CS21002FB06    I97 @T6G_MB_LIB.T6G(SCH_1):PAGE76
  R603    2      B Q_RES_0402LF-0,5%,1/16W,CHIP,CS00002JB13   I228 @T6G_MB_LIB.T6G(SCH_1):PAGE76
   J41  B12 AUX_PWR_EN SCONN168_ME1016810202011-SCONN168_ME1016810202011,A   I176 @T6G_MB_LIB.T6G(SCH_1):PAGE348

SPI_CPU0_LVC3_SCM_CS1_N @T6G_MB_LIB.T6G(SCH_1):SPI_CPU0_LVC3_SCM_CS1_N
  R600    2      B Q_RES_0402LF-0,5%,1/16W,CHIP,CS00002JB13   I180 @T6G_MB_LIB.T6G(SCH_1):PAGE76
 R1655    2      B Q_RES_0402LF-1K,1%,1/16W,EMPTY,CS21002FB06   I191 @T6G_MB_LIB.T6G(SCH_1):PAGE76

SPI_CPU0_LVC3_SCM_D0 @T6G_MB_LIB.T6G(SCH_1):SPI_CPU0_LVC3_SCM_D0
   R21    2      B Q_RES_0402LF-1K,1%,1/16W,EMPTY,CS21002FB06   I116 @T6G_MB_LIB.T6G(SCH_1):PAGE76
  R604    2      B Q_RES_0402LF-33.2,1%,1/16W,CHIP,CS03322FB03   I221 @T6G_MB_LIB.T6G(SCH_1):PAGE76
   J41  B13 GND_B13 SCONN168_ME1016810202011-SCONN168_ME1016810202011,A   I176 @T6G_MB_LIB.T6G(SCH_1):PAGE348

SPI_CPU0_LVC3_SCM_D1 @T6G_MB_LIB.T6G(SCH_1):SPI_CPU0_LVC3_SCM_D1
  R127    2      B Q_RES_0402LF-1K,1%,1/16W,EMPTY,CS21002FB06   I117 @T6G_MB_LIB.T6G(SCH_1):PAGE76
  R605    2      B Q_RES_0402LF-49.9,1%,1/16W,CHIP,CS04992FB07   I219 @T6G_MB_LIB.T6G(SCH_1):PAGE76
   J41  B14 REFCLKN0 SCONN168_ME1016810202011-SCONN168_ME1016810202011,A   I176 @T6G_MB_LIB.T6G(SCH_1):PAGE348

SPI_CPU0_LVC3_SCM_D2 @T6G_MB_LIB.T6G(SCH_1):SPI_CPU0_LVC3_SCM_D2
  R128    2      B Q_RES_0402LF-1K,1%,1/16W,EMPTY,CS21002FB06   I118 @T6G_MB_LIB.T6G(SCH_1):PAGE76
  R606    2      B Q_RES_0402LF-0,5%,1/16W,CHIP,CS00002JB13   I205 @T6G_MB_LIB.T6G(SCH_1):PAGE76
   J41  B15 REFCLKP0 SCONN168_ME1016810202011-SCONN168_ME1016810202011,A   I176 @T6G_MB_LIB.T6G(SCH_1):PAGE348

SPI_CPU0_LVC3_SCM_D3 @T6G_MB_LIB.T6G(SCH_1):SPI_CPU0_LVC3_SCM_D3
  R129    2      B Q_RES_0402LF-1K,1%,1/16W,EMPTY,CS21002FB06   I119 @T6G_MB_LIB.T6G(SCH_1):PAGE76
  R607    2      B Q_RES_0402LF-0,5%,1/16W,CHIP,CS00002JB13   I207 @T6G_MB_LIB.T6G(SCH_1):PAGE76
   J41  B16 GND_B16 SCONN168_ME1016810202011-SCONN168_ME1016810202011,A   I176 @T6G_MB_LIB.T6G(SCH_1):PAGE348

SPI_CPU0_LVC3_TPM_CS_N @T6G_MB_LIB.T6G(SCH_1):SPI_CPU0_LVC3_TPM_CS_N
 R1547    2      B Q_RES_0402LF-4.7K,5%,1/16W,CHIP,CS24702JB10   I148 @T6G_MB_LIB.T6G(SCH_1):PAGE76
   J41 OB12 REFCLKP2 SCONN168_ME1016810202011-SCONN168_ME1016810202011,A   I176 @T6G_MB_LIB.T6G(SCH_1):PAGE348
  R608    2      B Q_RES_0402LF-33,5%,1/16W,CHIP,CS03302JB10   I242 @T6G_MB_LIB.T6G(SCH_1):PAGE76

SPI_CPU0_R1_D0 @T6G_MB_LIB.T6G(SCH_1):SPI_CPU0_R1_D0
   U54    4     A3 PI4ULS3V304AZMAEX-PI4ULS3V304AZMAEX,SMLF,IC,AL0003A    I67 @T6G_MB_LIB.T6G(SCH_1):PAGE76
 R8007    2      B Q_RES_0402LF-33,5%,1/16W,CHIP,CS03302JB10   I240 @T6G_MB_LIB.T6G(SCH_1):PAGE76

SPI_CPU0_R1_D1 @T6G_MB_LIB.T6G(SCH_1):SPI_CPU0_R1_D1
   U54    5     A4 PI4ULS3V304AZMAEX-PI4ULS3V304AZMAEX,SMLF,IC,AL0003A    I67 @T6G_MB_LIB.T6G(SCH_1):PAGE76
 R8008    2      B Q_RES_0402LF-33,5%,1/16W,CHIP,CS03302JB10   I241 @T6G_MB_LIB.T6G(SCH_1):PAGE76

SPI_CPU0_R1_D2 @T6G_MB_LIB.T6G(SCH_1):SPI_CPU0_R1_D2
   U54    3     A2 PI4ULS3V304AZMAEX-PI4ULS3V304AZMAEX,SMLF,IC,AL0003A    I67 @T6G_MB_LIB.T6G(SCH_1):PAGE76
 R8006    2      B Q_RES_0402LF-33,5%,1/16W,CHIP,CS03302JB10   I239 @T6G_MB_LIB.T6G(SCH_1):PAGE76

SPI_CPU0_R1_D3 @T6G_MB_LIB.T6G(SCH_1):SPI_CPU0_R1_D3
   U54    2     A1 PI4ULS3V304AZMAEX-PI4ULS3V304AZMAEX,SMLF,IC,AL0003A    I67 @T6G_MB_LIB.T6G(SCH_1):PAGE76
 R8005    2      B Q_RES_0402LF-33,5%,1/16W,CHIP,CS03302JB10   I234 @T6G_MB_LIB.T6G(SCH_1):PAGE76

SPI_CPU0_R_CLK @T6G_MB_LIB.T6G(SCH_1):SPI_CPU0_R_CLK
   U25 DJ27 ESPI_CLK0||SPI_CLK0||AGPIO117 GENOA_SP5-SOCKET6096_13568-001,SMLF,IO,DGA^6000030   I287 @T6G_MB_LIB.T6G(SCH_1):PAGE29
  R461    2      B Q_RES_0402LF-33,5%,1/16W,CHIP,CS03302JB10   I409 @T6G_MB_LIB.T6G(SCH_1):PAGE29

SPI_CPU0_R_CS0_N @T6G_MB_LIB.T6G(SCH_1):SPI_CPU0_R_CS0_N
   U25 DF30 SPI_CS0_L||AGPIO118 GENOA_SP5-SOCKET6096_13568-001,SMLF,IO,DGA^6000030   I287 @T6G_MB_LIB.T6G(SCH_1):PAGE29
  R459    2      B Q_RES_0402LF-33,5%,1/16W,CHIP,CS03302JB10   I407 @T6G_MB_LIB.T6G(SCH_1):PAGE29

SPI_CPU0_R_CS1_N @T6G_MB_LIB.T6G(SCH_1):SPI_CPU0_R_CS1_N
   U25 DG26 SPI_CS1_L||AGPIO119 GENOA_SP5-SOCKET6096_13568-001,SMLF,IO,DGA^6000030   I287 @T6G_MB_LIB.T6G(SCH_1):PAGE29
  R460    2      B Q_RES_0402LF-33,5%,1/16W,CHIP,CS03302JB10   I408 @T6G_MB_LIB.T6G(SCH_1):PAGE29

SPI_CPU0_R_D0 @T6G_MB_LIB.T6G(SCH_1):SPI_CPU0_R_D0
   U25 DF28 ESPI0_DAT0||SPI0_DAT0||AGPIO120 GENOA_SP5-SOCKET6096_13568-001,SMLF,IO,DGA^6000030   I287 @T6G_MB_LIB.T6G(SCH_1):PAGE29
  R464    2      B Q_RES_0402LF-33,5%,1/16W,CHIP,CS03302JB10   I410 @T6G_MB_LIB.T6G(SCH_1):PAGE29

SPI_CPU0_R_D1 @T6G_MB_LIB.T6G(SCH_1):SPI_CPU0_R_D1
   U25 DG22 ESPI0_DAT1||SPI0_DAT1||AGPIO121 GENOA_SP5-SOCKET6096_13568-001,SMLF,IO,DGA^6000030   I287 @T6G_MB_LIB.T6G(SCH_1):PAGE29
  R465    2      B Q_RES_0402LF-49.9,1%,1/16W,CHIP,CS04992FB07   I411 @T6G_MB_LIB.T6G(SCH_1):PAGE29

SPI_CPU0_R_D2 @T6G_MB_LIB.T6G(SCH_1):SPI_CPU0_R_D2
   U25 DJ28 ESPI0_DAT2||SPI0_DAT2||AGPIO122 GENOA_SP5-SOCKET6096_13568-001,SMLF,IO,DGA^6000030   I287 @T6G_MB_LIB.T6G(SCH_1):PAGE29
  R466    2      B Q_RES_0402LF-33,5%,1/16W,CHIP,CS03302JB10   I412 @T6G_MB_LIB.T6G(SCH_1):PAGE29

SPI_CPU0_R_D3 @T6G_MB_LIB.T6G(SCH_1):SPI_CPU0_R_D3
   U25 DG29 ESPI0_DAT3||SPI0_DAT3||AGPIO123 GENOA_SP5-SOCKET6096_13568-001,SMLF,IO,DGA^6000030   I287 @T6G_MB_LIB.T6G(SCH_1):PAGE29
  R467    2      B Q_RES_0402LF-33,5%,1/16W,CHIP,CS03302JB10   I413 @T6G_MB_LIB.T6G(SCH_1):PAGE29

SPI_CPU0_R_TPM_CS_N @T6G_MB_LIB.T6G(SCH_1):SPI_CPU0_R_TPM_CS_N
   U25 DJ25 AGPIO76||SPI_TPM_CS_L GENOA_SP5-SOCKET6096_13568-001,SMLF,IO,DGA^6000030   I287 @T6G_MB_LIB.T6G(SCH_1):PAGE29
  R475    2      B Q_RES_0402LF-33,5%,1/16W,CHIP,CS03302JB10   I414 @T6G_MB_LIB.T6G(SCH_1):PAGE29

SPI_CPU0_TPM_CS_N @T6G_MB_LIB.T6G(SCH_1):SPI_CPU0_TPM_CS_N
   U53    6     A4 SN74AVC4T774PWR-SN74AVC4T774PWR,SMLF,IC,AL04T774K00    I63 @T6G_MB_LIB.T6G(SCH_1):PAGE76
  R659    2      B Q_RES_0402LF-1K,1%,1/16W,CHIP,CS21002FB06   I107 @T6G_MB_LIB.T6G(SCH_1):PAGE76
  R475    1      A Q_RES_0402LF-33,5%,1/16W,CHIP,CS03302JB10   I414 @T6G_MB_LIB.T6G(SCH_1):PAGE29

SPI_CPU1_CLK @T6G_MB_LIB.T6G(SCH_1):SPI_CPU1_CLK
  R738    1      A Q_RES_0402LF-33,5%,1/16W,CHIP,CS03302JB10    I11 @T6G_MB_LIB.T6G(SCH_1):PAGE56
  R730    2      B Q_RES_0402LF-10K,5%,1/16W,CHIP,CS31002JB08    I87 @T6G_MB_LIB.T6G(SCH_1):PAGE75
  R754    2      B Q_RES_0402LF-10K,5%,1/16W,EMPTY,CS31002JB08    I91 @T6G_MB_LIB.T6G(SCH_1):PAGE75

SPI_CPU1_R_CLK @T6G_MB_LIB.T6G(SCH_1):SPI_CPU1_R_CLK
   U26 DJ27 ESPI_CLK0||SPI_CLK0||AGPIO117 GENOA_SP5-SOCKET6096_13568-001,SMLF,IO,DGA^6000030     I8 @T6G_MB_LIB.T6G(SCH_1):PAGE56
  R738    2      B Q_RES_0402LF-33,5%,1/16W,CHIP,CS03302JB10    I11 @T6G_MB_LIB.T6G(SCH_1):PAGE56

SVID_PVDDCR_CPU0_P0_SVC @T6G_MB_LIB.T6G(SCH_1):SVID_PVDDCR_CPU0_P0_SVC
   U25  A23   SVC0 GENOA_SP5-SOCKET6096_13568-001,SMLF,IO,DGA^6000030   I227 @T6G_MB_LIB.T6G(SCH_1):PAGE27
 PR302    2      B Q_RES_0402LF-0,5%,1/16W,CHIP,CS00002JB13   I323 @T6G_MB_LIB.T6G(SCH_1):PAGE27

SVID_PVDDCR_CPU0_P0_SVC_R @T6G_MB_LIB.T6G(SCH_1):SVID_PVDDCR_CPU0_P0_SVC_R
 PR302    1      A Q_RES_0402LF-0,5%,1/16W,CHIP,CS00002JB13   I323 @T6G_MB_LIB.T6G(SCH_1):PAGE27
  C302    1      A Q_CAP_0402-10PF,50V,5%,EMPTY,CH01006JB08    I68 @T6G_MB_LIB.T6G(SCH_1):PAGE168
 R8293    2      B Q_RES_0402LF-1K,1%,1/16W,EMPTY,CS21002FB06    I71 @T6G_MB_LIB.T6G(SCH_1):PAGE168
PR8005    1      A Q_RES_0402LF-0,5%,1/16W,CHIP,CS00002JB13   I147 @T6G_MB_LIB.T6G(SCH_1):PAGE168

SVID_PVDDCR_CPU0_P0_SVC_R1 @T6G_MB_LIB.T6G(SCH_1):SVID_PVDDCR_CPU0_P0_SVC_R1
  PU42   22    SVC RAA229620GNPHA0-RAA229620GNP#HA0,SMLF,IC,ARF0TGP40A   I135 @T6G_MB_LIB.T6G(SCH_1):PAGE168
PR8005    2      B Q_RES_0402LF-0,5%,1/16W,CHIP,CS00002JB13   I147 @T6G_MB_LIB.T6G(SCH_1):PAGE168

SVID_PVDDCR_CPU0_P0_SVD @T6G_MB_LIB.T6G(SCH_1):SVID_PVDDCR_CPU0_P0_SVD
   U25  A22   SVD0 GENOA_SP5-SOCKET6096_13568-001,SMLF,IO,DGA^6000030   I227 @T6G_MB_LIB.T6G(SCH_1):PAGE27
 PR303    2      B Q_RES_0402LF-0,5%,1/16W,CHIP,CS00002JB13   I322 @T6G_MB_LIB.T6G(SCH_1):PAGE27

SVID_PVDDCR_CPU0_P0_SVD_R @T6G_MB_LIB.T6G(SCH_1):SVID_PVDDCR_CPU0_P0_SVD_R
 PR303    1      A Q_RES_0402LF-0,5%,1/16W,CHIP,CS00002JB13   I322 @T6G_MB_LIB.T6G(SCH_1):PAGE27
  C299    1      A Q_CAP_0402-10PF,50V,5%,EMPTY,CH01006JB08    I66 @T6G_MB_LIB.T6G(SCH_1):PAGE168
 R8289    2      B Q_RES_0402LF-1K,1%,1/16W,EMPTY,CS21002FB06    I70 @T6G_MB_LIB.T6G(SCH_1):PAGE168
PR8006    1      A Q_RES_0402LF-0,5%,1/16W,CHIP,CS00002JB13   I148 @T6G_MB_LIB.T6G(SCH_1):PAGE168

SVID_PVDDCR_CPU0_P0_SVD_R1 @T6G_MB_LIB.T6G(SCH_1):SVID_PVDDCR_CPU0_P0_SVD_R1
  PU42   21    SVD RAA229620GNPHA0-RAA229620GNP#HA0,SMLF,IC,ARF0TGP40A   I135 @T6G_MB_LIB.T6G(SCH_1):PAGE168
PR8006    2      B Q_RES_0402LF-0,5%,1/16W,CHIP,CS00002JB13   I148 @T6G_MB_LIB.T6G(SCH_1):PAGE168

SVID_PVDDCR_CPU0_P0_SVTI @T6G_MB_LIB.T6G(SCH_1):SVID_PVDDCR_CPU0_P0_SVTI
 PR283    1      A Q_RES_0402LF-0,5%,1/16W,CHIP,CS00002JB13     I4 @T6G_MB_LIB.T6G(SCH_1):PAGE168
 PR305    1      A Q_RES_0402LF-0,5%,1/16W,CHIP,CS00002JB13    I86 @T6G_MB_LIB.T6G(SCH_1):PAGE168
 PR284    2      B Q_RES_0402LF-1K,1%,1/16W,EMPTY,CS21002FB06    I10 @T6G_MB_LIB.T6G(SCH_1):PAGE168

SVID_PVDDCR_CPU0_P0_SVTI_R @T6G_MB_LIB.T6G(SCH_1):SVID_PVDDCR_CPU0_P0_SVTI_R
 PR305    2      B Q_RES_0402LF-0,5%,1/16W,CHIP,CS00002JB13    I86 @T6G_MB_LIB.T6G(SCH_1):PAGE168
  PU42   24   SVTI RAA229620GNPHA0-RAA229620GNP#HA0,SMLF,IC,ARF0TGP40A   I135 @T6G_MB_LIB.T6G(SCH_1):PAGE168

SVID_PVDDCR_CPU0_P0_SVTO @T6G_MB_LIB.T6G(SCH_1):SVID_PVDDCR_CPU0_P0_SVTO
   U25  B21   SVT0 GENOA_SP5-SOCKET6096_13568-001,SMLF,IO,DGA^6000030   I227 @T6G_MB_LIB.T6G(SCH_1):PAGE27
 R8304    1      A Q_RES_0402LF-49.9,1%,1/16W,CHIP,CS04992FB07    I87 @T6G_MB_LIB.T6G(SCH_1):PAGE168
 R8286    1      A Q_RES_0402LF-1K,1%,1/16W,EMPTY,CS21002FB06     I6 @T6G_MB_LIB.T6G(SCH_1):PAGE168
  C298    1      A Q_CAP_0402-10PF,50V,5%,EMPTY,CH01006JB08    I64 @T6G_MB_LIB.T6G(SCH_1):PAGE168
 R8287    2      B Q_RES_0402LF-1K,1%,1/16W,EMPTY,CS21002FB06    I69 @T6G_MB_LIB.T6G(SCH_1):PAGE168

SVID_PVDDCR_CPU0_P0_SVTO_R @T6G_MB_LIB.T6G(SCH_1):SVID_PVDDCR_CPU0_P0_SVTO_R
 R8304    2      B Q_RES_0402LF-49.9,1%,1/16W,CHIP,CS04992FB07    I87 @T6G_MB_LIB.T6G(SCH_1):PAGE168
  PU42   23   SVTO RAA229620GNPHA0-RAA229620GNP#HA0,SMLF,IC,ARF0TGP40A   I135 @T6G_MB_LIB.T6G(SCH_1):PAGE168

SVID_PVDDCR_CPU0_P1_SVC @T6G_MB_LIB.T6G(SCH_1):SVID_PVDDCR_CPU0_P1_SVC
   U26  A23   SVC0 GENOA_SP5-SOCKET6096_13568-001,SMLF,IO,DGA^6000030   I190 @T6G_MB_LIB.T6G(SCH_1):PAGE54
 PR169    2      B Q_RES_0402LF-0,5%,1/16W,CHIP,CS00002JB13   I334 @T6G_MB_LIB.T6G(SCH_1):PAGE54

SVID_PVDDCR_CPU0_P1_SVC_R @T6G_MB_LIB.T6G(SCH_1):SVID_PVDDCR_CPU0_P1_SVC_R
 PR169    1      A Q_RES_0402LF-0,5%,1/16W,CHIP,CS00002JB13   I334 @T6G_MB_LIB.T6G(SCH_1):PAGE54
  C297    1      A Q_CAP_0402-10PF,50V,5%,EMPTY,CH01006JB08    I66 @T6G_MB_LIB.T6G(SCH_1):PAGE185
 R8160    2      B Q_RES_0402LF-1K,1%,1/16W,EMPTY,CS21002FB06    I69 @T6G_MB_LIB.T6G(SCH_1):PAGE185
PR8009    1      A Q_RES_0402LF-0,5%,1/16W,CHIP,CS00002JB13   I143 @T6G_MB_LIB.T6G(SCH_1):PAGE185

SVID_PVDDCR_CPU0_P1_SVC_R1 @T6G_MB_LIB.T6G(SCH_1):SVID_PVDDCR_CPU0_P1_SVC_R1
  PU25   22    SVC RAA229620GNPHA0-RAA229620GNP#HA0,SMLF,IC,ARF0TGP40A   I133 @T6G_MB_LIB.T6G(SCH_1):PAGE185
PR8009    2      B Q_RES_0402LF-0,5%,1/16W,CHIP,CS00002JB13   I143 @T6G_MB_LIB.T6G(SCH_1):PAGE185

SVID_PVDDCR_CPU0_P1_SVD @T6G_MB_LIB.T6G(SCH_1):SVID_PVDDCR_CPU0_P1_SVD
   U26  A22   SVD0 GENOA_SP5-SOCKET6096_13568-001,SMLF,IO,DGA^6000030   I190 @T6G_MB_LIB.T6G(SCH_1):PAGE54
 PR170    2      B Q_RES_0402LF-0,5%,1/16W,CHIP,CS00002JB13   I333 @T6G_MB_LIB.T6G(SCH_1):PAGE54

SVID_PVDDCR_CPU0_P1_SVD_R @T6G_MB_LIB.T6G(SCH_1):SVID_PVDDCR_CPU0_P1_SVD_R
 PR170    1      A Q_RES_0402LF-0,5%,1/16W,CHIP,CS00002JB13   I333 @T6G_MB_LIB.T6G(SCH_1):PAGE54
 R8156    2      B Q_RES_0402LF-1K,1%,1/16W,EMPTY,CS21002FB06    I68 @T6G_MB_LIB.T6G(SCH_1):PAGE185
  C296    1      A Q_CAP_0402-10PF,50V,5%,EMPTY,CH01006JB08    I64 @T6G_MB_LIB.T6G(SCH_1):PAGE185
PR8010    1      A Q_RES_0402LF-0,5%,1/16W,CHIP,CS00002JB13   I144 @T6G_MB_LIB.T6G(SCH_1):PAGE185

SVID_PVDDCR_CPU0_P1_SVD_R1 @T6G_MB_LIB.T6G(SCH_1):SVID_PVDDCR_CPU0_P1_SVD_R1
  PU25   21    SVD RAA229620GNPHA0-RAA229620GNP#HA0,SMLF,IC,ARF0TGP40A   I133 @T6G_MB_LIB.T6G(SCH_1):PAGE185
PR8010    2      B Q_RES_0402LF-0,5%,1/16W,CHIP,CS00002JB13   I144 @T6G_MB_LIB.T6G(SCH_1):PAGE185

SVID_PVDDCR_CPU0_P1_SVTI @T6G_MB_LIB.T6G(SCH_1):SVID_PVDDCR_CPU0_P1_SVTI
 PR150    1      A Q_RES_0402LF-0,5%,1/16W,CHIP,CS00002JB13     I4 @T6G_MB_LIB.T6G(SCH_1):PAGE185
 PR172    1      A Q_RES_0402LF-0,5%,1/16W,CHIP,CS00002JB13    I82 @T6G_MB_LIB.T6G(SCH_1):PAGE185
 PR151    2      B Q_RES_0402LF-1K,1%,1/16W,EMPTY,CS21002FB06    I10 @T6G_MB_LIB.T6G(SCH_1):PAGE185

SVID_PVDDCR_CPU0_P1_SVTI_R @T6G_MB_LIB.T6G(SCH_1):SVID_PVDDCR_CPU0_P1_SVTI_R
 PR172    2      B Q_RES_0402LF-0,5%,1/16W,CHIP,CS00002JB13    I82 @T6G_MB_LIB.T6G(SCH_1):PAGE185
  PU25   24   SVTI RAA229620GNPHA0-RAA229620GNP#HA0,SMLF,IC,ARF0TGP40A   I133 @T6G_MB_LIB.T6G(SCH_1):PAGE185

SVID_PVDDCR_CPU0_P1_SVTO @T6G_MB_LIB.T6G(SCH_1):SVID_PVDDCR_CPU0_P1_SVTO
   U26  B21   SVT0 GENOA_SP5-SOCKET6096_13568-001,SMLF,IO,DGA^6000030   I190 @T6G_MB_LIB.T6G(SCH_1):PAGE54
  C295    1      A Q_CAP_0402-10PF,50V,5%,EMPTY,CH01006JB08    I62 @T6G_MB_LIB.T6G(SCH_1):PAGE185
  R154    2      B Q_RES_0402LF-1K,1%,1/16W,EMPTY,CS21002FB06    I67 @T6G_MB_LIB.T6G(SCH_1):PAGE185
 R8153    1      A Q_RES_0402LF-1K,1%,1/16W,EMPTY,CS21002FB06     I6 @T6G_MB_LIB.T6G(SCH_1):PAGE185
 R8171    1      A Q_RES_0402LF-49.9,1%,1/16W,CHIP,CS04992FB07    I83 @T6G_MB_LIB.T6G(SCH_1):PAGE185

SVID_PVDDCR_CPU0_P1_SVTO_R @T6G_MB_LIB.T6G(SCH_1):SVID_PVDDCR_CPU0_P1_SVTO_R
 R8171    2      B Q_RES_0402LF-49.9,1%,1/16W,CHIP,CS04992FB07    I83 @T6G_MB_LIB.T6G(SCH_1):PAGE185
  PU25   23   SVTO RAA229620GNPHA0-RAA229620GNP#HA0,SMLF,IC,ARF0TGP40A   I133 @T6G_MB_LIB.T6G(SCH_1):PAGE185

SVID_PVDDCR_CPU1_P0_SVC @T6G_MB_LIB.T6G(SCH_1):SVID_PVDDCR_CPU1_P0_SVC
   U25 DJ72   SVC1 GENOA_SP5-SOCKET6096_13568-001,SMLF,IO,DGA^6000030   I227 @T6G_MB_LIB.T6G(SCH_1):PAGE27
  PR59    2      B Q_RES_0402LF-0,5%,1/16W,CHIP,CS00002JB13   I318 @T6G_MB_LIB.T6G(SCH_1):PAGE27

SVID_PVDDCR_CPU1_P0_SVC_R @T6G_MB_LIB.T6G(SCH_1):SVID_PVDDCR_CPU1_P0_SVC_R
  PR59    1      A Q_RES_0402LF-0,5%,1/16W,CHIP,CS00002JB13   I318 @T6G_MB_LIB.T6G(SCH_1):PAGE27
  C305    1      A Q_CAP_0402-10PF,50V,5%,EMPTY,CH01006JB08    I35 @T6G_MB_LIB.T6G(SCH_1):PAGE175
 R8048    2      B Q_RES_0402LF-1K,1%,1/16W,EMPTY,CS21002FB06    I44 @T6G_MB_LIB.T6G(SCH_1):PAGE175
PR8007    1      A Q_RES_0402LF-0,5%,1/16W,CHIP,CS00002JB13   I137 @T6G_MB_LIB.T6G(SCH_1):PAGE175

SVID_PVDDCR_CPU1_P0_SVC_R1 @T6G_MB_LIB.T6G(SCH_1):SVID_PVDDCR_CPU1_P0_SVC_R1
  PU12   22    SVC RAA229620GNPHA0-RAA229620GNP#HA0,SMLF,IC,ARF0TGP40A   I128 @T6G_MB_LIB.T6G(SCH_1):PAGE175
PR8007    2      B Q_RES_0402LF-0,5%,1/16W,CHIP,CS00002JB13   I137 @T6G_MB_LIB.T6G(SCH_1):PAGE175

SVID_PVDDCR_CPU1_P0_SVD @T6G_MB_LIB.T6G(SCH_1):SVID_PVDDCR_CPU1_P0_SVD
   U25 DH72   SVD1 GENOA_SP5-SOCKET6096_13568-001,SMLF,IO,DGA^6000030   I227 @T6G_MB_LIB.T6G(SCH_1):PAGE27
  PR60    2      B Q_RES_0402LF-0,5%,1/16W,CHIP,CS00002JB13   I319 @T6G_MB_LIB.T6G(SCH_1):PAGE27

SVID_PVDDCR_CPU1_P0_SVD_R @T6G_MB_LIB.T6G(SCH_1):SVID_PVDDCR_CPU1_P0_SVD_R
  PR60    1      A Q_RES_0402LF-0,5%,1/16W,CHIP,CS00002JB13   I319 @T6G_MB_LIB.T6G(SCH_1):PAGE27
  C304    1      A Q_CAP_0402-10PF,50V,5%,EMPTY,CH01006JB08    I34 @T6G_MB_LIB.T6G(SCH_1):PAGE175
 R8045    2      B Q_RES_0402LF-1K,1%,1/16W,EMPTY,CS21002FB06    I43 @T6G_MB_LIB.T6G(SCH_1):PAGE175
PR8008    1      A Q_RES_0402LF-0,5%,1/16W,CHIP,CS00002JB13   I136 @T6G_MB_LIB.T6G(SCH_1):PAGE175

SVID_PVDDCR_CPU1_P0_SVD_R1 @T6G_MB_LIB.T6G(SCH_1):SVID_PVDDCR_CPU1_P0_SVD_R1
  PU12   21    SVD RAA229620GNPHA0-RAA229620GNP#HA0,SMLF,IC,ARF0TGP40A   I128 @T6G_MB_LIB.T6G(SCH_1):PAGE175
PR8008    2      B Q_RES_0402LF-0,5%,1/16W,CHIP,CS00002JB13   I136 @T6G_MB_LIB.T6G(SCH_1):PAGE175

SVID_PVDDCR_CPU1_P0_SVTI @T6G_MB_LIB.T6G(SCH_1):SVID_PVDDCR_CPU1_P0_SVTI
  PR40    1      A Q_RES_0402LF-0,5%,1/16W,CHIP,CS00002JB13    I28 @T6G_MB_LIB.T6G(SCH_1):PAGE175
  PR41    2      B Q_RES_0402LF-1K,1%,1/16W,EMPTY,CS21002FB06    I40 @T6G_MB_LIB.T6G(SCH_1):PAGE175
  PR62    1      A Q_RES_0402LF-0,5%,1/16W,CHIP,CS00002JB13    I84 @T6G_MB_LIB.T6G(SCH_1):PAGE175

SVID_PVDDCR_CPU1_P0_SVTI_R @T6G_MB_LIB.T6G(SCH_1):SVID_PVDDCR_CPU1_P0_SVTI_R
  PR62    2      B Q_RES_0402LF-0,5%,1/16W,CHIP,CS00002JB13    I84 @T6G_MB_LIB.T6G(SCH_1):PAGE175
  PU12   24   SVTI RAA229620GNPHA0-RAA229620GNP#HA0,SMLF,IC,ARF0TGP40A   I128 @T6G_MB_LIB.T6G(SCH_1):PAGE175

SVID_PVDDCR_CPU1_P0_SVTO @T6G_MB_LIB.T6G(SCH_1):SVID_PVDDCR_CPU1_P0_SVTO
   U25 DG73   SVT1 GENOA_SP5-SOCKET6096_13568-001,SMLF,IO,DGA^6000030   I227 @T6G_MB_LIB.T6G(SCH_1):PAGE27
 R8042    1      A Q_RES_0402LF-1K,1%,1/16W,EMPTY,CS21002FB06    I32 @T6G_MB_LIB.T6G(SCH_1):PAGE175
  C303    1      A Q_CAP_0402-10PF,50V,5%,EMPTY,CH01006JB08    I33 @T6G_MB_LIB.T6G(SCH_1):PAGE175
 R8043    2      B Q_RES_0402LF-1K,1%,1/16W,EMPTY,CS21002FB06    I42 @T6G_MB_LIB.T6G(SCH_1):PAGE175
   R61    1      A Q_RES_0402LF-49.9,1%,1/16W,CHIP,CS04992FB07    I83 @T6G_MB_LIB.T6G(SCH_1):PAGE175

SVID_PVDDCR_CPU1_P0_SVTO_R @T6G_MB_LIB.T6G(SCH_1):SVID_PVDDCR_CPU1_P0_SVTO_R
   R61    2      B Q_RES_0402LF-49.9,1%,1/16W,CHIP,CS04992FB07    I83 @T6G_MB_LIB.T6G(SCH_1):PAGE175
  PU12   23   SVTO RAA229620GNPHA0-RAA229620GNP#HA0,SMLF,IC,ARF0TGP40A   I128 @T6G_MB_LIB.T6G(SCH_1):PAGE175

SVID_PVDDCR_CPU1_P1_SVC @T6G_MB_LIB.T6G(SCH_1):SVID_PVDDCR_CPU1_P1_SVC
   U26 DJ72   SVC1 GENOA_SP5-SOCKET6096_13568-001,SMLF,IO,DGA^6000030   I190 @T6G_MB_LIB.T6G(SCH_1):PAGE54
 PR236    2      B Q_RES_0402LF-0,5%,1/16W,CHIP,CS00002JB13   I338 @T6G_MB_LIB.T6G(SCH_1):PAGE54

SVID_PVDDCR_CPU1_P1_SVC_R @T6G_MB_LIB.T6G(SCH_1):SVID_PVDDCR_CPU1_P1_SVC_R
 PR236    1      A Q_RES_0402LF-0,5%,1/16W,CHIP,CS00002JB13   I338 @T6G_MB_LIB.T6G(SCH_1):PAGE54
  C310    1      A Q_CAP_0402-10PF,50V,5%,EMPTY,CH01006JB08    I33 @T6G_MB_LIB.T6G(SCH_1):PAGE192
 R8225    2      B Q_RES_0402LF-1K,1%,1/16W,EMPTY,CS21002FB06    I42 @T6G_MB_LIB.T6G(SCH_1):PAGE192
PR8011    1      A Q_RES_0402LF-0,5%,1/16W,CHIP,CS00002JB13   I137 @T6G_MB_LIB.T6G(SCH_1):PAGE192

SVID_PVDDCR_CPU1_P1_SVC_R1 @T6G_MB_LIB.T6G(SCH_1):SVID_PVDDCR_CPU1_P1_SVC_R1
  PU34   22    SVC RAA229620GNPHA0-RAA229620GNP#HA0,SMLF,IC,ARF0TGP40A   I128 @T6G_MB_LIB.T6G(SCH_1):PAGE192
PR8011    2      B Q_RES_0402LF-0,5%,1/16W,CHIP,CS00002JB13   I137 @T6G_MB_LIB.T6G(SCH_1):PAGE192

SVID_PVDDCR_CPU1_P1_SVD @T6G_MB_LIB.T6G(SCH_1):SVID_PVDDCR_CPU1_P1_SVD
   U26 DH72   SVD1 GENOA_SP5-SOCKET6096_13568-001,SMLF,IO,DGA^6000030   I190 @T6G_MB_LIB.T6G(SCH_1):PAGE54
 PR237    2      B Q_RES_0402LF-0,5%,1/16W,CHIP,CS00002JB13   I337 @T6G_MB_LIB.T6G(SCH_1):PAGE54

SVID_PVDDCR_CPU1_P1_SVD_R @T6G_MB_LIB.T6G(SCH_1):SVID_PVDDCR_CPU1_P1_SVD_R
 PR237    1      A Q_RES_0402LF-0,5%,1/16W,CHIP,CS00002JB13   I337 @T6G_MB_LIB.T6G(SCH_1):PAGE54
  C309    1      A Q_CAP_0402-10PF,50V,5%,EMPTY,CH01006JB08    I32 @T6G_MB_LIB.T6G(SCH_1):PAGE192
 R8222    2      B Q_RES_0402LF-1K,1%,1/16W,EMPTY,CS21002FB06    I41 @T6G_MB_LIB.T6G(SCH_1):PAGE192
PR8012    1      A Q_RES_0402LF-0,5%,1/16W,CHIP,CS00002JB13   I138 @T6G_MB_LIB.T6G(SCH_1):PAGE192

SVID_PVDDCR_CPU1_P1_SVD_R1 @T6G_MB_LIB.T6G(SCH_1):SVID_PVDDCR_CPU1_P1_SVD_R1
  PU34   21    SVD RAA229620GNPHA0-RAA229620GNP#HA0,SMLF,IC,ARF0TGP40A   I128 @T6G_MB_LIB.T6G(SCH_1):PAGE192
PR8012    2      B Q_RES_0402LF-0,5%,1/16W,CHIP,CS00002JB13   I138 @T6G_MB_LIB.T6G(SCH_1):PAGE192

SVID_PVDDCR_CPU1_P1_SVTI @T6G_MB_LIB.T6G(SCH_1):SVID_PVDDCR_CPU1_P1_SVTI
 PR217    1      A Q_RES_0402LF-0,5%,1/16W,CHIP,CS00002JB13    I29 @T6G_MB_LIB.T6G(SCH_1):PAGE192
 PR218    2      B Q_RES_0402LF-1K,1%,1/16W,EMPTY,CS21002FB06    I38 @T6G_MB_LIB.T6G(SCH_1):PAGE192
 PR239    1      A Q_RES_0402LF-0,5%,1/16W,CHIP,CS00002JB13    I83 @T6G_MB_LIB.T6G(SCH_1):PAGE192

SVID_PVDDCR_CPU1_P1_SVTI_R @T6G_MB_LIB.T6G(SCH_1):SVID_PVDDCR_CPU1_P1_SVTI_R
 PR239    2      B Q_RES_0402LF-0,5%,1/16W,CHIP,CS00002JB13    I83 @T6G_MB_LIB.T6G(SCH_1):PAGE192
  PU34   24   SVTI RAA229620GNPHA0-RAA229620GNP#HA0,SMLF,IC,ARF0TGP40A   I128 @T6G_MB_LIB.T6G(SCH_1):PAGE192

SVID_PVDDCR_CPU1_P1_SVTO @T6G_MB_LIB.T6G(SCH_1):SVID_PVDDCR_CPU1_P1_SVTO
   U26 DG73   SVT1 GENOA_SP5-SOCKET6096_13568-001,SMLF,IO,DGA^6000030   I190 @T6G_MB_LIB.T6G(SCH_1):PAGE54
 R8219    1      A Q_RES_0402LF-1K,1%,1/16W,EMPTY,CS21002FB06    I30 @T6G_MB_LIB.T6G(SCH_1):PAGE192
  C308    1      A Q_CAP_0402-10PF,50V,5%,EMPTY,CH01006JB08    I31 @T6G_MB_LIB.T6G(SCH_1):PAGE192
 R8220    2      B Q_RES_0402LF-1K,1%,1/16W,EMPTY,CS21002FB06    I40 @T6G_MB_LIB.T6G(SCH_1):PAGE192
 R8238    1      A Q_RES_0402LF-49.9,1%,1/16W,CHIP,CS04992FB07    I82 @T6G_MB_LIB.T6G(SCH_1):PAGE192

SVID_PVDDCR_CPU1_P1_SVTO_R @T6G_MB_LIB.T6G(SCH_1):SVID_PVDDCR_CPU1_P1_SVTO_R
 R8238    2      B Q_RES_0402LF-49.9,1%,1/16W,CHIP,CS04992FB07    I82 @T6G_MB_LIB.T6G(SCH_1):PAGE192
  PU34   23   SVTO RAA229620GNPHA0-RAA229620GNP#HA0,SMLF,IC,ARF0TGP40A   I128 @T6G_MB_LIB.T6G(SCH_1):PAGE192

SWB_HSC_EN @T6G_MB_LIB.T6G(SCH_1):SWB_HSC_EN
  U316    1     A0 74LVC2G17GW-74LVC2G17GW,SMLF,IC,AL2G0017005    I86 @T6G_MB_LIB.T6G(SCH_1):PAGE331
 R4548    1      A Q_RES_0402LF-100K,1%,1/16W,CHIP,CS41002FB09    I87 @T6G_MB_LIB.T6G(SCH_1):PAGE331
 R4547    2      B Q_RES_0402LF-100K,1%,1/16W,EMPTY,CS41002FB09    I89 @T6G_MB_LIB.T6G(SCH_1):PAGE331
 R4558    2      B Q_RES_0402LF-33.2,1%,1/16W,CHIP,CS03322FB03   I228 @T6G_MB_LIB.T6G(SCH_1):PAGE80

SWB_HSC_EN_BUF @T6G_MB_LIB.T6G(SCH_1):SWB_HSC_EN_BUF
 R4550    2      B Q_RES_0402LF-49.9,1%,1/16W,CHIP,CS04992FB07    I97 @T6G_MB_LIB.T6G(SCH_1):PAGE331
  J107   N8     N8 CONN112_10137002101LF-CONN112_10137002-101LF,THLF,A    I70 @T6G_MB_LIB.T6G(SCH_1):PAGE317

SWB_HSC_EN_BUF_R @T6G_MB_LIB.T6G(SCH_1):SWB_HSC_EN_BUF_R
  U316    6     B0 74LVC2G17GW-74LVC2G17GW,SMLF,IC,AL2G0017005    I86 @T6G_MB_LIB.T6G(SCH_1):PAGE331
 R4550    1      A Q_RES_0402LF-49.9,1%,1/16W,CHIP,CS04992FB07    I97 @T6G_MB_LIB.T6G(SCH_1):PAGE331
 R4549    2      B Q_RES_0402LF-4.7K,5%,1/16W,EMPTY,CS24702JB10    I98 @T6G_MB_LIB.T6G(SCH_1):PAGE331
 R4555    1      A Q_RES_0402LF-4.7K,5%,1/16W,EMPTY,CS24702JB10    I99 @T6G_MB_LIB.T6G(SCH_1):PAGE331

SWB_HSC_EN_R @T6G_MB_LIB.T6G(SCH_1):SWB_HSC_EN_R
   U18  Y13  PB30C LCMXO3LF9400C5BG484C-LCMXO3LF-9400C-5BG484C,SMLF,IA   I216 @T6G_MB_LIB.T6G(SCH_1):PAGE80
 R4558    1      A Q_RES_0402LF-33.2,1%,1/16W,CHIP,CS03322FB03   I228 @T6G_MB_LIB.T6G(SCH_1):PAGE80

SWB_HSC_PWRGD @T6G_MB_LIB.T6G(SCH_1):SWB_HSC_PWRGD
  J107   A7     A7 CONN112_10137002101LF-CONN112_10137002-101LF,THLF,A    I70 @T6G_MB_LIB.T6G(SCH_1):PAGE317
 R4559    1      A Q_RES_0402LF-100K,1%,1/16W,CHIP,CS41002FB09    I54 @T6G_MB_LIB.T6G(SCH_1):PAGE332
 R4562    2      B Q_RES_0402LF-100K,1%,1/16W,EMPTY,CS41002FB09    I55 @T6G_MB_LIB.T6G(SCH_1):PAGE332
  Q146    2     G1 MOSFET_NCH_DUAL-PJT138K,SMLF,IC,BAM138K0003    I57 @T6G_MB_LIB.T6G(SCH_1):PAGE332

SWB_HSC_PWRGD_ISO @T6G_MB_LIB.T6G(SCH_1):SWB_HSC_PWRGD_ISO
 R4563    2      B Q_RES_0402LF-33.2,1%,1/16W,CHIP,CS03322FB03   I243 @T6G_MB_LIB.T6G(SCH_1):PAGE80
   C18    1      A Q_CAP_0402-0.1UF,25V,10%,X7R,CH4104K1B00    I61 @T6G_MB_LIB.T6G(SCH_1):PAGE332
 R4561    2      B Q_RES_0402LF-100K,1%,1/16W,CHIP,CS41002FB09   I110 @T6G_MB_LIB.T6G(SCH_1):PAGE332
  Q146    3     D2 MOSFET_NCH_DUAL-PJT138K,SMLF,IC,BAM138K0003   I134 @T6G_MB_LIB.T6G(SCH_1):PAGE332

SWB_HSC_PWRGD_ISO_R @T6G_MB_LIB.T6G(SCH_1):SWB_HSC_PWRGD_ISO_R
   U18  Y14  PB33C LCMXO3LF9400C5BG484C-LCMXO3LF-9400C-5BG484C,SMLF,IA   I216 @T6G_MB_LIB.T6G(SCH_1):PAGE80
 R4563    1      A Q_RES_0402LF-33.2,1%,1/16W,CHIP,CS03322FB03   I243 @T6G_MB_LIB.T6G(SCH_1):PAGE80

SWB_HSC_PWRGD_N @T6G_MB_LIB.T6G(SCH_1):SWB_HSC_PWRGD_N
  Q146    6     D1 MOSFET_NCH_DUAL-PJT138K,SMLF,IC,BAM138K0003    I57 @T6G_MB_LIB.T6G(SCH_1):PAGE332
 R4560    2      B Q_RES_0402LF-4.7K,5%,1/16W,CHIP,CS24702JB10    I62 @T6G_MB_LIB.T6G(SCH_1):PAGE332
  Q146    5     G2 MOSFET_NCH_DUAL-PJT138K,SMLF,IC,BAM138K0003   I134 @T6G_MB_LIB.T6G(SCH_1):PAGE332

SW_P0V9_RETIMER_CPU0_BOOT1 @T6G_MB_LIB.T6G(SCH_1):SW_P0V9_RETIMER_CPU0_BOOT1
PU6503   33   BOOT ISL99390FRZTR5935-ISL99390FRZ-TR5935,SMLF,IC,AL099A    I53 @T6G_MB_LIB.T6G(SCH_1):PAGE476
PR6554    1      A Q_RES_0402LF-5.6,1%,1/16W,CHIP,CS-5602FB01   I221 @T6G_MB_LIB.T6G(SCH_1):PAGE476

SW_P0V9_RETIMER_CPU0_BOOT1_RC @T6G_MB_LIB.T6G(SCH_1):SW_P0V9_RETIMER_CPU0_BOOT1_RC
PC6563    1      A Q_CAP_C0402-100NF,50V,10%,X7R,CH4106K1B01    I30 @T6G_MB_LIB.T6G(SCH_1):PAGE476
PR6554    2      B Q_RES_0402LF-5.6,1%,1/16W,CHIP,CS-5602FB01   I221 @T6G_MB_LIB.T6G(SCH_1):PAGE476

SW_P0V9_RETIMER_CPU0_BOOT2 @T6G_MB_LIB.T6G(SCH_1):SW_P0V9_RETIMER_CPU0_BOOT2
PR6562    1      A Q_RES_0402LF-5.6,1%,1/16W,CHIP,CS-5602FB01   I262 @T6G_MB_LIB.T6G(SCH_1):PAGE476
PU6504   33   BOOT ISL99390FRZTR5935-ISL99390FRZ-TR5935,SMLF,IC,AL099A   I270 @T6G_MB_LIB.T6G(SCH_1):PAGE476

SW_P0V9_RETIMER_CPU0_BOOT2_RC @T6G_MB_LIB.T6G(SCH_1):SW_P0V9_RETIMER_CPU0_BOOT2_RC
PC6584    1      A Q_CAP_C0402-100NF,50V,10%,X7R,CH4106K1B01   I253 @T6G_MB_LIB.T6G(SCH_1):PAGE476
PR6562    2      B Q_RES_0402LF-5.6,1%,1/16W,CHIP,CS-5602FB01   I262 @T6G_MB_LIB.T6G(SCH_1):PAGE476

SW_P0V9_RETIMER_CPU0_PH1 @T6G_MB_LIB.T6G(SCH_1):SW_P0V9_RETIMER_CPU0_PH1
PC6563    2      B Q_CAP_C0402-100NF,50V,10%,X7R,CH4106K1B01    I30 @T6G_MB_LIB.T6G(SCH_1):PAGE476
PU6503   32  PHASE ISL99390FRZTR5935-ISL99390FRZ-TR5935,SMLF,IC,AL099A    I53 @T6G_MB_LIB.T6G(SCH_1):PAGE476

SW_P0V9_RETIMER_CPU0_PH2 @T6G_MB_LIB.T6G(SCH_1):SW_P0V9_RETIMER_CPU0_PH2
PC6584    2      B Q_CAP_C0402-100NF,50V,10%,X7R,CH4106K1B01   I253 @T6G_MB_LIB.T6G(SCH_1):PAGE476
PU6504   32  PHASE ISL99390FRZTR5935-ISL99390FRZ-TR5935,SMLF,IC,AL099A   I270 @T6G_MB_LIB.T6G(SCH_1):PAGE476

SW_P0V9_RETIMER_CPU0_SW1 @T6G_MB_LIB.T6G(SCH_1):SW_P0V9_RETIMER_CPU0_SW1
PL6505    1      1 Q_INDUCTOR_SMLF-120NH/69A,IND,CV+12^0EZ03    I34 @T6G_MB_LIB.T6G(SCH_1):PAGE476
PU6503 10_19     SW ISL99390FRZTR5935-ISL99390FRZ-TR5935,SMLF,IC,AL099A    I53 @T6G_MB_LIB.T6G(SCH_1):PAGE476
PC6564    1      A Q_CAP_C0402-560PF,50V,10%,EMPTY,CH1566K1B09   I285 @T6G_MB_LIB.T6G(SCH_1):PAGE476

SW_P0V9_RETIMER_CPU0_SW1_RC @T6G_MB_LIB.T6G(SCH_1):SW_P0V9_RETIMER_CPU0_SW1_RC
PR6555    1      A Q_RES_0402LF-1.5,1%,1/8W,EMPTY,CS-1504FB00   I283 @T6G_MB_LIB.T6G(SCH_1):PAGE476
PC6564    2      B Q_CAP_C0402-560PF,50V,10%,EMPTY,CH1566K1B09   I285 @T6G_MB_LIB.T6G(SCH_1):PAGE476

SW_P0V9_RETIMER_CPU0_SW2 @T6G_MB_LIB.T6G(SCH_1):SW_P0V9_RETIMER_CPU0_SW2
PL6506    1      1 Q_INDUCTOR_SMLF-120NH/69A,IND,CV+12^0EZ03   I257 @T6G_MB_LIB.T6G(SCH_1):PAGE476
PU6504 10_19     SW ISL99390FRZTR5935-ISL99390FRZ-TR5935,SMLF,IC,AL099A   I270 @T6G_MB_LIB.T6G(SCH_1):PAGE476
PC6585    1      A Q_CAP_C0402-560PF,50V,10%,EMPTY,CH1566K1B09   I288 @T6G_MB_LIB.T6G(SCH_1):PAGE476

SW_P0V9_RETIMER_CPU0_SW2_RC @T6G_MB_LIB.T6G(SCH_1):SW_P0V9_RETIMER_CPU0_SW2_RC
PR6563    1      A Q_RES_0402LF-1.5,1%,1/8W,EMPTY,CS-1504FB00   I286 @T6G_MB_LIB.T6G(SCH_1):PAGE476
PC6585    2      B Q_CAP_C0402-560PF,50V,10%,EMPTY,CH1566K1B09   I288 @T6G_MB_LIB.T6G(SCH_1):PAGE476

SW_P0V9_RETIMER_CPU1_BOOT1 @T6G_MB_LIB.T6G(SCH_1):SW_P0V9_RETIMER_CPU1_BOOT1
PU6511   33   BOOT ISL99390FRZTR5935-ISL99390FRZ-TR5935,SMLF,IC,AL099A    I51 @T6G_MB_LIB.T6G(SCH_1):PAGE478
PR6623    1      A Q_RES_0402LF-5.6,1%,1/16W,CHIP,CS-5602FB01    I62 @T6G_MB_LIB.T6G(SCH_1):PAGE478

SW_P0V9_RETIMER_CPU1_BOOT1_RC @T6G_MB_LIB.T6G(SCH_1):SW_P0V9_RETIMER_CPU1_BOOT1_RC
PR6623    2      B Q_RES_0402LF-5.6,1%,1/16W,CHIP,CS-5602FB01    I62 @T6G_MB_LIB.T6G(SCH_1):PAGE478
PC6621    1      A Q_CAP_C0402-100NF,50V,10%,X7R,CH4106K1B01    I76 @T6G_MB_LIB.T6G(SCH_1):PAGE478

SW_P0V9_RETIMER_CPU1_BOOT2 @T6G_MB_LIB.T6G(SCH_1):SW_P0V9_RETIMER_CPU1_BOOT2
PU6512   33   BOOT ISL99390FRZTR5935-ISL99390FRZ-TR5935,SMLF,IC,AL099A    I12 @T6G_MB_LIB.T6G(SCH_1):PAGE478
PR6629    1      A Q_RES_0402LF-5.6,1%,1/16W,CHIP,CS-5602FB01    I19 @T6G_MB_LIB.T6G(SCH_1):PAGE478

SW_P0V9_RETIMER_CPU1_BOOT2_RC @T6G_MB_LIB.T6G(SCH_1):SW_P0V9_RETIMER_CPU1_BOOT2_RC
PR6629    2      B Q_RES_0402LF-5.6,1%,1/16W,CHIP,CS-5602FB01    I19 @T6G_MB_LIB.T6G(SCH_1):PAGE478
PC6640    1      A Q_CAP_C0402-100NF,50V,10%,X7R,CH4106K1B01    I26 @T6G_MB_LIB.T6G(SCH_1):PAGE478

SW_P0V9_RETIMER_CPU1_PH1 @T6G_MB_LIB.T6G(SCH_1):SW_P0V9_RETIMER_CPU1_PH1
PU6511   32  PHASE ISL99390FRZTR5935-ISL99390FRZ-TR5935,SMLF,IC,AL099A    I51 @T6G_MB_LIB.T6G(SCH_1):PAGE478
PC6621    2      B Q_CAP_C0402-100NF,50V,10%,X7R,CH4106K1B01    I76 @T6G_MB_LIB.T6G(SCH_1):PAGE478

SW_P0V9_RETIMER_CPU1_PH2 @T6G_MB_LIB.T6G(SCH_1):SW_P0V9_RETIMER_CPU1_PH2
PU6512   32  PHASE ISL99390FRZTR5935-ISL99390FRZ-TR5935,SMLF,IC,AL099A    I12 @T6G_MB_LIB.T6G(SCH_1):PAGE478
PC6640    2      B Q_CAP_C0402-100NF,50V,10%,X7R,CH4106K1B01    I26 @T6G_MB_LIB.T6G(SCH_1):PAGE478

SW_P0V9_RETIMER_CPU1_SW1 @T6G_MB_LIB.T6G(SCH_1):SW_P0V9_RETIMER_CPU1_SW1
PU6511 10_19     SW ISL99390FRZTR5935-ISL99390FRZ-TR5935,SMLF,IC,AL099A    I51 @T6G_MB_LIB.T6G(SCH_1):PAGE478
PL6511    1      1 Q_INDUCTOR_SMLF-120NH/69A,IND,CV+12^0EZ03    I65 @T6G_MB_LIB.T6G(SCH_1):PAGE478
PC6622    1      A Q_CAP_C0402-560PF,50V,10%,EMPTY,CH1566K1B09   I108 @T6G_MB_LIB.T6G(SCH_1):PAGE478

SW_P0V9_RETIMER_CPU1_SW1_RC @T6G_MB_LIB.T6G(SCH_1):SW_P0V9_RETIMER_CPU1_SW1_RC
PR6624    1      A Q_RES_0402LF-1.5,1%,1/8W,EMPTY,CS-1504FB00   I106 @T6G_MB_LIB.T6G(SCH_1):PAGE478
PC6622    2      B Q_CAP_C0402-560PF,50V,10%,EMPTY,CH1566K1B09   I108 @T6G_MB_LIB.T6G(SCH_1):PAGE478

SW_P0V9_RETIMER_CPU1_SW2 @T6G_MB_LIB.T6G(SCH_1):SW_P0V9_RETIMER_CPU1_SW2
PU6512 10_19     SW ISL99390FRZTR5935-ISL99390FRZ-TR5935,SMLF,IC,AL099A    I12 @T6G_MB_LIB.T6G(SCH_1):PAGE478
PL6512    1      1 Q_INDUCTOR_SMLF-120NH/69A,IND,CV+12^0EZ03    I22 @T6G_MB_LIB.T6G(SCH_1):PAGE478
PC6641    1      A Q_CAP_C0402-560PF,50V,10%,EMPTY,CH1566K1B09   I109 @T6G_MB_LIB.T6G(SCH_1):PAGE478

SW_P0V9_RETIMER_CPU1_SW2_RC @T6G_MB_LIB.T6G(SCH_1):SW_P0V9_RETIMER_CPU1_SW2_RC
PC6641    2      B Q_CAP_C0402-560PF,50V,10%,EMPTY,CH1566K1B09   I109 @T6G_MB_LIB.T6G(SCH_1):PAGE478
PR6630    1      A Q_RES_0402LF-1.5,1%,1/8W,EMPTY,CS-1504FB00   I110 @T6G_MB_LIB.T6G(SCH_1):PAGE478

SW_P12V_AUX_P0V9_RETIMER_CPU0_FLT @T6G_MB_LIB.T6G(SCH_1):SW_P12V_AUX_P0V9_RETIMER_CPU0_FLT
PC6555_1    1      A Q_CAP_0402-3300PF,50V,10%,X7R,TMP_QCH2336K1B12     I6 @T6G_MB_LIB.T6G(SCH_1):PAGE476
PC6558_1    1      A Q_CAP_C0805-22UF,16V,20%,X6S,CH6223MEA01    I21 @T6G_MB_LIB.T6G(SCH_1):PAGE476
PC6557_1    1      A Q_CAP_C0805-22UF,16V,20%,X6S,CH6223MEA01    I24 @T6G_MB_LIB.T6G(SCH_1):PAGE476
PC6556_1    1      A Q_CAP_C0805-22UF,16V,20%,X6S,CH6223MEA01    I27 @T6G_MB_LIB.T6G(SCH_1):PAGE476
PC6554_1    1      A Q_CAP_C0402-1UF,25V,10%,X6S,CH5104KEB02    I29 @T6G_MB_LIB.T6G(SCH_1):PAGE476
PU6503 25_29   VIN1 ISL99390FRZTR5935-ISL99390FRZ-TR5935,SMLF,IC,AL099A    I53 @T6G_MB_LIB.T6G(SCH_1):PAGE476
PU6503   30   VIN2 ISL99390FRZTR5935-ISL99390FRZ-TR5935,SMLF,IC,AL099A    I53 @T6G_MB_LIB.T6G(SCH_1):PAGE476
PL6504    1      1 Q_INDUCTOR_SMLF-100NH/16A,IND,CV+10G0MZ04   I182 @T6G_MB_LIB.T6G(SCH_1):PAGE476
PC6561    1      A Q_CAPP_SMLF-100UF,16V,20%,OSCON,CC71003MZ30   I209 @T6G_MB_LIB.T6G(SCH_1):PAGE476
PC6559_1    1      A Q_CAP_C0805-22UF,16V,20%,X6S,CH6223MEA01   I210 @T6G_MB_LIB.T6G(SCH_1):PAGE476
PC6816    1      A Q_CAP_C0805-22UF,16V,20%,X6S,CH6223MEA01   I216 @T6G_MB_LIB.T6G(SCH_1):PAGE476
PC6560    1      A Q_CAP_C0805-22UF,16V,20%,X6S,CH6223MEA01   I217 @T6G_MB_LIB.T6G(SCH_1):PAGE476
PC6810    1      A Q_CAPP_SMLF-100UF,16V,20%,OSCON,CC71003MZ30   I231 @T6G_MB_LIB.T6G(SCH_1):PAGE476
PC6817    1      A Q_CAP_C0805-22UF,16V,20%,X6S,CH6223MEA01   I232 @T6G_MB_LIB.T6G(SCH_1):PAGE476
PC6583    1      A Q_CAP_C0805-22UF,16V,20%,X6S,CH6223MEA01   I241 @T6G_MB_LIB.T6G(SCH_1):PAGE476
PC6582_2    1      A Q_CAP_C0805-22UF,16V,20%,X6S,CH6223MEA01   I242 @T6G_MB_LIB.T6G(SCH_1):PAGE476
PC6581_2    1      A Q_CAP_C0805-22UF,16V,20%,X6S,CH6223MEA01   I243 @T6G_MB_LIB.T6G(SCH_1):PAGE476
PC6580_2    1      A Q_CAP_C0805-22UF,16V,20%,X6S,CH6223MEA01   I244 @T6G_MB_LIB.T6G(SCH_1):PAGE476
PC6579_2    1      A Q_CAP_C0805-22UF,16V,20%,X6S,CH6223MEA01   I245 @T6G_MB_LIB.T6G(SCH_1):PAGE476
PC6577_2    1      A Q_CAP_C0402-1UF,25V,10%,X6S,CH5104KEB02   I258 @T6G_MB_LIB.T6G(SCH_1):PAGE476
PC6578_2    1      A Q_CAP_0402-3300PF,50V,10%,X7R,TMP_QCH2336K1B12   I259 @T6G_MB_LIB.T6G(SCH_1):PAGE476
PU6504 25_29   VIN1 ISL99390FRZTR5935-ISL99390FRZ-TR5935,SMLF,IC,AL099A   I270 @T6G_MB_LIB.T6G(SCH_1):PAGE476
PU6504   30   VIN2 ISL99390FRZTR5935-ISL99390FRZ-TR5935,SMLF,IC,AL099A   I270 @T6G_MB_LIB.T6G(SCH_1):PAGE476

SW_P12V_AUX_P0V9_RETIMER_CPU1_FLT @T6G_MB_LIB.T6G(SCH_1):SW_P12V_AUX_P0V9_RETIMER_CPU1_FLT
PU6512 25_29   VIN1 ISL99390FRZTR5935-ISL99390FRZ-TR5935,SMLF,IC,AL099A    I12 @T6G_MB_LIB.T6G(SCH_1):PAGE478
PU6512   30   VIN2 ISL99390FRZTR5935-ISL99390FRZ-TR5935,SMLF,IC,AL099A    I12 @T6G_MB_LIB.T6G(SCH_1):PAGE478
PC6634_2    1      A Q_CAP_0402-3300PF,50V,10%,X7R,TMP_QCH2336K1B12    I18 @T6G_MB_LIB.T6G(SCH_1):PAGE478
PC6633_2    1      A Q_CAP_C0402-1UF,25V,10%,X6S,CH5104KEB02    I21 @T6G_MB_LIB.T6G(SCH_1):PAGE478
PC6635_2    1      A Q_CAP_C0805-22UF,16V,20%,X6S,CH6223MEA01    I25 @T6G_MB_LIB.T6G(SCH_1):PAGE478
PC6636_2    1      A Q_CAP_C0805-22UF,16V,20%,X6S,CH6223MEA01    I28 @T6G_MB_LIB.T6G(SCH_1):PAGE478
PC6637_2    1      A Q_CAP_C0805-22UF,16V,20%,X6S,CH6223MEA01    I35 @T6G_MB_LIB.T6G(SCH_1):PAGE478
PC6638_2    1      A Q_CAP_C0805-22UF,16V,20%,X6S,CH6223MEA01    I36 @T6G_MB_LIB.T6G(SCH_1):PAGE478
PC6639    1      A Q_CAP_C0805-22UF,16V,20%,X6S,CH6223MEA01    I38 @T6G_MB_LIB.T6G(SCH_1):PAGE478
PU6511 25_29   VIN1 ISL99390FRZTR5935-ISL99390FRZ-TR5935,SMLF,IC,AL099A    I51 @T6G_MB_LIB.T6G(SCH_1):PAGE478
PU6511   30   VIN2 ISL99390FRZTR5935-ISL99390FRZ-TR5935,SMLF,IC,AL099A    I51 @T6G_MB_LIB.T6G(SCH_1):PAGE478
PC6613_1    1      A Q_CAP_0402-3300PF,50V,10%,X7R,TMP_QCH2336K1B12    I61 @T6G_MB_LIB.T6G(SCH_1):PAGE478
PC6612_1    1      A Q_CAP_C0402-1UF,25V,10%,X6S,CH5104KEB02    I64 @T6G_MB_LIB.T6G(SCH_1):PAGE478
PC6614_1    1      A Q_CAP_C0805-22UF,16V,20%,X6S,CH6223MEA01    I72 @T6G_MB_LIB.T6G(SCH_1):PAGE478
PC6615_1    1      A Q_CAP_C0805-22UF,16V,20%,X6S,CH6223MEA01    I74 @T6G_MB_LIB.T6G(SCH_1):PAGE478
PC6616_1    1      A Q_CAP_C0805-22UF,16V,20%,X6S,CH6223MEA01    I77 @T6G_MB_LIB.T6G(SCH_1):PAGE478
PC6617_1    1      A Q_CAP_C0805-22UF,16V,20%,X6S,CH6223MEA01    I79 @T6G_MB_LIB.T6G(SCH_1):PAGE478
PC6618    1      A Q_CAP_C0805-22UF,16V,20%,X6S,CH6223MEA01    I80 @T6G_MB_LIB.T6G(SCH_1):PAGE478
PC6818    1      A Q_CAP_C0805-22UF,16V,20%,X6S,CH6223MEA01    I86 @T6G_MB_LIB.T6G(SCH_1):PAGE478
 PC473    1      A Q_CAPP_SMLF-100UF,16V,20%,OSCON,CC71003MZ30    I88 @T6G_MB_LIB.T6G(SCH_1):PAGE478
PC6819    1      A Q_CAP_C0805-22UF,16V,20%,X6S,CH6223MEA01   I100 @T6G_MB_LIB.T6G(SCH_1):PAGE478
PC6619    1      A Q_CAPP_SMLF-100UF,16V,20%,OSCON,CC71003MZ30   I102 @T6G_MB_LIB.T6G(SCH_1):PAGE478
PL6510    1      1 Q_INDUCTOR_SMLF-100NH/16A,IND,CV+10G0MZ04   I104 @T6G_MB_LIB.T6G(SCH_1):PAGE478

SW_P12V_AUX_P1V2_AUX_FLT @T6G_MB_LIB.T6G(SCH_1):SW_P12V_AUX_P1V2_AUX_FLT
PL6003    2      2 Q_INDUCTOR_SMLF-BLM18SN220TN1D/8000MA,IND,CX220TN1A     I2 @T6G_MB_LIB.T6G(SCH_1):PAGE380
PC6013    1      A Q_CAP_C0805-22UF,16V,20%,X6S,CH6223MEA01     I3 @T6G_MB_LIB.T6G(SCH_1):PAGE380
PC6015    1      A Q_CAP_C0805-22UF,16V,20%,X6S,CH6223MEA01    I10 @T6G_MB_LIB.T6G(SCH_1):PAGE380
PC6011    1      A Q_CAP_C0402-1UF,25V,10%,X6S,CH5104KEB02    I12 @T6G_MB_LIB.T6G(SCH_1):PAGE380
PU6001    3    VIN MPQ8626GDZ-MPQ8626GD-Z,SMLF,IC,AL008626000    I16 @T6G_MB_LIB.T6G(SCH_1):PAGE380

SW_P12V_AUX_P1V8_AUX_FLT @T6G_MB_LIB.T6G(SCH_1):SW_P12V_AUX_P1V8_AUX_FLT
PL6002    2      2 Q_INDUCTOR_SMLF-BLM18SN220TN1D/8000MA,IND,CX220TN1A     I7 @T6G_MB_LIB.T6G(SCH_1):PAGE315
PC6012    1      A Q_CAP_C0805-22UF,16V,20%,X6S,CH6223MEA01     I8 @T6G_MB_LIB.T6G(SCH_1):PAGE315
PC6014    1      A Q_CAP_C0805-22UF,16V,20%,X6S,CH6223MEA01    I10 @T6G_MB_LIB.T6G(SCH_1):PAGE315
PU6000    3    VIN MPQ8626GDZ-MPQ8626GD-Z,SMLF,IC,AL008626000    I18 @T6G_MB_LIB.T6G(SCH_1):PAGE315
PC6010    1      A Q_CAP_C0402-1UF,25V,10%,X6S,CH5104KEB02    I19 @T6G_MB_LIB.T6G(SCH_1):PAGE315

SW_P12V_AUX_P1V8_RETIMER_CPU0_FLT @T6G_MB_LIB.T6G(SCH_1):SW_P12V_AUX_P1V8_RETIMER_CPU0_FLT
PC6800    1      A Q_CAPP_SMLF-270UF,16V,20%,OSCON,CC72703MZ11     I6 @T6G_MB_LIB.T6G(SCH_1):PAGE469
PC6802    1      A Q_CAP_C0805-22UF,16V,20%,X6S,CH6223MEA01     I7 @T6G_MB_LIB.T6G(SCH_1):PAGE469
PL6500    2      2 Q_INDUCTOR_SMLF-100NH/16A,IND,CV+10G0MZ04     I9 @T6G_MB_LIB.T6G(SCH_1):PAGE469
PC6501    1      A Q_CAP_C0805-22UF,16V,20%,X6S,CH6223MEA01    I16 @T6G_MB_LIB.T6G(SCH_1):PAGE469
PC6502    1      A Q_CAP_C0805-22UF,16V,20%,X6S,CH6223MEA01    I17 @T6G_MB_LIB.T6G(SCH_1):PAGE469
PC6503    1      A Q_CAP_C0805-22UF,16V,20%,X6S,CH6223MEA01    I18 @T6G_MB_LIB.T6G(SCH_1):PAGE469
PC6504    1      A Q_CAP_C0805-22UF,16V,20%,X6S,CH6223MEA01    I22 @T6G_MB_LIB.T6G(SCH_1):PAGE469
PC6505    1      A Q_CAP_C0402-1UF,25V,10%,X6S,CH5104KEB02    I23 @T6G_MB_LIB.T6G(SCH_1):PAGE469
PU6500   10   VIN1 MPQ8633BGLEC838Z-MPQ8633BGLE-C838-Z,SMLF,IC,AL0086A    I51 @T6G_MB_LIB.T6G(SCH_1):PAGE469
PU6500   21   VIN2 MPQ8633BGLEC838Z-MPQ8633BGLE-C838-Z,SMLF,IC,AL0086A    I51 @T6G_MB_LIB.T6G(SCH_1):PAGE469
PC6902    1      A Q_CAP_C0805-22UF,16V,20%,X6S,CH6223MEA01    I56 @T6G_MB_LIB.T6G(SCH_1):PAGE469
PC6901    1      A Q_CAP_C0805-22UF,16V,20%,X6S,CH6223MEA01    I57 @T6G_MB_LIB.T6G(SCH_1):PAGE469
PC6900    1      A Q_CAP_C0805-22UF,16V,20%,X6S,CH6223MEA01    I58 @T6G_MB_LIB.T6G(SCH_1):PAGE469

SW_P12V_AUX_P1V8_RETIMER_CPU1_FLT @T6G_MB_LIB.T6G(SCH_1):SW_P12V_AUX_P1V8_RETIMER_CPU1_FLT
PC6801    1      A Q_CAPP_SMLF-270UF,16V,20%,OSCON,CC72703MZ11     I6 @T6G_MB_LIB.T6G(SCH_1):PAGE470
PC6803    1      A Q_CAP_C0805-22UF,16V,20%,X6S,CH6223MEA01     I7 @T6G_MB_LIB.T6G(SCH_1):PAGE470
PL6503    2      2 Q_INDUCTOR_SMLF-100NH/16A,IND,CV+10G0MZ04     I9 @T6G_MB_LIB.T6G(SCH_1):PAGE470
PC6520    1      A Q_CAP_C0805-22UF,16V,20%,X6S,CH6223MEA01    I16 @T6G_MB_LIB.T6G(SCH_1):PAGE470
PC6521    1      A Q_CAP_C0805-22UF,16V,20%,X6S,CH6223MEA01    I17 @T6G_MB_LIB.T6G(SCH_1):PAGE470
PC6522    1      A Q_CAP_C0805-22UF,16V,20%,X6S,CH6223MEA01    I18 @T6G_MB_LIB.T6G(SCH_1):PAGE470
PC6523    1      A Q_CAP_C0805-22UF,16V,20%,X6S,CH6223MEA01    I22 @T6G_MB_LIB.T6G(SCH_1):PAGE470
PC6524    1      A Q_CAP_C0402-1UF,25V,10%,X6S,CH5104KEB02    I23 @T6G_MB_LIB.T6G(SCH_1):PAGE470
PU6501   10   VIN1 MPQ8633BGLEC838Z-MPQ8633BGLE-C838-Z,SMLF,IC,AL0086A    I51 @T6G_MB_LIB.T6G(SCH_1):PAGE470
PU6501   21   VIN2 MPQ8633BGLEC838Z-MPQ8633BGLE-C838-Z,SMLF,IC,AL0086A    I51 @T6G_MB_LIB.T6G(SCH_1):PAGE470
PC6905    1      A Q_CAP_C0805-22UF,16V,20%,X6S,CH6223MEA01    I55 @T6G_MB_LIB.T6G(SCH_1):PAGE470
PC6904    1      A Q_CAP_C0805-22UF,16V,20%,X6S,CH6223MEA01    I56 @T6G_MB_LIB.T6G(SCH_1):PAGE470
PC6903    1      A Q_CAP_C0805-22UF,16V,20%,X6S,CH6223MEA01    I57 @T6G_MB_LIB.T6G(SCH_1):PAGE470

SW_P12V_AUX_PVDD11_S3_P0_FLT @T6G_MB_LIB.T6G(SCH_1):SW_P12V_AUX_PVDD11_S3_P0_FLT
PC210_2    1      A Q_CAP_C0402-1UF,25V,10%,X6S,CH5104KEB02    I27 @T6G_MB_LIB.T6G(SCH_1):PAGE183
PC208_2    1      A Q_CAP_0402-0.1UF,25V,10%,X7R,CH4104K1B00    I29 @T6G_MB_LIB.T6G(SCH_1):PAGE183
PC209_1    1      A Q_CAP_C0402-1UF,25V,10%,X6S,CH5104KEB02    I44 @T6G_MB_LIB.T6G(SCH_1):PAGE183
PC211_1    1      A Q_CAP_C0805-22UF,16V,20%,X6S,CH6223MEA01    I48 @T6G_MB_LIB.T6G(SCH_1):PAGE183
  PU23 25_29   VIN1 ISL99390FRZTR5935-ISL99390FRZ-TR5935,SMLF,IC,AL099A    I13 @T6G_MB_LIB.T6G(SCH_1):PAGE183
  PU23   30   VIN2 ISL99390FRZTR5935-ISL99390FRZ-TR5935,SMLF,IC,AL099A    I13 @T6G_MB_LIB.T6G(SCH_1):PAGE183
PC212_2    1      A Q_CAP_C0805-22UF,16V,20%,X6S,CH6223MEA01    I30 @T6G_MB_LIB.T6G(SCH_1):PAGE183
PC214_2    1      A Q_CAP_C0805-22UF,16V,20%,X6S,CH6223MEA01    I31 @T6G_MB_LIB.T6G(SCH_1):PAGE183
PC207_1    1      A Q_CAP_0402-0.1UF,25V,10%,X7R,CH4104K1B00    I47 @T6G_MB_LIB.T6G(SCH_1):PAGE183
PC213_1    1      A Q_CAP_C0805-22UF,16V,20%,X6S,CH6223MEA01    I49 @T6G_MB_LIB.T6G(SCH_1):PAGE183
PC216_2    1      A Q_CAP_C0805-22UF,16V,20%,X6S,CH6223MEA01    I50 @T6G_MB_LIB.T6G(SCH_1):PAGE183
PC218_2    1      A Q_CAP_C0805-22UF,16V,20%,X6S,CH6223MEA01    I54 @T6G_MB_LIB.T6G(SCH_1):PAGE183
 PC220    1      A Q_CAPP_THLF-270UF,16V,20%,OSCON,CC72703MD38    I75 @T6G_MB_LIB.T6G(SCH_1):PAGE183
  PL24    1      1 Q_INDUCTOR_SMLF-100NH/16A,IND,CV+10G0MZ04    I78 @T6G_MB_LIB.T6G(SCH_1):PAGE183
PC215_1    1      A Q_CAP_C0805-22UF,16V,20%,X6S,CH6223MEA01    I87 @T6G_MB_LIB.T6G(SCH_1):PAGE183
PC219_1    1      A Q_CAP_C0805-22UF,16V,20%,X6S,CH6223MEA01    I88 @T6G_MB_LIB.T6G(SCH_1):PAGE183
  PU22 25_29   VIN1 ISL99390FRZTR5935-ISL99390FRZ-TR5935,SMLF,IC,AL099A    I92 @T6G_MB_LIB.T6G(SCH_1):PAGE183
  PU22   30   VIN2 ISL99390FRZTR5935-ISL99390FRZ-TR5935,SMLF,IC,AL099A    I92 @T6G_MB_LIB.T6G(SCH_1):PAGE183
PC8004    1      A Q_CAP_C0805-22UF,16V,20%,X6S,CH6223MEA01    I93 @T6G_MB_LIB.T6G(SCH_1):PAGE183
PC8005    1      A Q_CAP_C0805-22UF,16V,20%,X6S,CH6223MEA01    I94 @T6G_MB_LIB.T6G(SCH_1):PAGE183
PC7002    1      A Q_CAP_C0805-22UF,16V,20%,X6S,CH6223MEA01    I95 @T6G_MB_LIB.T6G(SCH_1):PAGE183

SW_P12V_AUX_PVDD11_S3_P1_FLT @T6G_MB_LIB.T6G(SCH_1):SW_P12V_AUX_PVDD11_S3_P1_FLT
PC510_2    1      A Q_CAP_0402-0.1UF,25V,10%,X7R,CH4104K1B00    I29 @T6G_MB_LIB.T6G(SCH_1):PAGE200
PC509_1    1      A Q_CAP_0402-0.1UF,25V,10%,X7R,CH4104K1B00    I48 @T6G_MB_LIB.T6G(SCH_1):PAGE200
PC518_2    1      A Q_CAP_C0805-22UF,16V,20%,X6S,CH6223MEA01    I52 @T6G_MB_LIB.T6G(SCH_1):PAGE200
 PC522    1      A Q_CAPP_THLF-270UF,16V,20%,OSCON,CC72703MD38    I81 @T6G_MB_LIB.T6G(SCH_1):PAGE200
  PL56    1      1 Q_INDUCTOR_SMLF-100NH/16A,IND,CV+10G0MZ04    I84 @T6G_MB_LIB.T6G(SCH_1):PAGE200
  PU44 25_29   VIN1 ISL99390FRZTR5935-ISL99390FRZ-TR5935,SMLF,IC,AL099A    I22 @T6G_MB_LIB.T6G(SCH_1):PAGE200
  PU44   30   VIN2 ISL99390FRZTR5935-ISL99390FRZ-TR5935,SMLF,IC,AL099A    I22 @T6G_MB_LIB.T6G(SCH_1):PAGE200
PC514_2    1      A Q_CAP_C0805-22UF,16V,20%,X6S,CH6223MEA01    I30 @T6G_MB_LIB.T6G(SCH_1):PAGE200
PC516_2    1      A Q_CAP_C0805-22UF,16V,20%,X6S,CH6223MEA01    I31 @T6G_MB_LIB.T6G(SCH_1):PAGE200
PC511_1    1      A Q_CAP_C0402-1UF,25V,10%,X6S,CH5104KEB02    I45 @T6G_MB_LIB.T6G(SCH_1):PAGE200
PC513_1    1      A Q_CAP_C0805-22UF,16V,20%,X6S,CH6223MEA01    I49 @T6G_MB_LIB.T6G(SCH_1):PAGE200
PC515_1    1      A Q_CAP_C0805-22UF,16V,20%,X6S,CH6223MEA01    I50 @T6G_MB_LIB.T6G(SCH_1):PAGE200
PC517_1    1      A Q_CAP_C0805-22UF,16V,20%,X6S,CH6223MEA01    I51 @T6G_MB_LIB.T6G(SCH_1):PAGE200
  PC27    1      A Q_CAP_C0805-22UF,16V,20%,X6S,CH6223MEA01    I58 @T6G_MB_LIB.T6G(SCH_1):PAGE200
PC521_1    1      A Q_CAP_C0805-22UF,16V,20%,X6S,CH6223MEA01    I80 @T6G_MB_LIB.T6G(SCH_1):PAGE200
PC512_2    1      A Q_CAP_C0402-1UF,25V,10%,X6S,CH5104KEB02    I91 @T6G_MB_LIB.T6G(SCH_1):PAGE200
  PU45 25_29   VIN1 ISL99390FRZTR5935-ISL99390FRZ-TR5935,SMLF,IC,AL099A    I92 @T6G_MB_LIB.T6G(SCH_1):PAGE200
  PU45   30   VIN2 ISL99390FRZTR5935-ISL99390FRZ-TR5935,SMLF,IC,AL099A    I92 @T6G_MB_LIB.T6G(SCH_1):PAGE200
PC8006    1      A Q_CAP_C0805-22UF,16V,20%,X6S,CH6223MEA01    I93 @T6G_MB_LIB.T6G(SCH_1):PAGE200
PC8007    1      A Q_CAP_C0805-22UF,16V,20%,X6S,CH6223MEA01    I94 @T6G_MB_LIB.T6G(SCH_1):PAGE200
PC7003    1      A Q_CAP_C0805-22UF,16V,20%,X6S,CH6223MEA01    I95 @T6G_MB_LIB.T6G(SCH_1):PAGE200

SW_P12V_AUX_PVDD18_S5_P0_FLT @T6G_MB_LIB.T6G(SCH_1):SW_P12V_AUX_PVDD18_S5_P0_FLT
  PL77    2      2 Q_INDUCTOR_SMLF-BLM18SN220TN1D/8000MA,IND,CX220TN1A     I7 @T6G_MB_LIB.T6G(SCH_1):PAGE184
 PC111    1      A Q_CAP_C0805-22UF,16V,20%,X6S,CH6223MEA01     I8 @T6G_MB_LIB.T6G(SCH_1):PAGE184
  PU57   10   VIN1 MPQ8633BGLEC838Z-MPQ8633BGLE-C838-Z,SMLF,IC,AL0086A    I18 @T6G_MB_LIB.T6G(SCH_1):PAGE184
  PU57   21   VIN2 MPQ8633BGLEC838Z-MPQ8633BGLE-C838-Z,SMLF,IC,AL0086A    I18 @T6G_MB_LIB.T6G(SCH_1):PAGE184
 PC227    1      A Q_CAP_C0805-22UF,16V,20%,X6S,CH6223MEA01    I25 @T6G_MB_LIB.T6G(SCH_1):PAGE184
 PC254    1      A Q_CAP_C0805-22UF,16V,20%,X6S,CH6223MEA01    I26 @T6G_MB_LIB.T6G(SCH_1):PAGE184
  PC81    1      A Q_CAP_C0805-22UF,16V,20%,X6S,CH6223MEA01    I27 @T6G_MB_LIB.T6G(SCH_1):PAGE184
 PC237    1      A Q_CAP_C0402-1UF,25V,10%,X6S,CH5104KEB02    I28 @T6G_MB_LIB.T6G(SCH_1):PAGE184
PC8002    1      A Q_CAP_C0805-22UF,16V,20%,X6S,CH6223MEA01    I57 @T6G_MB_LIB.T6G(SCH_1):PAGE184

SW_P12V_AUX_PVDD18_S5_P1_FLT @T6G_MB_LIB.T6G(SCH_1):SW_P12V_AUX_PVDD18_S5_P1_FLT
   PU3   10   VIN1 MPQ8633BGLEC838Z-MPQ8633BGLE-C838-Z,SMLF,IC,AL0086A    I15 @T6G_MB_LIB.T6G(SCH_1):PAGE201
   PU3   21   VIN2 MPQ8633BGLEC838Z-MPQ8633BGLE-C838-Z,SMLF,IC,AL0086A    I15 @T6G_MB_LIB.T6G(SCH_1):PAGE201
  PC61    1      A Q_CAP_C0805-22UF,16V,20%,X6S,CH6223MEA01    I21 @T6G_MB_LIB.T6G(SCH_1):PAGE201
 PC150    1      A Q_CAP_C0805-22UF,16V,20%,X6S,CH6223MEA01    I22 @T6G_MB_LIB.T6G(SCH_1):PAGE201
 PC152    1      A Q_CAP_C0805-22UF,16V,20%,X6S,CH6223MEA01    I23 @T6G_MB_LIB.T6G(SCH_1):PAGE201
  PC22    1      A Q_CAP_C0402-1UF,25V,10%,X6S,CH5104KEB02    I24 @T6G_MB_LIB.T6G(SCH_1):PAGE201
  PL26    2      2 Q_INDUCTOR_SMLF-BLM18SN220TN1D/8000MA,IND,CX220TN1A     I4 @T6G_MB_LIB.T6G(SCH_1):PAGE201
  PC60    1      A Q_CAP_C0805-22UF,16V,20%,X6S,CH6223MEA01    I54 @T6G_MB_LIB.T6G(SCH_1):PAGE201
PC8003    1      A Q_CAP_C0805-22UF,16V,20%,X6S,CH6223MEA01    I57 @T6G_MB_LIB.T6G(SCH_1):PAGE201

SW_P12V_AUX_PVDDCR_CPU0_P0_FLT @T6G_MB_LIB.T6G(SCH_1):SW_P12V_AUX_PVDDCR_CPU0_P0_FLT
  PU43 25_29   VIN1 ISL99390FRZTR5935-ISL99390FRZ-TR5935,SMLF,IC,AL099A    I16 @T6G_MB_LIB.T6G(SCH_1):PAGE169
  PU43   30   VIN2 ISL99390FRZTR5935-ISL99390FRZ-TR5935,SMLF,IC,AL099A    I16 @T6G_MB_LIB.T6G(SCH_1):PAGE169
   PU6 25_29   VIN1 ISL99390FRZTR5935-ISL99390FRZ-TR5935,SMLF,IC,AL099A    I26 @T6G_MB_LIB.T6G(SCH_1):PAGE169
   PU6   30   VIN2 ISL99390FRZTR5935-ISL99390FRZ-TR5935,SMLF,IC,AL099A    I26 @T6G_MB_LIB.T6G(SCH_1):PAGE169
PC482_2    1      A Q_CAP_0402-0.1UF,25V,10%,X7R,CH4104K1B00    I33 @T6G_MB_LIB.T6G(SCH_1):PAGE169
PC551_4    1      A Q_CAP_0402-0.1UF,25V,10%,X7R,CH4104K1B00    I21 @T6G_MB_LIB.T6G(SCH_1):PAGE170
PC555_4    1      A Q_CAP_C0805-22UF,16V,20%,X6S,CH6223MEA01    I23 @T6G_MB_LIB.T6G(SCH_1):PAGE170
PC480_2    1      A Q_CAP_C0402-1UF,25V,10%,X6S,CH5104KEB02    I34 @T6G_MB_LIB.T6G(SCH_1):PAGE169
PC484_2    1      A Q_CAP_C0805-22UF,16V,20%,X6S,CH6223MEA01    I36 @T6G_MB_LIB.T6G(SCH_1):PAGE169
PC486_2    1      A Q_CAP_C0805-22UF,16V,20%,X6S,CH6223MEA01    I37 @T6G_MB_LIB.T6G(SCH_1):PAGE169
PC488_2    1      A Q_CAP_C0805-22UF,16V,20%,X6S,CH6223MEA01    I39 @T6G_MB_LIB.T6G(SCH_1):PAGE169
PC479_1    1      A Q_CAP_0402-0.1UF,25V,10%,X7R,CH4104K1B00    I52 @T6G_MB_LIB.T6G(SCH_1):PAGE169
PC481_1    1      A Q_CAP_C0402-1UF,25V,10%,X6S,CH5104KEB02    I53 @T6G_MB_LIB.T6G(SCH_1):PAGE169
PC483_1    1      A Q_CAP_C0805-22UF,16V,20%,X6S,CH6223MEA01    I57 @T6G_MB_LIB.T6G(SCH_1):PAGE169
PC485_1    1      A Q_CAP_C0805-22UF,16V,20%,X6S,CH6223MEA01    I58 @T6G_MB_LIB.T6G(SCH_1):PAGE169
PC487_1    1      A Q_CAP_C0805-22UF,16V,20%,X6S,CH6223MEA01    I59 @T6G_MB_LIB.T6G(SCH_1):PAGE169
 PC491    1      A Q_CAPP_THLF-270UF,16V,20%,OSCON,CC72703MD38    I79 @T6G_MB_LIB.T6G(SCH_1):PAGE169
 PC492    1      A Q_CAPP_THLF-270UF,16V,20%,OSCON,CC72703MD38    I81 @T6G_MB_LIB.T6G(SCH_1):PAGE169
  PL53    1      1 Q_INDUCTOR_SMLF-50NH/86A,IND,CVA50^0MZ09    I82 @T6G_MB_LIB.T6G(SCH_1):PAGE169
  PU47 25_29   VIN1 ISL99390FRZTR5935-ISL99390FRZ-TR5935,SMLF,IC,AL099A     I9 @T6G_MB_LIB.T6G(SCH_1):PAGE170
  PU47   30   VIN2 ISL99390FRZTR5935-ISL99390FRZ-TR5935,SMLF,IC,AL099A     I9 @T6G_MB_LIB.T6G(SCH_1):PAGE170
PC553_4    1      A Q_CAP_C0402-1UF,25V,10%,X6S,CH5104KEB02    I22 @T6G_MB_LIB.T6G(SCH_1):PAGE170
PC557_4    1      A Q_CAP_C0805-22UF,16V,20%,X6S,CH6223MEA01    I24 @T6G_MB_LIB.T6G(SCH_1):PAGE170
  PU46 25_29   VIN1 ISL99390FRZTR5935-ISL99390FRZ-TR5935,SMLF,IC,AL099A    I38 @T6G_MB_LIB.T6G(SCH_1):PAGE170
  PU46   30   VIN2 ISL99390FRZTR5935-ISL99390FRZ-TR5935,SMLF,IC,AL099A    I38 @T6G_MB_LIB.T6G(SCH_1):PAGE170
PC552_3    1      A Q_CAP_0402-0.1UF,25V,10%,X7R,CH4104K1B00    I43 @T6G_MB_LIB.T6G(SCH_1):PAGE170
PC550_3    1      A Q_CAP_C0402-1UF,25V,10%,X6S,CH5104KEB02    I47 @T6G_MB_LIB.T6G(SCH_1):PAGE170
PC554_3    1      A Q_CAP_C0805-22UF,16V,20%,X6S,CH6223MEA01    I48 @T6G_MB_LIB.T6G(SCH_1):PAGE170
PC556_3    1      A Q_CAP_C0805-22UF,16V,20%,X6S,CH6223MEA01    I49 @T6G_MB_LIB.T6G(SCH_1):PAGE170
PC559_4    1      A Q_CAP_C0805-22UF,16V,20%,X6S,CH6223MEA01    I55 @T6G_MB_LIB.T6G(SCH_1):PAGE170
PC558_3    1      A Q_CAP_C0805-22UF,16V,20%,X6S,CH6223MEA01    I66 @T6G_MB_LIB.T6G(SCH_1):PAGE170
  PU48 25_29   VIN1 ISL99390FRZTR5935-ISL99390FRZ-TR5935,SMLF,IC,AL099A    I18 @T6G_MB_LIB.T6G(SCH_1):PAGE171
  PU48   30   VIN2 ISL99390FRZTR5935-ISL99390FRZ-TR5935,SMLF,IC,AL099A    I18 @T6G_MB_LIB.T6G(SCH_1):PAGE171
PC153_6    1      A Q_CAP_0402-0.1UF,25V,10%,X7R,CH4104K1B00    I24 @T6G_MB_LIB.T6G(SCH_1):PAGE171
PC154_6    1      A Q_CAP_C0402-1UF,25V,10%,X6S,CH5104KEB02    I27 @T6G_MB_LIB.T6G(SCH_1):PAGE171
PC157_6    1      A Q_CAP_C0805-22UF,16V,20%,X6S,CH6223MEA01    I28 @T6G_MB_LIB.T6G(SCH_1):PAGE171
PC158_6    1      A Q_CAP_C0805-22UF,16V,20%,X6S,CH6223MEA01    I29 @T6G_MB_LIB.T6G(SCH_1):PAGE171
PC570_5    1      A Q_CAP_0402-0.1UF,25V,10%,X7R,CH4104K1B00    I44 @T6G_MB_LIB.T6G(SCH_1):PAGE171
PC569_5    1      A Q_CAP_C0402-1UF,25V,10%,X6S,CH5104KEB02    I47 @T6G_MB_LIB.T6G(SCH_1):PAGE171
PC571_5    1      A Q_CAP_C0805-22UF,16V,20%,X6S,CH6223MEA01    I48 @T6G_MB_LIB.T6G(SCH_1):PAGE171
PC572_5    1      A Q_CAP_C0805-22UF,16V,20%,X6S,CH6223MEA01    I49 @T6G_MB_LIB.T6G(SCH_1):PAGE171
PC159_6    1      A Q_CAP_C0805-22UF,16V,20%,X6S,CH6223MEA01    I55 @T6G_MB_LIB.T6G(SCH_1):PAGE171
PC573_5    1      A Q_CAP_C0805-22UF,16V,20%,X6S,CH6223MEA01    I66 @T6G_MB_LIB.T6G(SCH_1):PAGE171
  PU10 25_29   VIN1 ISL99390FRZTR5935-ISL99390FRZ-TR5935,SMLF,IC,AL099A    I73 @T6G_MB_LIB.T6G(SCH_1):PAGE171
  PU10   30   VIN2 ISL99390FRZTR5935-ISL99390FRZ-TR5935,SMLF,IC,AL099A    I73 @T6G_MB_LIB.T6G(SCH_1):PAGE171

SW_P12V_AUX_PVDDCR_CPU0_P1_FLT @T6G_MB_LIB.T6G(SCH_1):SW_P12V_AUX_PVDDCR_CPU0_P1_FLT
PC263_2    1      A Q_CAP_C0402-1UF,25V,10%,X6S,CH5104KEB02    I26 @T6G_MB_LIB.T6G(SCH_1):PAGE186
PC269_2    1      A Q_CAP_C0805-22UF,16V,20%,X6S,CH6223MEA01    I31 @T6G_MB_LIB.T6G(SCH_1):PAGE186
PC260_1    1      A Q_CAP_0402-0.1UF,25V,10%,X7R,CH4104K1B00    I46 @T6G_MB_LIB.T6G(SCH_1):PAGE186
 PC273    1      A Q_CAPP_THLF-270UF,16V,20%,OSCON,CC72703MD38    I71 @T6G_MB_LIB.T6G(SCH_1):PAGE186
PC261_2    1      A Q_CAP_0402-0.1UF,25V,10%,X7R,CH4104K1B00    I25 @T6G_MB_LIB.T6G(SCH_1):PAGE186
PC265_2    1      A Q_CAP_C0805-22UF,16V,20%,X6S,CH6223MEA01    I28 @T6G_MB_LIB.T6G(SCH_1):PAGE186
PC267_2    1      A Q_CAP_C0805-22UF,16V,20%,X6S,CH6223MEA01    I29 @T6G_MB_LIB.T6G(SCH_1):PAGE186
PC262_1    1      A Q_CAP_C0402-1UF,25V,10%,X6S,CH5104KEB02    I47 @T6G_MB_LIB.T6G(SCH_1):PAGE186
PC264_1    1      A Q_CAP_C0805-22UF,16V,20%,X6S,CH6223MEA01    I51 @T6G_MB_LIB.T6G(SCH_1):PAGE186
PC266_1    1      A Q_CAP_C0805-22UF,16V,20%,X6S,CH6223MEA01    I52 @T6G_MB_LIB.T6G(SCH_1):PAGE186
PC268_1    1      A Q_CAP_C0805-22UF,16V,20%,X6S,CH6223MEA01    I53 @T6G_MB_LIB.T6G(SCH_1):PAGE186
 PC272    1      A Q_CAPP_THLF-270UF,16V,20%,OSCON,CC72703MD38    I70 @T6G_MB_LIB.T6G(SCH_1):PAGE186
  PL30    1      1 Q_INDUCTOR_SMLF-50NH/86A,IND,CVA50^0MZ09    I73 @T6G_MB_LIB.T6G(SCH_1):PAGE186
   PU4 25_29   VIN1 ISL99390FRZTR5935-ISL99390FRZ-TR5935,SMLF,IC,AL099A    I88 @T6G_MB_LIB.T6G(SCH_1):PAGE186
   PU4   30   VIN2 ISL99390FRZTR5935-ISL99390FRZ-TR5935,SMLF,IC,AL099A    I88 @T6G_MB_LIB.T6G(SCH_1):PAGE186
  PU26 25_29   VIN1 ISL99390FRZTR5935-ISL99390FRZ-TR5935,SMLF,IC,AL099A    I91 @T6G_MB_LIB.T6G(SCH_1):PAGE186
  PU26   30   VIN2 ISL99390FRZTR5935-ISL99390FRZ-TR5935,SMLF,IC,AL099A    I91 @T6G_MB_LIB.T6G(SCH_1):PAGE186
  PU28 25_29   VIN1 ISL99390FRZTR5935-ISL99390FRZ-TR5935,SMLF,IC,AL099A     I9 @T6G_MB_LIB.T6G(SCH_1):PAGE187
  PU28   30   VIN2 ISL99390FRZTR5935-ISL99390FRZ-TR5935,SMLF,IC,AL099A     I9 @T6G_MB_LIB.T6G(SCH_1):PAGE187
PC293_4    1      A Q_CAP_0402-0.1UF,25V,10%,X7R,CH4104K1B00    I22 @T6G_MB_LIB.T6G(SCH_1):PAGE187
PC291_4    1      A Q_CAP_C0402-1UF,25V,10%,X6S,CH5104KEB02    I23 @T6G_MB_LIB.T6G(SCH_1):PAGE187
PC295_4    1      A Q_CAP_C0805-22UF,16V,20%,X6S,CH6223MEA01    I24 @T6G_MB_LIB.T6G(SCH_1):PAGE187
PC297_4    1      A Q_CAP_C0805-22UF,16V,20%,X6S,CH6223MEA01    I25 @T6G_MB_LIB.T6G(SCH_1):PAGE187
  PU27 25_29   VIN1 ISL99390FRZTR5935-ISL99390FRZ-TR5935,SMLF,IC,AL099A    I39 @T6G_MB_LIB.T6G(SCH_1):PAGE187
  PU27   30   VIN2 ISL99390FRZTR5935-ISL99390FRZ-TR5935,SMLF,IC,AL099A    I39 @T6G_MB_LIB.T6G(SCH_1):PAGE187
PC290_3    1      A Q_CAP_0402-0.1UF,25V,10%,X7R,CH4104K1B00    I44 @T6G_MB_LIB.T6G(SCH_1):PAGE187
PC292_3    1      A Q_CAP_C0402-1UF,25V,10%,X6S,CH5104KEB02    I48 @T6G_MB_LIB.T6G(SCH_1):PAGE187
PC294_3    1      A Q_CAP_C0805-22UF,16V,20%,X6S,CH6223MEA01    I49 @T6G_MB_LIB.T6G(SCH_1):PAGE187
PC296_3    1      A Q_CAP_C0805-22UF,16V,20%,X6S,CH6223MEA01    I50 @T6G_MB_LIB.T6G(SCH_1):PAGE187
PC299_4    1      A Q_CAP_C0805-22UF,16V,20%,X6S,CH6223MEA01    I55 @T6G_MB_LIB.T6G(SCH_1):PAGE187
PC298_3    1      A Q_CAP_C0805-22UF,16V,20%,X6S,CH6223MEA01    I65 @T6G_MB_LIB.T6G(SCH_1):PAGE187
  PU29 25_29   VIN1 ISL99390FRZTR5935-ISL99390FRZ-TR5935,SMLF,IC,AL099A    I18 @T6G_MB_LIB.T6G(SCH_1):PAGE188
  PU29   30   VIN2 ISL99390FRZTR5935-ISL99390FRZ-TR5935,SMLF,IC,AL099A    I18 @T6G_MB_LIB.T6G(SCH_1):PAGE188
PC127_6    1      A Q_CAP_0402-0.1UF,25V,10%,X7R,CH4104K1B00    I25 @T6G_MB_LIB.T6G(SCH_1):PAGE188
PC128_6    1      A Q_CAP_C0402-1UF,25V,10%,X6S,CH5104KEB02    I27 @T6G_MB_LIB.T6G(SCH_1):PAGE188
PC129_6    1      A Q_CAP_C0805-22UF,16V,20%,X6S,CH6223MEA01    I29 @T6G_MB_LIB.T6G(SCH_1):PAGE188
PC130_6    1      A Q_CAP_C0805-22UF,16V,20%,X6S,CH6223MEA01    I30 @T6G_MB_LIB.T6G(SCH_1):PAGE188
PC309_5    1      A Q_CAP_0402-0.1UF,25V,10%,X7R,CH4104K1B00    I45 @T6G_MB_LIB.T6G(SCH_1):PAGE188
PC310_5    1      A Q_CAP_C0402-1UF,25V,10%,X6S,CH5104KEB02    I48 @T6G_MB_LIB.T6G(SCH_1):PAGE188
PC311_5    1      A Q_CAP_C0805-22UF,16V,20%,X6S,CH6223MEA01    I49 @T6G_MB_LIB.T6G(SCH_1):PAGE188
PC312_5    1      A Q_CAP_C0805-22UF,16V,20%,X6S,CH6223MEA01    I50 @T6G_MB_LIB.T6G(SCH_1):PAGE188
PC132_6    1      A Q_CAP_C0805-22UF,16V,20%,X6S,CH6223MEA01    I55 @T6G_MB_LIB.T6G(SCH_1):PAGE188
PC313_5    1      A Q_CAP_C0805-22UF,16V,20%,X6S,CH6223MEA01    I66 @T6G_MB_LIB.T6G(SCH_1):PAGE188
  PU24 25_29   VIN1 ISL99390FRZTR5935-ISL99390FRZ-TR5935,SMLF,IC,AL099A    I73 @T6G_MB_LIB.T6G(SCH_1):PAGE188
  PU24   30   VIN2 ISL99390FRZTR5935-ISL99390FRZ-TR5935,SMLF,IC,AL099A    I73 @T6G_MB_LIB.T6G(SCH_1):PAGE188

SW_P12V_AUX_PVDDCR_CPU1_P0_FLT @T6G_MB_LIB.T6G(SCH_1):SW_P12V_AUX_PVDDCR_CPU1_P0_FLT
PC88_2    1      A Q_CAP_C0402-1UF,25V,10%,X6S,CH5104KEB02    I47 @T6G_MB_LIB.T6G(SCH_1):PAGE176
PC95_1    1      A Q_CAP_C0805-22UF,16V,20%,X6S,CH6223MEA01    I65 @T6G_MB_LIB.T6G(SCH_1):PAGE176
 PC101    1      A Q_CAPP_THLF-270UF,16V,20%,OSCON,CC72703MD38    I66 @T6G_MB_LIB.T6G(SCH_1):PAGE176
PC114_6    1      A Q_CAP_0402-0.1UF,25V,10%,X7R,CH4104K1B00    I40 @T6G_MB_LIB.T6G(SCH_1):PAGE178
PC135_5    1      A Q_CAP_C0402-1UF,25V,10%,X6S,CH5104KEB02    I59 @T6G_MB_LIB.T6G(SCH_1):PAGE178
PC136_5    1      A Q_CAP_C0805-22UF,16V,20%,X6S,CH6223MEA01    I60 @T6G_MB_LIB.T6G(SCH_1):PAGE178
   PU2 25_29   VIN1 ISL99390FRZTR5935-ISL99390FRZ-TR5935,SMLF,IC,AL099A    I33 @T6G_MB_LIB.T6G(SCH_1):PAGE176
   PU2   30   VIN2 ISL99390FRZTR5935-ISL99390FRZ-TR5935,SMLF,IC,AL099A    I33 @T6G_MB_LIB.T6G(SCH_1):PAGE176
  PU13 25_29   VIN1 ISL99390FRZTR5935-ISL99390FRZ-TR5935,SMLF,IC,AL099A    I35 @T6G_MB_LIB.T6G(SCH_1):PAGE176
  PU13   30   VIN2 ISL99390FRZTR5935-ISL99390FRZ-TR5935,SMLF,IC,AL099A    I35 @T6G_MB_LIB.T6G(SCH_1):PAGE176
PC86_2    1      A Q_CAP_0402-0.1UF,25V,10%,X7R,CH4104K1B00    I37 @T6G_MB_LIB.T6G(SCH_1):PAGE176
PC90_2    1      A Q_CAP_C0805-22UF,16V,20%,X6S,CH6223MEA01    I48 @T6G_MB_LIB.T6G(SCH_1):PAGE176
PC93_2    1      A Q_CAP_C0805-22UF,16V,20%,X6S,CH6223MEA01    I51 @T6G_MB_LIB.T6G(SCH_1):PAGE176
PC96_2    1      A Q_CAP_C0805-22UF,16V,20%,X6S,CH6223MEA01    I52 @T6G_MB_LIB.T6G(SCH_1):PAGE176
PC85_1    1      A Q_CAP_0402-0.1UF,25V,10%,X7R,CH4104K1B00    I55 @T6G_MB_LIB.T6G(SCH_1):PAGE176
PC87_1    1      A Q_CAP_C0402-1UF,25V,10%,X6S,CH5104KEB02    I59 @T6G_MB_LIB.T6G(SCH_1):PAGE176
PC89_1    1      A Q_CAP_C0805-22UF,16V,20%,X6S,CH6223MEA01    I60 @T6G_MB_LIB.T6G(SCH_1):PAGE176
PC91_1    1      A Q_CAP_C0805-22UF,16V,20%,X6S,CH6223MEA01    I64 @T6G_MB_LIB.T6G(SCH_1):PAGE176
 PC104    1      A Q_CAPP_THLF-270UF,16V,20%,OSCON,CC72703MD38    I82 @T6G_MB_LIB.T6G(SCH_1):PAGE176
  PL12    1      1 Q_INDUCTOR_SMLF-50NH/86A,IND,CVA50^0MZ09    I83 @T6G_MB_LIB.T6G(SCH_1):PAGE176
  PU14 25_29   VIN1 ISL99390FRZTR5935-ISL99390FRZ-TR5935,SMLF,IC,AL099A    I21 @T6G_MB_LIB.T6G(SCH_1):PAGE177
  PU14   30   VIN2 ISL99390FRZTR5935-ISL99390FRZ-TR5935,SMLF,IC,AL099A    I21 @T6G_MB_LIB.T6G(SCH_1):PAGE177
  PU15 25_29   VIN1 ISL99390FRZTR5935-ISL99390FRZ-TR5935,SMLF,IC,AL099A    I23 @T6G_MB_LIB.T6G(SCH_1):PAGE177
  PU15   30   VIN2 ISL99390FRZTR5935-ISL99390FRZ-TR5935,SMLF,IC,AL099A    I23 @T6G_MB_LIB.T6G(SCH_1):PAGE177
PC115_4    1      A Q_CAP_0402-0.1UF,25V,10%,X7R,CH4104K1B00    I24 @T6G_MB_LIB.T6G(SCH_1):PAGE177
PC116_3    1      A Q_CAP_0402-0.1UF,25V,10%,X7R,CH4104K1B00    I34 @T6G_MB_LIB.T6G(SCH_1):PAGE177
PC117_4    1      A Q_CAP_C0402-1UF,25V,10%,X6S,CH5104KEB02    I43 @T6G_MB_LIB.T6G(SCH_1):PAGE177
PC119_4    1      A Q_CAP_C0805-22UF,16V,20%,X6S,CH6223MEA01    I44 @T6G_MB_LIB.T6G(SCH_1):PAGE177
PC123_4    1      A Q_CAP_C0805-22UF,16V,20%,X6S,CH6223MEA01    I47 @T6G_MB_LIB.T6G(SCH_1):PAGE177
PC125_4    1      A Q_CAP_C0805-22UF,16V,20%,X6S,CH6223MEA01    I49 @T6G_MB_LIB.T6G(SCH_1):PAGE177
PC118_3    1      A Q_CAP_C0402-1UF,25V,10%,X6S,CH5104KEB02    I60 @T6G_MB_LIB.T6G(SCH_1):PAGE177
PC120_3    1      A Q_CAP_C0805-22UF,16V,20%,X6S,CH6223MEA01    I61 @T6G_MB_LIB.T6G(SCH_1):PAGE177
PC124_3    1      A Q_CAP_C0805-22UF,16V,20%,X6S,CH6223MEA01    I65 @T6G_MB_LIB.T6G(SCH_1):PAGE177
PC126_3    1      A Q_CAP_C0805-22UF,16V,20%,X6S,CH6223MEA01    I66 @T6G_MB_LIB.T6G(SCH_1):PAGE177
  PU16 25_29   VIN1 ISL99390FRZTR5935-ISL99390FRZ-TR5935,SMLF,IC,AL099A    I22 @T6G_MB_LIB.T6G(SCH_1):PAGE178
  PU16   30   VIN2 ISL99390FRZTR5935-ISL99390FRZ-TR5935,SMLF,IC,AL099A    I22 @T6G_MB_LIB.T6G(SCH_1):PAGE178
PC115_6    1      A Q_CAP_C0402-1UF,25V,10%,X6S,CH5104KEB02    I41 @T6G_MB_LIB.T6G(SCH_1):PAGE178
PC116_6    1      A Q_CAP_C0805-22UF,16V,20%,X6S,CH6223MEA01    I42 @T6G_MB_LIB.T6G(SCH_1):PAGE178
PC118_6    1      A Q_CAP_C0805-22UF,16V,20%,X6S,CH6223MEA01    I45 @T6G_MB_LIB.T6G(SCH_1):PAGE178
PC119_6    1      A Q_CAP_C0805-22UF,16V,20%,X6S,CH6223MEA01    I47 @T6G_MB_LIB.T6G(SCH_1):PAGE178
PC134_5    1      A Q_CAP_0402-0.1UF,25V,10%,X7R,CH4104K1B00    I58 @T6G_MB_LIB.T6G(SCH_1):PAGE178
PC138_5    1      A Q_CAP_C0805-22UF,16V,20%,X6S,CH6223MEA01    I65 @T6G_MB_LIB.T6G(SCH_1):PAGE178
PC139_5    1      A Q_CAP_C0805-22UF,16V,20%,X6S,CH6223MEA01    I66 @T6G_MB_LIB.T6G(SCH_1):PAGE178
  PU11 25_29   VIN1 ISL99390FRZTR5935-ISL99390FRZ-TR5935,SMLF,IC,AL099A    I73 @T6G_MB_LIB.T6G(SCH_1):PAGE178
  PU11   30   VIN2 ISL99390FRZTR5935-ISL99390FRZ-TR5935,SMLF,IC,AL099A    I73 @T6G_MB_LIB.T6G(SCH_1):PAGE178

SW_P12V_AUX_PVDDCR_CPU1_P1_FLT @T6G_MB_LIB.T6G(SCH_1):SW_P12V_AUX_PVDDCR_CPU1_P1_FLT
PC382_2    1      A Q_CAP_C0805-22UF,16V,20%,X6S,CH6223MEA01    I46 @T6G_MB_LIB.T6G(SCH_1):PAGE193
PC409_4    1      A Q_CAP_C0805-22UF,16V,20%,X6S,CH6223MEA01    I42 @T6G_MB_LIB.T6G(SCH_1):PAGE194
PC410_3    1      A Q_CAP_C0805-22UF,16V,20%,X6S,CH6223MEA01    I55 @T6G_MB_LIB.T6G(SCH_1):PAGE194
PC140_6    1      A Q_CAP_C0402-1UF,25V,10%,X6S,CH5104KEB02    I40 @T6G_MB_LIB.T6G(SCH_1):PAGE195
PC427_5    1      A Q_CAP_C0805-22UF,16V,20%,X6S,CH6223MEA01    I60 @T6G_MB_LIB.T6G(SCH_1):PAGE195
   PU5 25_29   VIN1 ISL99390FRZTR5935-ISL99390FRZ-TR5935,SMLF,IC,AL099A    I31 @T6G_MB_LIB.T6G(SCH_1):PAGE193
   PU5   30   VIN2 ISL99390FRZTR5935-ISL99390FRZ-TR5935,SMLF,IC,AL099A    I31 @T6G_MB_LIB.T6G(SCH_1):PAGE193
PC376_2    1      A Q_CAP_0402-0.1UF,25V,10%,X7R,CH4104K1B00    I34 @T6G_MB_LIB.T6G(SCH_1):PAGE193
PC378_2    1      A Q_CAP_C0402-1UF,25V,10%,X6S,CH5104KEB02    I42 @T6G_MB_LIB.T6G(SCH_1):PAGE193
PC380_2    1      A Q_CAP_C0805-22UF,16V,20%,X6S,CH6223MEA01    I43 @T6G_MB_LIB.T6G(SCH_1):PAGE193
PC385_2    1      A Q_CAP_C0805-22UF,16V,20%,X6S,CH6223MEA01    I48 @T6G_MB_LIB.T6G(SCH_1):PAGE193
PC375_1    1      A Q_CAP_0402-0.1UF,25V,10%,X7R,CH4104K1B00    I50 @T6G_MB_LIB.T6G(SCH_1):PAGE193
PC377_1    1      A Q_CAP_C0402-1UF,25V,10%,X6S,CH5104KEB02    I53 @T6G_MB_LIB.T6G(SCH_1):PAGE193
PC379_1    1      A Q_CAP_C0805-22UF,16V,20%,X6S,CH6223MEA01    I54 @T6G_MB_LIB.T6G(SCH_1):PAGE193
PC381_1    1      A Q_CAP_C0805-22UF,16V,20%,X6S,CH6223MEA01    I58 @T6G_MB_LIB.T6G(SCH_1):PAGE193
PC384_1    1      A Q_CAP_C0805-22UF,16V,20%,X6S,CH6223MEA01    I60 @T6G_MB_LIB.T6G(SCH_1):PAGE193
  PL42    1      1 Q_INDUCTOR_SMLF-50NH/86A,IND,CVA50^0MZ09    I79 @T6G_MB_LIB.T6G(SCH_1):PAGE193
  PU35 25_29   VIN1 ISL99390FRZTR5935-ISL99390FRZ-TR5935,SMLF,IC,AL099A    I91 @T6G_MB_LIB.T6G(SCH_1):PAGE193
  PU35   30   VIN2 ISL99390FRZTR5935-ISL99390FRZ-TR5935,SMLF,IC,AL099A    I91 @T6G_MB_LIB.T6G(SCH_1):PAGE193
  PU36 25_29   VIN1 ISL99390FRZTR5935-ISL99390FRZ-TR5935,SMLF,IC,AL099A    I21 @T6G_MB_LIB.T6G(SCH_1):PAGE194
  PU36   30   VIN2 ISL99390FRZTR5935-ISL99390FRZ-TR5935,SMLF,IC,AL099A    I21 @T6G_MB_LIB.T6G(SCH_1):PAGE194
PC405_4    1      A Q_CAP_0402-0.1UF,25V,10%,X7R,CH4104K1B00    I23 @T6G_MB_LIB.T6G(SCH_1):PAGE194
PC408_3    1      A Q_CAP_0402-0.1UF,25V,10%,X7R,CH4104K1B00    I33 @T6G_MB_LIB.T6G(SCH_1):PAGE194
PC407_4    1      A Q_CAP_C0402-1UF,25V,10%,X6S,CH5104KEB02    I41 @T6G_MB_LIB.T6G(SCH_1):PAGE194
PC411_4    1      A Q_CAP_C0805-22UF,16V,20%,X6S,CH6223MEA01    I45 @T6G_MB_LIB.T6G(SCH_1):PAGE194
PC415_4    1      A Q_CAP_C0805-22UF,16V,20%,X6S,CH6223MEA01    I47 @T6G_MB_LIB.T6G(SCH_1):PAGE194
PC406_3    1      A Q_CAP_C0402-1UF,25V,10%,X6S,CH5104KEB02    I54 @T6G_MB_LIB.T6G(SCH_1):PAGE194
PC412_3    1      A Q_CAP_C0805-22UF,16V,20%,X6S,CH6223MEA01    I59 @T6G_MB_LIB.T6G(SCH_1):PAGE194
PC416_3    1      A Q_CAP_C0805-22UF,16V,20%,X6S,CH6223MEA01    I60 @T6G_MB_LIB.T6G(SCH_1):PAGE194
  PU37 25_29   VIN1 ISL99390FRZTR5935-ISL99390FRZ-TR5935,SMLF,IC,AL099A    I72 @T6G_MB_LIB.T6G(SCH_1):PAGE194
  PU37   30   VIN2 ISL99390FRZTR5935-ISL99390FRZ-TR5935,SMLF,IC,AL099A    I72 @T6G_MB_LIB.T6G(SCH_1):PAGE194
  PU33 25_29   VIN1 ISL99390FRZTR5935-ISL99390FRZ-TR5935,SMLF,IC,AL099A    I19 @T6G_MB_LIB.T6G(SCH_1):PAGE195
  PU33   30   VIN2 ISL99390FRZTR5935-ISL99390FRZ-TR5935,SMLF,IC,AL099A    I19 @T6G_MB_LIB.T6G(SCH_1):PAGE195
PC141_6    1      A Q_CAP_0402-0.1UF,25V,10%,X7R,CH4104K1B00    I38 @T6G_MB_LIB.T6G(SCH_1):PAGE195
PC144_6    1      A Q_CAP_C0805-22UF,16V,20%,X6S,CH6223MEA01    I41 @T6G_MB_LIB.T6G(SCH_1):PAGE195
PC145_6    1      A Q_CAP_C0805-22UF,16V,20%,X6S,CH6223MEA01    I44 @T6G_MB_LIB.T6G(SCH_1):PAGE195
PC147_6    1      A Q_CAP_C0805-22UF,16V,20%,X6S,CH6223MEA01    I47 @T6G_MB_LIB.T6G(SCH_1):PAGE195
PC425_5    1      A Q_CAP_0402-0.1UF,25V,10%,X7R,CH4104K1B00    I54 @T6G_MB_LIB.T6G(SCH_1):PAGE195
PC424_5    1      A Q_CAP_C0402-1UF,25V,10%,X6S,CH5104KEB02    I55 @T6G_MB_LIB.T6G(SCH_1):PAGE195
PC426_5    1      A Q_CAP_C0805-22UF,16V,20%,X6S,CH6223MEA01    I56 @T6G_MB_LIB.T6G(SCH_1):PAGE195
PC429_5    1      A Q_CAP_C0805-22UF,16V,20%,X6S,CH6223MEA01    I61 @T6G_MB_LIB.T6G(SCH_1):PAGE195
  PU38 25_29   VIN1 ISL99390FRZTR5935-ISL99390FRZ-TR5935,SMLF,IC,AL099A    I73 @T6G_MB_LIB.T6G(SCH_1):PAGE195
  PU38   30   VIN2 ISL99390FRZTR5935-ISL99390FRZ-TR5935,SMLF,IC,AL099A    I73 @T6G_MB_LIB.T6G(SCH_1):PAGE195
 PC393    1      A Q_CAPP_SMLF-270UF,16V,20%,OSCON,CC72703MZ11    I92 @T6G_MB_LIB.T6G(SCH_1):PAGE193
 PC390    1      A Q_CAPP_SMLF-270UF,16V,20%,OSCON,CC72703MZ11    I93 @T6G_MB_LIB.T6G(SCH_1):PAGE193

SW_P12V_AUX_PVDDCR_SOC_P0_FLT @T6G_MB_LIB.T6G(SCH_1):SW_P12V_AUX_PVDDCR_SOC_P0_FLT
PC584_2    1      A Q_CAP_C0402-1UF,25V,10%,X6S,CH5104KEB02    I23 @T6G_MB_LIB.T6G(SCH_1):PAGE173
PC588_2    1      A Q_CAP_C0805-22UF,16V,20%,X6S,CH6223MEA01    I24 @T6G_MB_LIB.T6G(SCH_1):PAGE173
PC590_2    1      A Q_CAP_C0805-22UF,16V,20%,X6S,CH6223MEA01    I25 @T6G_MB_LIB.T6G(SCH_1):PAGE173
PC583_1    1      A Q_CAP_0402-0.1UF,25V,10%,X7R,CH4104K1B00    I43 @T6G_MB_LIB.T6G(SCH_1):PAGE173
PC608_3    1      A Q_CAP_C0402-1UF,25V,10%,X6S,CH5104KEB02    I21 @T6G_MB_LIB.T6G(SCH_1):PAGE174
PC610_3    1      A Q_CAP_C0805-22UF,16V,20%,X6S,CH6223MEA01    I22 @T6G_MB_LIB.T6G(SCH_1):PAGE174
PC611_3    1      A Q_CAP_C0805-22UF,16V,20%,X6S,CH6223MEA01    I31 @T6G_MB_LIB.T6G(SCH_1):PAGE174
PC613_3    1      A Q_CAP_C0805-22UF,16V,20%,X6S,CH6223MEA01    I32 @T6G_MB_LIB.T6G(SCH_1):PAGE174
PC609_3    1      A Q_CAP_0402-0.1UF,25V,10%,X7R,CH4104K1B00    I37 @T6G_MB_LIB.T6G(SCH_1):PAGE174
  PU51 25_29   VIN1 ISL99390FRZTR5935-ISL99390FRZ-TR5935,SMLF,IC,AL099A    I38 @T6G_MB_LIB.T6G(SCH_1):PAGE174
  PU51   30   VIN2 ISL99390FRZTR5935-ISL99390FRZ-TR5935,SMLF,IC,AL099A    I38 @T6G_MB_LIB.T6G(SCH_1):PAGE174
PC586_2    1      A Q_CAP_0402-0.1UF,25V,10%,X7R,CH4104K1B00    I21 @T6G_MB_LIB.T6G(SCH_1):PAGE173
  PU49 25_29   VIN1 ISL99390FRZTR5935-ISL99390FRZ-TR5935,SMLF,IC,AL099A    I41 @T6G_MB_LIB.T6G(SCH_1):PAGE173
  PU49   30   VIN2 ISL99390FRZTR5935-ISL99390FRZ-TR5935,SMLF,IC,AL099A    I41 @T6G_MB_LIB.T6G(SCH_1):PAGE173
PC585_1    1      A Q_CAP_C0402-1UF,25V,10%,X6S,CH5104KEB02    I44 @T6G_MB_LIB.T6G(SCH_1):PAGE173
PC587_1    1      A Q_CAP_C0805-22UF,16V,20%,X6S,CH6223MEA01    I49 @T6G_MB_LIB.T6G(SCH_1):PAGE173
PC589_1    1      A Q_CAP_C0805-22UF,16V,20%,X6S,CH6223MEA01    I50 @T6G_MB_LIB.T6G(SCH_1):PAGE173
PC591_1    1      A Q_CAP_C0805-22UF,16V,20%,X6S,CH6223MEA01    I51 @T6G_MB_LIB.T6G(SCH_1):PAGE173
PC592_2    1      A Q_CAP_C0805-22UF,16V,20%,X6S,CH6223MEA01    I56 @T6G_MB_LIB.T6G(SCH_1):PAGE173
PC595_2    1      A Q_CAP_C0805-22UF,16V,20%,X6S,CH6223MEA01    I57 @T6G_MB_LIB.T6G(SCH_1):PAGE173
PC593_1    1      A Q_CAP_C0805-22UF,16V,20%,X6S,CH6223MEA01    I72 @T6G_MB_LIB.T6G(SCH_1):PAGE173
 PC596    1      A Q_CAPP_THLF-270UF,16V,20%,OSCON,CC72703MD38    I73 @T6G_MB_LIB.T6G(SCH_1):PAGE173
  PL65    1      1 Q_INDUCTOR_SMLF-50NH/86A,IND,CVA50^0MZ09    I74 @T6G_MB_LIB.T6G(SCH_1):PAGE173
  PU50 25_29   VIN1 ISL99390FRZTR5935-ISL99390FRZ-TR5935,SMLF,IC,AL099A    I86 @T6G_MB_LIB.T6G(SCH_1):PAGE173
  PU50   30   VIN2 ISL99390FRZTR5935-ISL99390FRZ-TR5935,SMLF,IC,AL099A    I86 @T6G_MB_LIB.T6G(SCH_1):PAGE173
PC612_3    1      A Q_CAP_C0805-22UF,16V,20%,X6S,CH6223MEA01    I34 @T6G_MB_LIB.T6G(SCH_1):PAGE174
PC8009    1      A Q_CAP_C0805-22UF,16V,20%,X6S,CH6223MEA01    I87 @T6G_MB_LIB.T6G(SCH_1):PAGE173
PC8010    1      A Q_CAP_C0805-22UF,16V,20%,X6S,CH6223MEA01    I88 @T6G_MB_LIB.T6G(SCH_1):PAGE173

SW_P12V_AUX_PVDDCR_SOC_P1_FLT @T6G_MB_LIB.T6G(SCH_1):SW_P12V_AUX_PVDDCR_SOC_P1_FLT
PC326_2    1      A Q_CAP_0402-0.1UF,25V,10%,X7R,CH4104K1B00    I22 @T6G_MB_LIB.T6G(SCH_1):PAGE190
PC324_2    1      A Q_CAP_C0402-1UF,25V,10%,X6S,CH5104KEB02    I25 @T6G_MB_LIB.T6G(SCH_1):PAGE190
PC328_2    1      A Q_CAP_C0805-22UF,16V,20%,X6S,CH6223MEA01    I26 @T6G_MB_LIB.T6G(SCH_1):PAGE190
PC325_1    1      A Q_CAP_0402-0.1UF,25V,10%,X7R,CH4104K1B00    I43 @T6G_MB_LIB.T6G(SCH_1):PAGE190
PC323_1    1      A Q_CAP_C0402-1UF,25V,10%,X6S,CH5104KEB02    I44 @T6G_MB_LIB.T6G(SCH_1):PAGE190
PC327_1    1      A Q_CAP_C0805-22UF,16V,20%,X6S,CH6223MEA01    I48 @T6G_MB_LIB.T6G(SCH_1):PAGE190
PC349_3    1      A Q_CAP_C0402-1UF,25V,10%,X6S,CH5104KEB02    I20 @T6G_MB_LIB.T6G(SCH_1):PAGE191
PC350_3    1      A Q_CAP_C0805-22UF,16V,20%,X6S,CH6223MEA01    I22 @T6G_MB_LIB.T6G(SCH_1):PAGE191
PC351_3    1      A Q_CAP_C0805-22UF,16V,20%,X6S,CH6223MEA01    I31 @T6G_MB_LIB.T6G(SCH_1):PAGE191
PC352_3    1      A Q_CAP_C0805-22UF,16V,20%,X6S,CH6223MEA01    I32 @T6G_MB_LIB.T6G(SCH_1):PAGE191
PC353_3    1      A Q_CAP_C0805-22UF,16V,20%,X6S,CH6223MEA01    I34 @T6G_MB_LIB.T6G(SCH_1):PAGE191
  PU32 25_29   VIN1 ISL99390FRZTR5935-ISL99390FRZ-TR5935,SMLF,IC,AL099A    I38 @T6G_MB_LIB.T6G(SCH_1):PAGE191
  PU32   30   VIN2 ISL99390FRZTR5935-ISL99390FRZ-TR5935,SMLF,IC,AL099A    I38 @T6G_MB_LIB.T6G(SCH_1):PAGE191
PC348_3    1      A Q_CAP_0402-0.1UF,25V,10%,X7R,CH4104K1B00    I19 @T6G_MB_LIB.T6G(SCH_1):PAGE191
  PU30 25_29   VIN1 ISL99390FRZTR5935-ISL99390FRZ-TR5935,SMLF,IC,AL099A    I17 @T6G_MB_LIB.T6G(SCH_1):PAGE190
  PU30   30   VIN2 ISL99390FRZTR5935-ISL99390FRZ-TR5935,SMLF,IC,AL099A    I17 @T6G_MB_LIB.T6G(SCH_1):PAGE190
PC330_2    1      A Q_CAP_C0805-22UF,16V,20%,X6S,CH6223MEA01    I27 @T6G_MB_LIB.T6G(SCH_1):PAGE190
PC329_1    1      A Q_CAP_C0805-22UF,16V,20%,X6S,CH6223MEA01    I49 @T6G_MB_LIB.T6G(SCH_1):PAGE190
PC331_1    1      A Q_CAP_C0805-22UF,16V,20%,X6S,CH6223MEA01    I50 @T6G_MB_LIB.T6G(SCH_1):PAGE190
PC332_2    1      A Q_CAP_C0805-22UF,16V,20%,X6S,CH6223MEA01    I56 @T6G_MB_LIB.T6G(SCH_1):PAGE190
PC335_2    1      A Q_CAP_C0805-22UF,16V,20%,X6S,CH6223MEA01    I57 @T6G_MB_LIB.T6G(SCH_1):PAGE190
PC334_1    1      A Q_CAP_C0805-22UF,16V,20%,X6S,CH6223MEA01    I71 @T6G_MB_LIB.T6G(SCH_1):PAGE190
 PC336    1      A Q_CAPP_THLF-270UF,16V,20%,OSCON,CC72703MD38    I73 @T6G_MB_LIB.T6G(SCH_1):PAGE190
  PL37    1      1 Q_INDUCTOR_SMLF-50NH/86A,IND,CVA50^0MZ09    I74 @T6G_MB_LIB.T6G(SCH_1):PAGE190
  PU31 25_29   VIN1 ISL99390FRZTR5935-ISL99390FRZ-TR5935,SMLF,IC,AL099A    I86 @T6G_MB_LIB.T6G(SCH_1):PAGE190
  PU31   30   VIN2 ISL99390FRZTR5935-ISL99390FRZ-TR5935,SMLF,IC,AL099A    I86 @T6G_MB_LIB.T6G(SCH_1):PAGE190
PC8011    1      A Q_CAP_C0805-22UF,16V,20%,X6S,CH6223MEA01    I87 @T6G_MB_LIB.T6G(SCH_1):PAGE190
PC8012    1      A Q_CAP_C0805-22UF,16V,20%,X6S,CH6223MEA01    I88 @T6G_MB_LIB.T6G(SCH_1):PAGE190

SW_P12V_AUX_PVDDIO_P0_FLT @T6G_MB_LIB.T6G(SCH_1):SW_P12V_AUX_PVDDIO_P0_FLT
PC182_4    1      A Q_CAP_C0805-22UF,16V,20%,X6S,CH6223MEA01    I46 @T6G_MB_LIB.T6G(SCH_1):PAGE181
  PU18 25_29   VIN1 ISL99390FRZTR5935-ISL99390FRZ-TR5935,SMLF,IC,AL099A    I15 @T6G_MB_LIB.T6G(SCH_1):PAGE180
  PU18   30   VIN2 ISL99390FRZTR5935-ISL99390FRZ-TR5935,SMLF,IC,AL099A    I15 @T6G_MB_LIB.T6G(SCH_1):PAGE180
PC149_2    1      A Q_CAP_0402-0.1UF,25V,10%,X7R,CH4104K1B00    I18 @T6G_MB_LIB.T6G(SCH_1):PAGE180
PC151_2    1      A Q_CAP_C0402-1UF,25V,10%,X6S,CH5104KEB02    I42 @T6G_MB_LIB.T6G(SCH_1):PAGE180
PC153_2    1      A Q_CAP_C0805-22UF,16V,20%,X6S,CH6223MEA01    I43 @T6G_MB_LIB.T6G(SCH_1):PAGE180
PC157_2    1      A Q_CAP_C0805-22UF,16V,20%,X6S,CH6223MEA01    I45 @T6G_MB_LIB.T6G(SCH_1):PAGE180
PC159_2    1      A Q_CAP_C0805-22UF,16V,20%,X6S,CH6223MEA01    I47 @T6G_MB_LIB.T6G(SCH_1):PAGE180
PC158_1    1      A Q_CAP_C0805-22UF,16V,20%,X6S,CH6223MEA01    I66 @T6G_MB_LIB.T6G(SCH_1):PAGE180
 PC164    1      A Q_CAPP_THLF-270UF,16V,20%,OSCON,CC72703MD38    I67 @T6G_MB_LIB.T6G(SCH_1):PAGE180
  PL19    1      1 Q_INDUCTOR_SMLF-50NH/86A,IND,CVA50^0MZ09    I69 @T6G_MB_LIB.T6G(SCH_1):PAGE180
PC154_1    1      A Q_CAP_C0805-22UF,16V,20%,X6S,CH6223MEA01    I80 @T6G_MB_LIB.T6G(SCH_1):PAGE180
PC152_1    1      A Q_CAP_C0805-22UF,16V,20%,X6S,CH6223MEA01    I81 @T6G_MB_LIB.T6G(SCH_1):PAGE180
PC150_1    1      A Q_CAP_C0402-1UF,25V,10%,X6S,CH5104KEB02    I82 @T6G_MB_LIB.T6G(SCH_1):PAGE180
PC148_1    1      A Q_CAP_0402-0.1UF,25V,10%,X7R,CH4104K1B00    I83 @T6G_MB_LIB.T6G(SCH_1):PAGE180
  PU17 25_29   VIN1 ISL99390FRZTR5935-ISL99390FRZ-TR5935,SMLF,IC,AL099A    I84 @T6G_MB_LIB.T6G(SCH_1):PAGE180
  PU17   30   VIN2 ISL99390FRZTR5935-ISL99390FRZ-TR5935,SMLF,IC,AL099A    I84 @T6G_MB_LIB.T6G(SCH_1):PAGE180
PC178_4    1      A Q_CAP_0402-0.1UF,25V,10%,X7R,CH4104K1B00    I17 @T6G_MB_LIB.T6G(SCH_1):PAGE181
  PU19 25_29   VIN1 ISL99390FRZTR5935-ISL99390FRZ-TR5935,SMLF,IC,AL099A    I32 @T6G_MB_LIB.T6G(SCH_1):PAGE181
  PU19   30   VIN2 ISL99390FRZTR5935-ISL99390FRZ-TR5935,SMLF,IC,AL099A    I32 @T6G_MB_LIB.T6G(SCH_1):PAGE181
PC177_3    1      A Q_CAP_0402-0.1UF,25V,10%,X7R,CH4104K1B00    I35 @T6G_MB_LIB.T6G(SCH_1):PAGE181
PC179_3    1      A Q_CAP_C0402-1UF,25V,10%,X6S,CH5104KEB02    I36 @T6G_MB_LIB.T6G(SCH_1):PAGE181
PC180_4    1      A Q_CAP_C0402-1UF,25V,10%,X6S,CH5104KEB02    I45 @T6G_MB_LIB.T6G(SCH_1):PAGE181
PC185_4    1      A Q_CAP_C0805-22UF,16V,20%,X6S,CH6223MEA01    I47 @T6G_MB_LIB.T6G(SCH_1):PAGE181
PC188_4    1      A Q_CAP_C0805-22UF,16V,20%,X6S,CH6223MEA01    I49 @T6G_MB_LIB.T6G(SCH_1):PAGE181
PC181_3    1      A Q_CAP_C0805-22UF,16V,20%,X6S,CH6223MEA01    I58 @T6G_MB_LIB.T6G(SCH_1):PAGE181
PC184_3    1      A Q_CAP_C0805-22UF,16V,20%,X6S,CH6223MEA01    I60 @T6G_MB_LIB.T6G(SCH_1):PAGE181
PC187_3    1      A Q_CAP_C0805-22UF,16V,20%,X6S,CH6223MEA01    I63 @T6G_MB_LIB.T6G(SCH_1):PAGE181
  PU20 25_29   VIN1 ISL99390FRZTR5935-ISL99390FRZ-TR5935,SMLF,IC,AL099A    I73 @T6G_MB_LIB.T6G(SCH_1):PAGE181
  PU20   30   VIN2 ISL99390FRZTR5935-ISL99390FRZ-TR5935,SMLF,IC,AL099A    I73 @T6G_MB_LIB.T6G(SCH_1):PAGE181
PC7000    1      A Q_CAP_C0805-22UF,16V,20%,X6S,CH6223MEA01    I85 @T6G_MB_LIB.T6G(SCH_1):PAGE180

SW_P12V_AUX_PVDDIO_P1_FLT @T6G_MB_LIB.T6G(SCH_1):SW_P12V_AUX_PVDDIO_P1_FLT
  PU53 25_29   VIN1 ISL99390FRZTR5935-ISL99390FRZ-TR5935,SMLF,IC,AL099A    I15 @T6G_MB_LIB.T6G(SCH_1):PAGE198
  PU53   30   VIN2 ISL99390FRZTR5935-ISL99390FRZ-TR5935,SMLF,IC,AL099A    I15 @T6G_MB_LIB.T6G(SCH_1):PAGE198
PC629_4    1      A Q_CAP_C0805-22UF,16V,20%,X6S,CH6223MEA01    I46 @T6G_MB_LIB.T6G(SCH_1):PAGE198
PC632_3    1      A Q_CAP_C0805-22UF,16V,20%,X6S,CH6223MEA01    I65 @T6G_MB_LIB.T6G(SCH_1):PAGE198
PC439_2    1      A Q_CAP_0402-0.1UF,25V,10%,X7R,CH4104K1B00    I21 @T6G_MB_LIB.T6G(SCH_1):PAGE197
PC441_2    1      A Q_CAP_C0402-1UF,25V,10%,X6S,CH5104KEB02    I23 @T6G_MB_LIB.T6G(SCH_1):PAGE197
  PU39 25_29   VIN1 ISL99390FRZTR5935-ISL99390FRZ-TR5935,SMLF,IC,AL099A    I39 @T6G_MB_LIB.T6G(SCH_1):PAGE197
  PU39   30   VIN2 ISL99390FRZTR5935-ISL99390FRZ-TR5935,SMLF,IC,AL099A    I39 @T6G_MB_LIB.T6G(SCH_1):PAGE197
PC438_1    1      A Q_CAP_0402-0.1UF,25V,10%,X7R,CH4104K1B00    I41 @T6G_MB_LIB.T6G(SCH_1):PAGE197
PC440_1    1      A Q_CAP_C0402-1UF,25V,10%,X6S,CH5104KEB02    I42 @T6G_MB_LIB.T6G(SCH_1):PAGE197
PC442_1    1      A Q_CAP_C0805-22UF,16V,20%,X6S,CH6223MEA01    I44 @T6G_MB_LIB.T6G(SCH_1):PAGE197
PC443_2    1      A Q_CAP_C0805-22UF,16V,20%,X6S,CH6223MEA01    I48 @T6G_MB_LIB.T6G(SCH_1):PAGE197
PC446_2    1      A Q_CAP_C0805-22UF,16V,20%,X6S,CH6223MEA01    I49 @T6G_MB_LIB.T6G(SCH_1):PAGE197
PC449_2    1      A Q_CAP_C0805-22UF,16V,20%,X6S,CH6223MEA01    I52 @T6G_MB_LIB.T6G(SCH_1):PAGE197
PC444_1    1      A Q_CAP_C0805-22UF,16V,20%,X6S,CH6223MEA01    I66 @T6G_MB_LIB.T6G(SCH_1):PAGE197
PC448_1    1      A Q_CAP_C0805-22UF,16V,20%,X6S,CH6223MEA01    I69 @T6G_MB_LIB.T6G(SCH_1):PAGE197
  PL49    1      1 Q_INDUCTOR_SMLF-50NH/86A,IND,CVA50^0MZ09    I72 @T6G_MB_LIB.T6G(SCH_1):PAGE197
  PU40 25_29   VIN1 ISL99390FRZTR5935-ISL99390FRZ-TR5935,SMLF,IC,AL099A    I84 @T6G_MB_LIB.T6G(SCH_1):PAGE197
  PU40   30   VIN2 ISL99390FRZTR5935-ISL99390FRZ-TR5935,SMLF,IC,AL099A    I84 @T6G_MB_LIB.T6G(SCH_1):PAGE197
PC623_4    1      A Q_CAP_0402-0.1UF,25V,10%,X7R,CH4104K1B00    I18 @T6G_MB_LIB.T6G(SCH_1):PAGE198
PC622_3    1      A Q_CAP_0402-0.1UF,25V,10%,X7R,CH4104K1B00    I35 @T6G_MB_LIB.T6G(SCH_1):PAGE198
PC624_3    1      A Q_CAP_C0402-1UF,25V,10%,X6S,CH5104KEB02    I36 @T6G_MB_LIB.T6G(SCH_1):PAGE198
PC625_4    1      A Q_CAP_C0402-1UF,25V,10%,X6S,CH5104KEB02    I45 @T6G_MB_LIB.T6G(SCH_1):PAGE198
PC633_4    1      A Q_CAP_C0805-22UF,16V,20%,X6S,CH6223MEA01    I48 @T6G_MB_LIB.T6G(SCH_1):PAGE198
PC626_3    1      A Q_CAP_C0805-22UF,16V,20%,X6S,CH6223MEA01    I60 @T6G_MB_LIB.T6G(SCH_1):PAGE198
PC628_3    1      A Q_CAP_C0805-22UF,16V,20%,X6S,CH6223MEA01    I61 @T6G_MB_LIB.T6G(SCH_1):PAGE198
PC627_4    1      A Q_CAP_C0805-22UF,16V,20%,X6S,CH6223MEA01    I72 @T6G_MB_LIB.T6G(SCH_1):PAGE198
  PU52 25_29   VIN1 ISL99390FRZTR5935-ISL99390FRZ-TR5935,SMLF,IC,AL099A    I73 @T6G_MB_LIB.T6G(SCH_1):PAGE198
  PU52   30   VIN2 ISL99390FRZTR5935-ISL99390FRZ-TR5935,SMLF,IC,AL099A    I73 @T6G_MB_LIB.T6G(SCH_1):PAGE198
 PC454    1      A Q_CAPP_SMLF-270UF,16V,20%,OSCON,CC72703MZ11    I85 @T6G_MB_LIB.T6G(SCH_1):PAGE197
PC7001    1      A Q_CAP_C0805-22UF,16V,20%,X6S,CH6223MEA01    I86 @T6G_MB_LIB.T6G(SCH_1):PAGE197

SW_P12V_AUX_PVDD_33_S5_FLT @T6G_MB_LIB.T6G(SCH_1):SW_P12V_AUX_PVDD_33_S5_FLT
  PL71    2      2 Q_INDUCTOR_SMLF-BLM18SN220TN1D/8000MA,IND,CX220TN1A    I10 @T6G_MB_LIB.T6G(SCH_1):PAGE167
 PC119    1      A Q_CAP_C0805-22UF,16V,20%,X6S,CH6223MEA01    I12 @T6G_MB_LIB.T6G(SCH_1):PAGE167
 PC120    1      A Q_CAP_C0805-22UF,16V,20%,X6S,CH6223MEA01    I13 @T6G_MB_LIB.T6G(SCH_1):PAGE167
 PC123    1      A Q_CAP_C0805-22UF,16V,20%,X6S,CH6223MEA01    I29 @T6G_MB_LIB.T6G(SCH_1):PAGE167
 PC126    1      A Q_CAP_C0402-1UF,25V,10%,X6S,CH5104KEB02    I30 @T6G_MB_LIB.T6G(SCH_1):PAGE167
  PU55   10   VIN1 MPQ8633AGLEC807Z-MPQ8633AGLE-C807-Z,SMLF,IC,AL0086A    I41 @T6G_MB_LIB.T6G(SCH_1):PAGE167
  PU55   21   VIN2 MPQ8633AGLEC807Z-MPQ8633AGLE-C807-Z,SMLF,IC,AL0086A    I41 @T6G_MB_LIB.T6G(SCH_1):PAGE167
PC8000    1      A Q_CAP_C0805-22UF,16V,20%,X6S,CH6223MEA01    I44 @T6G_MB_LIB.T6G(SCH_1):PAGE167
PC8001    1      A Q_CAP_C0805-22UF,16V,20%,X6S,CH6223MEA01    I45 @T6G_MB_LIB.T6G(SCH_1):PAGE167

SW_P1V2_AUX_BT @T6G_MB_LIB.T6G(SCH_1):SW_P1V2_AUX_BT
PU6001   10    BST MPQ8626GDZ-MPQ8626GD-Z,SMLF,IC,AL008626000    I16 @T6G_MB_LIB.T6G(SCH_1):PAGE380
PR8004    1      A Q_RES_0402LF-2.2,1%,1/16W,CHIP,CS-2202FB01    I45 @T6G_MB_LIB.T6G(SCH_1):PAGE380

SW_P1V2_AUX_BT_R @T6G_MB_LIB.T6G(SCH_1):SW_P1V2_AUX_BT_R
PC6017    1      A Q_CAP_C0402-0.22UF,25V,10%,X7R,CH4224K1B01    I18 @T6G_MB_LIB.T6G(SCH_1):PAGE380
PR8004    2      B Q_RES_0402LF-2.2,1%,1/16W,CHIP,CS-2202FB01    I45 @T6G_MB_LIB.T6G(SCH_1):PAGE380

SW_P1V2_AUX_PH @T6G_MB_LIB.T6G(SCH_1):SW_P1V2_AUX_PH
PU6001    2    SW1 MPQ8626GDZ-MPQ8626GD-Z,SMLF,IC,AL008626000    I16 @T6G_MB_LIB.T6G(SCH_1):PAGE380
PU6001   11    SW2 MPQ8626GDZ-MPQ8626GD-Z,SMLF,IC,AL008626000    I16 @T6G_MB_LIB.T6G(SCH_1):PAGE380
PC6017    2      B Q_CAP_C0402-0.22UF,25V,10%,X7R,CH4224K1B01    I18 @T6G_MB_LIB.T6G(SCH_1):PAGE380
PL6001    1      1 Q_INDUCTOR_SMLF-2.2UH,IND,CV-2280MZ15    I24 @T6G_MB_LIB.T6G(SCH_1):PAGE380

SW_P1V8_AUX_BT @T6G_MB_LIB.T6G(SCH_1):SW_P1V8_AUX_BT
PU6000   10    BST MPQ8626GDZ-MPQ8626GD-Z,SMLF,IC,AL008626000    I18 @T6G_MB_LIB.T6G(SCH_1):PAGE315
PR8003    1      A Q_RES_0402LF-2.2,1%,1/16W,CHIP,CS-2202FB01    I45 @T6G_MB_LIB.T6G(SCH_1):PAGE315

SW_P1V8_AUX_BT_R @T6G_MB_LIB.T6G(SCH_1):SW_P1V8_AUX_BT_R
 PC641    1      A Q_CAP_C0402-0.22UF,25V,10%,X7R,CH4224K1B01    I30 @T6G_MB_LIB.T6G(SCH_1):PAGE315
PR8003    2      B Q_RES_0402LF-2.2,1%,1/16W,CHIP,CS-2202FB01    I45 @T6G_MB_LIB.T6G(SCH_1):PAGE315

SW_P1V8_AUX_PH @T6G_MB_LIB.T6G(SCH_1):SW_P1V8_AUX_PH
PU6000    2    SW1 MPQ8626GDZ-MPQ8626GD-Z,SMLF,IC,AL008626000    I18 @T6G_MB_LIB.T6G(SCH_1):PAGE315
PU6000   11    SW2 MPQ8626GDZ-MPQ8626GD-Z,SMLF,IC,AL008626000    I18 @T6G_MB_LIB.T6G(SCH_1):PAGE315
PL6000    1      1 Q_INDUCTOR_SMLF-3.3UH/6A,IND,CV-3360MZ07    I25 @T6G_MB_LIB.T6G(SCH_1):PAGE315
 PC641    2      B Q_CAP_C0402-0.22UF,25V,10%,X7R,CH4224K1B01    I30 @T6G_MB_LIB.T6G(SCH_1):PAGE315

SW_P1V8_RETIMER_CPU0_BST @T6G_MB_LIB.T6G(SCH_1):SW_P1V8_RETIMER_CPU0_BST
PR6800    1      A Q_RES_0402LF-2.2,1%,1/16W,CHIP,CS-2202FB01    I29 @T6G_MB_LIB.T6G(SCH_1):PAGE469
PU6500    1    BST MPQ8633BGLEC838Z-MPQ8633BGLE-C838-Z,SMLF,IC,AL0086A    I51 @T6G_MB_LIB.T6G(SCH_1):PAGE469

SW_P1V8_RETIMER_CPU0_BST_R @T6G_MB_LIB.T6G(SCH_1):SW_P1V8_RETIMER_CPU0_BST_R
PR6800    2      B Q_RES_0402LF-2.2,1%,1/16W,CHIP,CS-2202FB01    I29 @T6G_MB_LIB.T6G(SCH_1):PAGE469
PC6507    1      A Q_CAP_0402-0.22UF,16V,10%,X7R,CH4223K1B00    I32 @T6G_MB_LIB.T6G(SCH_1):PAGE469

SW_P1V8_RETIMER_CPU0_SW @T6G_MB_LIB.T6G(SCH_1):SW_P1V8_RETIMER_CPU0_SW
PC6507    2      B Q_CAP_0402-0.22UF,16V,10%,X7R,CH4223K1B00    I32 @T6G_MB_LIB.T6G(SCH_1):PAGE469
PL6501    1      1 Q_INDUCTOR_SMLF-1UH,IND,CV-10U0MZ01    I36 @T6G_MB_LIB.T6G(SCH_1):PAGE469
PU6500   20     SW MPQ8633BGLEC838Z-MPQ8633BGLE-C838-Z,SMLF,IC,AL0086A    I51 @T6G_MB_LIB.T6G(SCH_1):PAGE469

SW_P1V8_RETIMER_CPU1_BST @T6G_MB_LIB.T6G(SCH_1):SW_P1V8_RETIMER_CPU1_BST
PR6801    1      A Q_RES_0402LF-2.2,1%,1/16W,CHIP,CS-2202FB01    I28 @T6G_MB_LIB.T6G(SCH_1):PAGE470
PU6501    1    BST MPQ8633BGLEC838Z-MPQ8633BGLE-C838-Z,SMLF,IC,AL0086A    I51 @T6G_MB_LIB.T6G(SCH_1):PAGE470

SW_P1V8_RETIMER_CPU1_BST_R @T6G_MB_LIB.T6G(SCH_1):SW_P1V8_RETIMER_CPU1_BST_R
PR6801    2      B Q_RES_0402LF-2.2,1%,1/16W,CHIP,CS-2202FB01    I28 @T6G_MB_LIB.T6G(SCH_1):PAGE470
PC6526    1      A Q_CAP_0402-0.22UF,16V,10%,X7R,CH4223K1B00    I35 @T6G_MB_LIB.T6G(SCH_1):PAGE470

SW_P1V8_RETIMER_CPU1_SW @T6G_MB_LIB.T6G(SCH_1):SW_P1V8_RETIMER_CPU1_SW
PC6526    2      B Q_CAP_0402-0.22UF,16V,10%,X7R,CH4223K1B00    I35 @T6G_MB_LIB.T6G(SCH_1):PAGE470
PL6502    1      1 Q_INDUCTOR_SMLF-1UH,IND,CV-10U0MZ01    I37 @T6G_MB_LIB.T6G(SCH_1):PAGE470
PU6501   20     SW MPQ8633BGLEC838Z-MPQ8633BGLE-C838-Z,SMLF,IC,AL0086A    I51 @T6G_MB_LIB.T6G(SCH_1):PAGE470

SW_P3V3_AUX_BOOT @T6G_MB_LIB.T6G(SCH_1):SW_P3V3_AUX_BOOT
   PU9   26   BOOT NCP3284AMNTXG-NCP3284AMNTXG,SMLF,IC,AL003284002    I21 @T6G_MB_LIB.T6G(SCH_1):PAGE245
 PR835    1      A Q_RES_0402LF-0,5%,1/16W,CHIP,CS00002JB13    I49 @T6G_MB_LIB.T6G(SCH_1):PAGE245

SW_P3V3_AUX_BOOTR @T6G_MB_LIB.T6G(SCH_1):SW_P3V3_AUX_BOOTR
   PU9   25  PHASE NCP3284AMNTXG-NCP3284AMNTXG,SMLF,IC,AL003284002    I21 @T6G_MB_LIB.T6G(SCH_1):PAGE245
 PC568    1      A Q_CAP_C0402-0.22UF,25V,10%,X7R,CH4224K1B01    I48 @T6G_MB_LIB.T6G(SCH_1):PAGE245

SW_P3V3_AUX_BOOT_R @T6G_MB_LIB.T6G(SCH_1):SW_P3V3_AUX_BOOT_R
 PC568    2      B Q_CAP_C0402-0.22UF,25V,10%,X7R,CH4224K1B01    I48 @T6G_MB_LIB.T6G(SCH_1):PAGE245
 PR835    2      B Q_RES_0402LF-0,5%,1/16W,CHIP,CS00002JB13    I49 @T6G_MB_LIB.T6G(SCH_1):PAGE245

SW_P3V3_AUX_FLT @T6G_MB_LIB.T6G(SCH_1):SW_P3V3_AUX_FLT
   PU9 20_24   PVIN NCP3284AMNTXG-NCP3284AMNTXG,SMLF,IC,AL003284002    I21 @T6G_MB_LIB.T6G(SCH_1):PAGE245
PC2260    1      A Q_CAP_C0805-22UF,16V,20%,X6S,CH6223MEA01    I26 @T6G_MB_LIB.T6G(SCH_1):PAGE245
   PC3    1      A Q_CAPP_THLF-270UF,16V,20%,OSCON,CC72703MD38    I29 @T6G_MB_LIB.T6G(SCH_1):PAGE245
 PC566    1      A Q_CAPP_THLF-270UF,16V,20%,OSCON,CC72703MD38    I30 @T6G_MB_LIB.T6G(SCH_1):PAGE245
PC2262    1      A Q_CAP_C0805-22UF,16V,20%,X6S,CH6223MEA01    I31 @T6G_MB_LIB.T6G(SCH_1):PAGE245
PC8567    1      A Q_CAP_C0805-22UF,16V,20%,X6S,CH6223MEA01    I32 @T6G_MB_LIB.T6G(SCH_1):PAGE245
PC2263    1      A Q_CAP_C0805-22UF,16V,20%,X6S,CH6223MEA01    I33 @T6G_MB_LIB.T6G(SCH_1):PAGE245
PC2342    1      A Q_CAP_C0805-22UF,16V,20%,X6S,CH6223MEA01    I34 @T6G_MB_LIB.T6G(SCH_1):PAGE245
 PC570    1      A Q_CAP_C0805-22UF,16V,20%,X6S,CH6223MEA01    I35 @T6G_MB_LIB.T6G(SCH_1):PAGE245
 PC571    1      A Q_CAP_C0805-22UF,16V,20%,X6S,CH6223MEA01    I36 @T6G_MB_LIB.T6G(SCH_1):PAGE245
PC2343    1      A Q_CAP_C0805-22UF,16V,20%,X6S,CH6223MEA01    I37 @T6G_MB_LIB.T6G(SCH_1):PAGE245
PC2344    1      A Q_CAP_C0805-22UF,16V,20%,X6S,CH6223MEA01    I38 @T6G_MB_LIB.T6G(SCH_1):PAGE245
 PC576    1      A Q_CAP_C0805-22UF,16V,20%,X6S,CH6223MEA01    I39 @T6G_MB_LIB.T6G(SCH_1):PAGE245
PC8071    1      A Q_CAP_C0805-22UF,16V,20%,X6S,CH6223MEA01    I40 @T6G_MB_LIB.T6G(SCH_1):PAGE245
 PC577    1      A Q_CAP_0402-0.1UF,25V,10%,X7R,CH4104K1B00    I41 @T6G_MB_LIB.T6G(SCH_1):PAGE245
PL8045    2      2 Q_INDUCTOR_SMLF-100NH/16A,IND,CV+10G0MZ04    I24 @T6G_MB_LIB.T6G(SCH_1):PAGE245
PC2261    1      A Q_CAP_C0805-22UF,16V,20%,X6S,CH6223MEA01    I27 @T6G_MB_LIB.T6G(SCH_1):PAGE245
PC8013    1      A Q_CAP_C0805-22UF,16V,20%,X6S,CH6223MEA01    I70 @T6G_MB_LIB.T6G(SCH_1):PAGE245
PC8014    1      A Q_CAP_C0805-22UF,16V,20%,X6S,CH6223MEA01    I71 @T6G_MB_LIB.T6G(SCH_1):PAGE245

SW_P3V3_AUX_SW @T6G_MB_LIB.T6G(SCH_1):SW_P3V3_AUX_SW
   PU9 11_18     SW NCP3284AMNTXG-NCP3284AMNTXG,SMLF,IC,AL003284002    I21 @T6G_MB_LIB.T6G(SCH_1):PAGE245
PL8066    1      1 Q_INDUCTOR_SMLF-1.5UH/53A,IND,CV-15^0MZ02    I55 @T6G_MB_LIB.T6G(SCH_1):PAGE245

SW_P3V3_EN @T6G_MB_LIB.T6G(SCH_1):SW_P3V3_EN
   U18  Y17  PB40C LCMXO3LF9400C5BG484C-LCMXO3LF-9400C-5BG484C,SMLF,IA   I216 @T6G_MB_LIB.T6G(SCH_1):PAGE80
 R6050    1      A Q_RES_0402LF-100K,1%,1/16W,EMPTY,CS41002FB09    I91 @T6G_MB_LIB.T6G(SCH_1):PAGE273
  R496    2      B Q_RES_0402LF-10K,1%,1/16W,EMPTY,CS31002FB08    I93 @T6G_MB_LIB.T6G(SCH_1):PAGE273
  R487    1      A Q_RES_0402LF-0,5%,1/16W,CHIP,CS00002JB13    I95 @T6G_MB_LIB.T6G(SCH_1):PAGE273

SW_P3V3_EN_ISO @T6G_MB_LIB.T6G(SCH_1):SW_P3V3_EN_ISO
    Q3    3     D2 MOSFET_NCH_DUAL-PJT138K,SMLF,IC,BAM138K0003   I108 @T6G_MB_LIB.T6G(SCH_1):PAGE273
  R569    2      B Q_RES_0402LF-1K,1%,1/16W,CHIP,CS21002FB06   I113 @T6G_MB_LIB.T6G(SCH_1):PAGE273

SW_P3V3_EN_ISO_R @T6G_MB_LIB.T6G(SCH_1):SW_P3V3_EN_ISO_R
   Q56    4      4 MOSFET_NCH_1D3S-PSMNR58-30YLH,SMLF,IC,BAMNR580000    I50 @T6G_MB_LIB.T6G(SCH_1):PAGE273
  R569    1      A Q_RES_0402LF-1K,1%,1/16W,CHIP,CS21002FB06   I113 @T6G_MB_LIB.T6G(SCH_1):PAGE273
  R568    2      B Q_RES_0402LF-10K,1%,1/16W,CHIP,CS31002FB08   I114 @T6G_MB_LIB.T6G(SCH_1):PAGE273
   C29    1      A Q_CAP_C0402-0.22UF,25V,10%,X7R,CH4224K1B01   I116 @T6G_MB_LIB.T6G(SCH_1):PAGE273

SW_P3V3_EN_N @T6G_MB_LIB.T6G(SCH_1):SW_P3V3_EN_N
    Q3    6     D1 MOSFET_NCH_DUAL-PJT138K,SMLF,IC,BAM138K0003   I107 @T6G_MB_LIB.T6G(SCH_1):PAGE273
    Q3    5     G2 MOSFET_NCH_DUAL-PJT138K,SMLF,IC,BAM138K0003   I108 @T6G_MB_LIB.T6G(SCH_1):PAGE273
  R554    2      B Q_RES_0402LF-100K,1%,1/16W,CHIP,CS41002FB09   I111 @T6G_MB_LIB.T6G(SCH_1):PAGE273

SW_P3V3_EN_R @T6G_MB_LIB.T6G(SCH_1):SW_P3V3_EN_R
  R490    2      B Q_RES_0402LF-0,5%,1/16W,EMPTY,CS00002JB13    I88 @T6G_MB_LIB.T6G(SCH_1):PAGE273
  R487    2      B Q_RES_0402LF-0,5%,1/16W,CHIP,CS00002JB13    I95 @T6G_MB_LIB.T6G(SCH_1):PAGE273
    Q3    2     G1 MOSFET_NCH_DUAL-PJT138K,SMLF,IC,BAM138K0003   I107 @T6G_MB_LIB.T6G(SCH_1):PAGE273

SW_P5V_AUX_BST @T6G_MB_LIB.T6G(SCH_1):SW_P5V_AUX_BST
PC1847    1      A Q_CAP_C0402-0.22UF,25V,10%,X7R,CH4224K1B01    I24 @T6G_MB_LIB.T6G(SCH_1):PAGE244
  U326    1    BST MPQ8633AGLEC807Z-MPQ8633AGLE-C807-Z,SMLF,IC,AL0086A    I38 @T6G_MB_LIB.T6G(SCH_1):PAGE244

SW_P5V_AUX_FLT @T6G_MB_LIB.T6G(SCH_1):SW_P5V_AUX_FLT
PL8064    2      2 Q_INDUCTOR_SMLF-BLM18SN220TN1D/8000MA,IND,CX220TN1A     I5 @T6G_MB_LIB.T6G(SCH_1):PAGE244
PC1849    1      A Q_CAP_C0805-22UF,16V,20%,X6S,CH6223MEA01     I7 @T6G_MB_LIB.T6G(SCH_1):PAGE244
PC1850    1      A Q_CAP_C0805-22UF,16V,20%,X6S,CH6223MEA01    I10 @T6G_MB_LIB.T6G(SCH_1):PAGE244
PC1898    1      A Q_CAP_C0805-22UF,16V,20%,X6S,CH6223MEA01    I11 @T6G_MB_LIB.T6G(SCH_1):PAGE244
PC1846    1      A Q_CAP_C0402-1UF,16V,10%,X6S,CH5103KEB01    I13 @T6G_MB_LIB.T6G(SCH_1):PAGE244
  U326   10   VIN1 MPQ8633AGLEC807Z-MPQ8633AGLE-C807-Z,SMLF,IC,AL0086A    I38 @T6G_MB_LIB.T6G(SCH_1):PAGE244
  U326   21   VIN2 MPQ8633AGLEC807Z-MPQ8633AGLE-C807-Z,SMLF,IC,AL0086A    I38 @T6G_MB_LIB.T6G(SCH_1):PAGE244

SW_P5V_AUX_SW @T6G_MB_LIB.T6G(SCH_1):SW_P5V_AUX_SW
PC1847    2      B Q_CAP_C0402-0.22UF,25V,10%,X7R,CH4224K1B01    I24 @T6G_MB_LIB.T6G(SCH_1):PAGE244
PL8065    1      1 Q_INDUCTOR_SMLF-4.7UH,IND,CV-47A0MZ10    I28 @T6G_MB_LIB.T6G(SCH_1):PAGE244
  U326   20     SW MPQ8633AGLEC807Z-MPQ8633AGLE-C807-Z,SMLF,IC,AL0086A    I38 @T6G_MB_LIB.T6G(SCH_1):PAGE244

SW_PVDD11_S3_P0_BOOT1 @T6G_MB_LIB.T6G(SCH_1):SW_PVDD11_S3_P0_BOOT1
 PR135    1      A Q_RES_0402LF-5.6,1%,1/16W,CHIP,CS-5602FB01    I46 @T6G_MB_LIB.T6G(SCH_1):PAGE183
  PU22   33   BOOT ISL99390FRZTR5935-ISL99390FRZ-TR5935,SMLF,IC,AL099A    I92 @T6G_MB_LIB.T6G(SCH_1):PAGE183

SW_PVDD11_S3_P0_BOOT1_RC @T6G_MB_LIB.T6G(SCH_1):SW_PVDD11_S3_P0_BOOT1_RC
 PR135    2      B Q_RES_0402LF-5.6,1%,1/16W,CHIP,CS-5602FB01    I46 @T6G_MB_LIB.T6G(SCH_1):PAGE183
 PC217    1      A Q_CAP_0402-0.22UF,16V,10%,X7R,CH4223K1B00    I71 @T6G_MB_LIB.T6G(SCH_1):PAGE183

SW_PVDD11_S3_P0_BOOT2 @T6G_MB_LIB.T6G(SCH_1):SW_PVDD11_S3_P0_BOOT2
 PR136    1      A Q_RES_0402LF-5.6,1%,1/16W,CHIP,CS-5602FB01    I25 @T6G_MB_LIB.T6G(SCH_1):PAGE183
  PU23   33   BOOT ISL99390FRZTR5935-ISL99390FRZ-TR5935,SMLF,IC,AL099A    I13 @T6G_MB_LIB.T6G(SCH_1):PAGE183

SW_PVDD11_S3_P0_BOOT2_RC @T6G_MB_LIB.T6G(SCH_1):SW_PVDD11_S3_P0_BOOT2_RC
 PR136    2      B Q_RES_0402LF-5.6,1%,1/16W,CHIP,CS-5602FB01    I25 @T6G_MB_LIB.T6G(SCH_1):PAGE183
 PC218    1      A Q_CAP_0402-0.22UF,16V,10%,X7R,CH4223K1B00    I51 @T6G_MB_LIB.T6G(SCH_1):PAGE183

SW_PVDD11_S3_P0_PH1 @T6G_MB_LIB.T6G(SCH_1):SW_PVDD11_S3_P0_PH1
 PC217    2      B Q_CAP_0402-0.22UF,16V,10%,X7R,CH4223K1B00    I71 @T6G_MB_LIB.T6G(SCH_1):PAGE183
  PU22   32  PHASE ISL99390FRZTR5935-ISL99390FRZ-TR5935,SMLF,IC,AL099A    I92 @T6G_MB_LIB.T6G(SCH_1):PAGE183

SW_PVDD11_S3_P0_PH2 @T6G_MB_LIB.T6G(SCH_1):SW_PVDD11_S3_P0_PH2
  PU23   32  PHASE ISL99390FRZTR5935-ISL99390FRZ-TR5935,SMLF,IC,AL099A    I13 @T6G_MB_LIB.T6G(SCH_1):PAGE183
 PC218    2      B Q_CAP_0402-0.22UF,16V,10%,X7R,CH4223K1B00    I51 @T6G_MB_LIB.T6G(SCH_1):PAGE183

SW_PVDD11_S3_P0_SW1 @T6G_MB_LIB.T6G(SCH_1):SW_PVDD11_S3_P0_SW1
 PC169    1      A Q_CAP_C0402-560PF,50V,10%,EMPTY,CH1566K1B09    I45 @T6G_MB_LIB.T6G(SCH_1):PAGE183
  PL23    1      1 Q_INDUCTOR_SMLF-90NH/155A,IND,CVA90^0KZ13    I73 @T6G_MB_LIB.T6G(SCH_1):PAGE183
  PU22 10_19     SW ISL99390FRZTR5935-ISL99390FRZ-TR5935,SMLF,IC,AL099A    I92 @T6G_MB_LIB.T6G(SCH_1):PAGE183

SW_PVDD11_S3_P0_SW1_RC @T6G_MB_LIB.T6G(SCH_1):SW_PVDD11_S3_P0_SW1_RC
 PR482    1      A Q_RES_0402LF-1.5,1%,1/8W,EMPTY,CS-1504FB00    I33 @T6G_MB_LIB.T6G(SCH_1):PAGE183
 PC169    2      B Q_CAP_C0402-560PF,50V,10%,EMPTY,CH1566K1B09    I45 @T6G_MB_LIB.T6G(SCH_1):PAGE183

SW_PVDD11_S3_P0_SW2 @T6G_MB_LIB.T6G(SCH_1):SW_PVDD11_S3_P0_SW2
 PC168    1      A Q_CAP_C0402-560PF,50V,10%,EMPTY,CH1566K1B09    I26 @T6G_MB_LIB.T6G(SCH_1):PAGE183
  PL22    1      1 Q_INDUCTOR_SMLF-90NH/155A,IND,CVA90^0KZ13    I52 @T6G_MB_LIB.T6G(SCH_1):PAGE183
  PU23 10_19     SW ISL99390FRZTR5935-ISL99390FRZ-TR5935,SMLF,IC,AL099A    I13 @T6G_MB_LIB.T6G(SCH_1):PAGE183

SW_PVDD11_S3_P0_SW2_RC @T6G_MB_LIB.T6G(SCH_1):SW_PVDD11_S3_P0_SW2_RC
 PR389    1      A Q_RES_0402LF-1.5,1%,1/8W,EMPTY,CS-1504FB00    I24 @T6G_MB_LIB.T6G(SCH_1):PAGE183
 PC168    2      B Q_CAP_C0402-560PF,50V,10%,EMPTY,CH1566K1B09    I26 @T6G_MB_LIB.T6G(SCH_1):PAGE183

SW_PVDD11_S3_P1_BOOT1 @T6G_MB_LIB.T6G(SCH_1):SW_PVDD11_S3_P1_BOOT1
  PU44   33   BOOT ISL99390FRZTR5935-ISL99390FRZ-TR5935,SMLF,IC,AL099A    I22 @T6G_MB_LIB.T6G(SCH_1):PAGE200
 PR330    1      A Q_RES_0402LF-5.6,1%,1/16W,CHIP,CS-5602FB01    I47 @T6G_MB_LIB.T6G(SCH_1):PAGE200

SW_PVDD11_S3_P1_BOOT1_RC @T6G_MB_LIB.T6G(SCH_1):SW_PVDD11_S3_P1_BOOT1_RC
 PR330    2      B Q_RES_0402LF-5.6,1%,1/16W,CHIP,CS-5602FB01    I47 @T6G_MB_LIB.T6G(SCH_1):PAGE200
 PC519    1      A Q_CAP_0402-0.22UF,16V,10%,X7R,CH4223K1B00    I76 @T6G_MB_LIB.T6G(SCH_1):PAGE200

SW_PVDD11_S3_P1_BOOT2 @T6G_MB_LIB.T6G(SCH_1):SW_PVDD11_S3_P1_BOOT2
 PR331    1      A Q_RES_0402LF-5.6,1%,1/16W,CHIP,CS-5602FB01    I26 @T6G_MB_LIB.T6G(SCH_1):PAGE200
  PU45   33   BOOT ISL99390FRZTR5935-ISL99390FRZ-TR5935,SMLF,IC,AL099A    I92 @T6G_MB_LIB.T6G(SCH_1):PAGE200

SW_PVDD11_S3_P1_BOOT2_RC @T6G_MB_LIB.T6G(SCH_1):SW_PVDD11_S3_P1_BOOT2_RC
 PR331    2      B Q_RES_0402LF-5.6,1%,1/16W,CHIP,CS-5602FB01    I26 @T6G_MB_LIB.T6G(SCH_1):PAGE200
 PC520    1      A Q_CAP_0402-0.22UF,16V,10%,X7R,CH4223K1B00    I54 @T6G_MB_LIB.T6G(SCH_1):PAGE200

SW_PVDD11_S3_P1_PH1 @T6G_MB_LIB.T6G(SCH_1):SW_PVDD11_S3_P1_PH1
  PU44   32  PHASE ISL99390FRZTR5935-ISL99390FRZ-TR5935,SMLF,IC,AL099A    I22 @T6G_MB_LIB.T6G(SCH_1):PAGE200
 PC519    2      B Q_CAP_0402-0.22UF,16V,10%,X7R,CH4223K1B00    I76 @T6G_MB_LIB.T6G(SCH_1):PAGE200

SW_PVDD11_S3_P1_PH2 @T6G_MB_LIB.T6G(SCH_1):SW_PVDD11_S3_P1_PH2
 PC520    2      B Q_CAP_0402-0.22UF,16V,10%,X7R,CH4223K1B00    I54 @T6G_MB_LIB.T6G(SCH_1):PAGE200
  PU45   32  PHASE ISL99390FRZTR5935-ISL99390FRZ-TR5935,SMLF,IC,AL099A    I92 @T6G_MB_LIB.T6G(SCH_1):PAGE200

SW_PVDD11_S3_P1_SW1 @T6G_MB_LIB.T6G(SCH_1):SW_PVDD11_S3_P1_SW1
  PU44 10_19     SW ISL99390FRZTR5935-ISL99390FRZ-TR5935,SMLF,IC,AL099A    I22 @T6G_MB_LIB.T6G(SCH_1):PAGE200
 PC315    1      A Q_CAP_C0402-560PF,50V,10%,EMPTY,CH1566K1B09    I46 @T6G_MB_LIB.T6G(SCH_1):PAGE200
  PL54    1      1 Q_INDUCTOR_SMLF-90NH/155A,IND,CVA90^0KZ13    I78 @T6G_MB_LIB.T6G(SCH_1):PAGE200

SW_PVDD11_S3_P1_SW1_RC @T6G_MB_LIB.T6G(SCH_1):SW_PVDD11_S3_P1_SW1_RC
 PR520    1      A Q_RES_0402LF-1.5,1%,1/8W,EMPTY,CS-1504FB00    I33 @T6G_MB_LIB.T6G(SCH_1):PAGE200
 PC315    2      B Q_CAP_C0402-560PF,50V,10%,EMPTY,CH1566K1B09    I46 @T6G_MB_LIB.T6G(SCH_1):PAGE200

SW_PVDD11_S3_P1_SW2 @T6G_MB_LIB.T6G(SCH_1):SW_PVDD11_S3_P1_SW2
 PC255    1      A Q_CAP_C0402-560PF,50V,10%,EMPTY,CH1566K1B09    I27 @T6G_MB_LIB.T6G(SCH_1):PAGE200
  PL55    1      1 Q_INDUCTOR_SMLF-90NH/155A,IND,CVA90^0KZ13    I55 @T6G_MB_LIB.T6G(SCH_1):PAGE200
  PU45 10_19     SW ISL99390FRZTR5935-ISL99390FRZ-TR5935,SMLF,IC,AL099A    I92 @T6G_MB_LIB.T6G(SCH_1):PAGE200

SW_PVDD11_S3_P1_SW2_RC @T6G_MB_LIB.T6G(SCH_1):SW_PVDD11_S3_P1_SW2_RC
 PR519    1      A Q_RES_0402LF-1.5,1%,1/8W,EMPTY,CS-1504FB00    I25 @T6G_MB_LIB.T6G(SCH_1):PAGE200
 PC255    2      B Q_CAP_C0402-560PF,50V,10%,EMPTY,CH1566K1B09    I27 @T6G_MB_LIB.T6G(SCH_1):PAGE200

SW_PVDD18_S5_P0_BST @T6G_MB_LIB.T6G(SCH_1):SW_PVDD18_S5_P0_BST
  PU57    1    BST MPQ8633BGLEC838Z-MPQ8633BGLE-C838-Z,SMLF,IC,AL0086A    I18 @T6G_MB_LIB.T6G(SCH_1):PAGE184
PR8001    1      A Q_RES_0402LF-2.2,1%,1/16W,CHIP,CS-2202FB01    I58 @T6G_MB_LIB.T6G(SCH_1):PAGE184

SW_PVDD18_S5_P0_BST_R @T6G_MB_LIB.T6G(SCH_1):SW_PVDD18_S5_P0_BST_R
 PC209    1      A Q_CAP_0402-0.22UF,16V,10%,X7R,CH4223K1B00    I24 @T6G_MB_LIB.T6G(SCH_1):PAGE184
PR8001    2      B Q_RES_0402LF-2.2,1%,1/16W,CHIP,CS-2202FB01    I58 @T6G_MB_LIB.T6G(SCH_1):PAGE184

SW_PVDD18_S5_P0_SW @T6G_MB_LIB.T6G(SCH_1):SW_PVDD18_S5_P0_SW
  PU57   20     SW MPQ8633BGLEC838Z-MPQ8633BGLE-C838-Z,SMLF,IC,AL0086A    I18 @T6G_MB_LIB.T6G(SCH_1):PAGE184
 PC209    2      B Q_CAP_0402-0.22UF,16V,10%,X7R,CH4223K1B00    I24 @T6G_MB_LIB.T6G(SCH_1):PAGE184
  PL78    1      1 Q_INDUCTOR_SMLF-1.0UH/18A,IND,CV-10I0MZ01    I36 @T6G_MB_LIB.T6G(SCH_1):PAGE184

SW_PVDD18_S5_P1_BST @T6G_MB_LIB.T6G(SCH_1):SW_PVDD18_S5_P1_BST
   PU3    1    BST MPQ8633BGLEC838Z-MPQ8633BGLE-C838-Z,SMLF,IC,AL0086A    I15 @T6G_MB_LIB.T6G(SCH_1):PAGE201
PR8002    1      A Q_RES_0402LF-2.2,1%,1/16W,CHIP,CS-2202FB01    I58 @T6G_MB_LIB.T6G(SCH_1):PAGE201

SW_PVDD18_S5_P1_BST_R @T6G_MB_LIB.T6G(SCH_1):SW_PVDD18_S5_P1_BST_R
  PC19    1      A Q_CAP_0402-0.22UF,16V,10%,X7R,CH4223K1B00    I25 @T6G_MB_LIB.T6G(SCH_1):PAGE201
PR8002    2      B Q_RES_0402LF-2.2,1%,1/16W,CHIP,CS-2202FB01    I58 @T6G_MB_LIB.T6G(SCH_1):PAGE201

SW_PVDD18_S5_P1_SW @T6G_MB_LIB.T6G(SCH_1):SW_PVDD18_S5_P1_SW
   PU3   20     SW MPQ8633BGLEC838Z-MPQ8633BGLE-C838-Z,SMLF,IC,AL0086A    I15 @T6G_MB_LIB.T6G(SCH_1):PAGE201
  PC19    2      B Q_CAP_0402-0.22UF,16V,10%,X7R,CH4223K1B00    I25 @T6G_MB_LIB.T6G(SCH_1):PAGE201
  PL57    1      1 Q_INDUCTOR_SMLF-1.0UH/18A,IND,CV-10I0MZ01    I33 @T6G_MB_LIB.T6G(SCH_1):PAGE201

SW_PVDDCR_CPU0_P0_BOOT1 @T6G_MB_LIB.T6G(SCH_1):SW_PVDDCR_CPU0_P0_BOOT1
   PU6   33   BOOT ISL99390FRZTR5935-ISL99390FRZ-TR5935,SMLF,IC,AL099A    I26 @T6G_MB_LIB.T6G(SCH_1):PAGE169
 PR322    1      A Q_RES_0402LF-5.6,1%,1/16W,CHIP,CS-5602FB01    I55 @T6G_MB_LIB.T6G(SCH_1):PAGE169

SW_PVDDCR_CPU0_P0_BOOT1_RC @T6G_MB_LIB.T6G(SCH_1):SW_PVDDCR_CPU0_P0_BOOT1_RC
 PR322    2      B Q_RES_0402LF-5.6,1%,1/16W,CHIP,CS-5602FB01    I55 @T6G_MB_LIB.T6G(SCH_1):PAGE169
 PC489    1      A Q_CAP_0402-0.22UF,16V,10%,X7R,CH4223K1B00    I76 @T6G_MB_LIB.T6G(SCH_1):PAGE169

SW_PVDDCR_CPU0_P0_BOOT2 @T6G_MB_LIB.T6G(SCH_1):SW_PVDDCR_CPU0_P0_BOOT2
  PU43   33   BOOT ISL99390FRZTR5935-ISL99390FRZ-TR5935,SMLF,IC,AL099A    I16 @T6G_MB_LIB.T6G(SCH_1):PAGE169
 PR323    1      A Q_RES_0402LF-5.6,1%,1/16W,CHIP,CS-5602FB01    I32 @T6G_MB_LIB.T6G(SCH_1):PAGE169

SW_PVDDCR_CPU0_P0_BOOT2_RC @T6G_MB_LIB.T6G(SCH_1):SW_PVDDCR_CPU0_P0_BOOT2_RC
 PR323    2      B Q_RES_0402LF-5.6,1%,1/16W,CHIP,CS-5602FB01    I32 @T6G_MB_LIB.T6G(SCH_1):PAGE169
 PC490    1      A Q_CAP_0402-0.22UF,16V,10%,X7R,CH4223K1B00    I61 @T6G_MB_LIB.T6G(SCH_1):PAGE169

SW_PVDDCR_CPU0_P0_BOOT3 @T6G_MB_LIB.T6G(SCH_1):SW_PVDDCR_CPU0_P0_BOOT3
  PU46   33   BOOT ISL99390FRZTR5935-ISL99390FRZ-TR5935,SMLF,IC,AL099A    I38 @T6G_MB_LIB.T6G(SCH_1):PAGE170
 PR348    1      A Q_RES_0402LF-5.6,1%,1/16W,CHIP,CS-5602FB01    I46 @T6G_MB_LIB.T6G(SCH_1):PAGE170

SW_PVDDCR_CPU0_P0_BOOT3_RC @T6G_MB_LIB.T6G(SCH_1):SW_PVDDCR_CPU0_P0_BOOT3_RC
 PR348    2      B Q_RES_0402LF-5.6,1%,1/16W,CHIP,CS-5602FB01    I46 @T6G_MB_LIB.T6G(SCH_1):PAGE170
 PC560    1      A Q_CAP_0402-0.22UF,16V,10%,X7R,CH4223K1B00    I63 @T6G_MB_LIB.T6G(SCH_1):PAGE170

SW_PVDDCR_CPU0_P0_BOOT4 @T6G_MB_LIB.T6G(SCH_1):SW_PVDDCR_CPU0_P0_BOOT4
 PR349    1      A Q_RES_0402LF-5.6,1%,1/16W,CHIP,CS-5602FB01    I20 @T6G_MB_LIB.T6G(SCH_1):PAGE170
  PU47   33   BOOT ISL99390FRZTR5935-ISL99390FRZ-TR5935,SMLF,IC,AL099A     I9 @T6G_MB_LIB.T6G(SCH_1):PAGE170

SW_PVDDCR_CPU0_P0_BOOT4_RC @T6G_MB_LIB.T6G(SCH_1):SW_PVDDCR_CPU0_P0_BOOT4_RC
 PR349    2      B Q_RES_0402LF-5.6,1%,1/16W,CHIP,CS-5602FB01    I20 @T6G_MB_LIB.T6G(SCH_1):PAGE170
 PC561    1      A Q_CAP_0402-0.22UF,16V,10%,X7R,CH4223K1B00    I53 @T6G_MB_LIB.T6G(SCH_1):PAGE170

SW_PVDDCR_CPU0_P0_BOOT5 @T6G_MB_LIB.T6G(SCH_1):SW_PVDDCR_CPU0_P0_BOOT5
  PU48   33   BOOT ISL99390FRZTR5935-ISL99390FRZ-TR5935,SMLF,IC,AL099A    I18 @T6G_MB_LIB.T6G(SCH_1):PAGE171
 PR354    1      A Q_RES_0402LF-5.6,1%,1/16W,CHIP,CS-5602FB01    I45 @T6G_MB_LIB.T6G(SCH_1):PAGE171

SW_PVDDCR_CPU0_P0_BOOT5_RC @T6G_MB_LIB.T6G(SCH_1):SW_PVDDCR_CPU0_P0_BOOT5_RC
 PR354    2      B Q_RES_0402LF-5.6,1%,1/16W,CHIP,CS-5602FB01    I45 @T6G_MB_LIB.T6G(SCH_1):PAGE171
 PC574    1      A Q_CAP_0402-0.22UF,16V,10%,X7R,CH4223K1B00    I63 @T6G_MB_LIB.T6G(SCH_1):PAGE171

SW_PVDDCR_CPU0_P0_BOOT6 @T6G_MB_LIB.T6G(SCH_1):SW_PVDDCR_CPU0_P0_BOOT6
 PR432    1      A Q_RES_0402LF-5.6,1%,1/16W,CHIP,CS-5602FB01    I26 @T6G_MB_LIB.T6G(SCH_1):PAGE171
  PU10   33   BOOT ISL99390FRZTR5935-ISL99390FRZ-TR5935,SMLF,IC,AL099A    I73 @T6G_MB_LIB.T6G(SCH_1):PAGE171

SW_PVDDCR_CPU0_P0_BOOT6_RC @T6G_MB_LIB.T6G(SCH_1):SW_PVDDCR_CPU0_P0_BOOT6_RC
 PR432    2      B Q_RES_0402LF-5.6,1%,1/16W,CHIP,CS-5602FB01    I26 @T6G_MB_LIB.T6G(SCH_1):PAGE171
 PC161    1      A Q_CAP_0402-0.22UF,16V,10%,X7R,CH4223K1B00    I54 @T6G_MB_LIB.T6G(SCH_1):PAGE171

SW_PVDDCR_CPU0_P0_PH1 @T6G_MB_LIB.T6G(SCH_1):SW_PVDDCR_CPU0_P0_PH1
   PU6   32  PHASE ISL99390FRZTR5935-ISL99390FRZ-TR5935,SMLF,IC,AL099A    I26 @T6G_MB_LIB.T6G(SCH_1):PAGE169
 PC489    2      B Q_CAP_0402-0.22UF,16V,10%,X7R,CH4223K1B00    I76 @T6G_MB_LIB.T6G(SCH_1):PAGE169

SW_PVDDCR_CPU0_P0_PH2 @T6G_MB_LIB.T6G(SCH_1):SW_PVDDCR_CPU0_P0_PH2
  PU43   32  PHASE ISL99390FRZTR5935-ISL99390FRZ-TR5935,SMLF,IC,AL099A    I16 @T6G_MB_LIB.T6G(SCH_1):PAGE169
 PC490    2      B Q_CAP_0402-0.22UF,16V,10%,X7R,CH4223K1B00    I61 @T6G_MB_LIB.T6G(SCH_1):PAGE169

SW_PVDDCR_CPU0_P0_PH3 @T6G_MB_LIB.T6G(SCH_1):SW_PVDDCR_CPU0_P0_PH3
  PU46   32  PHASE ISL99390FRZTR5935-ISL99390FRZ-TR5935,SMLF,IC,AL099A    I38 @T6G_MB_LIB.T6G(SCH_1):PAGE170
 PC560    2      B Q_CAP_0402-0.22UF,16V,10%,X7R,CH4223K1B00    I63 @T6G_MB_LIB.T6G(SCH_1):PAGE170

SW_PVDDCR_CPU0_P0_PH4 @T6G_MB_LIB.T6G(SCH_1):SW_PVDDCR_CPU0_P0_PH4
  PU47   32  PHASE ISL99390FRZTR5935-ISL99390FRZ-TR5935,SMLF,IC,AL099A     I9 @T6G_MB_LIB.T6G(SCH_1):PAGE170
 PC561    2      B Q_CAP_0402-0.22UF,16V,10%,X7R,CH4223K1B00    I53 @T6G_MB_LIB.T6G(SCH_1):PAGE170

SW_PVDDCR_CPU0_P0_PH5 @T6G_MB_LIB.T6G(SCH_1):SW_PVDDCR_CPU0_P0_PH5
  PU48   32  PHASE ISL99390FRZTR5935-ISL99390FRZ-TR5935,SMLF,IC,AL099A    I18 @T6G_MB_LIB.T6G(SCH_1):PAGE171
 PC574    2      B Q_CAP_0402-0.22UF,16V,10%,X7R,CH4223K1B00    I63 @T6G_MB_LIB.T6G(SCH_1):PAGE171

SW_PVDDCR_CPU0_P0_PH6 @T6G_MB_LIB.T6G(SCH_1):SW_PVDDCR_CPU0_P0_PH6
 PC161    2      B Q_CAP_0402-0.22UF,16V,10%,X7R,CH4223K1B00    I54 @T6G_MB_LIB.T6G(SCH_1):PAGE171
  PU10   32  PHASE ISL99390FRZTR5935-ISL99390FRZ-TR5935,SMLF,IC,AL099A    I73 @T6G_MB_LIB.T6G(SCH_1):PAGE171

SW_PVDDCR_CPU0_P0_SW1 @T6G_MB_LIB.T6G(SCH_1):SW_PVDDCR_CPU0_P0_SW1
   PU6 10_19     SW ISL99390FRZTR5935-ISL99390FRZ-TR5935,SMLF,IC,AL099A    I26 @T6G_MB_LIB.T6G(SCH_1):PAGE169
 PC178    1      A Q_CAP_C0402-560PF,50V,10%,EMPTY,CH1566K1B09    I54 @T6G_MB_LIB.T6G(SCH_1):PAGE169
  PL51    1      1 Q_INDUCTOR4P_14-150NH,SMLF,IND,CV+15^0TZ04    I77 @T6G_MB_LIB.T6G(SCH_1):PAGE169

SW_PVDDCR_CPU0_P0_SW1_RC @T6G_MB_LIB.T6G(SCH_1):SW_PVDDCR_CPU0_P0_SW1_RC
 PR495    1      A Q_RES_0402LF-1.5,1%,1/8W,EMPTY,CS-1504FB00    I42 @T6G_MB_LIB.T6G(SCH_1):PAGE169
 PC178    2      B Q_CAP_C0402-560PF,50V,10%,EMPTY,CH1566K1B09    I54 @T6G_MB_LIB.T6G(SCH_1):PAGE169

SW_PVDDCR_CPU0_P0_SW2 @T6G_MB_LIB.T6G(SCH_1):SW_PVDDCR_CPU0_P0_SW2
  PU43 10_19     SW ISL99390FRZTR5935-ISL99390FRZ-TR5935,SMLF,IC,AL099A    I16 @T6G_MB_LIB.T6G(SCH_1):PAGE169
 PC179    1      A Q_CAP_C0402-560PF,50V,10%,EMPTY,CH1566K1B09    I31 @T6G_MB_LIB.T6G(SCH_1):PAGE169
  PL52    1      1 Q_INDUCTOR4P_14-150NH,SMLF,IND,CV+15^0TZ04    I62 @T6G_MB_LIB.T6G(SCH_1):PAGE169

SW_PVDDCR_CPU0_P0_SW2_RC @T6G_MB_LIB.T6G(SCH_1):SW_PVDDCR_CPU0_P0_SW2_RC
 PC179    2      B Q_CAP_C0402-560PF,50V,10%,EMPTY,CH1566K1B09    I31 @T6G_MB_LIB.T6G(SCH_1):PAGE169
 PR496    1      A Q_RES_0402LF-1.5,1%,1/8W,EMPTY,CS-1504FB00    I28 @T6G_MB_LIB.T6G(SCH_1):PAGE169

SW_PVDDCR_CPU0_P0_SW3 @T6G_MB_LIB.T6G(SCH_1):SW_PVDDCR_CPU0_P0_SW3
  PU46 10_19     SW ISL99390FRZTR5935-ISL99390FRZ-TR5935,SMLF,IC,AL099A    I38 @T6G_MB_LIB.T6G(SCH_1):PAGE170
 PC180    1      A Q_CAP_C0402-560PF,50V,10%,EMPTY,CH1566K1B09    I45 @T6G_MB_LIB.T6G(SCH_1):PAGE170
  PL59    1      1 Q_INDUCTOR4P_14-150NH,SMLF,IND,CV+15^0TZ04    I64 @T6G_MB_LIB.T6G(SCH_1):PAGE170

SW_PVDDCR_CPU0_P0_SW3_RC @T6G_MB_LIB.T6G(SCH_1):SW_PVDDCR_CPU0_P0_SW3_RC
 PR498    1      A Q_RES_0402LF-1.5,1%,1/8W,EMPTY,CS-1504FB00    I44 @T6G_MB_LIB.T6G(SCH_1):PAGE170
 PC180    2      B Q_CAP_C0402-560PF,50V,10%,EMPTY,CH1566K1B09    I45 @T6G_MB_LIB.T6G(SCH_1):PAGE170

SW_PVDDCR_CPU0_P0_SW4 @T6G_MB_LIB.T6G(SCH_1):SW_PVDDCR_CPU0_P0_SW4
 PC181    1      A Q_CAP_C0402-560PF,50V,10%,EMPTY,CH1566K1B09    I19 @T6G_MB_LIB.T6G(SCH_1):PAGE170
  PU47 10_19     SW ISL99390FRZTR5935-ISL99390FRZ-TR5935,SMLF,IC,AL099A     I9 @T6G_MB_LIB.T6G(SCH_1):PAGE170
  PL60    1      1 Q_INDUCTOR4P_14-150NH,SMLF,IND,CV+15^0TZ04    I52 @T6G_MB_LIB.T6G(SCH_1):PAGE170

SW_PVDDCR_CPU0_P0_SW4_RC @T6G_MB_LIB.T6G(SCH_1):SW_PVDDCR_CPU0_P0_SW4_RC
 PR499    1      A Q_RES_0402LF-1.5,1%,1/8W,EMPTY,CS-1504FB00    I18 @T6G_MB_LIB.T6G(SCH_1):PAGE170
 PC181    2      B Q_CAP_C0402-560PF,50V,10%,EMPTY,CH1566K1B09    I19 @T6G_MB_LIB.T6G(SCH_1):PAGE170

SW_PVDDCR_CPU0_P0_SW5 @T6G_MB_LIB.T6G(SCH_1):SW_PVDDCR_CPU0_P0_SW5
  PU48 10_19     SW ISL99390FRZTR5935-ISL99390FRZ-TR5935,SMLF,IC,AL099A    I18 @T6G_MB_LIB.T6G(SCH_1):PAGE171
 PC184    1      A Q_CAP_C0402-560PF,50V,10%,EMPTY,CH1566K1B09    I46 @T6G_MB_LIB.T6G(SCH_1):PAGE171
  PL61    1      1 Q_INDUCTOR4P_14-150NH,SMLF,IND,CV+15^0TZ04    I64 @T6G_MB_LIB.T6G(SCH_1):PAGE171

SW_PVDDCR_CPU0_P0_SW5_RC @T6G_MB_LIB.T6G(SCH_1):SW_PVDDCR_CPU0_P0_SW5_RC
 PR501    1      A Q_RES_0402LF-1.5,1%,1/8W,EMPTY,CS-1504FB00    I31 @T6G_MB_LIB.T6G(SCH_1):PAGE171
 PC184    2      B Q_CAP_C0402-560PF,50V,10%,EMPTY,CH1566K1B09    I46 @T6G_MB_LIB.T6G(SCH_1):PAGE171

SW_PVDDCR_CPU0_P0_SW6 @T6G_MB_LIB.T6G(SCH_1):SW_PVDDCR_CPU0_P0_SW6
 PC182    1      A Q_CAP_C0402-560PF,50V,10%,EMPTY,CH1566K1B09    I23 @T6G_MB_LIB.T6G(SCH_1):PAGE171
  PL70    1      1 Q_INDUCTOR4P_14-150NH,SMLF,IND,CV+15^0TZ04    I52 @T6G_MB_LIB.T6G(SCH_1):PAGE171
  PU10 10_19     SW ISL99390FRZTR5935-ISL99390FRZ-TR5935,SMLF,IC,AL099A    I73 @T6G_MB_LIB.T6G(SCH_1):PAGE171

SW_PVDDCR_CPU0_P0_SW6_RC @T6G_MB_LIB.T6G(SCH_1):SW_PVDDCR_CPU0_P0_SW6_RC
 PR500    1      A Q_RES_0402LF-1.5,1%,1/8W,EMPTY,CS-1504FB00    I22 @T6G_MB_LIB.T6G(SCH_1):PAGE171
 PC182    2      B Q_CAP_C0402-560PF,50V,10%,EMPTY,CH1566K1B09    I23 @T6G_MB_LIB.T6G(SCH_1):PAGE171

SW_PVDDCR_CPU0_P1_BOOT1 @T6G_MB_LIB.T6G(SCH_1):SW_PVDDCR_CPU0_P1_BOOT1
 PR189    1      A Q_RES_0402LF-5.6,1%,1/16W,CHIP,CS-5602FB01    I49 @T6G_MB_LIB.T6G(SCH_1):PAGE186
   PU4   33   BOOT ISL99390FRZTR5935-ISL99390FRZ-TR5935,SMLF,IC,AL099A    I88 @T6G_MB_LIB.T6G(SCH_1):PAGE186

SW_PVDDCR_CPU0_P1_BOOT1_RC @T6G_MB_LIB.T6G(SCH_1):SW_PVDDCR_CPU0_P1_BOOT1_RC
 PR189    2      B Q_RES_0402LF-5.6,1%,1/16W,CHIP,CS-5602FB01    I49 @T6G_MB_LIB.T6G(SCH_1):PAGE186
 PC270    1      A Q_CAP_0402-0.22UF,16V,10%,X7R,CH4223K1B00    I89 @T6G_MB_LIB.T6G(SCH_1):PAGE186

SW_PVDDCR_CPU0_P1_BOOT2 @T6G_MB_LIB.T6G(SCH_1):SW_PVDDCR_CPU0_P1_BOOT2
 PR190    1      A Q_RES_0402LF-5.6,1%,1/16W,CHIP,CS-5602FB01    I83 @T6G_MB_LIB.T6G(SCH_1):PAGE186
  PU26   33   BOOT ISL99390FRZTR5935-ISL99390FRZ-TR5935,SMLF,IC,AL099A    I91 @T6G_MB_LIB.T6G(SCH_1):PAGE186

SW_PVDDCR_CPU0_P1_BOOT2_RC @T6G_MB_LIB.T6G(SCH_1):SW_PVDDCR_CPU0_P1_BOOT2_RC
 PC271    1      A Q_CAP_0402-0.22UF,16V,10%,X7R,CH4223K1B00    I55 @T6G_MB_LIB.T6G(SCH_1):PAGE186
 PR190    2      B Q_RES_0402LF-5.6,1%,1/16W,CHIP,CS-5602FB01    I83 @T6G_MB_LIB.T6G(SCH_1):PAGE186

SW_PVDDCR_CPU0_P1_BOOT3 @T6G_MB_LIB.T6G(SCH_1):SW_PVDDCR_CPU0_P1_BOOT3
  PU27   33   BOOT ISL99390FRZTR5935-ISL99390FRZ-TR5935,SMLF,IC,AL099A    I39 @T6G_MB_LIB.T6G(SCH_1):PAGE187
 PR197    1      A Q_RES_0402LF-5.6,1%,1/16W,CHIP,CS-5602FB01    I47 @T6G_MB_LIB.T6G(SCH_1):PAGE187

SW_PVDDCR_CPU0_P1_BOOT3_RC @T6G_MB_LIB.T6G(SCH_1):SW_PVDDCR_CPU0_P1_BOOT3_RC
 PR197    2      B Q_RES_0402LF-5.6,1%,1/16W,CHIP,CS-5602FB01    I47 @T6G_MB_LIB.T6G(SCH_1):PAGE187
 PC300    1      A Q_CAP_0402-0.22UF,16V,10%,X7R,CH4223K1B00    I63 @T6G_MB_LIB.T6G(SCH_1):PAGE187

SW_PVDDCR_CPU0_P1_BOOT4 @T6G_MB_LIB.T6G(SCH_1):SW_PVDDCR_CPU0_P1_BOOT4
  PU28   33   BOOT ISL99390FRZTR5935-ISL99390FRZ-TR5935,SMLF,IC,AL099A     I9 @T6G_MB_LIB.T6G(SCH_1):PAGE187
 PR198    1      A Q_RES_0402LF-5.6,1%,1/16W,CHIP,CS-5602FB01    I21 @T6G_MB_LIB.T6G(SCH_1):PAGE187

SW_PVDDCR_CPU0_P1_BOOT4_RC @T6G_MB_LIB.T6G(SCH_1):SW_PVDDCR_CPU0_P1_BOOT4_RC
 PR198    2      B Q_RES_0402LF-5.6,1%,1/16W,CHIP,CS-5602FB01    I21 @T6G_MB_LIB.T6G(SCH_1):PAGE187
 PC301    1      A Q_CAP_0402-0.22UF,16V,10%,X7R,CH4223K1B00    I52 @T6G_MB_LIB.T6G(SCH_1):PAGE187

SW_PVDDCR_CPU0_P1_BOOT5 @T6G_MB_LIB.T6G(SCH_1):SW_PVDDCR_CPU0_P1_BOOT5
  PU29   33   BOOT ISL99390FRZTR5935-ISL99390FRZ-TR5935,SMLF,IC,AL099A    I18 @T6G_MB_LIB.T6G(SCH_1):PAGE188
 PR203    1      A Q_RES_0402LF-5.6,1%,1/16W,CHIP,CS-5602FB01    I47 @T6G_MB_LIB.T6G(SCH_1):PAGE188

SW_PVDDCR_CPU0_P1_BOOT5_RC @T6G_MB_LIB.T6G(SCH_1):SW_PVDDCR_CPU0_P1_BOOT5_RC
 PR203    2      B Q_RES_0402LF-5.6,1%,1/16W,CHIP,CS-5602FB01    I47 @T6G_MB_LIB.T6G(SCH_1):PAGE188
 PC314    1      A Q_CAP_0402-0.22UF,16V,10%,X7R,CH4223K1B00    I63 @T6G_MB_LIB.T6G(SCH_1):PAGE188

SW_PVDDCR_CPU0_P1_BOOT6 @T6G_MB_LIB.T6G(SCH_1):SW_PVDDCR_CPU0_P1_BOOT6
 PR424    1      A Q_RES_0402LF-5.6,1%,1/16W,CHIP,CS-5602FB01    I28 @T6G_MB_LIB.T6G(SCH_1):PAGE188
  PU24   33   BOOT ISL99390FRZTR5935-ISL99390FRZ-TR5935,SMLF,IC,AL099A    I73 @T6G_MB_LIB.T6G(SCH_1):PAGE188

SW_PVDDCR_CPU0_P1_BOOT6_RC @T6G_MB_LIB.T6G(SCH_1):SW_PVDDCR_CPU0_P1_BOOT6_RC
 PR424    2      B Q_RES_0402LF-5.6,1%,1/16W,CHIP,CS-5602FB01    I28 @T6G_MB_LIB.T6G(SCH_1):PAGE188
 PC133    1      A Q_CAP_0402-0.22UF,16V,10%,X7R,CH4223K1B00    I52 @T6G_MB_LIB.T6G(SCH_1):PAGE188

SW_PVDDCR_CPU0_P1_PH1 @T6G_MB_LIB.T6G(SCH_1):SW_PVDDCR_CPU0_P1_PH1
   PU4   32  PHASE ISL99390FRZTR5935-ISL99390FRZ-TR5935,SMLF,IC,AL099A    I88 @T6G_MB_LIB.T6G(SCH_1):PAGE186
 PC270    2      B Q_CAP_0402-0.22UF,16V,10%,X7R,CH4223K1B00    I89 @T6G_MB_LIB.T6G(SCH_1):PAGE186

SW_PVDDCR_CPU0_P1_PH2 @T6G_MB_LIB.T6G(SCH_1):SW_PVDDCR_CPU0_P1_PH2
 PC271    2      B Q_CAP_0402-0.22UF,16V,10%,X7R,CH4223K1B00    I55 @T6G_MB_LIB.T6G(SCH_1):PAGE186
  PU26   32  PHASE ISL99390FRZTR5935-ISL99390FRZ-TR5935,SMLF,IC,AL099A    I91 @T6G_MB_LIB.T6G(SCH_1):PAGE186

SW_PVDDCR_CPU0_P1_PH3 @T6G_MB_LIB.T6G(SCH_1):SW_PVDDCR_CPU0_P1_PH3
  PU27   32  PHASE ISL99390FRZTR5935-ISL99390FRZ-TR5935,SMLF,IC,AL099A    I39 @T6G_MB_LIB.T6G(SCH_1):PAGE187
 PC300    2      B Q_CAP_0402-0.22UF,16V,10%,X7R,CH4223K1B00    I63 @T6G_MB_LIB.T6G(SCH_1):PAGE187

SW_PVDDCR_CPU0_P1_PH4 @T6G_MB_LIB.T6G(SCH_1):SW_PVDDCR_CPU0_P1_PH4
  PU28   32  PHASE ISL99390FRZTR5935-ISL99390FRZ-TR5935,SMLF,IC,AL099A     I9 @T6G_MB_LIB.T6G(SCH_1):PAGE187
 PC301    2      B Q_CAP_0402-0.22UF,16V,10%,X7R,CH4223K1B00    I52 @T6G_MB_LIB.T6G(SCH_1):PAGE187

SW_PVDDCR_CPU0_P1_PH5 @T6G_MB_LIB.T6G(SCH_1):SW_PVDDCR_CPU0_P1_PH5
  PU29   32  PHASE ISL99390FRZTR5935-ISL99390FRZ-TR5935,SMLF,IC,AL099A    I18 @T6G_MB_LIB.T6G(SCH_1):PAGE188
 PC314    2      B Q_CAP_0402-0.22UF,16V,10%,X7R,CH4223K1B00    I63 @T6G_MB_LIB.T6G(SCH_1):PAGE188

SW_PVDDCR_CPU0_P1_PH6 @T6G_MB_LIB.T6G(SCH_1):SW_PVDDCR_CPU0_P1_PH6
 PC133    2      B Q_CAP_0402-0.22UF,16V,10%,X7R,CH4223K1B00    I52 @T6G_MB_LIB.T6G(SCH_1):PAGE188
  PU24   32  PHASE ISL99390FRZTR5935-ISL99390FRZ-TR5935,SMLF,IC,AL099A    I73 @T6G_MB_LIB.T6G(SCH_1):PAGE188

SW_PVDDCR_CPU0_P1_SW1 @T6G_MB_LIB.T6G(SCH_1):SW_PVDDCR_CPU0_P1_SW1
 PC170    1      A Q_CAP_C0402-560PF,50V,10%,EMPTY,CH1566K1B09    I48 @T6G_MB_LIB.T6G(SCH_1):PAGE186
   PU4 10_19     SW ISL99390FRZTR5935-ISL99390FRZ-TR5935,SMLF,IC,AL099A    I88 @T6G_MB_LIB.T6G(SCH_1):PAGE186
  PL28    1      1 Q_INDUCTOR4P_14-150NH,SMLF,IND,CV+15^0TZ04    I90 @T6G_MB_LIB.T6G(SCH_1):PAGE186

SW_PVDDCR_CPU0_P1_SW1_RC @T6G_MB_LIB.T6G(SCH_1):SW_PVDDCR_CPU0_P1_SW1_RC
 PC170    2      B Q_CAP_C0402-560PF,50V,10%,EMPTY,CH1566K1B09    I48 @T6G_MB_LIB.T6G(SCH_1):PAGE186
 PR485    1      A Q_RES_0402LF-1.5,1%,1/8W,EMPTY,CS-1504FB00    I34 @T6G_MB_LIB.T6G(SCH_1):PAGE186

SW_PVDDCR_CPU0_P1_SW2 @T6G_MB_LIB.T6G(SCH_1):SW_PVDDCR_CPU0_P1_SW2
 PC173    1      A Q_CAP_C0402-560PF,50V,10%,EMPTY,CH1566K1B09    I24 @T6G_MB_LIB.T6G(SCH_1):PAGE186
  PL29    1      1 Q_INDUCTOR4P_14-150NH,SMLF,IND,CV+15^0TZ04    I56 @T6G_MB_LIB.T6G(SCH_1):PAGE186
  PU26 10_19     SW ISL99390FRZTR5935-ISL99390FRZ-TR5935,SMLF,IC,AL099A    I91 @T6G_MB_LIB.T6G(SCH_1):PAGE186

SW_PVDDCR_CPU0_P1_SW2_RC @T6G_MB_LIB.T6G(SCH_1):SW_PVDDCR_CPU0_P1_SW2_RC
 PC173    2      B Q_CAP_C0402-560PF,50V,10%,EMPTY,CH1566K1B09    I24 @T6G_MB_LIB.T6G(SCH_1):PAGE186
 PR486    1      A Q_RES_0402LF-1.5,1%,1/8W,EMPTY,CS-1504FB00    I22 @T6G_MB_LIB.T6G(SCH_1):PAGE186

SW_PVDDCR_CPU0_P1_SW3 @T6G_MB_LIB.T6G(SCH_1):SW_PVDDCR_CPU0_P1_SW3
  PU27 10_19     SW ISL99390FRZTR5935-ISL99390FRZ-TR5935,SMLF,IC,AL099A    I39 @T6G_MB_LIB.T6G(SCH_1):PAGE187
 PC316    1      A Q_CAP_C0402-560PF,50V,10%,EMPTY,CH1566K1B09    I46 @T6G_MB_LIB.T6G(SCH_1):PAGE187
  PL31    1      1 Q_INDUCTOR4P_14-150NH,SMLF,IND,CV+15^0TZ04    I67 @T6G_MB_LIB.T6G(SCH_1):PAGE187

SW_PVDDCR_CPU0_P1_SW3_RC @T6G_MB_LIB.T6G(SCH_1):SW_PVDDCR_CPU0_P1_SW3_RC
 PR522    1      A Q_RES_0402LF-1.5,1%,1/8W,EMPTY,CS-1504FB00    I45 @T6G_MB_LIB.T6G(SCH_1):PAGE187
 PC316    2      B Q_CAP_C0402-560PF,50V,10%,EMPTY,CH1566K1B09    I46 @T6G_MB_LIB.T6G(SCH_1):PAGE187

SW_PVDDCR_CPU0_P1_SW4 @T6G_MB_LIB.T6G(SCH_1):SW_PVDDCR_CPU0_P1_SW4
  PU28 10_19     SW ISL99390FRZTR5935-ISL99390FRZ-TR5935,SMLF,IC,AL099A     I9 @T6G_MB_LIB.T6G(SCH_1):PAGE187
 PC317    1      A Q_CAP_C0402-560PF,50V,10%,EMPTY,CH1566K1B09    I20 @T6G_MB_LIB.T6G(SCH_1):PAGE187
  PL32    1      1 Q_INDUCTOR4P_14-150NH,SMLF,IND,CV+15^0TZ04    I53 @T6G_MB_LIB.T6G(SCH_1):PAGE187

SW_PVDDCR_CPU0_P1_SW4_RC @T6G_MB_LIB.T6G(SCH_1):SW_PVDDCR_CPU0_P1_SW4_RC
 PR523    1      A Q_RES_0402LF-1.5,1%,1/8W,EMPTY,CS-1504FB00    I19 @T6G_MB_LIB.T6G(SCH_1):PAGE187
 PC317    2      B Q_CAP_C0402-560PF,50V,10%,EMPTY,CH1566K1B09    I20 @T6G_MB_LIB.T6G(SCH_1):PAGE187

SW_PVDDCR_CPU0_P1_SW5 @T6G_MB_LIB.T6G(SCH_1):SW_PVDDCR_CPU0_P1_SW5
  PU29 10_19     SW ISL99390FRZTR5935-ISL99390FRZ-TR5935,SMLF,IC,AL099A    I18 @T6G_MB_LIB.T6G(SCH_1):PAGE188
 PC318    1      A Q_CAP_C0402-560PF,50V,10%,EMPTY,CH1566K1B09    I46 @T6G_MB_LIB.T6G(SCH_1):PAGE188
  PL33    1      1 Q_INDUCTOR4P_14-150NH,SMLF,IND,CV+15^0TZ04    I64 @T6G_MB_LIB.T6G(SCH_1):PAGE188

SW_PVDDCR_CPU0_P1_SW5_RC @T6G_MB_LIB.T6G(SCH_1):SW_PVDDCR_CPU0_P1_SW5_RC
  PR46    1      A Q_RES_0402LF-1.5,1%,1/8W,EMPTY,CS-1504FB00    I32 @T6G_MB_LIB.T6G(SCH_1):PAGE188
 PC318    2      B Q_CAP_C0402-560PF,50V,10%,EMPTY,CH1566K1B09    I46 @T6G_MB_LIB.T6G(SCH_1):PAGE188

SW_PVDDCR_CPU0_P1_SW6 @T6G_MB_LIB.T6G(SCH_1):SW_PVDDCR_CPU0_P1_SW6
 PC321    1      A Q_CAP_C0402-560PF,50V,10%,EMPTY,CH1566K1B09    I23 @T6G_MB_LIB.T6G(SCH_1):PAGE188
   PL8    1      1 Q_INDUCTOR4P_14-150NH,SMLF,IND,CV+15^0TZ04    I53 @T6G_MB_LIB.T6G(SCH_1):PAGE188
  PU24 10_19     SW ISL99390FRZTR5935-ISL99390FRZ-TR5935,SMLF,IC,AL099A    I73 @T6G_MB_LIB.T6G(SCH_1):PAGE188

SW_PVDDCR_CPU0_P1_SW6_RC @T6G_MB_LIB.T6G(SCH_1):SW_PVDDCR_CPU0_P1_SW6_RC
 PR524    1      A Q_RES_0402LF-1.5,1%,1/8W,EMPTY,CS-1504FB00    I21 @T6G_MB_LIB.T6G(SCH_1):PAGE188
 PC321    2      B Q_CAP_C0402-560PF,50V,10%,EMPTY,CH1566K1B09    I23 @T6G_MB_LIB.T6G(SCH_1):PAGE188

SW_PVDDCR_CPU1_P0_BOOT1 @T6G_MB_LIB.T6G(SCH_1):SW_PVDDCR_CPU1_P0_BOOT1
  PU13   33   BOOT ISL99390FRZTR5935-ISL99390FRZ-TR5935,SMLF,IC,AL099A    I35 @T6G_MB_LIB.T6G(SCH_1):PAGE176
  PR82    1      A Q_RES_0402LF-5.6,1%,1/16W,CHIP,CS-5602FB01    I56 @T6G_MB_LIB.T6G(SCH_1):PAGE176

SW_PVDDCR_CPU1_P0_BOOT1_R @T6G_MB_LIB.T6G(SCH_1):SW_PVDDCR_CPU1_P0_BOOT1_R
  PR82    2      B Q_RES_0402LF-5.6,1%,1/16W,CHIP,CS-5602FB01    I56 @T6G_MB_LIB.T6G(SCH_1):PAGE176
  PC92    1      A Q_CAP_0402-0.22UF,16V,10%,X7R,CH4223K1B00    I61 @T6G_MB_LIB.T6G(SCH_1):PAGE176

SW_PVDDCR_CPU1_P0_BOOT2 @T6G_MB_LIB.T6G(SCH_1):SW_PVDDCR_CPU1_P0_BOOT2
   PU2   33   BOOT ISL99390FRZTR5935-ISL99390FRZ-TR5935,SMLF,IC,AL099A    I33 @T6G_MB_LIB.T6G(SCH_1):PAGE176
  PR81    1      A Q_RES_0402LF-5.6,1%,1/16W,CHIP,CS-5602FB01    I40 @T6G_MB_LIB.T6G(SCH_1):PAGE176

SW_PVDDCR_CPU1_P0_BOOT2_R @T6G_MB_LIB.T6G(SCH_1):SW_PVDDCR_CPU1_P0_BOOT2_R
  PR81    2      B Q_RES_0402LF-5.6,1%,1/16W,CHIP,CS-5602FB01    I40 @T6G_MB_LIB.T6G(SCH_1):PAGE176
  PC94    1      A Q_CAP_0402-0.22UF,16V,10%,X7R,CH4223K1B00    I44 @T6G_MB_LIB.T6G(SCH_1):PAGE176

SW_PVDDCR_CPU1_P0_BOOT3 @T6G_MB_LIB.T6G(SCH_1):SW_PVDDCR_CPU1_P0_BOOT3
  PU15   33   BOOT ISL99390FRZTR5935-ISL99390FRZ-TR5935,SMLF,IC,AL099A    I23 @T6G_MB_LIB.T6G(SCH_1):PAGE177
  PR90    1      A Q_RES_0402LF-5.6,1%,1/16W,CHIP,CS-5602FB01    I57 @T6G_MB_LIB.T6G(SCH_1):PAGE177

SW_PVDDCR_CPU1_P0_BOOT3_R @T6G_MB_LIB.T6G(SCH_1):SW_PVDDCR_CPU1_P0_BOOT3_R
  PR90    2      B Q_RES_0402LF-5.6,1%,1/16W,CHIP,CS-5602FB01    I57 @T6G_MB_LIB.T6G(SCH_1):PAGE177
 PC122    1      A Q_CAP_0402-0.22UF,16V,10%,X7R,CH4223K1B00    I62 @T6G_MB_LIB.T6G(SCH_1):PAGE177

SW_PVDDCR_CPU1_P0_BOOT4 @T6G_MB_LIB.T6G(SCH_1):SW_PVDDCR_CPU1_P0_BOOT4
  PR89    1      A Q_RES_0402LF-5.6,1%,1/16W,CHIP,CS-5602FB01    I37 @T6G_MB_LIB.T6G(SCH_1):PAGE177
  PU14   33   BOOT ISL99390FRZTR5935-ISL99390FRZ-TR5935,SMLF,IC,AL099A    I21 @T6G_MB_LIB.T6G(SCH_1):PAGE177

SW_PVDDCR_CPU1_P0_BOOT4_R @T6G_MB_LIB.T6G(SCH_1):SW_PVDDCR_CPU1_P0_BOOT4_R
  PR89    2      B Q_RES_0402LF-5.6,1%,1/16W,CHIP,CS-5602FB01    I37 @T6G_MB_LIB.T6G(SCH_1):PAGE177
 PC121    1      A Q_CAP_0402-0.22UF,16V,10%,X7R,CH4223K1B00    I41 @T6G_MB_LIB.T6G(SCH_1):PAGE177

SW_PVDDCR_CPU1_P0_BOOT5 @T6G_MB_LIB.T6G(SCH_1):SW_PVDDCR_CPU1_P0_BOOT5
  PU16   33   BOOT ISL99390FRZTR5935-ISL99390FRZ-TR5935,SMLF,IC,AL099A    I22 @T6G_MB_LIB.T6G(SCH_1):PAGE178
  PR95    1      A Q_RES_0402LF-5.6,1%,1/16W,CHIP,CS-5602FB01    I56 @T6G_MB_LIB.T6G(SCH_1):PAGE178

SW_PVDDCR_CPU1_P0_BOOT5_R @T6G_MB_LIB.T6G(SCH_1):SW_PVDDCR_CPU1_P0_BOOT5_R
  PR95    2      B Q_RES_0402LF-5.6,1%,1/16W,CHIP,CS-5602FB01    I56 @T6G_MB_LIB.T6G(SCH_1):PAGE178
 PC137    1      A Q_CAP_0402-0.22UF,16V,10%,X7R,CH4223K1B00    I62 @T6G_MB_LIB.T6G(SCH_1):PAGE178

SW_PVDDCR_CPU1_P0_BOOT6 @T6G_MB_LIB.T6G(SCH_1):SW_PVDDCR_CPU1_P0_BOOT6
 PR420    1      A Q_RES_0402LF-5.6,1%,1/16W,CHIP,CS-5602FB01    I39 @T6G_MB_LIB.T6G(SCH_1):PAGE178
  PU11   33   BOOT ISL99390FRZTR5935-ISL99390FRZ-TR5935,SMLF,IC,AL099A    I73 @T6G_MB_LIB.T6G(SCH_1):PAGE178

SW_PVDDCR_CPU1_P0_BOOT6_R @T6G_MB_LIB.T6G(SCH_1):SW_PVDDCR_CPU1_P0_BOOT6_R
 PR420    2      B Q_RES_0402LF-5.6,1%,1/16W,CHIP,CS-5602FB01    I39 @T6G_MB_LIB.T6G(SCH_1):PAGE178
 PC117    1      A Q_CAP_0402-0.22UF,16V,10%,X7R,CH4223K1B00    I37 @T6G_MB_LIB.T6G(SCH_1):PAGE178

SW_PVDDCR_CPU1_P0_BOOTR1 @T6G_MB_LIB.T6G(SCH_1):SW_PVDDCR_CPU1_P0_BOOTR1
  PU13   32  PHASE ISL99390FRZTR5935-ISL99390FRZ-TR5935,SMLF,IC,AL099A    I35 @T6G_MB_LIB.T6G(SCH_1):PAGE176
  PC92    2      B Q_CAP_0402-0.22UF,16V,10%,X7R,CH4223K1B00    I61 @T6G_MB_LIB.T6G(SCH_1):PAGE176

SW_PVDDCR_CPU1_P0_BOOTR2 @T6G_MB_LIB.T6G(SCH_1):SW_PVDDCR_CPU1_P0_BOOTR2
   PU2   32  PHASE ISL99390FRZTR5935-ISL99390FRZ-TR5935,SMLF,IC,AL099A    I33 @T6G_MB_LIB.T6G(SCH_1):PAGE176
  PC94    2      B Q_CAP_0402-0.22UF,16V,10%,X7R,CH4223K1B00    I44 @T6G_MB_LIB.T6G(SCH_1):PAGE176

SW_PVDDCR_CPU1_P0_BOOTR3 @T6G_MB_LIB.T6G(SCH_1):SW_PVDDCR_CPU1_P0_BOOTR3
  PU15   32  PHASE ISL99390FRZTR5935-ISL99390FRZ-TR5935,SMLF,IC,AL099A    I23 @T6G_MB_LIB.T6G(SCH_1):PAGE177
 PC122    2      B Q_CAP_0402-0.22UF,16V,10%,X7R,CH4223K1B00    I62 @T6G_MB_LIB.T6G(SCH_1):PAGE177

SW_PVDDCR_CPU1_P0_BOOTR4 @T6G_MB_LIB.T6G(SCH_1):SW_PVDDCR_CPU1_P0_BOOTR4
  PU14   32  PHASE ISL99390FRZTR5935-ISL99390FRZ-TR5935,SMLF,IC,AL099A    I21 @T6G_MB_LIB.T6G(SCH_1):PAGE177
 PC121    2      B Q_CAP_0402-0.22UF,16V,10%,X7R,CH4223K1B00    I41 @T6G_MB_LIB.T6G(SCH_1):PAGE177

SW_PVDDCR_CPU1_P0_BOOTR5 @T6G_MB_LIB.T6G(SCH_1):SW_PVDDCR_CPU1_P0_BOOTR5
  PU16   32  PHASE ISL99390FRZTR5935-ISL99390FRZ-TR5935,SMLF,IC,AL099A    I22 @T6G_MB_LIB.T6G(SCH_1):PAGE178
 PC137    2      B Q_CAP_0402-0.22UF,16V,10%,X7R,CH4223K1B00    I62 @T6G_MB_LIB.T6G(SCH_1):PAGE178

SW_PVDDCR_CPU1_P0_BOOTR6 @T6G_MB_LIB.T6G(SCH_1):SW_PVDDCR_CPU1_P0_BOOTR6
 PC117    2      B Q_CAP_0402-0.22UF,16V,10%,X7R,CH4223K1B00    I37 @T6G_MB_LIB.T6G(SCH_1):PAGE178
  PU11   32  PHASE ISL99390FRZTR5935-ISL99390FRZ-TR5935,SMLF,IC,AL099A    I73 @T6G_MB_LIB.T6G(SCH_1):PAGE178

SW_PVDDCR_CPU1_P0_SW1 @T6G_MB_LIB.T6G(SCH_1):SW_PVDDCR_CPU1_P0_SW1
  PU13 10_19     SW ISL99390FRZTR5935-ISL99390FRZ-TR5935,SMLF,IC,AL099A    I35 @T6G_MB_LIB.T6G(SCH_1):PAGE176
 PC189    1      A Q_CAP_C0402-560PF,50V,10%,EMPTY,CH1566K1B09    I57 @T6G_MB_LIB.T6G(SCH_1):PAGE176
  PL10    1      1 Q_INDUCTOR4P_14-150NH,SMLF,IND,CV+15^0TZ04    I62 @T6G_MB_LIB.T6G(SCH_1):PAGE176

SW_PVDDCR_CPU1_P0_SW1_RC @T6G_MB_LIB.T6G(SCH_1):SW_PVDDCR_CPU1_P0_SW1_RC
 PR506    1      A Q_RES_0402LF-1.5,1%,1/8W,EMPTY,CS-1504FB00    I50 @T6G_MB_LIB.T6G(SCH_1):PAGE176
 PC189    2      B Q_CAP_C0402-560PF,50V,10%,EMPTY,CH1566K1B09    I57 @T6G_MB_LIB.T6G(SCH_1):PAGE176

SW_PVDDCR_CPU1_P0_SW2 @T6G_MB_LIB.T6G(SCH_1):SW_PVDDCR_CPU1_P0_SW2
 PC190    1      A Q_CAP_C0402-560PF,50V,10%,EMPTY,CH1566K1B09    I41 @T6G_MB_LIB.T6G(SCH_1):PAGE176
  PL11    1      1 Q_INDUCTOR4P_14-150NH,SMLF,IND,CV+15^0TZ04    I46 @T6G_MB_LIB.T6G(SCH_1):PAGE176
   PU2 10_19     SW ISL99390FRZTR5935-ISL99390FRZ-TR5935,SMLF,IC,AL099A    I33 @T6G_MB_LIB.T6G(SCH_1):PAGE176

SW_PVDDCR_CPU1_P0_SW2_RC @T6G_MB_LIB.T6G(SCH_1):SW_PVDDCR_CPU1_P0_SW2_RC
 PC190    2      B Q_CAP_C0402-560PF,50V,10%,EMPTY,CH1566K1B09    I41 @T6G_MB_LIB.T6G(SCH_1):PAGE176
 PR507    1      A Q_RES_0402LF-1.5,1%,1/8W,EMPTY,CS-1504FB00    I39 @T6G_MB_LIB.T6G(SCH_1):PAGE176

SW_PVDDCR_CPU1_P0_SW3 @T6G_MB_LIB.T6G(SCH_1):SW_PVDDCR_CPU1_P0_SW3
  PU15 10_19     SW ISL99390FRZTR5935-ISL99390FRZ-TR5935,SMLF,IC,AL099A    I23 @T6G_MB_LIB.T6G(SCH_1):PAGE177
 PC192    1      A Q_CAP_C0402-560PF,50V,10%,EMPTY,CH1566K1B09    I58 @T6G_MB_LIB.T6G(SCH_1):PAGE177
  PL14    1      1 Q_INDUCTOR4P_14-150NH,SMLF,IND,CV+15^0TZ04    I64 @T6G_MB_LIB.T6G(SCH_1):PAGE177

SW_PVDDCR_CPU1_P0_SW3_RC @T6G_MB_LIB.T6G(SCH_1):SW_PVDDCR_CPU1_P0_SW3_RC
 PR510    1      A Q_RES_0402LF-1.5,1%,1/8W,EMPTY,CS-1504FB00    I46 @T6G_MB_LIB.T6G(SCH_1):PAGE177
 PC192    2      B Q_CAP_C0402-560PF,50V,10%,EMPTY,CH1566K1B09    I58 @T6G_MB_LIB.T6G(SCH_1):PAGE177

SW_PVDDCR_CPU1_P0_SW4 @T6G_MB_LIB.T6G(SCH_1):SW_PVDDCR_CPU1_P0_SW4
 PC191    1      A Q_CAP_C0402-560PF,50V,10%,EMPTY,CH1566K1B09    I38 @T6G_MB_LIB.T6G(SCH_1):PAGE177
  PL13    1      1 Q_INDUCTOR4P_14-150NH,SMLF,IND,CV+15^0TZ04    I42 @T6G_MB_LIB.T6G(SCH_1):PAGE177
  PU14 10_19     SW ISL99390FRZTR5935-ISL99390FRZ-TR5935,SMLF,IC,AL099A    I21 @T6G_MB_LIB.T6G(SCH_1):PAGE177

SW_PVDDCR_CPU1_P0_SW4_RC @T6G_MB_LIB.T6G(SCH_1):SW_PVDDCR_CPU1_P0_SW4_RC
 PC191    2      B Q_CAP_C0402-560PF,50V,10%,EMPTY,CH1566K1B09    I38 @T6G_MB_LIB.T6G(SCH_1):PAGE177
 PR509    1      A Q_RES_0402LF-1.5,1%,1/8W,EMPTY,CS-1504FB00    I36 @T6G_MB_LIB.T6G(SCH_1):PAGE177

SW_PVDDCR_CPU1_P0_SW5 @T6G_MB_LIB.T6G(SCH_1):SW_PVDDCR_CPU1_P0_SW5
  PU16 10_19     SW ISL99390FRZTR5935-ISL99390FRZ-TR5935,SMLF,IC,AL099A    I22 @T6G_MB_LIB.T6G(SCH_1):PAGE178
 PC157    1      A Q_CAP_C0402-560PF,50V,10%,EMPTY,CH1566K1B09    I57 @T6G_MB_LIB.T6G(SCH_1):PAGE178
  PL15    1      1 Q_INDUCTOR4P_14-150NH,SMLF,IND,CV+15^0TZ04    I63 @T6G_MB_LIB.T6G(SCH_1):PAGE178

SW_PVDDCR_CPU1_P0_SW5_RC @T6G_MB_LIB.T6G(SCH_1):SW_PVDDCR_CPU1_P0_SW5_RC
 PR158    1      A Q_RES_0402LF-1.5,1%,1/8W,EMPTY,CS-1504FB00    I44 @T6G_MB_LIB.T6G(SCH_1):PAGE178
 PC157    2      B Q_CAP_C0402-560PF,50V,10%,EMPTY,CH1566K1B09    I57 @T6G_MB_LIB.T6G(SCH_1):PAGE178

SW_PVDDCR_CPU1_P0_SW6 @T6G_MB_LIB.T6G(SCH_1):SW_PVDDCR_CPU1_P0_SW6
   PL7    1      1 Q_INDUCTOR4P_14-150NH,SMLF,IND,CV+15^0TZ04    I38 @T6G_MB_LIB.T6G(SCH_1):PAGE178
 PC154    1      A Q_CAP_C0402-560PF,50V,10%,EMPTY,CH1566K1B09    I72 @T6G_MB_LIB.T6G(SCH_1):PAGE178
  PU11 10_19     SW ISL99390FRZTR5935-ISL99390FRZ-TR5935,SMLF,IC,AL099A    I73 @T6G_MB_LIB.T6G(SCH_1):PAGE178

SW_PVDDCR_CPU1_P0_SW6_RC @T6G_MB_LIB.T6G(SCH_1):SW_PVDDCR_CPU1_P0_SW6_RC
 PR155    1      A Q_RES_0402LF-1.5,1%,1/8W,EMPTY,CS-1504FB00    I33 @T6G_MB_LIB.T6G(SCH_1):PAGE178
 PC154    2      B Q_CAP_C0402-560PF,50V,10%,EMPTY,CH1566K1B09    I72 @T6G_MB_LIB.T6G(SCH_1):PAGE178

SW_PVDDCR_CPU1_P1_BOOT1 @T6G_MB_LIB.T6G(SCH_1):SW_PVDDCR_CPU1_P1_BOOT1
 PR258    1      A Q_RES_0402LF-5.6,1%,1/16W,CHIP,CS-5602FB01    I51 @T6G_MB_LIB.T6G(SCH_1):PAGE193
  PU35   33   BOOT ISL99390FRZTR5935-ISL99390FRZ-TR5935,SMLF,IC,AL099A    I91 @T6G_MB_LIB.T6G(SCH_1):PAGE193

SW_PVDDCR_CPU1_P1_BOOT1_R @T6G_MB_LIB.T6G(SCH_1):SW_PVDDCR_CPU1_P1_BOOT1_R
 PR258    2      B Q_RES_0402LF-5.6,1%,1/16W,CHIP,CS-5602FB01    I51 @T6G_MB_LIB.T6G(SCH_1):PAGE193
 PC383    1      A Q_CAP_0402-0.22UF,16V,10%,X7R,CH4223K1B00    I57 @T6G_MB_LIB.T6G(SCH_1):PAGE193

SW_PVDDCR_CPU1_P1_BOOT2 @T6G_MB_LIB.T6G(SCH_1):SW_PVDDCR_CPU1_P1_BOOT2
 PR259    1      A Q_RES_0402LF-5.6,1%,1/16W,CHIP,CS-5602FB01    I41 @T6G_MB_LIB.T6G(SCH_1):PAGE193
   PU5   33   BOOT ISL99390FRZTR5935-ISL99390FRZ-TR5935,SMLF,IC,AL099A    I31 @T6G_MB_LIB.T6G(SCH_1):PAGE193

SW_PVDDCR_CPU1_P1_BOOT2_R @T6G_MB_LIB.T6G(SCH_1):SW_PVDDCR_CPU1_P1_BOOT2_R
 PR259    2      B Q_RES_0402LF-5.6,1%,1/16W,CHIP,CS-5602FB01    I41 @T6G_MB_LIB.T6G(SCH_1):PAGE193
 PC386    1      A Q_CAP_0402-0.22UF,16V,10%,X7R,CH4223K1B00    I40 @T6G_MB_LIB.T6G(SCH_1):PAGE193

SW_PVDDCR_CPU1_P1_BOOT3 @T6G_MB_LIB.T6G(SCH_1):SW_PVDDCR_CPU1_P1_BOOT3
 PR267    1      A Q_RES_0402LF-5.6,1%,1/16W,CHIP,CS-5602FB01    I52 @T6G_MB_LIB.T6G(SCH_1):PAGE194
  PU37   33   BOOT ISL99390FRZTR5935-ISL99390FRZ-TR5935,SMLF,IC,AL099A    I72 @T6G_MB_LIB.T6G(SCH_1):PAGE194

SW_PVDDCR_CPU1_P1_BOOT3_R @T6G_MB_LIB.T6G(SCH_1):SW_PVDDCR_CPU1_P1_BOOT3_R
 PR267    2      B Q_RES_0402LF-5.6,1%,1/16W,CHIP,CS-5602FB01    I52 @T6G_MB_LIB.T6G(SCH_1):PAGE194
 PC414    1      A Q_CAP_0402-0.22UF,16V,10%,X7R,CH4223K1B00    I57 @T6G_MB_LIB.T6G(SCH_1):PAGE194

SW_PVDDCR_CPU1_P1_BOOT4 @T6G_MB_LIB.T6G(SCH_1):SW_PVDDCR_CPU1_P1_BOOT4
  PU36   33   BOOT ISL99390FRZTR5935-ISL99390FRZ-TR5935,SMLF,IC,AL099A    I21 @T6G_MB_LIB.T6G(SCH_1):PAGE194
 PR266    1      A Q_RES_0402LF-5.6,1%,1/16W,CHIP,CS-5602FB01    I36 @T6G_MB_LIB.T6G(SCH_1):PAGE194

SW_PVDDCR_CPU1_P1_BOOT4_R @T6G_MB_LIB.T6G(SCH_1):SW_PVDDCR_CPU1_P1_BOOT4_R
 PC413    1      A Q_CAP_0402-0.22UF,16V,10%,X7R,CH4223K1B00    I40 @T6G_MB_LIB.T6G(SCH_1):PAGE194
 PR266    2      B Q_RES_0402LF-5.6,1%,1/16W,CHIP,CS-5602FB01    I36 @T6G_MB_LIB.T6G(SCH_1):PAGE194

SW_PVDDCR_CPU1_P1_BOOT5 @T6G_MB_LIB.T6G(SCH_1):SW_PVDDCR_CPU1_P1_BOOT5
 PR272    1      A Q_RES_0402LF-5.6,1%,1/16W,CHIP,CS-5602FB01    I52 @T6G_MB_LIB.T6G(SCH_1):PAGE195
  PU38   33   BOOT ISL99390FRZTR5935-ISL99390FRZ-TR5935,SMLF,IC,AL099A    I73 @T6G_MB_LIB.T6G(SCH_1):PAGE195

SW_PVDDCR_CPU1_P1_BOOT5_R @T6G_MB_LIB.T6G(SCH_1):SW_PVDDCR_CPU1_P1_BOOT5_R
 PR272    2      B Q_RES_0402LF-5.6,1%,1/16W,CHIP,CS-5602FB01    I52 @T6G_MB_LIB.T6G(SCH_1):PAGE195
 PC428    1      A Q_CAP_0402-0.22UF,16V,10%,X7R,CH4223K1B00    I57 @T6G_MB_LIB.T6G(SCH_1):PAGE195

SW_PVDDCR_CPU1_P1_BOOT6 @T6G_MB_LIB.T6G(SCH_1):SW_PVDDCR_CPU1_P1_BOOT6
 PR428    1      A Q_RES_0402LF-5.6,1%,1/16W,CHIP,CS-5602FB01    I39 @T6G_MB_LIB.T6G(SCH_1):PAGE195
  PU33   33   BOOT ISL99390FRZTR5935-ISL99390FRZ-TR5935,SMLF,IC,AL099A    I19 @T6G_MB_LIB.T6G(SCH_1):PAGE195

SW_PVDDCR_CPU1_P1_BOOT6_R @T6G_MB_LIB.T6G(SCH_1):SW_PVDDCR_CPU1_P1_BOOT6_R
 PR428    2      B Q_RES_0402LF-5.6,1%,1/16W,CHIP,CS-5602FB01    I39 @T6G_MB_LIB.T6G(SCH_1):PAGE195
 PC146    1      A Q_CAP_0402-0.22UF,16V,10%,X7R,CH4223K1B00    I45 @T6G_MB_LIB.T6G(SCH_1):PAGE195

SW_PVDDCR_CPU1_P1_BOOTR1 @T6G_MB_LIB.T6G(SCH_1):SW_PVDDCR_CPU1_P1_BOOTR1
 PC383    2      B Q_CAP_0402-0.22UF,16V,10%,X7R,CH4223K1B00    I57 @T6G_MB_LIB.T6G(SCH_1):PAGE193
  PU35   32  PHASE ISL99390FRZTR5935-ISL99390FRZ-TR5935,SMLF,IC,AL099A    I91 @T6G_MB_LIB.T6G(SCH_1):PAGE193

SW_PVDDCR_CPU1_P1_BOOTR2 @T6G_MB_LIB.T6G(SCH_1):SW_PVDDCR_CPU1_P1_BOOTR2
   PU5   32  PHASE ISL99390FRZTR5935-ISL99390FRZ-TR5935,SMLF,IC,AL099A    I31 @T6G_MB_LIB.T6G(SCH_1):PAGE193
 PC386    2      B Q_CAP_0402-0.22UF,16V,10%,X7R,CH4223K1B00    I40 @T6G_MB_LIB.T6G(SCH_1):PAGE193

SW_PVDDCR_CPU1_P1_BOOTR3 @T6G_MB_LIB.T6G(SCH_1):SW_PVDDCR_CPU1_P1_BOOTR3
 PC414    2      B Q_CAP_0402-0.22UF,16V,10%,X7R,CH4223K1B00    I57 @T6G_MB_LIB.T6G(SCH_1):PAGE194
  PU37   32  PHASE ISL99390FRZTR5935-ISL99390FRZ-TR5935,SMLF,IC,AL099A    I72 @T6G_MB_LIB.T6G(SCH_1):PAGE194

SW_PVDDCR_CPU1_P1_BOOTR4 @T6G_MB_LIB.T6G(SCH_1):SW_PVDDCR_CPU1_P1_BOOTR4
 PC413    2      B Q_CAP_0402-0.22UF,16V,10%,X7R,CH4223K1B00    I40 @T6G_MB_LIB.T6G(SCH_1):PAGE194
  PU36   32  PHASE ISL99390FRZTR5935-ISL99390FRZ-TR5935,SMLF,IC,AL099A    I21 @T6G_MB_LIB.T6G(SCH_1):PAGE194

SW_PVDDCR_CPU1_P1_BOOTR5 @T6G_MB_LIB.T6G(SCH_1):SW_PVDDCR_CPU1_P1_BOOTR5
 PC428    2      B Q_CAP_0402-0.22UF,16V,10%,X7R,CH4223K1B00    I57 @T6G_MB_LIB.T6G(SCH_1):PAGE195
  PU38   32  PHASE ISL99390FRZTR5935-ISL99390FRZ-TR5935,SMLF,IC,AL099A    I73 @T6G_MB_LIB.T6G(SCH_1):PAGE195

SW_PVDDCR_CPU1_P1_BOOTR6 @T6G_MB_LIB.T6G(SCH_1):SW_PVDDCR_CPU1_P1_BOOTR6
  PU33   32  PHASE ISL99390FRZTR5935-ISL99390FRZ-TR5935,SMLF,IC,AL099A    I19 @T6G_MB_LIB.T6G(SCH_1):PAGE195
 PC146    2      B Q_CAP_0402-0.22UF,16V,10%,X7R,CH4223K1B00    I45 @T6G_MB_LIB.T6G(SCH_1):PAGE195

SW_PVDDCR_CPU1_P1_SW1 @T6G_MB_LIB.T6G(SCH_1):SW_PVDDCR_CPU1_P1_SW1
 PC201    1      A Q_CAP_C0402-560PF,50V,10%,EMPTY,CH1566K1B09    I52 @T6G_MB_LIB.T6G(SCH_1):PAGE193
  PL40    1      1 Q_INDUCTOR4P_14-150NH,SMLF,IND,CV+15^0TZ04    I77 @T6G_MB_LIB.T6G(SCH_1):PAGE193
  PU35 10_19     SW ISL99390FRZTR5935-ISL99390FRZ-TR5935,SMLF,IC,AL099A    I91 @T6G_MB_LIB.T6G(SCH_1):PAGE193

SW_PVDDCR_CPU1_P1_SW1_RC @T6G_MB_LIB.T6G(SCH_1):SW_PVDDCR_CPU1_P1_SW1_RC
 PR512    1      A Q_RES_0402LF-1.5,1%,1/8W,EMPTY,CS-1504FB00    I45 @T6G_MB_LIB.T6G(SCH_1):PAGE193
 PC201    2      B Q_CAP_C0402-560PF,50V,10%,EMPTY,CH1566K1B09    I52 @T6G_MB_LIB.T6G(SCH_1):PAGE193

SW_PVDDCR_CPU1_P1_SW2 @T6G_MB_LIB.T6G(SCH_1):SW_PVDDCR_CPU1_P1_SW2
   PU5 10_19     SW ISL99390FRZTR5935-ISL99390FRZ-TR5935,SMLF,IC,AL099A    I31 @T6G_MB_LIB.T6G(SCH_1):PAGE193
 PC202    1      A Q_CAP_C0402-560PF,50V,10%,EMPTY,CH1566K1B09    I37 @T6G_MB_LIB.T6G(SCH_1):PAGE193
  PL41    1      1 Q_INDUCTOR4P_14-150NH,SMLF,IND,CV+15^0TZ04    I62 @T6G_MB_LIB.T6G(SCH_1):PAGE193

SW_PVDDCR_CPU1_P1_SW2_RC @T6G_MB_LIB.T6G(SCH_1):SW_PVDDCR_CPU1_P1_SW2_RC
 PR513    1      A Q_RES_0402LF-1.5,1%,1/8W,EMPTY,CS-1504FB00    I36 @T6G_MB_LIB.T6G(SCH_1):PAGE193
 PC202    2      B Q_CAP_C0402-560PF,50V,10%,EMPTY,CH1566K1B09    I37 @T6G_MB_LIB.T6G(SCH_1):PAGE193

SW_PVDDCR_CPU1_P1_SW3 @T6G_MB_LIB.T6G(SCH_1):SW_PVDDCR_CPU1_P1_SW3
 PC206    1      A Q_CAP_C0402-560PF,50V,10%,EMPTY,CH1566K1B09    I53 @T6G_MB_LIB.T6G(SCH_1):PAGE194
  PL44    1      1 Q_INDUCTOR4P_14-150NH,SMLF,IND,CV+15^0TZ04    I62 @T6G_MB_LIB.T6G(SCH_1):PAGE194
  PU37 10_19     SW ISL99390FRZTR5935-ISL99390FRZ-TR5935,SMLF,IC,AL099A    I72 @T6G_MB_LIB.T6G(SCH_1):PAGE194

SW_PVDDCR_CPU1_P1_SW3_RC @T6G_MB_LIB.T6G(SCH_1):SW_PVDDCR_CPU1_P1_SW3_RC
 PR516    1      A Q_RES_0402LF-1.5,1%,1/8W,EMPTY,CS-1504FB00    I44 @T6G_MB_LIB.T6G(SCH_1):PAGE194
 PC206    2      B Q_CAP_C0402-560PF,50V,10%,EMPTY,CH1566K1B09    I53 @T6G_MB_LIB.T6G(SCH_1):PAGE194

SW_PVDDCR_CPU1_P1_SW4 @T6G_MB_LIB.T6G(SCH_1):SW_PVDDCR_CPU1_P1_SW4
 PC205    1      A Q_CAP_C0402-560PF,50V,10%,EMPTY,CH1566K1B09    I37 @T6G_MB_LIB.T6G(SCH_1):PAGE194
  PL43    1      1 Q_INDUCTOR4P_14-150NH,SMLF,IND,CV+15^0TZ04    I50 @T6G_MB_LIB.T6G(SCH_1):PAGE194
  PU36 10_19     SW ISL99390FRZTR5935-ISL99390FRZ-TR5935,SMLF,IC,AL099A    I21 @T6G_MB_LIB.T6G(SCH_1):PAGE194

SW_PVDDCR_CPU1_P1_SW4_RC @T6G_MB_LIB.T6G(SCH_1):SW_PVDDCR_CPU1_P1_SW4_RC
 PC205    2      B Q_CAP_C0402-560PF,50V,10%,EMPTY,CH1566K1B09    I37 @T6G_MB_LIB.T6G(SCH_1):PAGE194
 PR515    1      A Q_RES_0402LF-1.5,1%,1/8W,EMPTY,CS-1504FB00    I35 @T6G_MB_LIB.T6G(SCH_1):PAGE194

SW_PVDDCR_CPU1_P1_SW5 @T6G_MB_LIB.T6G(SCH_1):SW_PVDDCR_CPU1_P1_SW5
 PC207    1      A Q_CAP_C0402-560PF,50V,10%,EMPTY,CH1566K1B09    I53 @T6G_MB_LIB.T6G(SCH_1):PAGE195
  PL45    1      1 Q_INDUCTOR4P_14-150NH,SMLF,IND,CV+15^0TZ04    I63 @T6G_MB_LIB.T6G(SCH_1):PAGE195
  PU38 10_19     SW ISL99390FRZTR5935-ISL99390FRZ-TR5935,SMLF,IC,AL099A    I73 @T6G_MB_LIB.T6G(SCH_1):PAGE195

SW_PVDDCR_CPU1_P1_SW5_RC @T6G_MB_LIB.T6G(SCH_1):SW_PVDDCR_CPU1_P1_SW5_RC
 PR517    1      A Q_RES_0402LF-1.5,1%,1/8W,EMPTY,CS-1504FB00    I43 @T6G_MB_LIB.T6G(SCH_1):PAGE195
 PC207    2      B Q_CAP_C0402-560PF,50V,10%,EMPTY,CH1566K1B09    I53 @T6G_MB_LIB.T6G(SCH_1):PAGE195

SW_PVDDCR_CPU1_P1_SW6 @T6G_MB_LIB.T6G(SCH_1):SW_PVDDCR_CPU1_P1_SW6
  PU33 10_19     SW ISL99390FRZTR5935-ISL99390FRZ-TR5935,SMLF,IC,AL099A    I19 @T6G_MB_LIB.T6G(SCH_1):PAGE195
 PC208    1      A Q_CAP_C0402-560PF,50V,10%,EMPTY,CH1566K1B09    I34 @T6G_MB_LIB.T6G(SCH_1):PAGE195
  PL69    1      1 Q_INDUCTOR4P_14-150NH,SMLF,IND,CV+15^0TZ04    I50 @T6G_MB_LIB.T6G(SCH_1):PAGE195

SW_PVDDCR_CPU1_P1_SW6_RC @T6G_MB_LIB.T6G(SCH_1):SW_PVDDCR_CPU1_P1_SW6_RC
 PR518    1      A Q_RES_0402LF-1.5,1%,1/8W,EMPTY,CS-1504FB00    I33 @T6G_MB_LIB.T6G(SCH_1):PAGE195
 PC208    2      B Q_CAP_C0402-560PF,50V,10%,EMPTY,CH1566K1B09    I34 @T6G_MB_LIB.T6G(SCH_1):PAGE195

SW_PVDDCR_SOC_P0_BOOT1 @T6G_MB_LIB.T6G(SCH_1):SW_PVDDCR_SOC_P0_BOOT1
 PR360    1      A Q_RES_0402LF-5.6,1%,1/16W,CHIP,CS-5602FB01    I48 @T6G_MB_LIB.T6G(SCH_1):PAGE173
  PU49   33   BOOT ISL99390FRZTR5935-ISL99390FRZ-TR5935,SMLF,IC,AL099A    I41 @T6G_MB_LIB.T6G(SCH_1):PAGE173

SW_PVDDCR_SOC_P0_BOOT1_RC @T6G_MB_LIB.T6G(SCH_1):SW_PVDDCR_SOC_P0_BOOT1_RC
 PR360    2      B Q_RES_0402LF-5.6,1%,1/16W,CHIP,CS-5602FB01    I48 @T6G_MB_LIB.T6G(SCH_1):PAGE173
 PC593    1      A Q_CAP_0402-0.22UF,16V,10%,X7R,CH4223K1B00    I68 @T6G_MB_LIB.T6G(SCH_1):PAGE173

SW_PVDDCR_SOC_P0_BOOT2 @T6G_MB_LIB.T6G(SCH_1):SW_PVDDCR_SOC_P0_BOOT2
 PR361    1      A Q_RES_0402LF-5.6,1%,1/16W,CHIP,CS-5602FB01    I22 @T6G_MB_LIB.T6G(SCH_1):PAGE173
  PU50   33   BOOT ISL99390FRZTR5935-ISL99390FRZ-TR5935,SMLF,IC,AL099A    I86 @T6G_MB_LIB.T6G(SCH_1):PAGE173

SW_PVDDCR_SOC_P0_BOOT2_RC @T6G_MB_LIB.T6G(SCH_1):SW_PVDDCR_SOC_P0_BOOT2_RC
 PR361    2      B Q_RES_0402LF-5.6,1%,1/16W,CHIP,CS-5602FB01    I22 @T6G_MB_LIB.T6G(SCH_1):PAGE173
 PC594    1      A Q_CAP_0402-0.22UF,16V,10%,X7R,CH4223K1B00    I52 @T6G_MB_LIB.T6G(SCH_1):PAGE173

SW_PVDDCR_SOC_P0_BOOT3 @T6G_MB_LIB.T6G(SCH_1):SW_PVDDCR_SOC_P0_BOOT3
 PR366    1      A Q_RES_0402LF-5.6,1%,1/16W,CHIP,CS-5602FB01    I20 @T6G_MB_LIB.T6G(SCH_1):PAGE174
  PU51   33   BOOT ISL99390FRZTR5935-ISL99390FRZ-TR5935,SMLF,IC,AL099A    I38 @T6G_MB_LIB.T6G(SCH_1):PAGE174

SW_PVDDCR_SOC_P0_BOOT3_RC @T6G_MB_LIB.T6G(SCH_1):SW_PVDDCR_SOC_P0_BOOT3_RC
 PR366    2      B Q_RES_0402LF-5.6,1%,1/16W,CHIP,CS-5602FB01    I20 @T6G_MB_LIB.T6G(SCH_1):PAGE174
 PC612    1      A Q_CAP_0402-0.22UF,16V,10%,X7R,CH4223K1B00    I30 @T6G_MB_LIB.T6G(SCH_1):PAGE174

SW_PVDDCR_SOC_P0_PH1 @T6G_MB_LIB.T6G(SCH_1):SW_PVDDCR_SOC_P0_PH1
 PC593    2      B Q_CAP_0402-0.22UF,16V,10%,X7R,CH4223K1B00    I68 @T6G_MB_LIB.T6G(SCH_1):PAGE173
  PU49   32  PHASE ISL99390FRZTR5935-ISL99390FRZ-TR5935,SMLF,IC,AL099A    I41 @T6G_MB_LIB.T6G(SCH_1):PAGE173

SW_PVDDCR_SOC_P0_PH2 @T6G_MB_LIB.T6G(SCH_1):SW_PVDDCR_SOC_P0_PH2
 PC594    2      B Q_CAP_0402-0.22UF,16V,10%,X7R,CH4223K1B00    I52 @T6G_MB_LIB.T6G(SCH_1):PAGE173
  PU50   32  PHASE ISL99390FRZTR5935-ISL99390FRZ-TR5935,SMLF,IC,AL099A    I86 @T6G_MB_LIB.T6G(SCH_1):PAGE173

SW_PVDDCR_SOC_P0_PH3 @T6G_MB_LIB.T6G(SCH_1):SW_PVDDCR_SOC_P0_PH3
  PU51   32  PHASE ISL99390FRZTR5935-ISL99390FRZ-TR5935,SMLF,IC,AL099A    I38 @T6G_MB_LIB.T6G(SCH_1):PAGE174
 PC612    2      B Q_CAP_0402-0.22UF,16V,10%,X7R,CH4223K1B00    I30 @T6G_MB_LIB.T6G(SCH_1):PAGE174

SW_PVDDCR_SOC_P0_SW1 @T6G_MB_LIB.T6G(SCH_1):SW_PVDDCR_SOC_P0_SW1
  PL63    1      1 Q_INDUCTOR4P_14-150NH,SMLF,IND,CV+15^0TZ04    I69 @T6G_MB_LIB.T6G(SCH_1):PAGE173
  PU49 10_19     SW ISL99390FRZTR5935-ISL99390FRZ-TR5935,SMLF,IC,AL099A    I41 @T6G_MB_LIB.T6G(SCH_1):PAGE173
 PC185    1      A Q_CAP_C0402-560PF,50V,10%,EMPTY,CH1566K1B09    I46 @T6G_MB_LIB.T6G(SCH_1):PAGE173

SW_PVDDCR_SOC_P0_SW1_RC @T6G_MB_LIB.T6G(SCH_1):SW_PVDDCR_SOC_P0_SW1_RC
 PR502    1      A Q_RES_0402LF-1.5,1%,1/8W,EMPTY,CS-1504FB00    I45 @T6G_MB_LIB.T6G(SCH_1):PAGE173
 PC185    2      B Q_CAP_C0402-560PF,50V,10%,EMPTY,CH1566K1B09    I46 @T6G_MB_LIB.T6G(SCH_1):PAGE173

SW_PVDDCR_SOC_P0_SW2 @T6G_MB_LIB.T6G(SCH_1):SW_PVDDCR_SOC_P0_SW2
  PL64    1      1 Q_INDUCTOR4P_14-150NH,SMLF,IND,CV+15^0TZ04    I53 @T6G_MB_LIB.T6G(SCH_1):PAGE173
 PC187    1      A Q_CAP_C0402-560PF,50V,10%,EMPTY,CH1566K1B09    I85 @T6G_MB_LIB.T6G(SCH_1):PAGE173
  PU50 10_19     SW ISL99390FRZTR5935-ISL99390FRZ-TR5935,SMLF,IC,AL099A    I86 @T6G_MB_LIB.T6G(SCH_1):PAGE173

SW_PVDDCR_SOC_P0_SW2_RC @T6G_MB_LIB.T6G(SCH_1):SW_PVDDCR_SOC_P0_SW2_RC
 PR503    1      A Q_RES_0402LF-1.5,1%,1/8W,EMPTY,CS-1504FB00    I19 @T6G_MB_LIB.T6G(SCH_1):PAGE173
 PC187    2      B Q_CAP_C0402-560PF,50V,10%,EMPTY,CH1566K1B09    I85 @T6G_MB_LIB.T6G(SCH_1):PAGE173

SW_PVDDCR_SOC_P0_SW3 @T6G_MB_LIB.T6G(SCH_1):SW_PVDDCR_SOC_P0_SW3
  PL66    1      1 Q_INDUCTOR4P_14-150NH,SMLF,IND,CV+15^0TZ04    I25 @T6G_MB_LIB.T6G(SCH_1):PAGE174
  PU51 10_19     SW ISL99390FRZTR5935-ISL99390FRZ-TR5935,SMLF,IC,AL099A    I38 @T6G_MB_LIB.T6G(SCH_1):PAGE174
 PC188    1      A Q_CAP_C0402-560PF,50V,10%,EMPTY,CH1566K1B09    I12 @T6G_MB_LIB.T6G(SCH_1):PAGE174

SW_PVDDCR_SOC_P0_SW3_RC @T6G_MB_LIB.T6G(SCH_1):SW_PVDDCR_SOC_P0_SW3_RC
 PR505    1      A Q_RES_0402LF-1.5,1%,1/8W,EMPTY,CS-1504FB00    I10 @T6G_MB_LIB.T6G(SCH_1):PAGE174
 PC188    2      B Q_CAP_C0402-560PF,50V,10%,EMPTY,CH1566K1B09    I12 @T6G_MB_LIB.T6G(SCH_1):PAGE174

SW_PVDDCR_SOC_P1_BOOT1 @T6G_MB_LIB.T6G(SCH_1):SW_PVDDCR_SOC_P1_BOOT1
  PU30   33   BOOT ISL99390FRZTR5935-ISL99390FRZ-TR5935,SMLF,IC,AL099A    I17 @T6G_MB_LIB.T6G(SCH_1):PAGE190
 PR209    1      A Q_RES_0402LF-5.6,1%,1/16W,CHIP,CS-5602FB01    I46 @T6G_MB_LIB.T6G(SCH_1):PAGE190

SW_PVDDCR_SOC_P1_BOOT1_RC @T6G_MB_LIB.T6G(SCH_1):SW_PVDDCR_SOC_P1_BOOT1_RC
 PC333    1      A Q_CAP_0402-0.22UF,16V,10%,X7R,CH4223K1B00    I68 @T6G_MB_LIB.T6G(SCH_1):PAGE190
 PR209    2      B Q_RES_0402LF-5.6,1%,1/16W,CHIP,CS-5602FB01    I46 @T6G_MB_LIB.T6G(SCH_1):PAGE190

SW_PVDDCR_SOC_P1_BOOT2 @T6G_MB_LIB.T6G(SCH_1):SW_PVDDCR_SOC_P1_BOOT2
 PR210    1      A Q_RES_0402LF-5.6,1%,1/16W,CHIP,CS-5602FB01    I24 @T6G_MB_LIB.T6G(SCH_1):PAGE190
  PU31   33   BOOT ISL99390FRZTR5935-ISL99390FRZ-TR5935,SMLF,IC,AL099A    I86 @T6G_MB_LIB.T6G(SCH_1):PAGE190

SW_PVDDCR_SOC_P1_BOOT2_RC @T6G_MB_LIB.T6G(SCH_1):SW_PVDDCR_SOC_P1_BOOT2_RC
 PR210    2      B Q_RES_0402LF-5.6,1%,1/16W,CHIP,CS-5602FB01    I24 @T6G_MB_LIB.T6G(SCH_1):PAGE190
 PC334    1      A Q_CAP_0402-0.22UF,16V,10%,X7R,CH4223K1B00    I54 @T6G_MB_LIB.T6G(SCH_1):PAGE190

SW_PVDDCR_SOC_P1_BOOT3 @T6G_MB_LIB.T6G(SCH_1):SW_PVDDCR_SOC_P1_BOOT3
 PR215    1      A Q_RES_0402LF-5.6,1%,1/16W,CHIP,CS-5602FB01    I21 @T6G_MB_LIB.T6G(SCH_1):PAGE191
  PU32   33   BOOT ISL99390FRZTR5935-ISL99390FRZ-TR5935,SMLF,IC,AL099A    I38 @T6G_MB_LIB.T6G(SCH_1):PAGE191

SW_PVDDCR_SOC_P1_BOOT3_RC @T6G_MB_LIB.T6G(SCH_1):SW_PVDDCR_SOC_P1_BOOT3_RC
 PR215    2      B Q_RES_0402LF-5.6,1%,1/16W,CHIP,CS-5602FB01    I21 @T6G_MB_LIB.T6G(SCH_1):PAGE191
 PC353    1      A Q_CAP_0402-0.22UF,16V,10%,X7R,CH4223K1B00    I33 @T6G_MB_LIB.T6G(SCH_1):PAGE191

SW_PVDDCR_SOC_P1_PH1 @T6G_MB_LIB.T6G(SCH_1):SW_PVDDCR_SOC_P1_PH1
 PC333    2      B Q_CAP_0402-0.22UF,16V,10%,X7R,CH4223K1B00    I68 @T6G_MB_LIB.T6G(SCH_1):PAGE190
  PU30   32  PHASE ISL99390FRZTR5935-ISL99390FRZ-TR5935,SMLF,IC,AL099A    I17 @T6G_MB_LIB.T6G(SCH_1):PAGE190

SW_PVDDCR_SOC_P1_PH2 @T6G_MB_LIB.T6G(SCH_1):SW_PVDDCR_SOC_P1_PH2
 PC334    2      B Q_CAP_0402-0.22UF,16V,10%,X7R,CH4223K1B00    I54 @T6G_MB_LIB.T6G(SCH_1):PAGE190
  PU31   32  PHASE ISL99390FRZTR5935-ISL99390FRZ-TR5935,SMLF,IC,AL099A    I86 @T6G_MB_LIB.T6G(SCH_1):PAGE190

SW_PVDDCR_SOC_P1_PH3 @T6G_MB_LIB.T6G(SCH_1):SW_PVDDCR_SOC_P1_PH3
  PU32   32  PHASE ISL99390FRZTR5935-ISL99390FRZ-TR5935,SMLF,IC,AL099A    I38 @T6G_MB_LIB.T6G(SCH_1):PAGE191
 PC353    2      B Q_CAP_0402-0.22UF,16V,10%,X7R,CH4223K1B00    I33 @T6G_MB_LIB.T6G(SCH_1):PAGE191

SW_PVDDCR_SOC_P1_SW1 @T6G_MB_LIB.T6G(SCH_1):SW_PVDDCR_SOC_P1_SW1
  PL35    1      1 Q_INDUCTOR4P_14-150NH,SMLF,IND,CV+15^0TZ04    I69 @T6G_MB_LIB.T6G(SCH_1):PAGE190
  PU30 10_19     SW ISL99390FRZTR5935-ISL99390FRZ-TR5935,SMLF,IC,AL099A    I17 @T6G_MB_LIB.T6G(SCH_1):PAGE190
 PC141    1      A Q_CAP_C0402-560PF,50V,10%,EMPTY,CH1566K1B09    I45 @T6G_MB_LIB.T6G(SCH_1):PAGE190

SW_PVDDCR_SOC_P1_SW1_RC @T6G_MB_LIB.T6G(SCH_1):SW_PVDDCR_SOC_P1_SW1_RC
 PR525    1      A Q_RES_0402LF-1.5,1%,1/8W,EMPTY,CS-1504FB00    I29 @T6G_MB_LIB.T6G(SCH_1):PAGE190
 PC141    2      B Q_CAP_C0402-560PF,50V,10%,EMPTY,CH1566K1B09    I45 @T6G_MB_LIB.T6G(SCH_1):PAGE190

SW_PVDDCR_SOC_P1_SW2 @T6G_MB_LIB.T6G(SCH_1):SW_PVDDCR_SOC_P1_SW2
  PL36    1      1 Q_INDUCTOR4P_14-150NH,SMLF,IND,CV+15^0TZ04    I52 @T6G_MB_LIB.T6G(SCH_1):PAGE190
 PC149    1      A Q_CAP_C0402-560PF,50V,10%,EMPTY,CH1566K1B09    I20 @T6G_MB_LIB.T6G(SCH_1):PAGE190
  PU31 10_19     SW ISL99390FRZTR5935-ISL99390FRZ-TR5935,SMLF,IC,AL099A    I86 @T6G_MB_LIB.T6G(SCH_1):PAGE190

SW_PVDDCR_SOC_P1_SW2_RC @T6G_MB_LIB.T6G(SCH_1):SW_PVDDCR_SOC_P1_SW2_RC
 PC149    2      B Q_CAP_C0402-560PF,50V,10%,EMPTY,CH1566K1B09    I20 @T6G_MB_LIB.T6G(SCH_1):PAGE190
 PR526    1      A Q_RES_0402LF-1.5,1%,1/8W,EMPTY,CS-1504FB00    I21 @T6G_MB_LIB.T6G(SCH_1):PAGE190

SW_PVDDCR_SOC_P1_SW3 @T6G_MB_LIB.T6G(SCH_1):SW_PVDDCR_SOC_P1_SW3
  PL38    1      1 Q_INDUCTOR4P_14-150NH,SMLF,IND,CV+15^0TZ04    I26 @T6G_MB_LIB.T6G(SCH_1):PAGE191
  PU32 10_19     SW ISL99390FRZTR5935-ISL99390FRZ-TR5935,SMLF,IC,AL099A    I38 @T6G_MB_LIB.T6G(SCH_1):PAGE191
 PC195    1      A Q_CAP_C0402-560PF,50V,10%,EMPTY,CH1566K1B09    I11 @T6G_MB_LIB.T6G(SCH_1):PAGE191

SW_PVDDCR_SOC_P1_SW3_RC @T6G_MB_LIB.T6G(SCH_1):SW_PVDDCR_SOC_P1_SW3_RC
 PR511    1      A Q_RES_0402LF-1.5,1%,1/8W,EMPTY,CS-1504FB00    I10 @T6G_MB_LIB.T6G(SCH_1):PAGE191
 PC195    2      B Q_CAP_C0402-560PF,50V,10%,EMPTY,CH1566K1B09    I11 @T6G_MB_LIB.T6G(SCH_1):PAGE191

SW_PVDDIO_P0_BOOT1 @T6G_MB_LIB.T6G(SCH_1):SW_PVDDIO_P0_BOOT1
 PR101    1      A Q_RES_0402LF-5.6,1%,1/16W,CHIP,CS-5602FB01    I34 @T6G_MB_LIB.T6G(SCH_1):PAGE180
  PU17   33   BOOT ISL99390FRZTR5935-ISL99390FRZ-TR5935,SMLF,IC,AL099A    I84 @T6G_MB_LIB.T6G(SCH_1):PAGE180

SW_PVDDIO_P0_BOOT1_R @T6G_MB_LIB.T6G(SCH_1):SW_PVDDIO_P0_BOOT1_R
 PR101    2      B Q_RES_0402LF-5.6,1%,1/16W,CHIP,CS-5602FB01    I34 @T6G_MB_LIB.T6G(SCH_1):PAGE180
 PC155    1      A Q_CAP_0402-0.22UF,16V,10%,X7R,CH4223K1B00    I63 @T6G_MB_LIB.T6G(SCH_1):PAGE180

SW_PVDDIO_P0_BOOT2 @T6G_MB_LIB.T6G(SCH_1):SW_PVDDIO_P0_BOOT2
  PU18   33   BOOT ISL99390FRZTR5935-ISL99390FRZ-TR5935,SMLF,IC,AL099A    I15 @T6G_MB_LIB.T6G(SCH_1):PAGE180
 PR102    1      A Q_RES_0402LF-5.6,1%,1/16W,CHIP,CS-5602FB01    I17 @T6G_MB_LIB.T6G(SCH_1):PAGE180

SW_PVDDIO_P0_BOOT2_R @T6G_MB_LIB.T6G(SCH_1):SW_PVDDIO_P0_BOOT2_R
 PR102    2      B Q_RES_0402LF-5.6,1%,1/16W,CHIP,CS-5602FB01    I17 @T6G_MB_LIB.T6G(SCH_1):PAGE180
 PC156    1      A Q_CAP_0402-0.22UF,16V,10%,X7R,CH4223K1B00    I41 @T6G_MB_LIB.T6G(SCH_1):PAGE180

SW_PVDDIO_P0_BOOT3 @T6G_MB_LIB.T6G(SCH_1):SW_PVDDIO_P0_BOOT3
  PU19   33   BOOT ISL99390FRZTR5935-ISL99390FRZ-TR5935,SMLF,IC,AL099A    I32 @T6G_MB_LIB.T6G(SCH_1):PAGE181
 PR110    1      A Q_RES_0402LF-5.6,1%,1/16W,CHIP,CS-5602FB01    I34 @T6G_MB_LIB.T6G(SCH_1):PAGE181

SW_PVDDIO_P0_BOOT3_R @T6G_MB_LIB.T6G(SCH_1):SW_PVDDIO_P0_BOOT3_R
 PC186    1      A Q_CAP_0402-0.22UF,16V,10%,X7R,CH4223K1B00    I59 @T6G_MB_LIB.T6G(SCH_1):PAGE181
 PR110    2      B Q_RES_0402LF-5.6,1%,1/16W,CHIP,CS-5602FB01    I34 @T6G_MB_LIB.T6G(SCH_1):PAGE181

SW_PVDDIO_P0_BOOT4 @T6G_MB_LIB.T6G(SCH_1):SW_PVDDIO_P0_BOOT4
 PR109    1      A Q_RES_0402LF-5.6,1%,1/16W,CHIP,CS-5602FB01    I16 @T6G_MB_LIB.T6G(SCH_1):PAGE181
  PU20   33   BOOT ISL99390FRZTR5935-ISL99390FRZ-TR5935,SMLF,IC,AL099A    I73 @T6G_MB_LIB.T6G(SCH_1):PAGE181

SW_PVDDIO_P0_BOOT4_R @T6G_MB_LIB.T6G(SCH_1):SW_PVDDIO_P0_BOOT4_R
 PC183    1      A Q_CAP_0402-0.22UF,16V,10%,X7R,CH4223K1B00    I44 @T6G_MB_LIB.T6G(SCH_1):PAGE181
 PR109    2      B Q_RES_0402LF-5.6,1%,1/16W,CHIP,CS-5602FB01    I16 @T6G_MB_LIB.T6G(SCH_1):PAGE181

SW_PVDDIO_P0_BOOTR1 @T6G_MB_LIB.T6G(SCH_1):SW_PVDDIO_P0_BOOTR1
 PC155    2      B Q_CAP_0402-0.22UF,16V,10%,X7R,CH4223K1B00    I63 @T6G_MB_LIB.T6G(SCH_1):PAGE180
  PU17   32  PHASE ISL99390FRZTR5935-ISL99390FRZ-TR5935,SMLF,IC,AL099A    I84 @T6G_MB_LIB.T6G(SCH_1):PAGE180

SW_PVDDIO_P0_BOOTR2 @T6G_MB_LIB.T6G(SCH_1):SW_PVDDIO_P0_BOOTR2
  PU18   32  PHASE ISL99390FRZTR5935-ISL99390FRZ-TR5935,SMLF,IC,AL099A    I15 @T6G_MB_LIB.T6G(SCH_1):PAGE180
 PC156    2      B Q_CAP_0402-0.22UF,16V,10%,X7R,CH4223K1B00    I41 @T6G_MB_LIB.T6G(SCH_1):PAGE180

SW_PVDDIO_P0_BOOTR3 @T6G_MB_LIB.T6G(SCH_1):SW_PVDDIO_P0_BOOTR3
 PC186    2      B Q_CAP_0402-0.22UF,16V,10%,X7R,CH4223K1B00    I59 @T6G_MB_LIB.T6G(SCH_1):PAGE181
  PU19   32  PHASE ISL99390FRZTR5935-ISL99390FRZ-TR5935,SMLF,IC,AL099A    I32 @T6G_MB_LIB.T6G(SCH_1):PAGE181

SW_PVDDIO_P0_BOOTR4 @T6G_MB_LIB.T6G(SCH_1):SW_PVDDIO_P0_BOOTR4
 PC183    2      B Q_CAP_0402-0.22UF,16V,10%,X7R,CH4223K1B00    I44 @T6G_MB_LIB.T6G(SCH_1):PAGE181
  PU20   32  PHASE ISL99390FRZTR5935-ISL99390FRZ-TR5935,SMLF,IC,AL099A    I73 @T6G_MB_LIB.T6G(SCH_1):PAGE181

SW_PVDDIO_P0_SW1 @T6G_MB_LIB.T6G(SCH_1):SW_PVDDIO_P0_SW1
 PC158    1      A Q_CAP_C0402-560PF,50V,10%,EMPTY,CH1566K1B09    I61 @T6G_MB_LIB.T6G(SCH_1):PAGE180
  PL17    1      1 Q_INDUCTOR4P_14-150NH,SMLF,IND,CV+15^0TZ04    I64 @T6G_MB_LIB.T6G(SCH_1):PAGE180
  PU17 10_19     SW ISL99390FRZTR5935-ISL99390FRZ-TR5935,SMLF,IC,AL099A    I84 @T6G_MB_LIB.T6G(SCH_1):PAGE180

SW_PVDDIO_P0_SW1_RC @T6G_MB_LIB.T6G(SCH_1):SW_PVDDIO_P0_SW1_RC
 PR221    1      A Q_RES_0402LF-1.5,1%,1/8W,EMPTY,CS-1504FB00    I60 @T6G_MB_LIB.T6G(SCH_1):PAGE180
 PC158    2      B Q_CAP_C0402-560PF,50V,10%,EMPTY,CH1566K1B09    I61 @T6G_MB_LIB.T6G(SCH_1):PAGE180

SW_PVDDIO_P0_SW2 @T6G_MB_LIB.T6G(SCH_1):SW_PVDDIO_P0_SW2
  PU18 10_19     SW ISL99390FRZTR5935-ISL99390FRZ-TR5935,SMLF,IC,AL099A    I15 @T6G_MB_LIB.T6G(SCH_1):PAGE180
 PC159    1      A Q_CAP_C0402-560PF,50V,10%,EMPTY,CH1566K1B09    I37 @T6G_MB_LIB.T6G(SCH_1):PAGE180
  PL18    1      1 Q_INDUCTOR4P_14-150NH,SMLF,IND,CV+15^0TZ04    I40 @T6G_MB_LIB.T6G(SCH_1):PAGE180

SW_PVDDIO_P0_SW2_RC @T6G_MB_LIB.T6G(SCH_1):SW_PVDDIO_P0_SW2_RC
 PR223    1      A Q_RES_0402LF-1.5,1%,1/8W,EMPTY,CS-1504FB00    I36 @T6G_MB_LIB.T6G(SCH_1):PAGE180
 PC159    2      B Q_CAP_C0402-560PF,50V,10%,EMPTY,CH1566K1B09    I37 @T6G_MB_LIB.T6G(SCH_1):PAGE180

SW_PVDDIO_P0_SW3 @T6G_MB_LIB.T6G(SCH_1):SW_PVDDIO_P0_SW3
  PU19 10_19     SW ISL99390FRZTR5935-ISL99390FRZ-TR5935,SMLF,IC,AL099A    I32 @T6G_MB_LIB.T6G(SCH_1):PAGE181
 PC166    1      A Q_CAP_C0402-560PF,50V,10%,EMPTY,CH1566K1B09    I56 @T6G_MB_LIB.T6G(SCH_1):PAGE181
  PL21    1      1 Q_INDUCTOR4P_14-150NH,SMLF,IND,CV+15^0TZ04    I61 @T6G_MB_LIB.T6G(SCH_1):PAGE181

SW_PVDDIO_P0_SW3_RC @T6G_MB_LIB.T6G(SCH_1):SW_PVDDIO_P0_SW3_RC
 PR379    1      A Q_RES_0402LF-1.5,1%,1/8W,EMPTY,CS-1504FB00    I55 @T6G_MB_LIB.T6G(SCH_1):PAGE181
 PC166    2      B Q_CAP_C0402-560PF,50V,10%,EMPTY,CH1566K1B09    I56 @T6G_MB_LIB.T6G(SCH_1):PAGE181

SW_PVDDIO_P0_SW4 @T6G_MB_LIB.T6G(SCH_1):SW_PVDDIO_P0_SW4
 PC163    1      A Q_CAP_C0402-560PF,50V,10%,EMPTY,CH1566K1B09    I39 @T6G_MB_LIB.T6G(SCH_1):PAGE181
  PL20    1      1 Q_INDUCTOR4P_14-150NH,SMLF,IND,CV+15^0TZ04    I42 @T6G_MB_LIB.T6G(SCH_1):PAGE181
  PU20 10_19     SW ISL99390FRZTR5935-ISL99390FRZ-TR5935,SMLF,IC,AL099A    I73 @T6G_MB_LIB.T6G(SCH_1):PAGE181

SW_PVDDIO_P0_SW4_RC @T6G_MB_LIB.T6G(SCH_1):SW_PVDDIO_P0_SW4_RC
 PR291    1      A Q_RES_0402LF-1.5,1%,1/8W,EMPTY,CS-1504FB00    I38 @T6G_MB_LIB.T6G(SCH_1):PAGE181
 PC163    2      B Q_CAP_C0402-560PF,50V,10%,EMPTY,CH1566K1B09    I39 @T6G_MB_LIB.T6G(SCH_1):PAGE181

SW_PVDDIO_P1_BOOT1 @T6G_MB_LIB.T6G(SCH_1):SW_PVDDIO_P1_BOOT1
  PU39   33   BOOT ISL99390FRZTR5935-ISL99390FRZ-TR5935,SMLF,IC,AL099A    I39 @T6G_MB_LIB.T6G(SCH_1):PAGE197
 PR279    1      A Q_RES_0402LF-5.6,1%,1/16W,CHIP,CS-5602FB01    I43 @T6G_MB_LIB.T6G(SCH_1):PAGE197

SW_PVDDIO_P1_BOOT1_R @T6G_MB_LIB.T6G(SCH_1):SW_PVDDIO_P1_BOOT1_R
 PR279    2      B Q_RES_0402LF-5.6,1%,1/16W,CHIP,CS-5602FB01    I43 @T6G_MB_LIB.T6G(SCH_1):PAGE197
 PC447    1      A Q_CAP_0402-0.22UF,16V,10%,X7R,CH4223K1B00    I65 @T6G_MB_LIB.T6G(SCH_1):PAGE197

SW_PVDDIO_P1_BOOT2 @T6G_MB_LIB.T6G(SCH_1):SW_PVDDIO_P1_BOOT2
 PR278    1      A Q_RES_0402LF-5.6,1%,1/16W,CHIP,CS-5602FB01    I22 @T6G_MB_LIB.T6G(SCH_1):PAGE197
  PU40   33   BOOT ISL99390FRZTR5935-ISL99390FRZ-TR5935,SMLF,IC,AL099A    I84 @T6G_MB_LIB.T6G(SCH_1):PAGE197

SW_PVDDIO_P1_BOOT2_R @T6G_MB_LIB.T6G(SCH_1):SW_PVDDIO_P1_BOOT2_R
 PR278    2      B Q_RES_0402LF-5.6,1%,1/16W,CHIP,CS-5602FB01    I22 @T6G_MB_LIB.T6G(SCH_1):PAGE197
 PC445    1      A Q_CAP_0402-0.22UF,16V,10%,X7R,CH4223K1B00    I47 @T6G_MB_LIB.T6G(SCH_1):PAGE197

SW_PVDDIO_P1_BOOT3 @T6G_MB_LIB.T6G(SCH_1):SW_PVDDIO_P1_BOOT3
 PR373    1      A Q_RES_0402LF-5.6,1%,1/16W,CHIP,CS-5602FB01    I34 @T6G_MB_LIB.T6G(SCH_1):PAGE198
  PU52   33   BOOT ISL99390FRZTR5935-ISL99390FRZ-TR5935,SMLF,IC,AL099A    I73 @T6G_MB_LIB.T6G(SCH_1):PAGE198

SW_PVDDIO_P1_BOOT3_R @T6G_MB_LIB.T6G(SCH_1):SW_PVDDIO_P1_BOOT3_R
 PR373    2      B Q_RES_0402LF-5.6,1%,1/16W,CHIP,CS-5602FB01    I34 @T6G_MB_LIB.T6G(SCH_1):PAGE198
 PC631    1      A Q_CAP_0402-0.22UF,16V,10%,X7R,CH4223K1B00    I63 @T6G_MB_LIB.T6G(SCH_1):PAGE198

SW_PVDDIO_P1_BOOT4 @T6G_MB_LIB.T6G(SCH_1):SW_PVDDIO_P1_BOOT4
  PU53   33   BOOT ISL99390FRZTR5935-ISL99390FRZ-TR5935,SMLF,IC,AL099A    I15 @T6G_MB_LIB.T6G(SCH_1):PAGE198
 PR372    1      A Q_RES_0402LF-5.6,1%,1/16W,CHIP,CS-5602FB01    I17 @T6G_MB_LIB.T6G(SCH_1):PAGE198

SW_PVDDIO_P1_BOOT4_R @T6G_MB_LIB.T6G(SCH_1):SW_PVDDIO_P1_BOOT4_R
 PC630    1      A Q_CAP_0402-0.22UF,16V,10%,X7R,CH4223K1B00    I44 @T6G_MB_LIB.T6G(SCH_1):PAGE198
 PR372    2      B Q_RES_0402LF-5.6,1%,1/16W,CHIP,CS-5602FB01    I17 @T6G_MB_LIB.T6G(SCH_1):PAGE198

SW_PVDDIO_P1_BOOTR1 @T6G_MB_LIB.T6G(SCH_1):SW_PVDDIO_P1_BOOTR1
  PU39   32  PHASE ISL99390FRZTR5935-ISL99390FRZ-TR5935,SMLF,IC,AL099A    I39 @T6G_MB_LIB.T6G(SCH_1):PAGE197
 PC447    2      B Q_CAP_0402-0.22UF,16V,10%,X7R,CH4223K1B00    I65 @T6G_MB_LIB.T6G(SCH_1):PAGE197

SW_PVDDIO_P1_BOOTR2 @T6G_MB_LIB.T6G(SCH_1):SW_PVDDIO_P1_BOOTR2
 PC445    2      B Q_CAP_0402-0.22UF,16V,10%,X7R,CH4223K1B00    I47 @T6G_MB_LIB.T6G(SCH_1):PAGE197
  PU40   32  PHASE ISL99390FRZTR5935-ISL99390FRZ-TR5935,SMLF,IC,AL099A    I84 @T6G_MB_LIB.T6G(SCH_1):PAGE197

SW_PVDDIO_P1_BOOTR3 @T6G_MB_LIB.T6G(SCH_1):SW_PVDDIO_P1_BOOTR3
 PC631    2      B Q_CAP_0402-0.22UF,16V,10%,X7R,CH4223K1B00    I63 @T6G_MB_LIB.T6G(SCH_1):PAGE198
  PU52   32  PHASE ISL99390FRZTR5935-ISL99390FRZ-TR5935,SMLF,IC,AL099A    I73 @T6G_MB_LIB.T6G(SCH_1):PAGE198

SW_PVDDIO_P1_BOOTR4 @T6G_MB_LIB.T6G(SCH_1):SW_PVDDIO_P1_BOOTR4
  PU53   32  PHASE ISL99390FRZTR5935-ISL99390FRZ-TR5935,SMLF,IC,AL099A    I15 @T6G_MB_LIB.T6G(SCH_1):PAGE198
 PC630    2      B Q_CAP_0402-0.22UF,16V,10%,X7R,CH4223K1B00    I44 @T6G_MB_LIB.T6G(SCH_1):PAGE198

SW_PVDDIO_P1_SW1 @T6G_MB_LIB.T6G(SCH_1):SW_PVDDIO_P1_SW1
  PU39 10_19     SW ISL99390FRZTR5935-ISL99390FRZ-TR5935,SMLF,IC,AL099A    I39 @T6G_MB_LIB.T6G(SCH_1):PAGE197
 PC174    1      A Q_CAP_C0402-560PF,50V,10%,EMPTY,CH1566K1B09    I40 @T6G_MB_LIB.T6G(SCH_1):PAGE197
  PL47    1      1 Q_INDUCTOR4P_14-150NH,SMLF,IND,CV+15^0TZ04    I71 @T6G_MB_LIB.T6G(SCH_1):PAGE197

SW_PVDDIO_P1_SW1_RC @T6G_MB_LIB.T6G(SCH_1):SW_PVDDIO_P1_SW1_RC
 PR488    1      A Q_RES_0402LF-1.5,1%,1/8W,EMPTY,CS-1504FB00    I26 @T6G_MB_LIB.T6G(SCH_1):PAGE197
 PC174    2      B Q_CAP_C0402-560PF,50V,10%,EMPTY,CH1566K1B09    I40 @T6G_MB_LIB.T6G(SCH_1):PAGE197

SW_PVDDIO_P1_SW2 @T6G_MB_LIB.T6G(SCH_1):SW_PVDDIO_P1_SW2
 PC175    1      A Q_CAP_C0402-560PF,50V,10%,EMPTY,CH1566K1B09    I20 @T6G_MB_LIB.T6G(SCH_1):PAGE197
  PL48    1      1 Q_INDUCTOR4P_14-150NH,SMLF,IND,CV+15^0TZ04    I83 @T6G_MB_LIB.T6G(SCH_1):PAGE197
  PU40 10_19     SW ISL99390FRZTR5935-ISL99390FRZ-TR5935,SMLF,IC,AL099A    I84 @T6G_MB_LIB.T6G(SCH_1):PAGE197

SW_PVDDIO_P1_SW2_RC @T6G_MB_LIB.T6G(SCH_1):SW_PVDDIO_P1_SW2_RC
 PR489    1      A Q_RES_0402LF-1.5,1%,1/8W,EMPTY,CS-1504FB00    I19 @T6G_MB_LIB.T6G(SCH_1):PAGE197
 PC175    2      B Q_CAP_C0402-560PF,50V,10%,EMPTY,CH1566K1B09    I20 @T6G_MB_LIB.T6G(SCH_1):PAGE197

SW_PVDDIO_P1_SW3 @T6G_MB_LIB.T6G(SCH_1):SW_PVDDIO_P1_SW3
 PC177    1      A Q_CAP_C0402-560PF,50V,10%,EMPTY,CH1566K1B09    I58 @T6G_MB_LIB.T6G(SCH_1):PAGE198
  PL68    1      1 Q_INDUCTOR4P_14-150NH,SMLF,IND,CV+15^0TZ04    I62 @T6G_MB_LIB.T6G(SCH_1):PAGE198
  PU52 10_19     SW ISL99390FRZTR5935-ISL99390FRZ-TR5935,SMLF,IC,AL099A    I73 @T6G_MB_LIB.T6G(SCH_1):PAGE198

SW_PVDDIO_P1_SW3_RC @T6G_MB_LIB.T6G(SCH_1):SW_PVDDIO_P1_SW3_RC
 PR492    1      A Q_RES_0402LF-1.5,1%,1/8W,EMPTY,CS-1504FB00    I57 @T6G_MB_LIB.T6G(SCH_1):PAGE198
 PC177    2      B Q_CAP_C0402-560PF,50V,10%,EMPTY,CH1566K1B09    I58 @T6G_MB_LIB.T6G(SCH_1):PAGE198

SW_PVDDIO_P1_SW4 @T6G_MB_LIB.T6G(SCH_1):SW_PVDDIO_P1_SW4
  PU53 10_19     SW ISL99390FRZTR5935-ISL99390FRZ-TR5935,SMLF,IC,AL099A    I15 @T6G_MB_LIB.T6G(SCH_1):PAGE198
 PC176    1      A Q_CAP_C0402-560PF,50V,10%,EMPTY,CH1566K1B09    I37 @T6G_MB_LIB.T6G(SCH_1):PAGE198
  PL67    1      1 Q_INDUCTOR4P_14-150NH,SMLF,IND,CV+15^0TZ04    I42 @T6G_MB_LIB.T6G(SCH_1):PAGE198

SW_PVDDIO_P1_SW4_RC @T6G_MB_LIB.T6G(SCH_1):SW_PVDDIO_P1_SW4_RC
 PC176    2      B Q_CAP_C0402-560PF,50V,10%,EMPTY,CH1566K1B09    I37 @T6G_MB_LIB.T6G(SCH_1):PAGE198
 PR491    1      A Q_RES_0402LF-1.5,1%,1/8W,EMPTY,CS-1504FB00    I39 @T6G_MB_LIB.T6G(SCH_1):PAGE198

SW_PVDD_33_S5_BST @T6G_MB_LIB.T6G(SCH_1):SW_PVDD_33_S5_BST
  PU55    1    BST MPQ8633AGLEC807Z-MPQ8633AGLE-C807-Z,SMLF,IC,AL0086A    I41 @T6G_MB_LIB.T6G(SCH_1):PAGE167
PR8000    1      A Q_RES_0402LF-0,5%,1/16W,CHIP,CS00002JB13    I46 @T6G_MB_LIB.T6G(SCH_1):PAGE167

SW_PVDD_33_S5_BST_R @T6G_MB_LIB.T6G(SCH_1):SW_PVDD_33_S5_BST_R
 PC128    1      A Q_CAP_0402-0.1UF,25V,10%,X7R,CH4104K1B00    I40 @T6G_MB_LIB.T6G(SCH_1):PAGE167
PR8000    2      B Q_RES_0402LF-0,5%,1/16W,CHIP,CS00002JB13    I46 @T6G_MB_LIB.T6G(SCH_1):PAGE167

SW_PVDD_33_S5_SW @T6G_MB_LIB.T6G(SCH_1):SW_PVDD_33_S5_SW
 PC128    2      B Q_CAP_0402-0.1UF,25V,10%,X7R,CH4104K1B00    I40 @T6G_MB_LIB.T6G(SCH_1):PAGE167
  PU55   20     SW MPQ8633AGLEC807Z-MPQ8633AGLE-C807-Z,SMLF,IC,AL0086A    I41 @T6G_MB_LIB.T6G(SCH_1):PAGE167
  PL72    1      1 Q_INDUCTOR_SMLF-1.5UH,IND,CV-15I0MZ28    I47 @T6G_MB_LIB.T6G(SCH_1):PAGE167

T1_GND @T6G_MB_LIB.T6G(SCH_1):T1_GND
   DB6    1    GND TDR_3P_TH2-EMPTY,N_A     I2 @T6G_MB_LIB.T6G(SCH_1):PAGE265
  DB14    1    GND TDR_3P_TH2-EMPTY,N_A     I5 @T6G_MB_LIB.T6G(SCH_1):PAGE265
  DB13    1    GND TDR_3P_TH2-EMPTY,N_A     I8 @T6G_MB_LIB.T6G(SCH_1):PAGE265
   DB5    1    GND TDR_3P_TH2-EMPTY,N_A     I9 @T6G_MB_LIB.T6G(SCH_1):PAGE265
   DB4    1    GND TDR_3P_TH2-EMPTY,N_A    I12 @T6G_MB_LIB.T6G(SCH_1):PAGE265
   DB3    1    GND TDR_3P_TH2-EMPTY,N_A    I13 @T6G_MB_LIB.T6G(SCH_1):PAGE265
   DB2    1    GND TDR_3P_TH2-EMPTY,N_A    I15 @T6G_MB_LIB.T6G(SCH_1):PAGE265
   DB1    1    GND TDR_3P_TH2-EMPTY,N_A    I16 @T6G_MB_LIB.T6G(SCH_1):PAGE265
  DB12    1    GND TDR_3P_TH2-EMPTY,N_A    I18 @T6G_MB_LIB.T6G(SCH_1):PAGE265
  DB16    1    GND TDR_3P_TH2-EMPTY,N_A    I20 @T6G_MB_LIB.T6G(SCH_1):PAGE265
  DB15    1    GND TDR_3P_TH2-EMPTY,N_A    I22 @T6G_MB_LIB.T6G(SCH_1):PAGE265
  DB11    1    GND TDR_3P_TH2-EMPTY,N_A    I25 @T6G_MB_LIB.T6G(SCH_1):PAGE265
    X6    2     P1 TP_TDR_4P_FTS_TH-TP_TDR_4P_DIP,EMPTY,TP15    I29 @T6G_MB_LIB.T6G(SCH_1):PAGE265
    X6    3     P2 TP_TDR_4P_FTS_TH-TP_TDR_4P_DIP,EMPTY,TP15    I29 @T6G_MB_LIB.T6G(SCH_1):PAGE265
   X26    2     P1 TP_TDR_4P_FTS_TH-TP_TDR_4P_DIP,EMPTY,TP15    I30 @T6G_MB_LIB.T6G(SCH_1):PAGE265
   X26    3     P2 TP_TDR_4P_FTS_TH-TP_TDR_4P_DIP,EMPTY,TP15    I30 @T6G_MB_LIB.T6G(SCH_1):PAGE265
   X25    2     P1 TP_TDR_4P_FTS_TH-TP_TDR_4P_DIP,EMPTY,TP15    I31 @T6G_MB_LIB.T6G(SCH_1):PAGE265
   X25    3     P2 TP_TDR_4P_FTS_TH-TP_TDR_4P_DIP,EMPTY,TP15    I31 @T6G_MB_LIB.T6G(SCH_1):PAGE265
    X5    2     P1 TP_TDR_4P_FTS_TH-TP_TDR_4P_DIP,EMPTY,TP15    I35 @T6G_MB_LIB.T6G(SCH_1):PAGE265
    X5    3     P2 TP_TDR_4P_FTS_TH-TP_TDR_4P_DIP,EMPTY,TP15    I35 @T6G_MB_LIB.T6G(SCH_1):PAGE265
    X4    2     P1 TP_TDR_4P_FTS_TH-TP_TDR_4P_DIP,EMPTY,TP15    I36 @T6G_MB_LIB.T6G(SCH_1):PAGE265
    X4    3     P2 TP_TDR_4P_FTS_TH-TP_TDR_4P_DIP,EMPTY,TP15    I36 @T6G_MB_LIB.T6G(SCH_1):PAGE265
    X3    2     P1 TP_TDR_4P_FTS_TH-TP_TDR_4P_DIP,EMPTY,TP15    I37 @T6G_MB_LIB.T6G(SCH_1):PAGE265
    X3    3     P2 TP_TDR_4P_FTS_TH-TP_TDR_4P_DIP,EMPTY,TP15    I37 @T6G_MB_LIB.T6G(SCH_1):PAGE265
  DB10    1    GND TDR_3P_TH2-EMPTY,N_A    I38 @T6G_MB_LIB.T6G(SCH_1):PAGE265
   DB9    1    GND TDR_3P_TH2-EMPTY,N_A    I40 @T6G_MB_LIB.T6G(SCH_1):PAGE265
   DB8    1    GND TDR_3P_TH2-EMPTY,N_A    I42 @T6G_MB_LIB.T6G(SCH_1):PAGE265
   DB7    1    GND TDR_3P_TH2-EMPTY,N_A    I44 @T6G_MB_LIB.T6G(SCH_1):PAGE265
    X2    2     P1 TP_TDR_4P_FTS_TH-TP_TDR_4P_DIP,EMPTY,TP15    I47 @T6G_MB_LIB.T6G(SCH_1):PAGE265
    X2    3     P2 TP_TDR_4P_FTS_TH-TP_TDR_4P_DIP,EMPTY,TP15    I47 @T6G_MB_LIB.T6G(SCH_1):PAGE265
    X1    2     P1 TP_TDR_4P_FTS_TH-TP_TDR_4P_DIP,EMPTY,TP15    I48 @T6G_MB_LIB.T6G(SCH_1):PAGE265
    X1    3     P2 TP_TDR_4P_FTS_TH-TP_TDR_4P_DIP,EMPTY,TP15    I48 @T6G_MB_LIB.T6G(SCH_1):PAGE265
   X12    2     P1 TP_TDR_4P_FTS_TH-TP_TDR_4P_DIP,EMPTY,TP15    I49 @T6G_MB_LIB.T6G(SCH_1):PAGE265
   X12    3     P2 TP_TDR_4P_FTS_TH-TP_TDR_4P_DIP,EMPTY,TP15    I49 @T6G_MB_LIB.T6G(SCH_1):PAGE265
   X28    2     P1 TP_TDR_4P_FTS_TH-TP_TDR_4P_DIP,EMPTY,TP15    I52 @T6G_MB_LIB.T6G(SCH_1):PAGE265
   X28    3     P2 TP_TDR_4P_FTS_TH-TP_TDR_4P_DIP,EMPTY,TP15    I52 @T6G_MB_LIB.T6G(SCH_1):PAGE265
   X27    2     P1 TP_TDR_4P_FTS_TH-TP_TDR_4P_DIP,EMPTY,TP15    I53 @T6G_MB_LIB.T6G(SCH_1):PAGE265
   X27    3     P2 TP_TDR_4P_FTS_TH-TP_TDR_4P_DIP,EMPTY,TP15    I53 @T6G_MB_LIB.T6G(SCH_1):PAGE265
 X8006    2     P1 TP_TDR_4P_FTS_TH-TP_TDR_4P_DIP,EMPTY,TP15    I56 @T6G_MB_LIB.T6G(SCH_1):PAGE265
 X8006    3     P2 TP_TDR_4P_FTS_TH-TP_TDR_4P_DIP,EMPTY,TP15    I56 @T6G_MB_LIB.T6G(SCH_1):PAGE265
 X8026    2     P1 TP_TDR_4P_FTS_TH-TP_TDR_4P_DIP,EMPTY,TP15    I58 @T6G_MB_LIB.T6G(SCH_1):PAGE265
 X8026    3     P2 TP_TDR_4P_FTS_TH-TP_TDR_4P_DIP,EMPTY,TP15    I58 @T6G_MB_LIB.T6G(SCH_1):PAGE265
 X8025    2     P1 TP_TDR_4P_FTS_TH-TP_TDR_4P_DIP,EMPTY,TP15    I60 @T6G_MB_LIB.T6G(SCH_1):PAGE265
 X8025    3     P2 TP_TDR_4P_FTS_TH-TP_TDR_4P_DIP,EMPTY,TP15    I60 @T6G_MB_LIB.T6G(SCH_1):PAGE265
   X10    2     P1 TP_TDR_4P_FTS_TH-TP_TDR_4P_DIP,EMPTY,TP15    I61 @T6G_MB_LIB.T6G(SCH_1):PAGE265
   X10    3     P2 TP_TDR_4P_FTS_TH-TP_TDR_4P_DIP,EMPTY,TP15    I61 @T6G_MB_LIB.T6G(SCH_1):PAGE265
    X9    2     P1 TP_TDR_4P_FTS_TH-TP_TDR_4P_DIP,EMPTY,TP15    I62 @T6G_MB_LIB.T6G(SCH_1):PAGE265
    X9    3     P2 TP_TDR_4P_FTS_TH-TP_TDR_4P_DIP,EMPTY,TP15    I62 @T6G_MB_LIB.T6G(SCH_1):PAGE265
 X8005    2     P1 TP_TDR_4P_FTS_TH-TP_TDR_4P_DIP,EMPTY,TP15    I66 @T6G_MB_LIB.T6G(SCH_1):PAGE265
 X8005    3     P2 TP_TDR_4P_FTS_TH-TP_TDR_4P_DIP,EMPTY,TP15    I66 @T6G_MB_LIB.T6G(SCH_1):PAGE265
 X8004    2     P1 TP_TDR_4P_FTS_TH-TP_TDR_4P_DIP,EMPTY,TP15    I68 @T6G_MB_LIB.T6G(SCH_1):PAGE265
 X8004    3     P2 TP_TDR_4P_FTS_TH-TP_TDR_4P_DIP,EMPTY,TP15    I68 @T6G_MB_LIB.T6G(SCH_1):PAGE265
 X8003    2     P1 TP_TDR_4P_FTS_TH-TP_TDR_4P_DIP,EMPTY,TP15    I70 @T6G_MB_LIB.T6G(SCH_1):PAGE265
 X8003    3     P2 TP_TDR_4P_FTS_TH-TP_TDR_4P_DIP,EMPTY,TP15    I70 @T6G_MB_LIB.T6G(SCH_1):PAGE265
 X8028    2     P1 TP_TDR_4P_FTS_TH-TP_TDR_4P_DIP,EMPTY,TP15    I73 @T6G_MB_LIB.T6G(SCH_1):PAGE265
 X8028    3     P2 TP_TDR_4P_FTS_TH-TP_TDR_4P_DIP,EMPTY,TP15    I73 @T6G_MB_LIB.T6G(SCH_1):PAGE265
 X8027    2     P1 TP_TDR_4P_FTS_TH-TP_TDR_4P_DIP,EMPTY,TP15    I74 @T6G_MB_LIB.T6G(SCH_1):PAGE265
 X8027    3     P2 TP_TDR_4P_FTS_TH-TP_TDR_4P_DIP,EMPTY,TP15    I74 @T6G_MB_LIB.T6G(SCH_1):PAGE265
 X8011    2     P1 TP_TDR_4P_FTS_TH-TP_TDR_4P_DIP,EMPTY,TP15    I76 @T6G_MB_LIB.T6G(SCH_1):PAGE265
 X8011    3     P2 TP_TDR_4P_FTS_TH-TP_TDR_4P_DIP,EMPTY,TP15    I76 @T6G_MB_LIB.T6G(SCH_1):PAGE265
 X8010    2     P1 TP_TDR_4P_FTS_TH-TP_TDR_4P_DIP,EMPTY,TP15    I78 @T6G_MB_LIB.T6G(SCH_1):PAGE265
 X8010    3     P2 TP_TDR_4P_FTS_TH-TP_TDR_4P_DIP,EMPTY,TP15    I78 @T6G_MB_LIB.T6G(SCH_1):PAGE265
 X8009    2     P1 TP_TDR_4P_FTS_TH-TP_TDR_4P_DIP,EMPTY,TP15    I79 @T6G_MB_LIB.T6G(SCH_1):PAGE265
 X8009    3     P2 TP_TDR_4P_FTS_TH-TP_TDR_4P_DIP,EMPTY,TP15    I79 @T6G_MB_LIB.T6G(SCH_1):PAGE265
    X8    2     P1 TP_TDR_4P_FTS_TH-TP_TDR_4P_DIP,EMPTY,TP15    I82 @T6G_MB_LIB.T6G(SCH_1):PAGE265
    X8    3     P2 TP_TDR_4P_FTS_TH-TP_TDR_4P_DIP,EMPTY,TP15    I82 @T6G_MB_LIB.T6G(SCH_1):PAGE265
    X7    2     P1 TP_TDR_4P_FTS_TH-TP_TDR_4P_DIP,EMPTY,TP15    I84 @T6G_MB_LIB.T6G(SCH_1):PAGE265
    X7    3     P2 TP_TDR_4P_FTS_TH-TP_TDR_4P_DIP,EMPTY,TP15    I84 @T6G_MB_LIB.T6G(SCH_1):PAGE265
 X8002    2     P1 TP_TDR_4P_FTS_TH-TP_TDR_4P_DIP,EMPTY,TP15    I87 @T6G_MB_LIB.T6G(SCH_1):PAGE265
 X8002    3     P2 TP_TDR_4P_FTS_TH-TP_TDR_4P_DIP,EMPTY,TP15    I87 @T6G_MB_LIB.T6G(SCH_1):PAGE265
 X8001    2     P1 TP_TDR_4P_FTS_TH-TP_TDR_4P_DIP,EMPTY,TP15    I89 @T6G_MB_LIB.T6G(SCH_1):PAGE265
 X8001    3     P2 TP_TDR_4P_FTS_TH-TP_TDR_4P_DIP,EMPTY,TP15    I89 @T6G_MB_LIB.T6G(SCH_1):PAGE265
 X8008    2     P1 TP_TDR_4P_FTS_TH-TP_TDR_4P_DIP,EMPTY,TP15    I90 @T6G_MB_LIB.T6G(SCH_1):PAGE265
 X8008    3     P2 TP_TDR_4P_FTS_TH-TP_TDR_4P_DIP,EMPTY,TP15    I90 @T6G_MB_LIB.T6G(SCH_1):PAGE265
 X8007    2     P1 TP_TDR_4P_FTS_TH-TP_TDR_4P_DIP,EMPTY,TP15    I92 @T6G_MB_LIB.T6G(SCH_1):PAGE265
 X8007    3     P2 TP_TDR_4P_FTS_TH-TP_TDR_4P_DIP,EMPTY,TP15    I92 @T6G_MB_LIB.T6G(SCH_1):PAGE265
 X8012    2     P1 TP_TDR_4P_FTS_TH-TP_TDR_4P_DIP,EMPTY,TP15    I94 @T6G_MB_LIB.T6G(SCH_1):PAGE265
 X8012    3     P2 TP_TDR_4P_FTS_TH-TP_TDR_4P_DIP,EMPTY,TP15    I94 @T6G_MB_LIB.T6G(SCH_1):PAGE265
   X11    2     P1 TP_TDR_4P_FTS_TH-TP_TDR_4P_DIP,EMPTY,TP15    I96 @T6G_MB_LIB.T6G(SCH_1):PAGE265
   X11    3     P2 TP_TDR_4P_FTS_TH-TP_TDR_4P_DIP,EMPTY,TP15    I96 @T6G_MB_LIB.T6G(SCH_1):PAGE265
 X9026    2     P1 TP_TDR_4P_FTS_TH-TP_TDR_4P_DIP,EMPTY,TP15     I2 @T6G_MB_LIB.T6G(SCH_1):PAGE266
 X9026    3     P2 TP_TDR_4P_FTS_TH-TP_TDR_4P_DIP,EMPTY,TP15     I2 @T6G_MB_LIB.T6G(SCH_1):PAGE266
 X9025    2     P1 TP_TDR_4P_FTS_TH-TP_TDR_4P_DIP,EMPTY,TP15     I4 @T6G_MB_LIB.T6G(SCH_1):PAGE266
 X9025    3     P2 TP_TDR_4P_FTS_TH-TP_TDR_4P_DIP,EMPTY,TP15     I4 @T6G_MB_LIB.T6G(SCH_1):PAGE266
 X9005    2     P1 TP_TDR_4P_FTS_TH-TP_TDR_4P_DIP,EMPTY,TP15     I7 @T6G_MB_LIB.T6G(SCH_1):PAGE266
 X9005    3     P2 TP_TDR_4P_FTS_TH-TP_TDR_4P_DIP,EMPTY,TP15     I7 @T6G_MB_LIB.T6G(SCH_1):PAGE266
 X9004    2     P1 TP_TDR_4P_FTS_TH-TP_TDR_4P_DIP,EMPTY,TP15     I8 @T6G_MB_LIB.T6G(SCH_1):PAGE266
 X9004    3     P2 TP_TDR_4P_FTS_TH-TP_TDR_4P_DIP,EMPTY,TP15     I8 @T6G_MB_LIB.T6G(SCH_1):PAGE266
 X9003    2     P1 TP_TDR_4P_FTS_TH-TP_TDR_4P_DIP,EMPTY,TP15    I10 @T6G_MB_LIB.T6G(SCH_1):PAGE266
 X9003    3     P2 TP_TDR_4P_FTS_TH-TP_TDR_4P_DIP,EMPTY,TP15    I10 @T6G_MB_LIB.T6G(SCH_1):PAGE266
 X9002    2     P1 TP_TDR_4P_FTS_TH-TP_TDR_4P_DIP,EMPTY,TP15    I12 @T6G_MB_LIB.T6G(SCH_1):PAGE266
 X9002    3     P2 TP_TDR_4P_FTS_TH-TP_TDR_4P_DIP,EMPTY,TP15    I12 @T6G_MB_LIB.T6G(SCH_1):PAGE266
 X9028    2     P1 TP_TDR_4P_FTS_TH-TP_TDR_4P_DIP,EMPTY,TP15    I13 @T6G_MB_LIB.T6G(SCH_1):PAGE266
 X9028    3     P2 TP_TDR_4P_FTS_TH-TP_TDR_4P_DIP,EMPTY,TP15    I13 @T6G_MB_LIB.T6G(SCH_1):PAGE266
 X9027    2     P1 TP_TDR_4P_FTS_TH-TP_TDR_4P_DIP,EMPTY,TP15    I15 @T6G_MB_LIB.T6G(SCH_1):PAGE266
 X9027    3     P2 TP_TDR_4P_FTS_TH-TP_TDR_4P_DIP,EMPTY,TP15    I15 @T6G_MB_LIB.T6G(SCH_1):PAGE266
 X9010    2     P1 TP_TDR_4P_FTS_TH-TP_TDR_4P_DIP,EMPTY,TP15    I16 @T6G_MB_LIB.T6G(SCH_1):PAGE266
 X9010    3     P2 TP_TDR_4P_FTS_TH-TP_TDR_4P_DIP,EMPTY,TP15    I16 @T6G_MB_LIB.T6G(SCH_1):PAGE266
 X9011    2     P1 TP_TDR_4P_FTS_TH-TP_TDR_4P_DIP,EMPTY,TP15    I17 @T6G_MB_LIB.T6G(SCH_1):PAGE266
 X9011    3     P2 TP_TDR_4P_FTS_TH-TP_TDR_4P_DIP,EMPTY,TP15    I17 @T6G_MB_LIB.T6G(SCH_1):PAGE266
 X9009    2     P1 TP_TDR_4P_FTS_TH-TP_TDR_4P_DIP,EMPTY,TP15    I37 @T6G_MB_LIB.T6G(SCH_1):PAGE266
 X9009    3     P2 TP_TDR_4P_FTS_TH-TP_TDR_4P_DIP,EMPTY,TP15    I37 @T6G_MB_LIB.T6G(SCH_1):PAGE266
 X9008    2     P1 TP_TDR_4P_FTS_TH-TP_TDR_4P_DIP,EMPTY,TP15    I38 @T6G_MB_LIB.T6G(SCH_1):PAGE266
 X9008    3     P2 TP_TDR_4P_FTS_TH-TP_TDR_4P_DIP,EMPTY,TP15    I38 @T6G_MB_LIB.T6G(SCH_1):PAGE266

TCA9539_0_ADD0 @T6G_MB_LIB.T6G(SCH_1):TCA9539_0_ADD0
 R2696    1      A Q_RES_0402LF-1K,1%,1/16W,CHIP,CS21002FB06     I6 @T6G_MB_LIB.T6G(SCH_1):PAGE246
 R2695    2      B Q_RES_0402LF-1K,1%,1/16W,EMPTY,CS21002FB06     I7 @T6G_MB_LIB.T6G(SCH_1):PAGE246
  U181   21     A0 PCA9539RPW-PCA9539RPW,SMLF,IC,AL009539K07    I83 @T6G_MB_LIB.T6G(SCH_1):PAGE246

TCA9539_0_ADD1 @T6G_MB_LIB.T6G(SCH_1):TCA9539_0_ADD1
 R2694    1      A Q_RES_0402LF-1K,1%,1/16W,CHIP,CS21002FB06     I2 @T6G_MB_LIB.T6G(SCH_1):PAGE246
 R2693    2      B Q_RES_0402LF-1K,1%,1/16W,EMPTY,CS21002FB06     I3 @T6G_MB_LIB.T6G(SCH_1):PAGE246
  U181    2     A1 PCA9539RPW-PCA9539RPW,SMLF,IC,AL009539K07    I83 @T6G_MB_LIB.T6G(SCH_1):PAGE246

TDR_DIFF_80_BOT_DN @T6G_MB_LIB.T6G(SCH_1):TDR_DIFF_80_BOT_DN
    X6    4     S2 TP_TDR_4P_FTS_TH-TP_TDR_4P_DIP,EMPTY,TP15    I29 @T6G_MB_LIB.T6G(SCH_1):PAGE265
   X12    1     S1 TP_TDR_4P_FTS_TH-TP_TDR_4P_DIP,EMPTY,TP15    I49 @T6G_MB_LIB.T6G(SCH_1):PAGE265

TDR_DIFF_80_BOT_DP @T6G_MB_LIB.T6G(SCH_1):TDR_DIFF_80_BOT_DP
    X6    1     S1 TP_TDR_4P_FTS_TH-TP_TDR_4P_DIP,EMPTY,TP15    I29 @T6G_MB_LIB.T6G(SCH_1):PAGE265
   X12    4     S2 TP_TDR_4P_FTS_TH-TP_TDR_4P_DIP,EMPTY,TP15    I49 @T6G_MB_LIB.T6G(SCH_1):PAGE265

TDR_DIFF_80_IN1_DN @T6G_MB_LIB.T6G(SCH_1):TDR_DIFF_80_IN1_DN
    X2    4     S2 TP_TDR_4P_FTS_TH-TP_TDR_4P_DIP,EMPTY,TP15    I47 @T6G_MB_LIB.T6G(SCH_1):PAGE265
    X8    1     S1 TP_TDR_4P_FTS_TH-TP_TDR_4P_DIP,EMPTY,TP15    I82 @T6G_MB_LIB.T6G(SCH_1):PAGE265

TDR_DIFF_80_IN1_DP @T6G_MB_LIB.T6G(SCH_1):TDR_DIFF_80_IN1_DP
    X2    1     S1 TP_TDR_4P_FTS_TH-TP_TDR_4P_DIP,EMPTY,TP15    I47 @T6G_MB_LIB.T6G(SCH_1):PAGE265
    X8    4     S2 TP_TDR_4P_FTS_TH-TP_TDR_4P_DIP,EMPTY,TP15    I82 @T6G_MB_LIB.T6G(SCH_1):PAGE265

TDR_DIFF_80_IN2_DN @T6G_MB_LIB.T6G(SCH_1):TDR_DIFF_80_IN2_DN
    X3    4     S2 TP_TDR_4P_FTS_TH-TP_TDR_4P_DIP,EMPTY,TP15    I37 @T6G_MB_LIB.T6G(SCH_1):PAGE265
    X9    1     S1 TP_TDR_4P_FTS_TH-TP_TDR_4P_DIP,EMPTY,TP15    I62 @T6G_MB_LIB.T6G(SCH_1):PAGE265

TDR_DIFF_80_IN2_DP @T6G_MB_LIB.T6G(SCH_1):TDR_DIFF_80_IN2_DP
    X3    1     S1 TP_TDR_4P_FTS_TH-TP_TDR_4P_DIP,EMPTY,TP15    I37 @T6G_MB_LIB.T6G(SCH_1):PAGE265
    X9    4     S2 TP_TDR_4P_FTS_TH-TP_TDR_4P_DIP,EMPTY,TP15    I62 @T6G_MB_LIB.T6G(SCH_1):PAGE265

TDR_DIFF_80_IN3_DN @T6G_MB_LIB.T6G(SCH_1):TDR_DIFF_80_IN3_DN
    X4    4     S2 TP_TDR_4P_FTS_TH-TP_TDR_4P_DIP,EMPTY,TP15    I36 @T6G_MB_LIB.T6G(SCH_1):PAGE265
   X10    1     S1 TP_TDR_4P_FTS_TH-TP_TDR_4P_DIP,EMPTY,TP15    I61 @T6G_MB_LIB.T6G(SCH_1):PAGE265

TDR_DIFF_80_IN3_DP @T6G_MB_LIB.T6G(SCH_1):TDR_DIFF_80_IN3_DP
    X4    1     S1 TP_TDR_4P_FTS_TH-TP_TDR_4P_DIP,EMPTY,TP15    I36 @T6G_MB_LIB.T6G(SCH_1):PAGE265
   X10    4     S2 TP_TDR_4P_FTS_TH-TP_TDR_4P_DIP,EMPTY,TP15    I61 @T6G_MB_LIB.T6G(SCH_1):PAGE265

TDR_DIFF_80_IN4_DN @T6G_MB_LIB.T6G(SCH_1):TDR_DIFF_80_IN4_DN
    X5    4     S2 TP_TDR_4P_FTS_TH-TP_TDR_4P_DIP,EMPTY,TP15    I35 @T6G_MB_LIB.T6G(SCH_1):PAGE265
   X11    1     S1 TP_TDR_4P_FTS_TH-TP_TDR_4P_DIP,EMPTY,TP15    I96 @T6G_MB_LIB.T6G(SCH_1):PAGE265

TDR_DIFF_80_IN4_DP @T6G_MB_LIB.T6G(SCH_1):TDR_DIFF_80_IN4_DP
    X5    1     S1 TP_TDR_4P_FTS_TH-TP_TDR_4P_DIP,EMPTY,TP15    I35 @T6G_MB_LIB.T6G(SCH_1):PAGE265
   X11    4     S2 TP_TDR_4P_FTS_TH-TP_TDR_4P_DIP,EMPTY,TP15    I96 @T6G_MB_LIB.T6G(SCH_1):PAGE265

TDR_DIFF_80_IN5_DN @T6G_MB_LIB.T6G(SCH_1):TDR_DIFF_80_IN5_DN
   X25    4     S2 TP_TDR_4P_FTS_TH-TP_TDR_4P_DIP,EMPTY,TP15    I31 @T6G_MB_LIB.T6G(SCH_1):PAGE265
   X27    1     S1 TP_TDR_4P_FTS_TH-TP_TDR_4P_DIP,EMPTY,TP15    I53 @T6G_MB_LIB.T6G(SCH_1):PAGE265

TDR_DIFF_80_IN5_DP @T6G_MB_LIB.T6G(SCH_1):TDR_DIFF_80_IN5_DP
   X25    1     S1 TP_TDR_4P_FTS_TH-TP_TDR_4P_DIP,EMPTY,TP15    I31 @T6G_MB_LIB.T6G(SCH_1):PAGE265
   X27    4     S2 TP_TDR_4P_FTS_TH-TP_TDR_4P_DIP,EMPTY,TP15    I53 @T6G_MB_LIB.T6G(SCH_1):PAGE265

TDR_DIFF_80_IN6_DN @T6G_MB_LIB.T6G(SCH_1):TDR_DIFF_80_IN6_DN
   X26    4     S2 TP_TDR_4P_FTS_TH-TP_TDR_4P_DIP,EMPTY,TP15    I30 @T6G_MB_LIB.T6G(SCH_1):PAGE265
   X28    1     S1 TP_TDR_4P_FTS_TH-TP_TDR_4P_DIP,EMPTY,TP15    I52 @T6G_MB_LIB.T6G(SCH_1):PAGE265

TDR_DIFF_80_IN6_DP @T6G_MB_LIB.T6G(SCH_1):TDR_DIFF_80_IN6_DP
   X26    1     S1 TP_TDR_4P_FTS_TH-TP_TDR_4P_DIP,EMPTY,TP15    I30 @T6G_MB_LIB.T6G(SCH_1):PAGE265
   X28    4     S2 TP_TDR_4P_FTS_TH-TP_TDR_4P_DIP,EMPTY,TP15    I52 @T6G_MB_LIB.T6G(SCH_1):PAGE265

TDR_DIFF_80_TOP_DN @T6G_MB_LIB.T6G(SCH_1):TDR_DIFF_80_TOP_DN
    X1    4     S2 TP_TDR_4P_FTS_TH-TP_TDR_4P_DIP,EMPTY,TP15    I48 @T6G_MB_LIB.T6G(SCH_1):PAGE265
    X7    1     S1 TP_TDR_4P_FTS_TH-TP_TDR_4P_DIP,EMPTY,TP15    I84 @T6G_MB_LIB.T6G(SCH_1):PAGE265

TDR_DIFF_80_TOP_DP @T6G_MB_LIB.T6G(SCH_1):TDR_DIFF_80_TOP_DP
    X1    1     S1 TP_TDR_4P_FTS_TH-TP_TDR_4P_DIP,EMPTY,TP15    I48 @T6G_MB_LIB.T6G(SCH_1):PAGE265
    X7    4     S2 TP_TDR_4P_FTS_TH-TP_TDR_4P_DIP,EMPTY,TP15    I84 @T6G_MB_LIB.T6G(SCH_1):PAGE265

TDR_DIFF_85_BOT_DN @T6G_MB_LIB.T6G(SCH_1):TDR_DIFF_85_BOT_DN
 X8006    4     S2 TP_TDR_4P_FTS_TH-TP_TDR_4P_DIP,EMPTY,TP15    I56 @T6G_MB_LIB.T6G(SCH_1):PAGE265
 X8012    1     S1 TP_TDR_4P_FTS_TH-TP_TDR_4P_DIP,EMPTY,TP15    I94 @T6G_MB_LIB.T6G(SCH_1):PAGE265

TDR_DIFF_85_BOT_DP @T6G_MB_LIB.T6G(SCH_1):TDR_DIFF_85_BOT_DP
 X8006    1     S1 TP_TDR_4P_FTS_TH-TP_TDR_4P_DIP,EMPTY,TP15    I56 @T6G_MB_LIB.T6G(SCH_1):PAGE265
 X8012    4     S2 TP_TDR_4P_FTS_TH-TP_TDR_4P_DIP,EMPTY,TP15    I94 @T6G_MB_LIB.T6G(SCH_1):PAGE265

TDR_DIFF_85_IN1_DN @T6G_MB_LIB.T6G(SCH_1):TDR_DIFF_85_IN1_DN
 X8002    4     S2 TP_TDR_4P_FTS_TH-TP_TDR_4P_DIP,EMPTY,TP15    I87 @T6G_MB_LIB.T6G(SCH_1):PAGE265
 X8008    1     S1 TP_TDR_4P_FTS_TH-TP_TDR_4P_DIP,EMPTY,TP15    I90 @T6G_MB_LIB.T6G(SCH_1):PAGE265

TDR_DIFF_85_IN1_DP @T6G_MB_LIB.T6G(SCH_1):TDR_DIFF_85_IN1_DP
 X8002    1     S1 TP_TDR_4P_FTS_TH-TP_TDR_4P_DIP,EMPTY,TP15    I87 @T6G_MB_LIB.T6G(SCH_1):PAGE265
 X8008    4     S2 TP_TDR_4P_FTS_TH-TP_TDR_4P_DIP,EMPTY,TP15    I90 @T6G_MB_LIB.T6G(SCH_1):PAGE265

TDR_DIFF_85_IN2_DN @T6G_MB_LIB.T6G(SCH_1):TDR_DIFF_85_IN2_DN
 X8003    4     S2 TP_TDR_4P_FTS_TH-TP_TDR_4P_DIP,EMPTY,TP15    I70 @T6G_MB_LIB.T6G(SCH_1):PAGE265
 X8009    1     S1 TP_TDR_4P_FTS_TH-TP_TDR_4P_DIP,EMPTY,TP15    I79 @T6G_MB_LIB.T6G(SCH_1):PAGE265

TDR_DIFF_85_IN2_DP @T6G_MB_LIB.T6G(SCH_1):TDR_DIFF_85_IN2_DP
 X8003    1     S1 TP_TDR_4P_FTS_TH-TP_TDR_4P_DIP,EMPTY,TP15    I70 @T6G_MB_LIB.T6G(SCH_1):PAGE265
 X8009    4     S2 TP_TDR_4P_FTS_TH-TP_TDR_4P_DIP,EMPTY,TP15    I79 @T6G_MB_LIB.T6G(SCH_1):PAGE265

TDR_DIFF_85_IN3_DN @T6G_MB_LIB.T6G(SCH_1):TDR_DIFF_85_IN3_DN
 X8004    4     S2 TP_TDR_4P_FTS_TH-TP_TDR_4P_DIP,EMPTY,TP15    I68 @T6G_MB_LIB.T6G(SCH_1):PAGE265
 X8010    1     S1 TP_TDR_4P_FTS_TH-TP_TDR_4P_DIP,EMPTY,TP15    I78 @T6G_MB_LIB.T6G(SCH_1):PAGE265

TDR_DIFF_85_IN3_DP @T6G_MB_LIB.T6G(SCH_1):TDR_DIFF_85_IN3_DP
 X8004    1     S1 TP_TDR_4P_FTS_TH-TP_TDR_4P_DIP,EMPTY,TP15    I68 @T6G_MB_LIB.T6G(SCH_1):PAGE265
 X8010    4     S2 TP_TDR_4P_FTS_TH-TP_TDR_4P_DIP,EMPTY,TP15    I78 @T6G_MB_LIB.T6G(SCH_1):PAGE265

TDR_DIFF_85_IN4_DN @T6G_MB_LIB.T6G(SCH_1):TDR_DIFF_85_IN4_DN
 X8005    4     S2 TP_TDR_4P_FTS_TH-TP_TDR_4P_DIP,EMPTY,TP15    I66 @T6G_MB_LIB.T6G(SCH_1):PAGE265
 X8011    1     S1 TP_TDR_4P_FTS_TH-TP_TDR_4P_DIP,EMPTY,TP15    I76 @T6G_MB_LIB.T6G(SCH_1):PAGE265

TDR_DIFF_85_IN4_DP @T6G_MB_LIB.T6G(SCH_1):TDR_DIFF_85_IN4_DP
 X8005    1     S1 TP_TDR_4P_FTS_TH-TP_TDR_4P_DIP,EMPTY,TP15    I66 @T6G_MB_LIB.T6G(SCH_1):PAGE265
 X8011    4     S2 TP_TDR_4P_FTS_TH-TP_TDR_4P_DIP,EMPTY,TP15    I76 @T6G_MB_LIB.T6G(SCH_1):PAGE265

TDR_DIFF_85_IN5_DN @T6G_MB_LIB.T6G(SCH_1):TDR_DIFF_85_IN5_DN
 X8025    4     S2 TP_TDR_4P_FTS_TH-TP_TDR_4P_DIP,EMPTY,TP15    I60 @T6G_MB_LIB.T6G(SCH_1):PAGE265
 X8027    1     S1 TP_TDR_4P_FTS_TH-TP_TDR_4P_DIP,EMPTY,TP15    I74 @T6G_MB_LIB.T6G(SCH_1):PAGE265

TDR_DIFF_85_IN5_DP @T6G_MB_LIB.T6G(SCH_1):TDR_DIFF_85_IN5_DP
 X8025    1     S1 TP_TDR_4P_FTS_TH-TP_TDR_4P_DIP,EMPTY,TP15    I60 @T6G_MB_LIB.T6G(SCH_1):PAGE265
 X8027    4     S2 TP_TDR_4P_FTS_TH-TP_TDR_4P_DIP,EMPTY,TP15    I74 @T6G_MB_LIB.T6G(SCH_1):PAGE265

TDR_DIFF_85_IN6_DN @T6G_MB_LIB.T6G(SCH_1):TDR_DIFF_85_IN6_DN
 X8026    4     S2 TP_TDR_4P_FTS_TH-TP_TDR_4P_DIP,EMPTY,TP15    I58 @T6G_MB_LIB.T6G(SCH_1):PAGE265
 X8028    1     S1 TP_TDR_4P_FTS_TH-TP_TDR_4P_DIP,EMPTY,TP15    I73 @T6G_MB_LIB.T6G(SCH_1):PAGE265

TDR_DIFF_85_IN6_DP @T6G_MB_LIB.T6G(SCH_1):TDR_DIFF_85_IN6_DP
 X8026    1     S1 TP_TDR_4P_FTS_TH-TP_TDR_4P_DIP,EMPTY,TP15    I58 @T6G_MB_LIB.T6G(SCH_1):PAGE265
 X8028    4     S2 TP_TDR_4P_FTS_TH-TP_TDR_4P_DIP,EMPTY,TP15    I73 @T6G_MB_LIB.T6G(SCH_1):PAGE265

TDR_DIFF_85_NECK_IN1_DN @T6G_MB_LIB.T6G(SCH_1):TDR_DIFF_85_NECK_IN1_DN
 X9002    4     S2 TP_TDR_4P_FTS_TH-TP_TDR_4P_DIP,EMPTY,TP15    I12 @T6G_MB_LIB.T6G(SCH_1):PAGE266
 X9008    1     S1 TP_TDR_4P_FTS_TH-TP_TDR_4P_DIP,EMPTY,TP15    I38 @T6G_MB_LIB.T6G(SCH_1):PAGE266

TDR_DIFF_85_NECK_IN1_DP @T6G_MB_LIB.T6G(SCH_1):TDR_DIFF_85_NECK_IN1_DP
 X9002    1     S1 TP_TDR_4P_FTS_TH-TP_TDR_4P_DIP,EMPTY,TP15    I12 @T6G_MB_LIB.T6G(SCH_1):PAGE266
 X9008    4     S2 TP_TDR_4P_FTS_TH-TP_TDR_4P_DIP,EMPTY,TP15    I38 @T6G_MB_LIB.T6G(SCH_1):PAGE266

TDR_DIFF_85_NECK_IN2_DN @T6G_MB_LIB.T6G(SCH_1):TDR_DIFF_85_NECK_IN2_DN
 X9003    4     S2 TP_TDR_4P_FTS_TH-TP_TDR_4P_DIP,EMPTY,TP15    I10 @T6G_MB_LIB.T6G(SCH_1):PAGE266
 X9009    1     S1 TP_TDR_4P_FTS_TH-TP_TDR_4P_DIP,EMPTY,TP15    I37 @T6G_MB_LIB.T6G(SCH_1):PAGE266

TDR_DIFF_85_NECK_IN2_DP @T6G_MB_LIB.T6G(SCH_1):TDR_DIFF_85_NECK_IN2_DP
 X9003    1     S1 TP_TDR_4P_FTS_TH-TP_TDR_4P_DIP,EMPTY,TP15    I10 @T6G_MB_LIB.T6G(SCH_1):PAGE266
 X9009    4     S2 TP_TDR_4P_FTS_TH-TP_TDR_4P_DIP,EMPTY,TP15    I37 @T6G_MB_LIB.T6G(SCH_1):PAGE266

TDR_DIFF_85_NECK_IN3_DN @T6G_MB_LIB.T6G(SCH_1):TDR_DIFF_85_NECK_IN3_DN
 X9004    4     S2 TP_TDR_4P_FTS_TH-TP_TDR_4P_DIP,EMPTY,TP15     I8 @T6G_MB_LIB.T6G(SCH_1):PAGE266
 X9010    1     S1 TP_TDR_4P_FTS_TH-TP_TDR_4P_DIP,EMPTY,TP15    I16 @T6G_MB_LIB.T6G(SCH_1):PAGE266

TDR_DIFF_85_NECK_IN3_DP @T6G_MB_LIB.T6G(SCH_1):TDR_DIFF_85_NECK_IN3_DP
 X9004    1     S1 TP_TDR_4P_FTS_TH-TP_TDR_4P_DIP,EMPTY,TP15     I8 @T6G_MB_LIB.T6G(SCH_1):PAGE266
 X9010    4     S2 TP_TDR_4P_FTS_TH-TP_TDR_4P_DIP,EMPTY,TP15    I16 @T6G_MB_LIB.T6G(SCH_1):PAGE266

TDR_DIFF_85_NECK_IN4_DN @T6G_MB_LIB.T6G(SCH_1):TDR_DIFF_85_NECK_IN4_DN
 X9005    4     S2 TP_TDR_4P_FTS_TH-TP_TDR_4P_DIP,EMPTY,TP15     I7 @T6G_MB_LIB.T6G(SCH_1):PAGE266
 X9011    1     S1 TP_TDR_4P_FTS_TH-TP_TDR_4P_DIP,EMPTY,TP15    I17 @T6G_MB_LIB.T6G(SCH_1):PAGE266

TDR_DIFF_85_NECK_IN4_DP @T6G_MB_LIB.T6G(SCH_1):TDR_DIFF_85_NECK_IN4_DP
 X9005    1     S1 TP_TDR_4P_FTS_TH-TP_TDR_4P_DIP,EMPTY,TP15     I7 @T6G_MB_LIB.T6G(SCH_1):PAGE266
 X9011    4     S2 TP_TDR_4P_FTS_TH-TP_TDR_4P_DIP,EMPTY,TP15    I17 @T6G_MB_LIB.T6G(SCH_1):PAGE266

TDR_DIFF_85_NECK_IN5_DN @T6G_MB_LIB.T6G(SCH_1):TDR_DIFF_85_NECK_IN5_DN
 X9025    4     S2 TP_TDR_4P_FTS_TH-TP_TDR_4P_DIP,EMPTY,TP15     I4 @T6G_MB_LIB.T6G(SCH_1):PAGE266
 X9027    1     S1 TP_TDR_4P_FTS_TH-TP_TDR_4P_DIP,EMPTY,TP15    I15 @T6G_MB_LIB.T6G(SCH_1):PAGE266

TDR_DIFF_85_NECK_IN5_DP @T6G_MB_LIB.T6G(SCH_1):TDR_DIFF_85_NECK_IN5_DP
 X9025    1     S1 TP_TDR_4P_FTS_TH-TP_TDR_4P_DIP,EMPTY,TP15     I4 @T6G_MB_LIB.T6G(SCH_1):PAGE266
 X9027    4     S2 TP_TDR_4P_FTS_TH-TP_TDR_4P_DIP,EMPTY,TP15    I15 @T6G_MB_LIB.T6G(SCH_1):PAGE266

TDR_DIFF_85_NECK_IN6_DN @T6G_MB_LIB.T6G(SCH_1):TDR_DIFF_85_NECK_IN6_DN
 X9026    4     S2 TP_TDR_4P_FTS_TH-TP_TDR_4P_DIP,EMPTY,TP15     I2 @T6G_MB_LIB.T6G(SCH_1):PAGE266
 X9028    1     S1 TP_TDR_4P_FTS_TH-TP_TDR_4P_DIP,EMPTY,TP15    I13 @T6G_MB_LIB.T6G(SCH_1):PAGE266

TDR_DIFF_85_NECK_IN6_DP @T6G_MB_LIB.T6G(SCH_1):TDR_DIFF_85_NECK_IN6_DP
 X9026    1     S1 TP_TDR_4P_FTS_TH-TP_TDR_4P_DIP,EMPTY,TP15     I2 @T6G_MB_LIB.T6G(SCH_1):PAGE266
 X9028    4     S2 TP_TDR_4P_FTS_TH-TP_TDR_4P_DIP,EMPTY,TP15    I13 @T6G_MB_LIB.T6G(SCH_1):PAGE266

TDR_DIFF_85_TOP_DN @T6G_MB_LIB.T6G(SCH_1):TDR_DIFF_85_TOP_DN
 X8001    4     S2 TP_TDR_4P_FTS_TH-TP_TDR_4P_DIP,EMPTY,TP15    I89 @T6G_MB_LIB.T6G(SCH_1):PAGE265
 X8007    1     S1 TP_TDR_4P_FTS_TH-TP_TDR_4P_DIP,EMPTY,TP15    I92 @T6G_MB_LIB.T6G(SCH_1):PAGE265

TDR_DIFF_85_TOP_DP @T6G_MB_LIB.T6G(SCH_1):TDR_DIFF_85_TOP_DP
 X8001    1     S1 TP_TDR_4P_FTS_TH-TP_TDR_4P_DIP,EMPTY,TP15    I89 @T6G_MB_LIB.T6G(SCH_1):PAGE265
 X8007    4     S2 TP_TDR_4P_FTS_TH-TP_TDR_4P_DIP,EMPTY,TP15    I92 @T6G_MB_LIB.T6G(SCH_1):PAGE265

TDR_SE_45_OHM_BOT @T6G_MB_LIB.T6G(SCH_1):TDR_SE_45_OHM_BOT
   DB6    2    IO1 TDR_3P_TH2-EMPTY,N_A     I2 @T6G_MB_LIB.T6G(SCH_1):PAGE265
   DB6    3    IO2 TDR_3P_TH2-EMPTY,N_A     I2 @T6G_MB_LIB.T6G(SCH_1):PAGE265

TDR_SE_45_OHM_IN1 @T6G_MB_LIB.T6G(SCH_1):TDR_SE_45_OHM_IN1
   DB2    2    IO1 TDR_3P_TH2-EMPTY,N_A    I15 @T6G_MB_LIB.T6G(SCH_1):PAGE265
   DB2    3    IO2 TDR_3P_TH2-EMPTY,N_A    I15 @T6G_MB_LIB.T6G(SCH_1):PAGE265

TDR_SE_45_OHM_IN2 @T6G_MB_LIB.T6G(SCH_1):TDR_SE_45_OHM_IN2
   DB3    2    IO1 TDR_3P_TH2-EMPTY,N_A    I13 @T6G_MB_LIB.T6G(SCH_1):PAGE265
   DB3    3    IO2 TDR_3P_TH2-EMPTY,N_A    I13 @T6G_MB_LIB.T6G(SCH_1):PAGE265

TDR_SE_45_OHM_IN3 @T6G_MB_LIB.T6G(SCH_1):TDR_SE_45_OHM_IN3
   DB4    2    IO1 TDR_3P_TH2-EMPTY,N_A    I12 @T6G_MB_LIB.T6G(SCH_1):PAGE265
   DB4    3    IO2 TDR_3P_TH2-EMPTY,N_A    I12 @T6G_MB_LIB.T6G(SCH_1):PAGE265

TDR_SE_45_OHM_IN4 @T6G_MB_LIB.T6G(SCH_1):TDR_SE_45_OHM_IN4
   DB5    2    IO1 TDR_3P_TH2-EMPTY,N_A     I9 @T6G_MB_LIB.T6G(SCH_1):PAGE265
   DB5    3    IO2 TDR_3P_TH2-EMPTY,N_A     I9 @T6G_MB_LIB.T6G(SCH_1):PAGE265

TDR_SE_45_OHM_IN5 @T6G_MB_LIB.T6G(SCH_1):TDR_SE_45_OHM_IN5
  DB13    2    IO1 TDR_3P_TH2-EMPTY,N_A     I8 @T6G_MB_LIB.T6G(SCH_1):PAGE265
  DB13    3    IO2 TDR_3P_TH2-EMPTY,N_A     I8 @T6G_MB_LIB.T6G(SCH_1):PAGE265

TDR_SE_45_OHM_IN6 @T6G_MB_LIB.T6G(SCH_1):TDR_SE_45_OHM_IN6
  DB14    2    IO1 TDR_3P_TH2-EMPTY,N_A     I5 @T6G_MB_LIB.T6G(SCH_1):PAGE265
  DB14    3    IO2 TDR_3P_TH2-EMPTY,N_A     I5 @T6G_MB_LIB.T6G(SCH_1):PAGE265

TDR_SE_45_OHM_TOP @T6G_MB_LIB.T6G(SCH_1):TDR_SE_45_OHM_TOP
   DB1    2    IO1 TDR_3P_TH2-EMPTY,N_A    I16 @T6G_MB_LIB.T6G(SCH_1):PAGE265
   DB1    3    IO2 TDR_3P_TH2-EMPTY,N_A    I16 @T6G_MB_LIB.T6G(SCH_1):PAGE265

TDR_SE_50_OHM_BOT @T6G_MB_LIB.T6G(SCH_1):TDR_SE_50_OHM_BOT
  DB12    2    IO1 TDR_3P_TH2-EMPTY,N_A    I18 @T6G_MB_LIB.T6G(SCH_1):PAGE265
  DB12    3    IO2 TDR_3P_TH2-EMPTY,N_A    I18 @T6G_MB_LIB.T6G(SCH_1):PAGE265

TDR_SE_50_OHM_IN1 @T6G_MB_LIB.T6G(SCH_1):TDR_SE_50_OHM_IN1
   DB8    2    IO1 TDR_3P_TH2-EMPTY,N_A    I42 @T6G_MB_LIB.T6G(SCH_1):PAGE265
   DB8    3    IO2 TDR_3P_TH2-EMPTY,N_A    I42 @T6G_MB_LIB.T6G(SCH_1):PAGE265

TDR_SE_50_OHM_IN2 @T6G_MB_LIB.T6G(SCH_1):TDR_SE_50_OHM_IN2
   DB9    2    IO1 TDR_3P_TH2-EMPTY,N_A    I40 @T6G_MB_LIB.T6G(SCH_1):PAGE265
   DB9    3    IO2 TDR_3P_TH2-EMPTY,N_A    I40 @T6G_MB_LIB.T6G(SCH_1):PAGE265

TDR_SE_50_OHM_IN3 @T6G_MB_LIB.T6G(SCH_1):TDR_SE_50_OHM_IN3
  DB10    2    IO1 TDR_3P_TH2-EMPTY,N_A    I38 @T6G_MB_LIB.T6G(SCH_1):PAGE265
  DB10    3    IO2 TDR_3P_TH2-EMPTY,N_A    I38 @T6G_MB_LIB.T6G(SCH_1):PAGE265

TDR_SE_50_OHM_IN4 @T6G_MB_LIB.T6G(SCH_1):TDR_SE_50_OHM_IN4
  DB11    2    IO1 TDR_3P_TH2-EMPTY,N_A    I25 @T6G_MB_LIB.T6G(SCH_1):PAGE265
  DB11    3    IO2 TDR_3P_TH2-EMPTY,N_A    I25 @T6G_MB_LIB.T6G(SCH_1):PAGE265

TDR_SE_50_OHM_IN5 @T6G_MB_LIB.T6G(SCH_1):TDR_SE_50_OHM_IN5
  DB15    2    IO1 TDR_3P_TH2-EMPTY,N_A    I22 @T6G_MB_LIB.T6G(SCH_1):PAGE265
  DB15    3    IO2 TDR_3P_TH2-EMPTY,N_A    I22 @T6G_MB_LIB.T6G(SCH_1):PAGE265

TDR_SE_50_OHM_IN6 @T6G_MB_LIB.T6G(SCH_1):TDR_SE_50_OHM_IN6
  DB16    2    IO1 TDR_3P_TH2-EMPTY,N_A    I20 @T6G_MB_LIB.T6G(SCH_1):PAGE265
  DB16    3    IO2 TDR_3P_TH2-EMPTY,N_A    I20 @T6G_MB_LIB.T6G(SCH_1):PAGE265

TDR_SE_50_OHM_TOP @T6G_MB_LIB.T6G(SCH_1):TDR_SE_50_OHM_TOP
   DB7    2    IO1 TDR_3P_TH2-EMPTY,N_A    I44 @T6G_MB_LIB.T6G(SCH_1):PAGE265
   DB7    3    IO2 TDR_3P_TH2-EMPTY,N_A    I44 @T6G_MB_LIB.T6G(SCH_1):PAGE265

TEST0_RT_CPU0_P0 @T6G_MB_LIB.T6G(SCH_1):TEST0_RT_CPU0_P0
  R982    1      A Q_RES_0201LF-4.7K,5%,1/20W,CHIP,CS24701JE04    I29 @T6G_MB_LIB.T6G(SCH_1):PAGE385
  R981    2      B Q_RES_0201LF-4.7K,5%,1/20W,EMPTY,CS24701JE04    I31 @T6G_MB_LIB.T6G(SCH_1):PAGE385
 U6010 FF24  TEST0 PT5161LRS-PT5161LRS,SMLF,IC,AJ051610U03    I53 @T6G_MB_LIB.T6G(SCH_1):PAGE385

TEST0_RT_CPU0_P1 @T6G_MB_LIB.T6G(SCH_1):TEST0_RT_CPU0_P1
 R1031    1      A Q_RES_0201LF-4.7K,5%,1/20W,CHIP,CS24701JE04     I9 @T6G_MB_LIB.T6G(SCH_1):PAGE408
 R1030    2      B Q_RES_0201LF-4.7K,5%,1/20W,EMPTY,CS24701JE04    I11 @T6G_MB_LIB.T6G(SCH_1):PAGE408
 U6011 FF24  TEST0 PT5161LRS-PT5161LRS,SMLF,IC,AJ051610U03    I83 @T6G_MB_LIB.T6G(SCH_1):PAGE408

TEST0_RT_CPU0_P2 @T6G_MB_LIB.T6G(SCH_1):TEST0_RT_CPU0_P2
 R1074    1      A Q_RES_0201LF-4.7K,5%,1/20W,CHIP,CS24701JE04     I9 @T6G_MB_LIB.T6G(SCH_1):PAGE419
 R1073    2      B Q_RES_0201LF-4.7K,5%,1/20W,EMPTY,CS24701JE04    I11 @T6G_MB_LIB.T6G(SCH_1):PAGE419
 U6012 FF24  TEST0 PT5161LRS-PT5161LRS,SMLF,IC,AJ051610U03    I83 @T6G_MB_LIB.T6G(SCH_1):PAGE419

TEST0_RT_CPU0_P3 @T6G_MB_LIB.T6G(SCH_1):TEST0_RT_CPU0_P3
 R1115    1      A Q_RES_0201LF-4.7K,5%,1/20W,CHIP,CS24701JE04     I9 @T6G_MB_LIB.T6G(SCH_1):PAGE430
 R1114    2      B Q_RES_0201LF-4.7K,5%,1/20W,EMPTY,CS24701JE04    I11 @T6G_MB_LIB.T6G(SCH_1):PAGE430
 U6013 FF24  TEST0 PT5161LRS-PT5161LRS,SMLF,IC,AJ051610U03    I83 @T6G_MB_LIB.T6G(SCH_1):PAGE430

TEST0_RT_CPU1_P0 @T6G_MB_LIB.T6G(SCH_1):TEST0_RT_CPU1_P0
 U6014 FF24  TEST0 PT5161LRS-PT5161LRS,SMLF,IC,AJ051610U03     I1 @T6G_MB_LIB.T6G(SCH_1):PAGE401
  R716    2      B Q_RES_0201LF-4.7K,5%,1/20W,EMPTY,CS24701JE04    I27 @T6G_MB_LIB.T6G(SCH_1):PAGE401
  R719    1      A Q_RES_0201LF-4.7K,5%,1/20W,CHIP,CS24701JE04    I34 @T6G_MB_LIB.T6G(SCH_1):PAGE401

TEST0_RT_CPU1_P1 @T6G_MB_LIB.T6G(SCH_1):TEST0_RT_CPU1_P1
  R785    1      A Q_RES_0201LF-4.7K,5%,1/20W,CHIP,CS24701JE04    I23 @T6G_MB_LIB.T6G(SCH_1):PAGE392
  R784    2      B Q_RES_0201LF-4.7K,5%,1/20W,EMPTY,CS24701JE04    I25 @T6G_MB_LIB.T6G(SCH_1):PAGE392
 U6015 FF24  TEST0 PT5161LRS-PT5161LRS,SMLF,IC,AJ051610U03    I47 @T6G_MB_LIB.T6G(SCH_1):PAGE392

TEST0_RT_CPU1_P2 @T6G_MB_LIB.T6G(SCH_1):TEST0_RT_CPU1_P2
  R879    1      A Q_RES_0201LF-4.7K,5%,1/20W,CHIP,CS24701JE04    I42 @T6G_MB_LIB.T6G(SCH_1):PAGE451
  R878    2      B Q_RES_0201LF-4.7K,5%,1/20W,EMPTY,CS24701JE04    I47 @T6G_MB_LIB.T6G(SCH_1):PAGE451
 U6016 FF24  TEST0 PT5161LRS-PT5161LRS,SMLF,IC,AJ051610U03    I97 @T6G_MB_LIB.T6G(SCH_1):PAGE451

TEST0_RT_CPU1_P3 @T6G_MB_LIB.T6G(SCH_1):TEST0_RT_CPU1_P3
  R919    1      A Q_RES_0201LF-4.7K,5%,1/20W,CHIP,CS24701JE04    I21 @T6G_MB_LIB.T6G(SCH_1):PAGE462
  R918    2      B Q_RES_0201LF-4.7K,5%,1/20W,EMPTY,CS24701JE04    I23 @T6G_MB_LIB.T6G(SCH_1):PAGE462
 U6017 FF24  TEST0 PT5161LRS-PT5161LRS,SMLF,IC,AJ051610U03    I97 @T6G_MB_LIB.T6G(SCH_1):PAGE462

TEST1_RT_CPU0_P0 @T6G_MB_LIB.T6G(SCH_1):TEST1_RT_CPU0_P0
 U6010 FF27  TEST1 PT5161LRS-PT5161LRS,SMLF,IC,AJ051610U03    I53 @T6G_MB_LIB.T6G(SCH_1):PAGE385
  R984    1      A Q_RES_0201LF-4.7K,5%,1/20W,CHIP,CS24701JE04    I57 @T6G_MB_LIB.T6G(SCH_1):PAGE385
  R983    2      B Q_RES_0201LF-4.7K,5%,1/20W,EMPTY,CS24701JE04    I61 @T6G_MB_LIB.T6G(SCH_1):PAGE385

TEST1_RT_CPU0_P1 @T6G_MB_LIB.T6G(SCH_1):TEST1_RT_CPU0_P1
 R1033    1      A Q_RES_0201LF-4.7K,5%,1/20W,CHIP,CS24701JE04    I36 @T6G_MB_LIB.T6G(SCH_1):PAGE408
 R1032    2      B Q_RES_0201LF-4.7K,5%,1/20W,EMPTY,CS24701JE04    I40 @T6G_MB_LIB.T6G(SCH_1):PAGE408
 U6011 FF27  TEST1 PT5161LRS-PT5161LRS,SMLF,IC,AJ051610U03    I83 @T6G_MB_LIB.T6G(SCH_1):PAGE408

TEST1_RT_CPU0_P2 @T6G_MB_LIB.T6G(SCH_1):TEST1_RT_CPU0_P2
 R1076    1      A Q_RES_0201LF-4.7K,5%,1/20W,CHIP,CS24701JE04    I36 @T6G_MB_LIB.T6G(SCH_1):PAGE419
 R1075    2      B Q_RES_0201LF-4.7K,5%,1/20W,EMPTY,CS24701JE04    I40 @T6G_MB_LIB.T6G(SCH_1):PAGE419
 U6012 FF27  TEST1 PT5161LRS-PT5161LRS,SMLF,IC,AJ051610U03    I83 @T6G_MB_LIB.T6G(SCH_1):PAGE419

TEST1_RT_CPU0_P3 @T6G_MB_LIB.T6G(SCH_1):TEST1_RT_CPU0_P3
 R1118    1      A Q_RES_0201LF-4.7K,5%,1/20W,CHIP,CS24701JE04    I36 @T6G_MB_LIB.T6G(SCH_1):PAGE430
 R1116    2      B Q_RES_0201LF-4.7K,5%,1/20W,EMPTY,CS24701JE04    I40 @T6G_MB_LIB.T6G(SCH_1):PAGE430
 U6013 FF27  TEST1 PT5161LRS-PT5161LRS,SMLF,IC,AJ051610U03    I83 @T6G_MB_LIB.T6G(SCH_1):PAGE430

TEST1_RT_CPU1_P0 @T6G_MB_LIB.T6G(SCH_1):TEST1_RT_CPU1_P0
 U6014 FF27  TEST1 PT5161LRS-PT5161LRS,SMLF,IC,AJ051610U03     I1 @T6G_MB_LIB.T6G(SCH_1):PAGE401
  R720    2      B Q_RES_0201LF-4.7K,5%,1/20W,EMPTY,CS24701JE04    I26 @T6G_MB_LIB.T6G(SCH_1):PAGE401
  R723    1      A Q_RES_0201LF-4.7K,5%,1/20W,CHIP,CS24701JE04    I33 @T6G_MB_LIB.T6G(SCH_1):PAGE401

TEST1_RT_CPU1_P1 @T6G_MB_LIB.T6G(SCH_1):TEST1_RT_CPU1_P1
 U6015 FF27  TEST1 PT5161LRS-PT5161LRS,SMLF,IC,AJ051610U03    I47 @T6G_MB_LIB.T6G(SCH_1):PAGE392
  R787    1      A Q_RES_0201LF-4.7K,5%,1/20W,CHIP,CS24701JE04    I51 @T6G_MB_LIB.T6G(SCH_1):PAGE392
  R786    2      B Q_RES_0201LF-4.7K,5%,1/20W,EMPTY,CS24701JE04    I55 @T6G_MB_LIB.T6G(SCH_1):PAGE392

TEST1_RT_CPU1_P2 @T6G_MB_LIB.T6G(SCH_1):TEST1_RT_CPU1_P2
  R881    1      A Q_RES_0201LF-4.7K,5%,1/20W,CHIP,CS24701JE04    I43 @T6G_MB_LIB.T6G(SCH_1):PAGE451
  R880    2      B Q_RES_0201LF-4.7K,5%,1/20W,EMPTY,CS24701JE04    I48 @T6G_MB_LIB.T6G(SCH_1):PAGE451
 U6016 FF27  TEST1 PT5161LRS-PT5161LRS,SMLF,IC,AJ051610U03    I97 @T6G_MB_LIB.T6G(SCH_1):PAGE451

TEST1_RT_CPU1_P3 @T6G_MB_LIB.T6G(SCH_1):TEST1_RT_CPU1_P3
  R921    1      A Q_RES_0201LF-4.7K,5%,1/20W,CHIP,CS24701JE04    I50 @T6G_MB_LIB.T6G(SCH_1):PAGE462
  R920    2      B Q_RES_0201LF-4.7K,5%,1/20W,EMPTY,CS24701JE04    I54 @T6G_MB_LIB.T6G(SCH_1):PAGE462
 U6017 FF27  TEST1 PT5161LRS-PT5161LRS,SMLF,IC,AJ051610U03    I97 @T6G_MB_LIB.T6G(SCH_1):PAGE462

TEST2_RT_CPU0_P0 @T6G_MB_LIB.T6G(SCH_1):TEST2_RT_CPU0_P0
 U6010 FF30  TEST2 PT5161LRS-PT5161LRS,SMLF,IC,AJ051610U03    I53 @T6G_MB_LIB.T6G(SCH_1):PAGE385
  R995    1      A Q_RES_0201LF-4.7K,5%,1/20W,CHIP,CS24701JE04    I58 @T6G_MB_LIB.T6G(SCH_1):PAGE385
  R985    2      B Q_RES_0201LF-4.7K,5%,1/20W,EMPTY,CS24701JE04    I62 @T6G_MB_LIB.T6G(SCH_1):PAGE385

TEST2_RT_CPU0_P1 @T6G_MB_LIB.T6G(SCH_1):TEST2_RT_CPU0_P1
 R1035    1      A Q_RES_0201LF-4.7K,5%,1/20W,CHIP,CS24701JE04    I37 @T6G_MB_LIB.T6G(SCH_1):PAGE408
 R1034    2      B Q_RES_0201LF-4.7K,5%,1/20W,EMPTY,CS24701JE04    I41 @T6G_MB_LIB.T6G(SCH_1):PAGE408
 U6011 FF30  TEST2 PT5161LRS-PT5161LRS,SMLF,IC,AJ051610U03    I83 @T6G_MB_LIB.T6G(SCH_1):PAGE408

TEST2_RT_CPU0_P2 @T6G_MB_LIB.T6G(SCH_1):TEST2_RT_CPU0_P2
 R1078    1      A Q_RES_0201LF-4.7K,5%,1/20W,CHIP,CS24701JE04    I37 @T6G_MB_LIB.T6G(SCH_1):PAGE419
 R1077    2      B Q_RES_0201LF-4.7K,5%,1/20W,EMPTY,CS24701JE04    I41 @T6G_MB_LIB.T6G(SCH_1):PAGE419
 U6012 FF30  TEST2 PT5161LRS-PT5161LRS,SMLF,IC,AJ051610U03    I83 @T6G_MB_LIB.T6G(SCH_1):PAGE419

TEST2_RT_CPU0_P3 @T6G_MB_LIB.T6G(SCH_1):TEST2_RT_CPU0_P3
 R1120    1      A Q_RES_0201LF-4.7K,5%,1/20W,CHIP,CS24701JE04    I37 @T6G_MB_LIB.T6G(SCH_1):PAGE430
 R1119    2      B Q_RES_0201LF-4.7K,5%,1/20W,EMPTY,CS24701JE04    I41 @T6G_MB_LIB.T6G(SCH_1):PAGE430
 U6013 FF30  TEST2 PT5161LRS-PT5161LRS,SMLF,IC,AJ051610U03    I83 @T6G_MB_LIB.T6G(SCH_1):PAGE430

TEST2_RT_CPU1_P0 @T6G_MB_LIB.T6G(SCH_1):TEST2_RT_CPU1_P0
 U6014 FF30  TEST2 PT5161LRS-PT5161LRS,SMLF,IC,AJ051610U03     I1 @T6G_MB_LIB.T6G(SCH_1):PAGE401
  R724    2      B Q_RES_0201LF-4.7K,5%,1/20W,EMPTY,CS24701JE04    I25 @T6G_MB_LIB.T6G(SCH_1):PAGE401
  R725    1      A Q_RES_0201LF-4.7K,5%,1/20W,CHIP,CS24701JE04    I32 @T6G_MB_LIB.T6G(SCH_1):PAGE401

TEST2_RT_CPU1_P1 @T6G_MB_LIB.T6G(SCH_1):TEST2_RT_CPU1_P1
 U6015 FF30  TEST2 PT5161LRS-PT5161LRS,SMLF,IC,AJ051610U03    I47 @T6G_MB_LIB.T6G(SCH_1):PAGE392
  R791    1      A Q_RES_0201LF-4.7K,5%,1/20W,CHIP,CS24701JE04    I52 @T6G_MB_LIB.T6G(SCH_1):PAGE392
  R788    2      B Q_RES_0201LF-4.7K,5%,1/20W,EMPTY,CS24701JE04    I56 @T6G_MB_LIB.T6G(SCH_1):PAGE392

TEST2_RT_CPU1_P2 @T6G_MB_LIB.T6G(SCH_1):TEST2_RT_CPU1_P2
  R883    1      A Q_RES_0201LF-4.7K,5%,1/20W,CHIP,CS24701JE04    I45 @T6G_MB_LIB.T6G(SCH_1):PAGE451
  R882    2      B Q_RES_0201LF-4.7K,5%,1/20W,EMPTY,CS24701JE04    I49 @T6G_MB_LIB.T6G(SCH_1):PAGE451
 U6016 FF30  TEST2 PT5161LRS-PT5161LRS,SMLF,IC,AJ051610U03    I97 @T6G_MB_LIB.T6G(SCH_1):PAGE451

TEST2_RT_CPU1_P3 @T6G_MB_LIB.T6G(SCH_1):TEST2_RT_CPU1_P3
  R923    1      A Q_RES_0201LF-4.7K,5%,1/20W,CHIP,CS24701JE04    I51 @T6G_MB_LIB.T6G(SCH_1):PAGE462
  R922    2      B Q_RES_0201LF-4.7K,5%,1/20W,EMPTY,CS24701JE04    I55 @T6G_MB_LIB.T6G(SCH_1):PAGE462
 U6017 FF30  TEST2 PT5161LRS-PT5161LRS,SMLF,IC,AJ051610U03    I97 @T6G_MB_LIB.T6G(SCH_1):PAGE462

TP_ADC128_2_INT @T6G_MB_LIB.T6G(SCH_1):TP_ADC128_2_INT
   U51    6   INT# ADC128D818CIMTXNOPB-ADC128D818CIMTX/NOPB,SMLF,IC,AA   I142 @T6G_MB_LIB.T6G(SCH_1):PAGE263

TP_ADC128_INT @T6G_MB_LIB.T6G(SCH_1):TP_ADC128_INT
  U269    6   INT# ADC128D818CIMTXNOPB-ADC128D818CIMTX/NOPB,SMLF,IC,AA   I142 @T6G_MB_LIB.T6G(SCH_1):PAGE369

TP_BEEP_LED @T6G_MB_LIB.T6G(SCH_1):TP_BEEP_LED
   J41  B69 RFU1_NC_B69 SCONN168_ME1016810202011-SCONN168_ME1016810202011,A   I176 @T6G_MB_LIB.T6G(SCH_1):PAGE348

TP_CHASI @T6G_MB_LIB.T6G(SCH_1):TP_CHASI
   J41  A54 PERP11 SCONN168_ME1016810202011-SCONN168_ME1016810202011,A   I176 @T6G_MB_LIB.T6G(SCH_1):PAGE348
 R4809    1      A Q_RES_0402LF-0,5%,1/16W,CHIP,CS00002JB13   I220 @T6G_MB_LIB.T6G(SCH_1):PAGE348

TP_CLK_100M_E1S_0_DN @T6G_MB_LIB.T6G(SCH_1):TP_CLK_100M_E1S_0_DN
   J90  A14 REFCLK_N1 SCONN56_123276793-SCONN56_1-2327679-3,SMLF,IO,DFHSA    I90 @T6G_MB_LIB.T6G(SCH_1):PAGE297

TP_CLK_100M_E1S_0_DP @T6G_MB_LIB.T6G(SCH_1):TP_CLK_100M_E1S_0_DP
   J90  A15 REFCLK_P1 SCONN56_123276793-SCONN56_1-2327679-3,SMLF,IO,DFHSA    I90 @T6G_MB_LIB.T6G(SCH_1):PAGE297

TP_CLK_50M_Y3 @T6G_MB_LIB.T6G(SCH_1):TP_CLK_50M_Y3
   U90    8     Y3 PI6CV304LE-PI6CV304LE,SMLF,IC,AL000304K01    I16 @T6G_MB_LIB.T6G(SCH_1):PAGE337

TP_CPU0_TEST41_IDO @T6G_MB_LIB.T6G(SCH_1):TP_CPU0_TEST41_IDO
   U25  W31 TEST41_IOD GENOA_SP5-SOCKET6096_13568-001,SMLF,IO,DGA^6000030   I227 @T6G_MB_LIB.T6G(SCH_1):PAGE27

TP_CPU0_TEST47_CCD0 @T6G_MB_LIB.T6G(SCH_1):TP_CPU0_TEST47_CCD0
   U25  B60 TEST47_CCD0 GENOA_SP5-SOCKET6096_13568-001,SMLF,IO,DGA^6000030   I227 @T6G_MB_LIB.T6G(SCH_1):PAGE27

TP_CPU0_TEST47_CCD1 @T6G_MB_LIB.T6G(SCH_1):TP_CPU0_TEST47_CCD1
   U25 CJ24 TEST47_CCD1 GENOA_SP5-SOCKET6096_13568-001,SMLF,IO,DGA^6000030   I227 @T6G_MB_LIB.T6G(SCH_1):PAGE27

TP_CPU0_TEST47_CCD2 @T6G_MB_LIB.T6G(SCH_1):TP_CPU0_TEST47_CCD2
   U25 CK46 TEST47_CCD2 GENOA_SP5-SOCKET6096_13568-001,SMLF,IO,DGA^6000030   I227 @T6G_MB_LIB.T6G(SCH_1):PAGE27

TP_CPU0_TEST47_CCD3 @T6G_MB_LIB.T6G(SCH_1):TP_CPU0_TEST47_CCD3
   U25  E32 TEST47_CCD3 GENOA_SP5-SOCKET6096_13568-001,SMLF,IO,DGA^6000030   I227 @T6G_MB_LIB.T6G(SCH_1):PAGE27

TP_CPU0_TEST47_IOD0 @T6G_MB_LIB.T6G(SCH_1):TP_CPU0_TEST47_IOD0
   U25  B58 TEST47_IOD0 GENOA_SP5-SOCKET6096_13568-001,SMLF,IO,DGA^6000030   I227 @T6G_MB_LIB.T6G(SCH_1):PAGE27

TP_CPU0_TEST47_IOD1 @T6G_MB_LIB.T6G(SCH_1):TP_CPU0_TEST47_IOD1
   U25   D7 TEST47_IOD1 GENOA_SP5-SOCKET6096_13568-001,SMLF,IO,DGA^6000030   I227 @T6G_MB_LIB.T6G(SCH_1):PAGE27

TP_CPU0_TEST4_CCD0 @T6G_MB_LIB.T6G(SCH_1):TP_CPU0_TEST4_CCD0
   U25 AA50 TEST4_CCD0 GENOA_SP5-SOCKET6096_13568-001,SMLF,IO,DGA^6000030   I227 @T6G_MB_LIB.T6G(SCH_1):PAGE27

TP_CPU0_TEST4_CCD1 @T6G_MB_LIB.T6G(SCH_1):TP_CPU0_TEST4_CCD1
   U25 CJ28 TEST4_CCD1 GENOA_SP5-SOCKET6096_13568-001,SMLF,IO,DGA^6000030   I227 @T6G_MB_LIB.T6G(SCH_1):PAGE27

TP_CPU0_TEST4_CCD10 @T6G_MB_LIB.T6G(SCH_1):TP_CPU0_TEST4_CCD10
   U25 CJ47 TEST4_CCD10 GENOA_SP5-SOCKET6096_13568-001,SMLF,IO,DGA^6000030   I227 @T6G_MB_LIB.T6G(SCH_1):PAGE27

TP_CPU0_TEST4_CCD11 @T6G_MB_LIB.T6G(SCH_1):TP_CPU0_TEST4_CCD11
   U25 AA28 TEST4_CCD11 GENOA_SP5-SOCKET6096_13568-001,SMLF,IO,DGA^6000030   I227 @T6G_MB_LIB.T6G(SCH_1):PAGE27

TP_CPU0_TEST4_CCD2 @T6G_MB_LIB.T6G(SCH_1):TP_CPU0_TEST4_CCD2
   U25 CJ48 TEST4_CCD2 GENOA_SP5-SOCKET6096_13568-001,SMLF,IO,DGA^6000030   I227 @T6G_MB_LIB.T6G(SCH_1):PAGE27

TP_CPU0_TEST4_CCD3 @T6G_MB_LIB.T6G(SCH_1):TP_CPU0_TEST4_CCD3
   U25 AA30 TEST4_CCD3 GENOA_SP5-SOCKET6096_13568-001,SMLF,IO,DGA^6000030   I227 @T6G_MB_LIB.T6G(SCH_1):PAGE27

TP_CPU0_TEST4_CCD4 @T6G_MB_LIB.T6G(SCH_1):TP_CPU0_TEST4_CCD4
   U25 AA52 TEST4_CCD4 GENOA_SP5-SOCKET6096_13568-001,SMLF,IO,DGA^6000030   I227 @T6G_MB_LIB.T6G(SCH_1):PAGE27

TP_CPU0_TEST4_CCD5 @T6G_MB_LIB.T6G(SCH_1):TP_CPU0_TEST4_CCD5
   U25 CJ26 TEST4_CCD5 GENOA_SP5-SOCKET6096_13568-001,SMLF,IO,DGA^6000030   I227 @T6G_MB_LIB.T6G(SCH_1):PAGE27

TP_CPU0_TEST4_CCD6 @T6G_MB_LIB.T6G(SCH_1):TP_CPU0_TEST4_CCD6
   U25 CJ50 TEST4_CCD6 GENOA_SP5-SOCKET6096_13568-001,SMLF,IO,DGA^6000030   I227 @T6G_MB_LIB.T6G(SCH_1):PAGE27

TP_CPU0_TEST4_CCD7 @T6G_MB_LIB.T6G(SCH_1):TP_CPU0_TEST4_CCD7
   U25 AA27 TEST4_CCD7 GENOA_SP5-SOCKET6096_13568-001,SMLF,IO,DGA^6000030   I227 @T6G_MB_LIB.T6G(SCH_1):PAGE27

TP_CPU0_TEST4_CCD8 @T6G_MB_LIB.T6G(SCH_1):TP_CPU0_TEST4_CCD8
   U25 AA48 TEST4_CCD8 GENOA_SP5-SOCKET6096_13568-001,SMLF,IO,DGA^6000030   I227 @T6G_MB_LIB.T6G(SCH_1):PAGE27

TP_CPU0_TEST4_CCD9 @T6G_MB_LIB.T6G(SCH_1):TP_CPU0_TEST4_CCD9
   U25 CK30 TEST4_CCD9 GENOA_SP5-SOCKET6096_13568-001,SMLF,IO,DGA^6000030   I227 @T6G_MB_LIB.T6G(SCH_1):PAGE27

TP_CPU0_TEST4_IOD @T6G_MB_LIB.T6G(SCH_1):TP_CPU0_TEST4_IOD
   U25 AA25 TEST4_IOD GENOA_SP5-SOCKET6096_13568-001,SMLF,IO,DGA^6000030   I227 @T6G_MB_LIB.T6G(SCH_1):PAGE27

TP_CPU0_TEST50_IOD @T6G_MB_LIB.T6G(SCH_1):TP_CPU0_TEST50_IOD
   U25  B61 TEST50_IOD GENOA_SP5-SOCKET6096_13568-001,SMLF,IO,DGA^6000030   I227 @T6G_MB_LIB.T6G(SCH_1):PAGE27

TP_CPU0_TEST5_CCD0 @T6G_MB_LIB.T6G(SCH_1):TP_CPU0_TEST5_CCD0
   U25 AA51 TEST5_CCD0 GENOA_SP5-SOCKET6096_13568-001,SMLF,IO,DGA^6000030   I227 @T6G_MB_LIB.T6G(SCH_1):PAGE27

TP_CPU0_TEST5_CCD1 @T6G_MB_LIB.T6G(SCH_1):TP_CPU0_TEST5_CCD1
   U25 CJ27 TEST5_CCD1 GENOA_SP5-SOCKET6096_13568-001,SMLF,IO,DGA^6000030   I227 @T6G_MB_LIB.T6G(SCH_1):PAGE27

TP_CPU0_TEST5_CCD10 @T6G_MB_LIB.T6G(SCH_1):TP_CPU0_TEST5_CCD10
   U25 CK47 TEST5_CCD10 GENOA_SP5-SOCKET6096_13568-001,SMLF,IO,DGA^6000030   I227 @T6G_MB_LIB.T6G(SCH_1):PAGE27

TP_CPU0_TEST5_CCD11 @T6G_MB_LIB.T6G(SCH_1):TP_CPU0_TEST5_CCD11
   U25  Y29 TEST5_CCD11 GENOA_SP5-SOCKET6096_13568-001,SMLF,IO,DGA^6000030   I227 @T6G_MB_LIB.T6G(SCH_1):PAGE27

TP_CPU0_TEST5_CCD2 @T6G_MB_LIB.T6G(SCH_1):TP_CPU0_TEST5_CCD2
   U25 CJ49 TEST5_CCD2 GENOA_SP5-SOCKET6096_13568-001,SMLF,IO,DGA^6000030   I227 @T6G_MB_LIB.T6G(SCH_1):PAGE27

TP_CPU0_TEST5_CCD3 @T6G_MB_LIB.T6G(SCH_1):TP_CPU0_TEST5_CCD3
   U25  Y30 TEST5_CCD3 GENOA_SP5-SOCKET6096_13568-001,SMLF,IO,DGA^6000030   I227 @T6G_MB_LIB.T6G(SCH_1):PAGE27

TP_CPU0_TEST5_CCD4 @T6G_MB_LIB.T6G(SCH_1):TP_CPU0_TEST5_CCD4
   U25 AA53 TEST5_CCD4 GENOA_SP5-SOCKET6096_13568-001,SMLF,IO,DGA^6000030   I227 @T6G_MB_LIB.T6G(SCH_1):PAGE27

TP_CPU0_TEST5_CCD5 @T6G_MB_LIB.T6G(SCH_1):TP_CPU0_TEST5_CCD5
   U25 CJ25 TEST5_CCD5 GENOA_SP5-SOCKET6096_13568-001,SMLF,IO,DGA^6000030   I227 @T6G_MB_LIB.T6G(SCH_1):PAGE27

TP_CPU0_TEST5_CCD6 @T6G_MB_LIB.T6G(SCH_1):TP_CPU0_TEST5_CCD6
   U25 CJ51 TEST5_CCD6 GENOA_SP5-SOCKET6096_13568-001,SMLF,IO,DGA^6000030   I227 @T6G_MB_LIB.T6G(SCH_1):PAGE27

TP_CPU0_TEST5_CCD7 @T6G_MB_LIB.T6G(SCH_1):TP_CPU0_TEST5_CCD7
   U25 AA26 TEST5_CCD7 GENOA_SP5-SOCKET6096_13568-001,SMLF,IO,DGA^6000030   I227 @T6G_MB_LIB.T6G(SCH_1):PAGE27

TP_CPU0_TEST5_CCD8 @T6G_MB_LIB.T6G(SCH_1):TP_CPU0_TEST5_CCD8
   U25  Y47 TEST5_CCD8 GENOA_SP5-SOCKET6096_13568-001,SMLF,IO,DGA^6000030   I227 @T6G_MB_LIB.T6G(SCH_1):PAGE27

TP_CPU0_TEST5_CCD9 @T6G_MB_LIB.T6G(SCH_1):TP_CPU0_TEST5_CCD9
   U25 CK29 TEST5_CCD9 GENOA_SP5-SOCKET6096_13568-001,SMLF,IO,DGA^6000030   I227 @T6G_MB_LIB.T6G(SCH_1):PAGE27

TP_CPU0_TEST5_IOD @T6G_MB_LIB.T6G(SCH_1):TP_CPU0_TEST5_IOD
   U25 AA24 TEST5_IOD GENOA_SP5-SOCKET6096_13568-001,SMLF,IO,DGA^6000030   I227 @T6G_MB_LIB.T6G(SCH_1):PAGE27

TP_CPU0_TEST6_CCD0 @T6G_MB_LIB.T6G(SCH_1):TP_CPU0_TEST6_CCD0
   U25 AA46 TEST6_CCD0 GENOA_SP5-SOCKET6096_13568-001,SMLF,IO,DGA^6000030   I227 @T6G_MB_LIB.T6G(SCH_1):PAGE27

TP_CPU0_TEST6_CCD1 @T6G_MB_LIB.T6G(SCH_1):TP_CPU0_TEST6_CCD1
   U25 CJ30 TEST6_CCD1 GENOA_SP5-SOCKET6096_13568-001,SMLF,IO,DGA^6000030   I227 @T6G_MB_LIB.T6G(SCH_1):PAGE27

TP_CPU0_TEST6_CCD2 @T6G_MB_LIB.T6G(SCH_1):TP_CPU0_TEST6_CCD2
   U25 CJ46 TEST6_CCD2 GENOA_SP5-SOCKET6096_13568-001,SMLF,IO,DGA^6000030   I227 @T6G_MB_LIB.T6G(SCH_1):PAGE27

TP_CPU0_TEST6_CCD3 @T6G_MB_LIB.T6G(SCH_1):TP_CPU0_TEST6_CCD3
   U25  Y46 TEST6_CCD3 GENOA_SP5-SOCKET6096_13568-001,SMLF,IO,DGA^6000030   I227 @T6G_MB_LIB.T6G(SCH_1):PAGE27

TP_CPU0_TEST6_IOD @T6G_MB_LIB.T6G(SCH_1):TP_CPU0_TEST6_IOD
   U25 AA49 TEST6_IOD GENOA_SP5-SOCKET6096_13568-001,SMLF,IO,DGA^6000030   I227 @T6G_MB_LIB.T6G(SCH_1):PAGE27

TP_CPU0_TEST6_X3D0 @T6G_MB_LIB.T6G(SCH_1):TP_CPU0_TEST6_X3D0
   U25 AA47 TEST6_X3D0 GENOA_SP5-SOCKET6096_13568-001,SMLF,IO,DGA^6000030   I227 @T6G_MB_LIB.T6G(SCH_1):PAGE27

TP_CPU0_TEST6_X3D1 @T6G_MB_LIB.T6G(SCH_1):TP_CPU0_TEST6_X3D1
   U25 CJ29 TEST6_X3D1 GENOA_SP5-SOCKET6096_13568-001,SMLF,IO,DGA^6000030   I227 @T6G_MB_LIB.T6G(SCH_1):PAGE27

TP_CPU0_TEST6_X3D2 @T6G_MB_LIB.T6G(SCH_1):TP_CPU0_TEST6_X3D2
   U25 AA29 TEST6_X3D2 GENOA_SP5-SOCKET6096_13568-001,SMLF,IO,DGA^6000030   I227 @T6G_MB_LIB.T6G(SCH_1):PAGE27

TP_CPU0_TEST6_X3D3 @T6G_MB_LIB.T6G(SCH_1):TP_CPU0_TEST6_X3D3
   U25 CJ52 TEST6_X3D3 GENOA_SP5-SOCKET6096_13568-001,SMLF,IO,DGA^6000030   I227 @T6G_MB_LIB.T6G(SCH_1):PAGE27

TP_CPU0_TEST6_X3D4 @T6G_MB_LIB.T6G(SCH_1):TP_CPU0_TEST6_X3D4
   U25 AA23 TEST6_X3D4 GENOA_SP5-SOCKET6096_13568-001,SMLF,IO,DGA^6000030   I227 @T6G_MB_LIB.T6G(SCH_1):PAGE27

TP_CPU0_TEST6_X3D5 @T6G_MB_LIB.T6G(SCH_1):TP_CPU0_TEST6_X3D5
   U25 CJ53 TEST6_X3D5 GENOA_SP5-SOCKET6096_13568-001,SMLF,IO,DGA^6000030   I227 @T6G_MB_LIB.T6G(SCH_1):PAGE27

TP_CPU0_UART0_INTR @T6G_MB_LIB.T6G(SCH_1):TP_CPU0_UART0_INTR
   U25 DG34 UART0_INTR||AGPIO139 GENOA_SP5-SOCKET6096_13568-001,SMLF,IO,DGA^6000030   I227 @T6G_MB_LIB.T6G(SCH_1):PAGE27

TP_CPU0_USB_HUB1_SUSPEND @T6G_MB_LIB.T6G(SCH_1):TP_CPU0_USB_HUB1_SUSPEND
 U6001   20 SUSPEND CYUSB330468LTXI-CYUSB3304-68LTXI,SMLF,IC,AJ0330400A     I1 @T6G_MB_LIB.T6G(SCH_1):PAGE153

TP_CPU1_TEST41_IOD @T6G_MB_LIB.T6G(SCH_1):TP_CPU1_TEST41_IOD
   U26  W31 TEST41_IOD GENOA_SP5-SOCKET6096_13568-001,SMLF,IO,DGA^6000030   I190 @T6G_MB_LIB.T6G(SCH_1):PAGE54

TP_CPU1_TEST47_CCD0 @T6G_MB_LIB.T6G(SCH_1):TP_CPU1_TEST47_CCD0
   U26  B60 TEST47_CCD0 GENOA_SP5-SOCKET6096_13568-001,SMLF,IO,DGA^6000030   I190 @T6G_MB_LIB.T6G(SCH_1):PAGE54

TP_CPU1_TEST47_CCD1 @T6G_MB_LIB.T6G(SCH_1):TP_CPU1_TEST47_CCD1
   U26 CJ24 TEST47_CCD1 GENOA_SP5-SOCKET6096_13568-001,SMLF,IO,DGA^6000030   I190 @T6G_MB_LIB.T6G(SCH_1):PAGE54

TP_CPU1_TEST47_CCD2 @T6G_MB_LIB.T6G(SCH_1):TP_CPU1_TEST47_CCD2
   U26 CK46 TEST47_CCD2 GENOA_SP5-SOCKET6096_13568-001,SMLF,IO,DGA^6000030   I190 @T6G_MB_LIB.T6G(SCH_1):PAGE54

TP_CPU1_TEST47_CCD3 @T6G_MB_LIB.T6G(SCH_1):TP_CPU1_TEST47_CCD3
   U26  E32 TEST47_CCD3 GENOA_SP5-SOCKET6096_13568-001,SMLF,IO,DGA^6000030   I190 @T6G_MB_LIB.T6G(SCH_1):PAGE54

TP_CPU1_TEST47_IOD0 @T6G_MB_LIB.T6G(SCH_1):TP_CPU1_TEST47_IOD0
   U26  B58 TEST47_IOD0 GENOA_SP5-SOCKET6096_13568-001,SMLF,IO,DGA^6000030   I190 @T6G_MB_LIB.T6G(SCH_1):PAGE54

TP_CPU1_TEST47_IOD1 @T6G_MB_LIB.T6G(SCH_1):TP_CPU1_TEST47_IOD1
   U26   D7 TEST47_IOD1 GENOA_SP5-SOCKET6096_13568-001,SMLF,IO,DGA^6000030   I190 @T6G_MB_LIB.T6G(SCH_1):PAGE54

TP_CPU1_TEST4_CCD0 @T6G_MB_LIB.T6G(SCH_1):TP_CPU1_TEST4_CCD0
   U26 AA50 TEST4_CCD0 GENOA_SP5-SOCKET6096_13568-001,SMLF,IO,DGA^6000030   I190 @T6G_MB_LIB.T6G(SCH_1):PAGE54

TP_CPU1_TEST4_CCD1 @T6G_MB_LIB.T6G(SCH_1):TP_CPU1_TEST4_CCD1
   U26 CJ28 TEST4_CCD1 GENOA_SP5-SOCKET6096_13568-001,SMLF,IO,DGA^6000030   I190 @T6G_MB_LIB.T6G(SCH_1):PAGE54

TP_CPU1_TEST4_CCD10 @T6G_MB_LIB.T6G(SCH_1):TP_CPU1_TEST4_CCD10
   U26 CJ47 TEST4_CCD10 GENOA_SP5-SOCKET6096_13568-001,SMLF,IO,DGA^6000030   I190 @T6G_MB_LIB.T6G(SCH_1):PAGE54

TP_CPU1_TEST4_CCD11 @T6G_MB_LIB.T6G(SCH_1):TP_CPU1_TEST4_CCD11
   U26 AA28 TEST4_CCD11 GENOA_SP5-SOCKET6096_13568-001,SMLF,IO,DGA^6000030   I190 @T6G_MB_LIB.T6G(SCH_1):PAGE54

TP_CPU1_TEST4_CCD2 @T6G_MB_LIB.T6G(SCH_1):TP_CPU1_TEST4_CCD2
   U26 CJ48 TEST4_CCD2 GENOA_SP5-SOCKET6096_13568-001,SMLF,IO,DGA^6000030   I190 @T6G_MB_LIB.T6G(SCH_1):PAGE54

TP_CPU1_TEST4_CCD3 @T6G_MB_LIB.T6G(SCH_1):TP_CPU1_TEST4_CCD3
   U26 AA30 TEST4_CCD3 GENOA_SP5-SOCKET6096_13568-001,SMLF,IO,DGA^6000030   I190 @T6G_MB_LIB.T6G(SCH_1):PAGE54

TP_CPU1_TEST4_CCD4 @T6G_MB_LIB.T6G(SCH_1):TP_CPU1_TEST4_CCD4
   U26 AA52 TEST4_CCD4 GENOA_SP5-SOCKET6096_13568-001,SMLF,IO,DGA^6000030   I190 @T6G_MB_LIB.T6G(SCH_1):PAGE54

TP_CPU1_TEST4_CCD5 @T6G_MB_LIB.T6G(SCH_1):TP_CPU1_TEST4_CCD5
   U26 CJ26 TEST4_CCD5 GENOA_SP5-SOCKET6096_13568-001,SMLF,IO,DGA^6000030   I190 @T6G_MB_LIB.T6G(SCH_1):PAGE54

TP_CPU1_TEST4_CCD6 @T6G_MB_LIB.T6G(SCH_1):TP_CPU1_TEST4_CCD6
   U26 CJ50 TEST4_CCD6 GENOA_SP5-SOCKET6096_13568-001,SMLF,IO,DGA^6000030   I190 @T6G_MB_LIB.T6G(SCH_1):PAGE54

TP_CPU1_TEST4_CCD7 @T6G_MB_LIB.T6G(SCH_1):TP_CPU1_TEST4_CCD7
   U26 AA27 TEST4_CCD7 GENOA_SP5-SOCKET6096_13568-001,SMLF,IO,DGA^6000030   I190 @T6G_MB_LIB.T6G(SCH_1):PAGE54

TP_CPU1_TEST4_CCD8 @T6G_MB_LIB.T6G(SCH_1):TP_CPU1_TEST4_CCD8
   U26 AA48 TEST4_CCD8 GENOA_SP5-SOCKET6096_13568-001,SMLF,IO,DGA^6000030   I190 @T6G_MB_LIB.T6G(SCH_1):PAGE54

TP_CPU1_TEST4_CCD9 @T6G_MB_LIB.T6G(SCH_1):TP_CPU1_TEST4_CCD9
   U26 CK30 TEST4_CCD9 GENOA_SP5-SOCKET6096_13568-001,SMLF,IO,DGA^6000030   I190 @T6G_MB_LIB.T6G(SCH_1):PAGE54

TP_CPU1_TEST4_IOD @T6G_MB_LIB.T6G(SCH_1):TP_CPU1_TEST4_IOD
   U26 AA25 TEST4_IOD GENOA_SP5-SOCKET6096_13568-001,SMLF,IO,DGA^6000030   I190 @T6G_MB_LIB.T6G(SCH_1):PAGE54

TP_CPU1_TEST50_IOD @T6G_MB_LIB.T6G(SCH_1):TP_CPU1_TEST50_IOD
   U26  B61 TEST50_IOD GENOA_SP5-SOCKET6096_13568-001,SMLF,IO,DGA^6000030   I190 @T6G_MB_LIB.T6G(SCH_1):PAGE54

TP_CPU1_TEST5_CCD0 @T6G_MB_LIB.T6G(SCH_1):TP_CPU1_TEST5_CCD0
   U26 AA51 TEST5_CCD0 GENOA_SP5-SOCKET6096_13568-001,SMLF,IO,DGA^6000030   I190 @T6G_MB_LIB.T6G(SCH_1):PAGE54

TP_CPU1_TEST5_CCD1 @T6G_MB_LIB.T6G(SCH_1):TP_CPU1_TEST5_CCD1
   U26 CJ27 TEST5_CCD1 GENOA_SP5-SOCKET6096_13568-001,SMLF,IO,DGA^6000030   I190 @T6G_MB_LIB.T6G(SCH_1):PAGE54

TP_CPU1_TEST5_CCD10 @T6G_MB_LIB.T6G(SCH_1):TP_CPU1_TEST5_CCD10
   U26 CK47 TEST5_CCD10 GENOA_SP5-SOCKET6096_13568-001,SMLF,IO,DGA^6000030   I190 @T6G_MB_LIB.T6G(SCH_1):PAGE54

TP_CPU1_TEST5_CCD11 @T6G_MB_LIB.T6G(SCH_1):TP_CPU1_TEST5_CCD11
   U26  Y29 TEST5_CCD11 GENOA_SP5-SOCKET6096_13568-001,SMLF,IO,DGA^6000030   I190 @T6G_MB_LIB.T6G(SCH_1):PAGE54

TP_CPU1_TEST5_CCD2 @T6G_MB_LIB.T6G(SCH_1):TP_CPU1_TEST5_CCD2
   U26 CJ49 TEST5_CCD2 GENOA_SP5-SOCKET6096_13568-001,SMLF,IO,DGA^6000030   I190 @T6G_MB_LIB.T6G(SCH_1):PAGE54

TP_CPU1_TEST5_CCD3 @T6G_MB_LIB.T6G(SCH_1):TP_CPU1_TEST5_CCD3
   U26  Y30 TEST5_CCD3 GENOA_SP5-SOCKET6096_13568-001,SMLF,IO,DGA^6000030   I190 @T6G_MB_LIB.T6G(SCH_1):PAGE54

TP_CPU1_TEST5_CCD4 @T6G_MB_LIB.T6G(SCH_1):TP_CPU1_TEST5_CCD4
   U26 AA53 TEST5_CCD4 GENOA_SP5-SOCKET6096_13568-001,SMLF,IO,DGA^6000030   I190 @T6G_MB_LIB.T6G(SCH_1):PAGE54

TP_CPU1_TEST5_CCD5 @T6G_MB_LIB.T6G(SCH_1):TP_CPU1_TEST5_CCD5
   U26 CJ25 TEST5_CCD5 GENOA_SP5-SOCKET6096_13568-001,SMLF,IO,DGA^6000030   I190 @T6G_MB_LIB.T6G(SCH_1):PAGE54

TP_CPU1_TEST5_CCD6 @T6G_MB_LIB.T6G(SCH_1):TP_CPU1_TEST5_CCD6
   U26 CJ51 TEST5_CCD6 GENOA_SP5-SOCKET6096_13568-001,SMLF,IO,DGA^6000030   I190 @T6G_MB_LIB.T6G(SCH_1):PAGE54

TP_CPU1_TEST5_CCD7 @T6G_MB_LIB.T6G(SCH_1):TP_CPU1_TEST5_CCD7
   U26 AA26 TEST5_CCD7 GENOA_SP5-SOCKET6096_13568-001,SMLF,IO,DGA^6000030   I190 @T6G_MB_LIB.T6G(SCH_1):PAGE54

TP_CPU1_TEST5_CCD8 @T6G_MB_LIB.T6G(SCH_1):TP_CPU1_TEST5_CCD8
   U26  Y47 TEST5_CCD8 GENOA_SP5-SOCKET6096_13568-001,SMLF,IO,DGA^6000030   I190 @T6G_MB_LIB.T6G(SCH_1):PAGE54

TP_CPU1_TEST5_CCD9 @T6G_MB_LIB.T6G(SCH_1):TP_CPU1_TEST5_CCD9
   U26 CK29 TEST5_CCD9 GENOA_SP5-SOCKET6096_13568-001,SMLF,IO,DGA^6000030   I190 @T6G_MB_LIB.T6G(SCH_1):PAGE54

TP_CPU1_TEST5_IOD @T6G_MB_LIB.T6G(SCH_1):TP_CPU1_TEST5_IOD
   U26 AA24 TEST5_IOD GENOA_SP5-SOCKET6096_13568-001,SMLF,IO,DGA^6000030   I190 @T6G_MB_LIB.T6G(SCH_1):PAGE54

TP_CPU1_TEST6_CCD0 @T6G_MB_LIB.T6G(SCH_1):TP_CPU1_TEST6_CCD0
   U26 AA46 TEST6_CCD0 GENOA_SP5-SOCKET6096_13568-001,SMLF,IO,DGA^6000030   I190 @T6G_MB_LIB.T6G(SCH_1):PAGE54

TP_CPU1_TEST6_CCD1 @T6G_MB_LIB.T6G(SCH_1):TP_CPU1_TEST6_CCD1
   U26 CJ30 TEST6_CCD1 GENOA_SP5-SOCKET6096_13568-001,SMLF,IO,DGA^6000030   I190 @T6G_MB_LIB.T6G(SCH_1):PAGE54

TP_CPU1_TEST6_CCD2 @T6G_MB_LIB.T6G(SCH_1):TP_CPU1_TEST6_CCD2
   U26 CJ46 TEST6_CCD2 GENOA_SP5-SOCKET6096_13568-001,SMLF,IO,DGA^6000030   I190 @T6G_MB_LIB.T6G(SCH_1):PAGE54

TP_CPU1_TEST6_CCD3 @T6G_MB_LIB.T6G(SCH_1):TP_CPU1_TEST6_CCD3
   U26  Y46 TEST6_CCD3 GENOA_SP5-SOCKET6096_13568-001,SMLF,IO,DGA^6000030   I190 @T6G_MB_LIB.T6G(SCH_1):PAGE54

TP_CPU1_TEST6_IOD @T6G_MB_LIB.T6G(SCH_1):TP_CPU1_TEST6_IOD
   U26 AA49 TEST6_IOD GENOA_SP5-SOCKET6096_13568-001,SMLF,IO,DGA^6000030   I190 @T6G_MB_LIB.T6G(SCH_1):PAGE54

TP_CPU1_TEST6_X3D0 @T6G_MB_LIB.T6G(SCH_1):TP_CPU1_TEST6_X3D0
   U26 AA47 TEST6_X3D0 GENOA_SP5-SOCKET6096_13568-001,SMLF,IO,DGA^6000030   I190 @T6G_MB_LIB.T6G(SCH_1):PAGE54

TP_CPU1_TEST6_X3D1 @T6G_MB_LIB.T6G(SCH_1):TP_CPU1_TEST6_X3D1
   U26 CJ29 TEST6_X3D1 GENOA_SP5-SOCKET6096_13568-001,SMLF,IO,DGA^6000030   I190 @T6G_MB_LIB.T6G(SCH_1):PAGE54

TP_CPU1_TEST6_X3D2 @T6G_MB_LIB.T6G(SCH_1):TP_CPU1_TEST6_X3D2
   U26 AA29 TEST6_X3D2 GENOA_SP5-SOCKET6096_13568-001,SMLF,IO,DGA^6000030   I190 @T6G_MB_LIB.T6G(SCH_1):PAGE54

TP_CPU1_TEST6_X3D3 @T6G_MB_LIB.T6G(SCH_1):TP_CPU1_TEST6_X3D3
   U26 CJ52 TEST6_X3D3 GENOA_SP5-SOCKET6096_13568-001,SMLF,IO,DGA^6000030   I190 @T6G_MB_LIB.T6G(SCH_1):PAGE54

TP_CPU1_TEST6_X3D4 @T6G_MB_LIB.T6G(SCH_1):TP_CPU1_TEST6_X3D4
   U26 AA23 TEST6_X3D4 GENOA_SP5-SOCKET6096_13568-001,SMLF,IO,DGA^6000030   I190 @T6G_MB_LIB.T6G(SCH_1):PAGE54

TP_CPU1_TEST6_X3D5 @T6G_MB_LIB.T6G(SCH_1):TP_CPU1_TEST6_X3D5
   U26 CJ53 TEST6_X3D5 GENOA_SP5-SOCKET6096_13568-001,SMLF,IO,DGA^6000030   I190 @T6G_MB_LIB.T6G(SCH_1):PAGE54

TP_CPU1_UART0_CTS_N @T6G_MB_LIB.T6G(SCH_1):TP_CPU1_UART0_CTS_N
   U26 DJ33 UART0_CTS_L||UART2_TXD||AGPIO135 GENOA_SP5-SOCKET6096_13568-001,SMLF,IO,DGA^6000030   I190 @T6G_MB_LIB.T6G(SCH_1):PAGE54

TP_CPU1_UART0_INTR @T6G_MB_LIB.T6G(SCH_1):TP_CPU1_UART0_INTR
   U26 DG34 UART0_INTR||AGPIO139 GENOA_SP5-SOCKET6096_13568-001,SMLF,IO,DGA^6000030   I190 @T6G_MB_LIB.T6G(SCH_1):PAGE54

TP_CPU1_UART0_RTS_N @T6G_MB_LIB.T6G(SCH_1):TP_CPU1_UART0_RTS_N
   U26 DF34 UART0_RTS_L||UART2_RXD||AGPIO137 GENOA_SP5-SOCKET6096_13568-001,SMLF,IO,DGA^6000030   I190 @T6G_MB_LIB.T6G(SCH_1):PAGE54

TP_CPU1_UART0_RX @T6G_MB_LIB.T6G(SCH_1):TP_CPU1_UART0_RX
   U26 DG35 UART0_RXD||AGPIO136 GENOA_SP5-SOCKET6096_13568-001,SMLF,IO,DGA^6000030   I190 @T6G_MB_LIB.T6G(SCH_1):PAGE54

TP_CPU1_UART0_TX @T6G_MB_LIB.T6G(SCH_1):TP_CPU1_UART0_TX
   U26 DJ34 UART0_TXD||AGPIO138 GENOA_SP5-SOCKET6096_13568-001,SMLF,IO,DGA^6000030   I190 @T6G_MB_LIB.T6G(SCH_1):PAGE54

TP_CPU1_UART1_RX @T6G_MB_LIB.T6G(SCH_1):TP_CPU1_UART1_RX
   U26 DH33 UART1_RXD||AGPIO141 GENOA_SP5-SOCKET6096_13568-001,SMLF,IO,DGA^6000030   I190 @T6G_MB_LIB.T6G(SCH_1):PAGE54

TP_E1S_0_MFG @T6G_MB_LIB.T6G(SCH_1):TP_E1S_0_MFG
   J90   B7    MFG SCONN56_123276793-SCONN56_1-2327679-3,SMLF,IO,DFHSA    I90 @T6G_MB_LIB.T6G(SCH_1):PAGE297

TP_E1S_0_RFU @T6G_MB_LIB.T6G(SCH_1):TP_E1S_0_RFU
   J90   B8    RFU SCONN56_123276793-SCONN56_1-2327679-3,SMLF,IO,DFHSA    I90 @T6G_MB_LIB.T6G(SCH_1):PAGE297

TP_FM_CLK_BUFFER_EN_R @T6G_MB_LIB.T6G(SCH_1):TP_FM_CLK_BUFFER_EN_R
   U18  V19  PR29D LCMXO3LF9400C5BG484C-LCMXO3LF-9400C-5BG484C,SMLF,IA   I217 @T6G_MB_LIB.T6G(SCH_1):PAGE80

TP_J45_A1 @T6G_MB_LIB.T6G(SCH_1):TP_J45_A1
   J45   A1     A1 CONN60_101062636003K02LF-CONN60_10106263-6003K02LFA   I466 @T6G_MB_LIB.T6G(SCH_1):PAGE363

TP_JTAG_SCM_SLOT3_R_TCK @T6G_MB_LIB.T6G(SCH_1):TP_JTAG_SCM_SLOT3_R_TCK
  U160   12    1Y0 74LV4052PW-74LV4052PW,SMLF,IC,ALLV4052K19   I266 @T6G_MB_LIB.T6G(SCH_1):PAGE148

TP_JTAG_SCM_SLOT3_R_TDI @T6G_MB_LIB.T6G(SCH_1):TP_JTAG_SCM_SLOT3_R_TDI
  U212   12    1Y0 74LV4052PW-74LV4052PW,SMLF,IC,ALLV4052K19   I302 @T6G_MB_LIB.T6G(SCH_1):PAGE148

TP_JTAG_SCM_SLOT3_R_TDO @T6G_MB_LIB.T6G(SCH_1):TP_JTAG_SCM_SLOT3_R_TDO
  U212    1    2Y0 74LV4052PW-74LV4052PW,SMLF,IC,ALLV4052K19   I302 @T6G_MB_LIB.T6G(SCH_1):PAGE148

TP_JTAG_SCM_SLOT3_R_TMS @T6G_MB_LIB.T6G(SCH_1):TP_JTAG_SCM_SLOT3_R_TMS
  U160    1    2Y0 74LV4052PW-74LV4052PW,SMLF,IC,ALLV4052K19   I266 @T6G_MB_LIB.T6G(SCH_1):PAGE148

TP_M_A_CPU0_SA_TEST39A @T6G_MB_LIB.T6G(SCH_1):TP_M_A_CPU0_SA_TEST39A
   U25 BF72 TEST39A GENOA_SP5-SOCKET6096_13568-001,SMLF,IO,DGA^6000030   I200 @T6G_MB_LIB.T6G(SCH_1):PAGE10

TP_M_A_CPU0_SA_TEST40 @T6G_MB_LIB.T6G(SCH_1):TP_M_A_CPU0_SA_TEST40
   U25  C60 TEST40 GENOA_SP5-SOCKET6096_13568-001,SMLF,IO,DGA^6000030   I200 @T6G_MB_LIB.T6G(SCH_1):PAGE10

TP_M_A_CPU1_SA_TEST39A @T6G_MB_LIB.T6G(SCH_1):TP_M_A_CPU1_SA_TEST39A
   U26 BF72 TEST39A GENOA_SP5-SOCKET6096_13568-001,SMLF,IO,DGA^6000030   I167 @T6G_MB_LIB.T6G(SCH_1):PAGE37

TP_M_A_CPU1_SA_TEST40 @T6G_MB_LIB.T6G(SCH_1):TP_M_A_CPU1_SA_TEST40
   U26  C60 TEST40 GENOA_SP5-SOCKET6096_13568-001,SMLF,IO,DGA^6000030   I167 @T6G_MB_LIB.T6G(SCH_1):PAGE37

TP_M_B_CPU0_SA_TEST39B @T6G_MB_LIB.T6G(SCH_1):TP_M_B_CPU0_SA_TEST39B
   U25 BF62 TEST39B GENOA_SP5-SOCKET6096_13568-001,SMLF,IO,DGA^6000030   I171 @T6G_MB_LIB.T6G(SCH_1):PAGE11

TP_M_B_CPU1_SA_TEST39B @T6G_MB_LIB.T6G(SCH_1):TP_M_B_CPU1_SA_TEST39B
   U26 BF62 TEST39B GENOA_SP5-SOCKET6096_13568-001,SMLF,IO,DGA^6000030   I159 @T6G_MB_LIB.T6G(SCH_1):PAGE38

TP_M_C_CPU0_SA_TEST39C @T6G_MB_LIB.T6G(SCH_1):TP_M_C_CPU0_SA_TEST39C
   U25 BF55 TEST39C GENOA_SP5-SOCKET6096_13568-001,SMLF,IO,DGA^6000030   I159 @T6G_MB_LIB.T6G(SCH_1):PAGE12

TP_M_C_CPU1_SA_TEST39C @T6G_MB_LIB.T6G(SCH_1):TP_M_C_CPU1_SA_TEST39C
   U26 BF55 TEST39C GENOA_SP5-SOCKET6096_13568-001,SMLF,IO,DGA^6000030   I159 @T6G_MB_LIB.T6G(SCH_1):PAGE39

TP_M_D_CPU0_SA_TEST39D @T6G_MB_LIB.T6G(SCH_1):TP_M_D_CPU0_SA_TEST39D
   U25 BF58 TEST39D GENOA_SP5-SOCKET6096_13568-001,SMLF,IO,DGA^6000030   I159 @T6G_MB_LIB.T6G(SCH_1):PAGE13

TP_M_D_CPU1_SA_TEST39D @T6G_MB_LIB.T6G(SCH_1):TP_M_D_CPU1_SA_TEST39D
   U26 BF58 TEST39D GENOA_SP5-SOCKET6096_13568-001,SMLF,IO,DGA^6000030   I159 @T6G_MB_LIB.T6G(SCH_1):PAGE40

TP_M_E_CPU0_SA_TEST39E @T6G_MB_LIB.T6G(SCH_1):TP_M_E_CPU0_SA_TEST39E
   U25 BF69 TEST39E GENOA_SP5-SOCKET6096_13568-001,SMLF,IO,DGA^6000030   I159 @T6G_MB_LIB.T6G(SCH_1):PAGE14

TP_M_E_CPU1_SA_TEST39E @T6G_MB_LIB.T6G(SCH_1):TP_M_E_CPU1_SA_TEST39E
   U26 BF69 TEST39E GENOA_SP5-SOCKET6096_13568-001,SMLF,IO,DGA^6000030   I159 @T6G_MB_LIB.T6G(SCH_1):PAGE41

TP_M_F_CPU0_SA_TEST39F @T6G_MB_LIB.T6G(SCH_1):TP_M_F_CPU0_SA_TEST39F
   U25 BF65 TEST39F GENOA_SP5-SOCKET6096_13568-001,SMLF,IO,DGA^6000030   I159 @T6G_MB_LIB.T6G(SCH_1):PAGE15

TP_M_F_CPU1_SA_TEST39F @T6G_MB_LIB.T6G(SCH_1):TP_M_F_CPU1_SA_TEST39F
   U26 BF65 TEST39F GENOA_SP5-SOCKET6096_13568-001,SMLF,IO,DGA^6000030   I159 @T6G_MB_LIB.T6G(SCH_1):PAGE42

TP_M_G_CPU0_SA_TEST39G @T6G_MB_LIB.T6G(SCH_1):TP_M_G_CPU0_SA_TEST39G
   U25  BF4 TEST39G GENOA_SP5-SOCKET6096_13568-001,SMLF,IO,DGA^6000030   I167 @T6G_MB_LIB.T6G(SCH_1):PAGE16

TP_M_G_CPU1_SA_TEST39G @T6G_MB_LIB.T6G(SCH_1):TP_M_G_CPU1_SA_TEST39G
   U26  BF4 TEST39G GENOA_SP5-SOCKET6096_13568-001,SMLF,IO,DGA^6000030   I167 @T6G_MB_LIB.T6G(SCH_1):PAGE43

TP_M_H_CPU0_SA_TEST39H @T6G_MB_LIB.T6G(SCH_1):TP_M_H_CPU0_SA_TEST39H
   U25 BF14 TEST39H GENOA_SP5-SOCKET6096_13568-001,SMLF,IO,DGA^6000030   I159 @T6G_MB_LIB.T6G(SCH_1):PAGE17

TP_M_H_CPU1_SA_TEST39H @T6G_MB_LIB.T6G(SCH_1):TP_M_H_CPU1_SA_TEST39H
   U26 BF14 TEST39H GENOA_SP5-SOCKET6096_13568-001,SMLF,IO,DGA^6000030   I159 @T6G_MB_LIB.T6G(SCH_1):PAGE44

TP_M_I_CPU0_SA_TEST39I @T6G_MB_LIB.T6G(SCH_1):TP_M_I_CPU0_SA_TEST39I
   U25 BF21 TEST39I GENOA_SP5-SOCKET6096_13568-001,SMLF,IO,DGA^6000030   I159 @T6G_MB_LIB.T6G(SCH_1):PAGE18

TP_M_I_CPU1_SA_TEST39I @T6G_MB_LIB.T6G(SCH_1):TP_M_I_CPU1_SA_TEST39I
   U26 BF21 TEST39I GENOA_SP5-SOCKET6096_13568-001,SMLF,IO,DGA^6000030   I159 @T6G_MB_LIB.T6G(SCH_1):PAGE45

TP_M_J_CPU0_SA_TEST39J @T6G_MB_LIB.T6G(SCH_1):TP_M_J_CPU0_SA_TEST39J
   U25 BF18 TEST39J GENOA_SP5-SOCKET6096_13568-001,SMLF,IO,DGA^6000030   I159 @T6G_MB_LIB.T6G(SCH_1):PAGE19

TP_M_J_CPU1_SA_TEST39J @T6G_MB_LIB.T6G(SCH_1):TP_M_J_CPU1_SA_TEST39J
   U26 BF18 TEST39J GENOA_SP5-SOCKET6096_13568-001,SMLF,IO,DGA^6000030   I159 @T6G_MB_LIB.T6G(SCH_1):PAGE46

TP_M_K_CPU0_SA_TEST39K @T6G_MB_LIB.T6G(SCH_1):TP_M_K_CPU0_SA_TEST39K
   U25  BF7 TEST39K GENOA_SP5-SOCKET6096_13568-001,SMLF,IO,DGA^6000030   I159 @T6G_MB_LIB.T6G(SCH_1):PAGE20

TP_M_K_CPU1_SA_TEST39K @T6G_MB_LIB.T6G(SCH_1):TP_M_K_CPU1_SA_TEST39K
   U26  BF7 TEST39K GENOA_SP5-SOCKET6096_13568-001,SMLF,IO,DGA^6000030   I159 @T6G_MB_LIB.T6G(SCH_1):PAGE47

TP_M_L_CPU0_SA_TEST39L @T6G_MB_LIB.T6G(SCH_1):TP_M_L_CPU0_SA_TEST39L
   U25 BF11 TEST39L GENOA_SP5-SOCKET6096_13568-001,SMLF,IO,DGA^6000030   I159 @T6G_MB_LIB.T6G(SCH_1):PAGE21

TP_M_L_CPU1_SA_TEST39L @T6G_MB_LIB.T6G(SCH_1):TP_M_L_CPU1_SA_TEST39L
   U26 BF11 TEST39L GENOA_SP5-SOCKET6096_13568-001,SMLF,IO,DGA^6000030   I159 @T6G_MB_LIB.T6G(SCH_1):PAGE48

TP_OCP_SFF_B68 @T6G_MB_LIB.T6G(SCH_1):TP_OCP_SFF_B68
   J38  B68 RFU1_NC_B68 SCONN168_ME1016810202011-SCONN168_ME1016810202011,A   I168 @T6G_MB_LIB.T6G(SCH_1):PAGE335

TP_OCP_SFF_B69 @T6G_MB_LIB.T6G(SCH_1):TP_OCP_SFF_B69
   J38  B69 RFU1_NC_B69 SCONN168_ME1016810202011-SCONN168_ME1016810202011,A   I168 @T6G_MB_LIB.T6G(SCH_1):PAGE335

TP_OCP_V3_2_B68 @T6G_MB_LIB.T6G(SCH_1):TP_OCP_V3_2_B68
   J35  B68 RFU1_NC_B68 SCONN168_ME1016810202011-SCONN168_ME1016810202011,A   I168 @T6G_MB_LIB.T6G(SCH_1):PAGE341

TP_OCP_V3_2_B69 @T6G_MB_LIB.T6G(SCH_1):TP_OCP_V3_2_B69
   J35  B69 RFU1_NC_B69 SCONN168_ME1016810202011-SCONN168_ME1016810202011,A   I168 @T6G_MB_LIB.T6G(SCH_1):PAGE341

TP_P0V9_RETIMER_CPU0_PMALERT @T6G_MB_LIB.T6G(SCH_1):TP_P0V9_RETIMER_CPU0_PMALERT
PU6502   11 NPMALERT# ISL69260IRAZT-ISL69260IRAZ-T,SMLF,IC,AL069260000    I42 @T6G_MB_LIB.T6G(SCH_1):PAGE475
  R649    2      B Q_RES_0402LF-4.7K,1%,1/16W,EMPTY,CS24702FB06   I207 @T6G_MB_LIB.T6G(SCH_1):PAGE475

TP_P0V9_RETIMER_CPU0_SVID_ALERT_N @T6G_MB_LIB.T6G(SCH_1):TP_P0V9_RETIMER_CPU0_SVID_ALERT_N
PU6502   19 NSVALERT# ISL69260IRAZT-ISL69260IRAZ-T,SMLF,IC,AL069260000    I42 @T6G_MB_LIB.T6G(SCH_1):PAGE475
PR6817    2      B Q_RES_0402LF-1K,1%,1/16W,EMPTY,CS21002FB06   I169 @T6G_MB_LIB.T6G(SCH_1):PAGE475
 PR883    1      A Q_RES_0402LF-0,5%,1/16W,EMPTY,CS00002JB13   I210 @T6G_MB_LIB.T6G(SCH_1):PAGE475

TP_P0V9_RETIMER_CPU0_VRHOT @T6G_MB_LIB.T6G(SCH_1):TP_P0V9_RETIMER_CPU0_VRHOT
PR6615    2      B Q_RES_0402LF-1K,1%,1/16W,CHIP,CS21002FB06   I135 @T6G_MB_LIB.T6G(SCH_1):PAGE475
PR6616    2      B Q_RES_0402LF-0,5%,1/16W,CHIP,CS00002JB13   I136 @T6G_MB_LIB.T6G(SCH_1):PAGE475

TP_P0V9_RETIMER_CPU1_PMALERT @T6G_MB_LIB.T6G(SCH_1):TP_P0V9_RETIMER_CPU1_PMALERT
PU6510   11 NPMALERT# ISL69260IRAZT-ISL69260IRAZ-T,SMLF,IC,AL069260000    I88 @T6G_MB_LIB.T6G(SCH_1):PAGE477
  R660    2      B Q_RES_0402LF-4.7K,1%,1/16W,EMPTY,CS24702FB06    I89 @T6G_MB_LIB.T6G(SCH_1):PAGE477

TP_P0V9_RETIMER_CPU1_SVID_ALERT_N @T6G_MB_LIB.T6G(SCH_1):TP_P0V9_RETIMER_CPU1_SVID_ALERT_N
PR6818    2      B Q_RES_0402LF-1K,1%,1/16W,EMPTY,CS21002FB06    I32 @T6G_MB_LIB.T6G(SCH_1):PAGE477
PR6802    1      A Q_RES_0402LF-0,5%,1/16W,EMPTY,CS00002JB13    I44 @T6G_MB_LIB.T6G(SCH_1):PAGE477
PU6510   19 NSVALERT# ISL69260IRAZT-ISL69260IRAZ-T,SMLF,IC,AL069260000    I88 @T6G_MB_LIB.T6G(SCH_1):PAGE477

TP_P0V9_RETIMER_CPU1_VRHOT @T6G_MB_LIB.T6G(SCH_1):TP_P0V9_RETIMER_CPU1_VRHOT
PR6816    2      B Q_RES_0402LF-0,5%,1/16W,CHIP,CS00002JB13    I56 @T6G_MB_LIB.T6G(SCH_1):PAGE477
PR6812    2      B Q_RES_0402LF-1K,1%,1/16W,CHIP,CS21002FB06    I86 @T6G_MB_LIB.T6G(SCH_1):PAGE477

TP_P12V_AUX_CPU0_DIMM_ISEN_N @T6G_MB_LIB.T6G(SCH_1):TP_P12V_AUX_CPU0_DIMM_ISEN_N
 R1838    4      4 Q_RES_4P_12-0.001,1%,3W,SMLF,CHIP,SP_CS+001DFR10    I58 @T6G_MB_LIB.T6G(SCH_1):PAGE264

TP_P12V_AUX_CPU0_DIMM_ISEN_P @T6G_MB_LIB.T6G(SCH_1):TP_P12V_AUX_CPU0_DIMM_ISEN_P
 R1838    3      3 Q_RES_4P_12-0.001,1%,3W,SMLF,CHIP,SP_CS+001DFR10    I58 @T6G_MB_LIB.T6G(SCH_1):PAGE264

TP_P12V_AUX_CPU1_DIMM_ISEN_N @T6G_MB_LIB.T6G(SCH_1):TP_P12V_AUX_CPU1_DIMM_ISEN_N
 R1837    4      4 Q_RES_4P_12-0.001,1%,3W,SMLF,CHIP,SP_CS+001DFR10    I54 @T6G_MB_LIB.T6G(SCH_1):PAGE264

TP_P12V_AUX_CPU1_DIMM_ISEN_P @T6G_MB_LIB.T6G(SCH_1):TP_P12V_AUX_CPU1_DIMM_ISEN_P
 R1837    3      3 Q_RES_4P_12-0.001,1%,3W,SMLF,CHIP,SP_CS+001DFR10    I54 @T6G_MB_LIB.T6G(SCH_1):PAGE264

TP_PCIE_RXN<1> @T6G_MB_LIB.T6G(SCH_1):TP_PCIE_RXN(1)
   J41  A63 PERP14 SCONN168_ME1016810202011-SCONN168_ME1016810202011,A   I176 @T6G_MB_LIB.T6G(SCH_1):PAGE348

TP_PCIE_RXP<1> @T6G_MB_LIB.T6G(SCH_1):TP_PCIE_RXP(1)
   J41  A62 PERN14 SCONN168_ME1016810202011-SCONN168_ME1016810202011,A   I176 @T6G_MB_LIB.T6G(SCH_1):PAGE348

TP_PCIE_TXN<1> @T6G_MB_LIB.T6G(SCH_1):TP_PCIE_TXN(1)
   J41  B63 PETP14 SCONN168_ME1016810202011-SCONN168_ME1016810202011,A   I176 @T6G_MB_LIB.T6G(SCH_1):PAGE348

TP_PCIE_TXP<1> @T6G_MB_LIB.T6G(SCH_1):TP_PCIE_TXP(1)
   J41  B62 PETN14 SCONN168_ME1016810202011-SCONN168_ME1016810202011,A   I176 @T6G_MB_LIB.T6G(SCH_1):PAGE348

TP_PCIE_TXP<3> @T6G_MB_LIB.T6G(SCH_1):TP_PCIE_TXP(3)
 R3254    1      A Q_RES_0402LF-0,5%,1/16W,EMPTY,CS00002JB13    I50 @T6G_MB_LIB.T6G(SCH_1):PAGE348
   J41  B68 RFU1_NC_B68 SCONN168_ME1016810202011-SCONN168_ME1016810202011,A   I176 @T6G_MB_LIB.T6G(SCH_1):PAGE348

TP_PECI_BMC @T6G_MB_LIB.T6G(SCH_1):TP_PECI_BMC
   J41  B27  PETP3 SCONN168_ME1016810202011-SCONN168_ME1016810202011,A   I176 @T6G_MB_LIB.T6G(SCH_1):PAGE348

TP_PVCCIO_PECI_BMC @T6G_MB_LIB.T6G(SCH_1):TP_PVCCIO_PECI_BMC
   J41  B28 GND_B28 SCONN168_ME1016810202011-SCONN168_ME1016810202011,A   I176 @T6G_MB_LIB.T6G(SCH_1):PAGE348

TP_PWRGD_P12V_FAN_DR_R @T6G_MB_LIB.T6G(SCH_1):TP_PWRGD_P12V_FAN_DR_R
   U18  N20  PR19C LCMXO3LF9400C5BG484C-LCMXO3LF-9400C-5BG484C,SMLF,IA   I217 @T6G_MB_LIB.T6G(SCH_1):PAGE80

TP_SLOT1_CLKREQ_0_R_N @T6G_MB_LIB.T6G(SCH_1):TP_SLOT1_CLKREQ_0_R_N
   U18  F18   PR5C LCMXO3LF9400C5BG484C-LCMXO3LF-9400C-5BG484C,SMLF,IA   I217 @T6G_MB_LIB.T6G(SCH_1):PAGE80

TP_SLOT2_BUF_SKU_ID0 @T6G_MB_LIB.T6G(SCH_1):TP_SLOT2_BUF_SKU_ID0
   U26 DF33 AGPIO21 GENOA_SP5-SOCKET6096_13568-001,SMLF,IO,DGA^6000030   I182 @T6G_MB_LIB.T6G(SCH_1):PAGE55

TP_SLOT2_BUF_SKU_ID1 @T6G_MB_LIB.T6G(SCH_1):TP_SLOT2_BUF_SKU_ID1
   U26 DE32 AGPIO22 GENOA_SP5-SOCKET6096_13568-001,SMLF,IO,DGA^6000030   I182 @T6G_MB_LIB.T6G(SCH_1):PAGE55

TP_SLOT2_CLKREQ_0_R_N @T6G_MB_LIB.T6G(SCH_1):TP_SLOT2_CLKREQ_0_R_N
   U18  J21  PR12A LCMXO3LF9400C5BG484C-LCMXO3LF-9400C-5BG484C,SMLF,IA   I217 @T6G_MB_LIB.T6G(SCH_1):PAGE80

TP_SPI_2_PLD_CLK @T6G_MB_LIB.T6G(SCH_1):TP_SPI_2_PLD_CLK
   J41  B43 GND_B43 SCONN168_ME1016810202011-SCONN168_ME1016810202011,A   I176 @T6G_MB_LIB.T6G(SCH_1):PAGE348

TP_SPI_2_PLD_CS_N @T6G_MB_LIB.T6G(SCH_1):TP_SPI_2_PLD_CS_N
   J41  B44  PETN8 SCONN168_ME1016810202011-SCONN168_ME1016810202011,A   I176 @T6G_MB_LIB.T6G(SCH_1):PAGE348

TP_SPI_2_PLD_IO0 @T6G_MB_LIB.T6G(SCH_1):TP_SPI_2_PLD_IO0
   J41  B45  PETP8 SCONN168_ME1016810202011-SCONN168_ME1016810202011,A   I176 @T6G_MB_LIB.T6G(SCH_1):PAGE348

TP_SPI_2_PLD_IO1 @T6G_MB_LIB.T6G(SCH_1):TP_SPI_2_PLD_IO1
   J41  B46 GND_B46 SCONN168_ME1016810202011-SCONN168_ME1016810202011,A   I176 @T6G_MB_LIB.T6G(SCH_1):PAGE348

TP_SPI_2_PLD_IO2 @T6G_MB_LIB.T6G(SCH_1):TP_SPI_2_PLD_IO2
   J41  B47  PETN9 SCONN168_ME1016810202011-SCONN168_ME1016810202011,A   I176 @T6G_MB_LIB.T6G(SCH_1):PAGE348

TP_SPI_2_PLD_IO3 @T6G_MB_LIB.T6G(SCH_1):TP_SPI_2_PLD_IO3
   J41  B48  PETP9 SCONN168_ME1016810202011-SCONN168_ME1016810202011,A   I176 @T6G_MB_LIB.T6G(SCH_1):PAGE348

TP_STBY_EN @T6G_MB_LIB.T6G(SCH_1):TP_STBY_EN
   J41  A45  PERP8 SCONN168_ME1016810202011-SCONN168_ME1016810202011,A   I176 @T6G_MB_LIB.T6G(SCH_1):PAGE348

TP_TCA9539_0_P0_2 @T6G_MB_LIB.T6G(SCH_1):TP_TCA9539_0_P0_2
  U181    6  IO0_2 PCA9539RPW-PCA9539RPW,SMLF,IC,AL009539K07    I83 @T6G_MB_LIB.T6G(SCH_1):PAGE246

TP_TCA9539_0_P0_3 @T6G_MB_LIB.T6G(SCH_1):TP_TCA9539_0_P0_3
  U181    7  IO0_3 PCA9539RPW-PCA9539RPW,SMLF,IC,AL009539K07    I83 @T6G_MB_LIB.T6G(SCH_1):PAGE246

TP_U27_EN @T6G_MB_LIB.T6G(SCH_1):TP_U27_EN
   U27    5     EN PCA9617ADP-PCA9617ADP,SMLF,IC,AL009617K02    I18 @T6G_MB_LIB.T6G(SCH_1):PAGE34

TP_UART_CPU0_UART0_RTS_N @T6G_MB_LIB.T6G(SCH_1):TP_UART_CPU0_UART0_RTS_N
   U25 DF34 UART0_RTS_L||UART2_RXD||AGPIO137 GENOA_SP5-SOCKET6096_13568-001,SMLF,IO,DGA^6000030   I227 @T6G_MB_LIB.T6G(SCH_1):PAGE27

TP_USB2_CD @T6G_MB_LIB.T6G(SCH_1):TP_USB2_CD
 U5201    4     CD TUSB211IRWBR-TUSB211IRWBR,SMLF,EMPTY,AL000211007    I84 @T6G_MB_LIB.T6G(SCH_1):PAGE358

TP_USB2_ENA_HS @T6G_MB_LIB.T6G(SCH_1):TP_USB2_ENA_HS
 U5201    9 ENA_HS TUSB211IRWBR-TUSB211IRWBR,SMLF,EMPTY,AL000211007    I84 @T6G_MB_LIB.T6G(SCH_1):PAGE358

TP_USB2_TEST @T6G_MB_LIB.T6G(SCH_1):TP_USB2_TEST
 U5201    3   TEST TUSB211IRWBR-TUSB211IRWBR,SMLF,EMPTY,AL000211007    I84 @T6G_MB_LIB.T6G(SCH_1):PAGE358

TP_VSENSE_PVDD33_S5_P0 @T6G_MB_LIB.T6G(SCH_1):TP_VSENSE_PVDD33_S5_P0
   U25 BP53 VDD_33_S5_SENSE GENOA_SP5-SOCKET6096_13568-001,SMLF,IO,DGA^6000030   I227 @T6G_MB_LIB.T6G(SCH_1):PAGE27

TP_VSENSE_PVDD33_S5_P1 @T6G_MB_LIB.T6G(SCH_1):TP_VSENSE_PVDD33_S5_P1
   U26 BP53 VDD_33_S5_SENSE GENOA_SP5-SOCKET6096_13568-001,SMLF,IO,DGA^6000030   I190 @T6G_MB_LIB.T6G(SCH_1):PAGE54

U11_E2 @T6G_MB_LIB.T6G(SCH_1):U11_E2
   U11    3     E2 M24M02DRMN6TP-M24M02-DRMN6TP,SMLF,IC,AKE33Z00600     I3 @T6G_MB_LIB.T6G(SCH_1):PAGE387
 R6822    1      A Q_RES_0201LF-1K,1%,1/20W,CHIP,CS21001FE07    I24 @T6G_MB_LIB.T6G(SCH_1):PAGE387

U124_VCC @T6G_MB_LIB.T6G(SCH_1):U124_VCC
  U124    5    VCC SN74LVC1G07DBVR_SMLF-SN74LVC1G07DBVR,IC,AL1G0007024    I38 @T6G_MB_LIB.T6G(SCH_1):PAGE144
  C693    1      A Q_CAP_0402-0.1UF,25V,10%,X7R,CH4104K1B00    I39 @T6G_MB_LIB.T6G(SCH_1):PAGE144
 R8018    2      B Q_RES_0402LF-0,5%,1/16W,CHIP,CS00002JB13    I84 @T6G_MB_LIB.T6G(SCH_1):PAGE144
 R8017    2      B Q_RES_0402LF-0,5%,1/16W,EMPTY,CS00002JB13    I85 @T6G_MB_LIB.T6G(SCH_1):PAGE144

U12_E2 @T6G_MB_LIB.T6G(SCH_1):U12_E2
   U12    3     E2 M24M02DRMN6TP-M24M02-DRMN6TP,SMLF,IC,AKE33Z00600     I5 @T6G_MB_LIB.T6G(SCH_1):PAGE399
 R6788    1      A Q_RES_0201LF-1K,1%,1/20W,CHIP,CS21001FE07    I13 @T6G_MB_LIB.T6G(SCH_1):PAGE399

U142_VS @T6G_MB_LIB.T6G(SCH_1):U142_VS
  U142    5     VS LT6700CS61TRPBF-LT6700CS6-1#TRPBF,SMLF,EMPTY,AL006A    I50 @T6G_MB_LIB.T6G(SCH_1):PAGE371
 C6084    1      A Q_CAP_0402-0.1UF,25V,10%,EMPTY,CH4104K1B00   I107 @T6G_MB_LIB.T6G(SCH_1):PAGE371
 R9020    2      B Q_RES_0402LF-1K,1%,1/16W,EMPTY,CS21002FB06   I108 @T6G_MB_LIB.T6G(SCH_1):PAGE371
 C9003    1      A Q_CAP_C0402-1UF,25V,10%,EMPTY,CH5104KEB02   I110 @T6G_MB_LIB.T6G(SCH_1):PAGE371

U152_OE_N @T6G_MB_LIB.T6G(SCH_1):U152_OE_N
  U152    2   OE_# SN74AVC2T245RSWR-SN74AVC2T245RSWR,SMLF,IC,AL02T245A    I60 @T6G_MB_LIB.T6G(SCH_1):PAGE150
 R1637    1      A Q_RES_0402LF-4.7K,5%,1/16W,CHIP,CS24702JB10    I71 @T6G_MB_LIB.T6G(SCH_1):PAGE150

U15_E2 @T6G_MB_LIB.T6G(SCH_1):U15_E2
   U15    3     E2 M24M02DRMN6TP-M24M02-DRMN6TP,SMLF,IC,AKE33Z00600     I5 @T6G_MB_LIB.T6G(SCH_1):PAGE410
 R1044    1      A Q_RES_0201LF-1K,1%,1/20W,CHIP,CS21001FE07    I20 @T6G_MB_LIB.T6G(SCH_1):PAGE410

U160_EN_N @T6G_MB_LIB.T6G(SCH_1):U160_EN_N
  U160    6    E_N 74LV4052PW-74LV4052PW,SMLF,IC,ALLV4052K19   I266 @T6G_MB_LIB.T6G(SCH_1):PAGE148
JP6001    2      2 CONN3_210HP1030BR1-CONN3_210-HP1-030BR1,THLF,IO,DFA   I387 @T6G_MB_LIB.T6G(SCH_1):PAGE148

U16_E2 @T6G_MB_LIB.T6G(SCH_1):U16_E2
   U16    3     E2 M24M02DRMN6TP-M24M02-DRMN6TP,SMLF,IC,AKE33Z00600     I5 @T6G_MB_LIB.T6G(SCH_1):PAGE421
 R1085    1      A Q_RES_0201LF-1K,1%,1/20W,CHIP,CS21001FE07    I18 @T6G_MB_LIB.T6G(SCH_1):PAGE421

U17_E2 @T6G_MB_LIB.T6G(SCH_1):U17_E2
   U17    3     E2 M24M02DRMN6TP-M24M02-DRMN6TP,SMLF,IC,AKE33Z00600     I5 @T6G_MB_LIB.T6G(SCH_1):PAGE432
 R1127    1      A Q_RES_0201LF-1K,1%,1/20W,CHIP,CS21001FE07    I18 @T6G_MB_LIB.T6G(SCH_1):PAGE432

U19_E2 @T6G_MB_LIB.T6G(SCH_1):U19_E2
   U19    3     E2 M24M02DRMN6TP-M24M02-DRMN6TP,SMLF,IC,AKE33Z00600     I5 @T6G_MB_LIB.T6G(SCH_1):PAGE442
 R6789    1      A Q_RES_0201LF-1K,1%,1/20W,CHIP,CS21001FE07    I19 @T6G_MB_LIB.T6G(SCH_1):PAGE442

U206_VS @T6G_MB_LIB.T6G(SCH_1):U206_VS
  U206    5     VS LT6700CS61TRPBF-LT6700CS6-1#TRPBF,SMLF,EMPTY,AL006A    I49 @T6G_MB_LIB.T6G(SCH_1):PAGE372
 C1561    1      A Q_CAP_0402-0.1UF,25V,10%,EMPTY,CH4104K1B00    I96 @T6G_MB_LIB.T6G(SCH_1):PAGE372
 R9021    2      B Q_RES_0402LF-1K,1%,1/16W,EMPTY,CS21002FB06    I97 @T6G_MB_LIB.T6G(SCH_1):PAGE372
 C9004    1      A Q_CAP_C0402-1UF,25V,10%,EMPTY,CH5104KEB02    I99 @T6G_MB_LIB.T6G(SCH_1):PAGE372

U20_E2 @T6G_MB_LIB.T6G(SCH_1):U20_E2
   U20    3     E2 M24M02DRMN6TP-M24M02-DRMN6TP,SMLF,IC,AKE33Z00600     I5 @T6G_MB_LIB.T6G(SCH_1):PAGE453
 R6790    1      A Q_RES_0201LF-1K,1%,1/20W,CHIP,CS21001FE07    I19 @T6G_MB_LIB.T6G(SCH_1):PAGE453

U212_EN_N @T6G_MB_LIB.T6G(SCH_1):U212_EN_N
  U212    6    E_N 74LV4052PW-74LV4052PW,SMLF,IC,ALLV4052K19   I302 @T6G_MB_LIB.T6G(SCH_1):PAGE148
JP6000    2      2 CONN3_210HP1030BR1-CONN3_210-HP1-030BR1,THLF,IO,DFA   I386 @T6G_MB_LIB.T6G(SCH_1):PAGE148

U21_E2 @T6G_MB_LIB.T6G(SCH_1):U21_E2
   U21    3     E2 M24M02DRMN6TP-M24M02-DRMN6TP,SMLF,IC,AKE33Z00600     I5 @T6G_MB_LIB.T6G(SCH_1):PAGE464
 R6791    1      A Q_RES_0201LF-1K,1%,1/20W,CHIP,CS21001FE07    I22 @T6G_MB_LIB.T6G(SCH_1):PAGE464

U270_0_ADD0 @T6G_MB_LIB.T6G(SCH_1):U270_0_ADD0
 R4207    1      A Q_RES_0402LF-1K,1%,1/16W,CHIP,CS21002FB06    I85 @T6G_MB_LIB.T6G(SCH_1):PAGE359
 R4206    2      B Q_RES_0402LF-1K,1%,1/16W,EMPTY,CS21002FB06    I86 @T6G_MB_LIB.T6G(SCH_1):PAGE359
  U270    7     A0 LM75BD-LM75BD,SMLF,IC,AL0075BD000   I164 @T6G_MB_LIB.T6G(SCH_1):PAGE359

U270_0_ADD1 @T6G_MB_LIB.T6G(SCH_1):U270_0_ADD1
 R4199    1      A Q_RES_0402LF-1K,1%,1/16W,CHIP,CS21002FB06    I81 @T6G_MB_LIB.T6G(SCH_1):PAGE359
 R4198    2      B Q_RES_0402LF-1K,1%,1/16W,EMPTY,CS21002FB06    I82 @T6G_MB_LIB.T6G(SCH_1):PAGE359
  U270    6     A1 LM75BD-LM75BD,SMLF,IC,AL0075BD000   I164 @T6G_MB_LIB.T6G(SCH_1):PAGE359

U270_0_ADD2 @T6G_MB_LIB.T6G(SCH_1):U270_0_ADD2
 R4191    1      A Q_RES_0402LF-1K,1%,1/16W,CHIP,CS21002FB06    I89 @T6G_MB_LIB.T6G(SCH_1):PAGE359
 R4190    2      B Q_RES_0402LF-1K,1%,1/16W,EMPTY,CS21002FB06    I91 @T6G_MB_LIB.T6G(SCH_1):PAGE359
  U270    5     A2 LM75BD-LM75BD,SMLF,IC,AL0075BD000   I164 @T6G_MB_LIB.T6G(SCH_1):PAGE359

U271_1_ADD0 @T6G_MB_LIB.T6G(SCH_1):U271_1_ADD0
 R4204    2      B Q_RES_0402LF-1K,1%,1/16W,EMPTY,CS21002FB06    I94 @T6G_MB_LIB.T6G(SCH_1):PAGE359
 R4205    1      A Q_RES_0402LF-1K,1%,1/16W,CHIP,CS21002FB06    I96 @T6G_MB_LIB.T6G(SCH_1):PAGE359
  U271    7     A0 LM75BD-LM75BD,SMLF,IC,AL0075BD000   I165 @T6G_MB_LIB.T6G(SCH_1):PAGE359

U271_1_ADD1 @T6G_MB_LIB.T6G(SCH_1):U271_1_ADD1
 R4196    2      B Q_RES_0402LF-1K,1%,1/16W,EMPTY,CS21002FB06    I95 @T6G_MB_LIB.T6G(SCH_1):PAGE359
 R4197    1      A Q_RES_0402LF-1K,1%,1/16W,CHIP,CS21002FB06    I98 @T6G_MB_LIB.T6G(SCH_1):PAGE359
  U271    6     A1 LM75BD-LM75BD,SMLF,IC,AL0075BD000   I165 @T6G_MB_LIB.T6G(SCH_1):PAGE359

U271_1_ADD2 @T6G_MB_LIB.T6G(SCH_1):U271_1_ADD2
 R4188    2      B Q_RES_0402LF-1K,1%,1/16W,EMPTY,CS21002FB06   I101 @T6G_MB_LIB.T6G(SCH_1):PAGE359
 R4189    1      A Q_RES_0402LF-1K,1%,1/16W,CHIP,CS21002FB06   I102 @T6G_MB_LIB.T6G(SCH_1):PAGE359
  U271    5     A2 LM75BD-LM75BD,SMLF,IC,AL0075BD000   I165 @T6G_MB_LIB.T6G(SCH_1):PAGE359

U272_2_ADD0 @T6G_MB_LIB.T6G(SCH_1):U272_2_ADD0
 R4203    1      A Q_RES_0402LF-1K,1%,1/16W,CHIP,CS21002FB06   I127 @T6G_MB_LIB.T6G(SCH_1):PAGE359
 R4202    2      B Q_RES_0402LF-1K,1%,1/16W,EMPTY,CS21002FB06   I129 @T6G_MB_LIB.T6G(SCH_1):PAGE359
  U272    7     A0 LM75BD-LM75BD,SMLF,IC,AL0075BD000   I166 @T6G_MB_LIB.T6G(SCH_1):PAGE359

U272_2_ADD1 @T6G_MB_LIB.T6G(SCH_1):U272_2_ADD1
 R4195    1      A Q_RES_0402LF-1K,1%,1/16W,CHIP,CS21002FB06   I125 @T6G_MB_LIB.T6G(SCH_1):PAGE359
 R4194    2      B Q_RES_0402LF-1K,1%,1/16W,EMPTY,CS21002FB06   I128 @T6G_MB_LIB.T6G(SCH_1):PAGE359
  U272    6     A1 LM75BD-LM75BD,SMLF,IC,AL0075BD000   I166 @T6G_MB_LIB.T6G(SCH_1):PAGE359

U272_2_ADD2 @T6G_MB_LIB.T6G(SCH_1):U272_2_ADD2
 R4187    1      A Q_RES_0402LF-1K,1%,1/16W,CHIP,CS21002FB06   I121 @T6G_MB_LIB.T6G(SCH_1):PAGE359
 R4186    2      B Q_RES_0402LF-1K,1%,1/16W,EMPTY,CS21002FB06   I122 @T6G_MB_LIB.T6G(SCH_1):PAGE359
  U272    5     A2 LM75BD-LM75BD,SMLF,IC,AL0075BD000   I166 @T6G_MB_LIB.T6G(SCH_1):PAGE359

U273_3_ADD0 @T6G_MB_LIB.T6G(SCH_1):U273_3_ADD0
 R4201    1      A Q_RES_0402LF-1K,1%,1/16W,CHIP,CS21002FB06   I147 @T6G_MB_LIB.T6G(SCH_1):PAGE359
 R4200    2      B Q_RES_0402LF-1K,1%,1/16W,EMPTY,CS21002FB06   I149 @T6G_MB_LIB.T6G(SCH_1):PAGE359
  U273    7     A0 LM75BD-LM75BD,SMLF,IC,AL0075BD000   I167 @T6G_MB_LIB.T6G(SCH_1):PAGE359

U273_3_ADD1 @T6G_MB_LIB.T6G(SCH_1):U273_3_ADD1
 R4193    1      A Q_RES_0402LF-1K,1%,1/16W,CHIP,CS21002FB06   I145 @T6G_MB_LIB.T6G(SCH_1):PAGE359
 R4192    2      B Q_RES_0402LF-1K,1%,1/16W,EMPTY,CS21002FB06   I148 @T6G_MB_LIB.T6G(SCH_1):PAGE359
  U273    6     A1 LM75BD-LM75BD,SMLF,IC,AL0075BD000   I167 @T6G_MB_LIB.T6G(SCH_1):PAGE359

U273_3_ADD2 @T6G_MB_LIB.T6G(SCH_1):U273_3_ADD2
 R4185    1      A Q_RES_0402LF-1K,1%,1/16W,CHIP,CS21002FB06   I141 @T6G_MB_LIB.T6G(SCH_1):PAGE359
 R4184    2      B Q_RES_0402LF-1K,1%,1/16W,EMPTY,CS21002FB06   I142 @T6G_MB_LIB.T6G(SCH_1):PAGE359
  U273    5     A2 LM75BD-LM75BD,SMLF,IC,AL0075BD000   I167 @T6G_MB_LIB.T6G(SCH_1):PAGE359

U9_NR @T6G_MB_LIB.T6G(SCH_1):U9_NR
    U9    4 NR||FB TPS71715DCKR-TPS71715DCKR,SMLF,EMPTY,AL071715001    I91 @T6G_MB_LIB.T6G(SCH_1):PAGE156
   C22    1      A Q_CAP_C0402-0.01UF,50V,10%,EMPTY,CH31006KB18   I113 @T6G_MB_LIB.T6G(SCH_1):PAGE156

UART_BMC_BIC_BUF_RX @T6G_MB_LIB.T6G(SCH_1):UART_BMC_BIC_BUF_RX
 R3036    2      B Q_RES_0402LF-33.2,1%,1/16W,CHIP,CS03322FB03   I197 @T6G_MB_LIB.T6G(SCH_1):PAGE256
   J41  OB6    CLK SCONN168_ME1016810202011-SCONN168_ME1016810202011,A   I176 @T6G_MB_LIB.T6G(SCH_1):PAGE348

UART_BMC_BIC_RX @T6G_MB_LIB.T6G(SCH_1):UART_BMC_BIC_RX
 R3033    1      A Q_RES_0402LF-0,5%,1/16W,CHIP,CS00002JB13   I170 @T6G_MB_LIB.T6G(SCH_1):PAGE256
 R4515    2      B Q_RES_0402LF-100K,1%,1/16W,CHIP,CS41002FB09   I200 @T6G_MB_LIB.T6G(SCH_1):PAGE256
  J106   N6     N6 CONN112_10137002101LF-CONN112_10137002-101LF,THLF,A    I19 @T6G_MB_LIB.T6G(SCH_1):PAGE327

UART_BMC_BIC_R_BUF_RX @T6G_MB_LIB.T6G(SCH_1):UART_BMC_BIC_R_BUF_RX
  U204    4      Y 74LVC1G126SE7-74LVC1G126SE-7,SMLF,IC,AL1G0126009   I195 @T6G_MB_LIB.T6G(SCH_1):PAGE256
 R3036    1      A Q_RES_0402LF-33.2,1%,1/16W,CHIP,CS03322FB03   I197 @T6G_MB_LIB.T6G(SCH_1):PAGE256
 R4173    2      B Q_RES_0402LF-100K,1%,1/16W,EMPTY,CS41002FB09   I204 @T6G_MB_LIB.T6G(SCH_1):PAGE256

UART_BMC_BIC_R_RX @T6G_MB_LIB.T6G(SCH_1):UART_BMC_BIC_R_RX
 R3033    2      B Q_RES_0402LF-0,5%,1/16W,CHIP,CS00002JB13   I170 @T6G_MB_LIB.T6G(SCH_1):PAGE256
  U204    2      A 74LVC1G126SE7-74LVC1G126SE-7,SMLF,IC,AL1G0126009   I195 @T6G_MB_LIB.T6G(SCH_1):PAGE256

UART_BMC_BIC_TX @T6G_MB_LIB.T6G(SCH_1):UART_BMC_BIC_TX
   J41  OB5 DATA_OUT SCONN168_ME1016810202011-SCONN168_ME1016810202011,A   I176 @T6G_MB_LIB.T6G(SCH_1):PAGE348
  J106   N8     N8 CONN112_10137002101LF-CONN112_10137002-101LF,THLF,A    I19 @T6G_MB_LIB.T6G(SCH_1):PAGE327

UART_CPU0_LVC3_UART0_RX @T6G_MB_LIB.T6G(SCH_1):UART_CPU0_LVC3_UART0_RX
  C364    1      A Q_CAP_C0402-220PF,50V,5%,C0G,CH12206JB00   I187 @T6G_MB_LIB.T6G(SCH_1):PAGE141
   J13    2      2 CONN4_HFK1040L0P1L7H-CONN4_HFK1040-L0P1L-7H,THLF,IA   I195 @T6G_MB_LIB.T6G(SCH_1):PAGE141
  R825    2      B Q_RES_0402LF-10K,5%,1/16W,EMPTY,CS31002JB08   I203 @T6G_MB_LIB.T6G(SCH_1):PAGE141
  R819    2      B Q_RES_0402LF-0,5%,1/16W,CHIP,CS00002JB13   I212 @T6G_MB_LIB.T6G(SCH_1):PAGE141

UART_CPU0_LVC3_UART0_R_RX @T6G_MB_LIB.T6G(SCH_1):UART_CPU0_LVC3_UART0_R_RX
  U116   11     B4 SN74AVC4T774PWR-SN74AVC4T774PWR,SMLF,IC,AL04T774K00   I117 @T6G_MB_LIB.T6G(SCH_1):PAGE141
  R819    1      A Q_RES_0402LF-0,5%,1/16W,CHIP,CS00002JB13   I212 @T6G_MB_LIB.T6G(SCH_1):PAGE141

UART_CPU0_LVC3_UART0_R_TX @T6G_MB_LIB.T6G(SCH_1):UART_CPU0_LVC3_UART0_R_TX
  U116   12     B3 SN74AVC4T774PWR-SN74AVC4T774PWR,SMLF,IC,AL04T774K00   I117 @T6G_MB_LIB.T6G(SCH_1):PAGE141
  R818    1      A Q_RES_0402LF-0,5%,1/16W,CHIP,CS00002JB13   I220 @T6G_MB_LIB.T6G(SCH_1):PAGE141

UART_CPU0_LVC3_UART0_TX @T6G_MB_LIB.T6G(SCH_1):UART_CPU0_LVC3_UART0_TX
  C363    1      A Q_CAP_C0402-220PF,50V,5%,C0G,CH12206JB00   I190 @T6G_MB_LIB.T6G(SCH_1):PAGE141
   J13    3      3 CONN4_HFK1040L0P1L7H-CONN4_HFK1040-L0P1L-7H,THLF,IA   I195 @T6G_MB_LIB.T6G(SCH_1):PAGE141
  R824    2      B Q_RES_0402LF-10K,5%,1/16W,CHIP,CS31002JB08   I204 @T6G_MB_LIB.T6G(SCH_1):PAGE141
  R818    2      B Q_RES_0402LF-0,5%,1/16W,CHIP,CS00002JB13   I220 @T6G_MB_LIB.T6G(SCH_1):PAGE141

UART_CPU0_SCM_LVC3_UART1_R1_TX @T6G_MB_LIB.T6G(SCH_1):UART_CPU0_SCM_LVC3_UART1_R1_TX
   J41  OB9 RBT_RXD0 SCONN168_ME1016810202011-SCONN168_ME1016810202011,A   I176 @T6G_MB_LIB.T6G(SCH_1):PAGE348
 R6065    1      A Q_RES_0402LF-0,5%,1/16W,EMPTY,CS00002JB13   I178 @T6G_MB_LIB.T6G(SCH_1):PAGE348

UART_CPU0_SCM_LVC3_UART1_RX @T6G_MB_LIB.T6G(SCH_1):UART_CPU0_SCM_LVC3_UART1_RX
   J41  OB8 RBT_RXD1 SCONN168_ME1016810202011-SCONN168_ME1016810202011,A   I176 @T6G_MB_LIB.T6G(SCH_1):PAGE348
 R6064    1      A Q_RES_0402LF-0,5%,1/16W,EMPTY,CS00002JB13   I177 @T6G_MB_LIB.T6G(SCH_1):PAGE348

UART_CPU0_SCM_LVC3_UART1_R_RX @T6G_MB_LIB.T6G(SCH_1):UART_CPU0_SCM_LVC3_UART1_R_RX
  U116   13     B2 SN74AVC4T774PWR-SN74AVC4T774PWR,SMLF,IC,AL04T774K00   I117 @T6G_MB_LIB.T6G(SCH_1):PAGE141
  R823    2      B Q_RES_0402LF-10K,5%,1/16W,EMPTY,CS31002JB08   I205 @T6G_MB_LIB.T6G(SCH_1):PAGE141
   C63    1      A Q_CAP_C0402-220PF,50V,5%,C0G,CH12206JB00   I112 @T6G_MB_LIB.T6G(SCH_1):PAGE349
    J8    2      2 CONN4_HFK1040L0P1L7H-CONN4_HFK1040-L0P1L-7H,THLF,IA   I148 @T6G_MB_LIB.T6G(SCH_1):PAGE349
 R6064    2      B Q_RES_0402LF-0,5%,1/16W,EMPTY,CS00002JB13   I177 @T6G_MB_LIB.T6G(SCH_1):PAGE348

UART_CPU0_SCM_LVC3_UART1_R_TX @T6G_MB_LIB.T6G(SCH_1):UART_CPU0_SCM_LVC3_UART1_R_TX
  U116   14     B1 SN74AVC4T774PWR-SN74AVC4T774PWR,SMLF,IC,AL04T774K00   I117 @T6G_MB_LIB.T6G(SCH_1):PAGE141
 R1425    1      A Q_RES_0402LF-0,5%,1/16W,CHIP,CS00002JB13   I221 @T6G_MB_LIB.T6G(SCH_1):PAGE141

UART_CPU0_SCM_LVC3_UART1_TX @T6G_MB_LIB.T6G(SCH_1):UART_CPU0_SCM_LVC3_UART1_TX
  R822    2      B Q_RES_0402LF-10K,5%,1/16W,CHIP,CS31002JB08   I206 @T6G_MB_LIB.T6G(SCH_1):PAGE141
    J8    3      3 CONN4_HFK1040L0P1L7H-CONN4_HFK1040-L0P1L-7H,THLF,IA   I148 @T6G_MB_LIB.T6G(SCH_1):PAGE349
   C62    1      A Q_CAP_C0402-220PF,50V,5%,C0G,CH12206JB00    I69 @T6G_MB_LIB.T6G(SCH_1):PAGE349
 R6065    2      B Q_RES_0402LF-0,5%,1/16W,EMPTY,CS00002JB13   I178 @T6G_MB_LIB.T6G(SCH_1):PAGE348
 R1425    2      B Q_RES_0402LF-0,5%,1/16W,CHIP,CS00002JB13   I221 @T6G_MB_LIB.T6G(SCH_1):PAGE141

UART_CPU0_SCM_UART1_RX @T6G_MB_LIB.T6G(SCH_1):UART_CPU0_SCM_UART1_RX
   U25 DH33 UART1_RXD||AGPIO141 GENOA_SP5-SOCKET6096_13568-001,SMLF,IO,DGA^6000030   I227 @T6G_MB_LIB.T6G(SCH_1):PAGE27
  R816    2      B Q_RES_0402LF-10K,5%,1/16W,CHIP,CS31002JB08   I196 @T6G_MB_LIB.T6G(SCH_1):PAGE141
 R1423    1      A Q_RES_0402LF-0,5%,1/16W,CHIP,CS00002JB13   I232 @T6G_MB_LIB.T6G(SCH_1):PAGE141

UART_CPU0_SCM_UART1_R_RX @T6G_MB_LIB.T6G(SCH_1):UART_CPU0_SCM_UART1_R_RX
  U116    4     A2 SN74AVC4T774PWR-SN74AVC4T774PWR,SMLF,IC,AL04T774K00   I117 @T6G_MB_LIB.T6G(SCH_1):PAGE141
 R1423    2      B Q_RES_0402LF-0,5%,1/16W,CHIP,CS00002JB13   I232 @T6G_MB_LIB.T6G(SCH_1):PAGE141

UART_CPU0_SCM_UART1_R_TX @T6G_MB_LIB.T6G(SCH_1):UART_CPU0_SCM_UART1_R_TX
   U25 DJ32 UART1_TXD||AGPIO142 GENOA_SP5-SOCKET6096_13568-001,SMLF,IO,DGA^6000030   I227 @T6G_MB_LIB.T6G(SCH_1):PAGE27
 R2318    1      A Q_RES_0402LF-0,5%,1/16W,CHIP,CS00002JB13   I288 @T6G_MB_LIB.T6G(SCH_1):PAGE27

UART_CPU0_SCM_UART1_TX @T6G_MB_LIB.T6G(SCH_1):UART_CPU0_SCM_UART1_TX
 R2318    2      B Q_RES_0402LF-0,5%,1/16W,CHIP,CS00002JB13   I288 @T6G_MB_LIB.T6G(SCH_1):PAGE27
  R747    2      B Q_RES_0402LF-1K,1%,1/16W,CHIP,CS21002FB06     I8 @T6G_MB_LIB.T6G(SCH_1):PAGE75
  R729    2      B Q_RES_0402LF-10K,5%,1/16W,EMPTY,CS31002JB08    I41 @T6G_MB_LIB.T6G(SCH_1):PAGE75
  U116    3     A1 SN74AVC4T774PWR-SN74AVC4T774PWR,SMLF,IC,AL04T774K00   I117 @T6G_MB_LIB.T6G(SCH_1):PAGE141
  R815    2      B Q_RES_0402LF-10K,5%,1/16W,EMPTY,CS31002JB08   I197 @T6G_MB_LIB.T6G(SCH_1):PAGE141

UART_CPU0_UART0_RX @T6G_MB_LIB.T6G(SCH_1):UART_CPU0_UART0_RX
   U25 DG35 UART0_RXD||AGPIO136 GENOA_SP5-SOCKET6096_13568-001,SMLF,IO,DGA^6000030   I227 @T6G_MB_LIB.T6G(SCH_1):PAGE27
  R813    2      B Q_RES_0402LF-10K,5%,1/16W,CHIP,CS31002JB08   I199 @T6G_MB_LIB.T6G(SCH_1):PAGE141
  R817    1      A Q_RES_0402LF-0,5%,1/16W,CHIP,CS00002JB13   I231 @T6G_MB_LIB.T6G(SCH_1):PAGE141

UART_CPU0_UART0_R_RX @T6G_MB_LIB.T6G(SCH_1):UART_CPU0_UART0_R_RX
  U116    6     A4 SN74AVC4T774PWR-SN74AVC4T774PWR,SMLF,IC,AL04T774K00   I117 @T6G_MB_LIB.T6G(SCH_1):PAGE141
  R817    2      B Q_RES_0402LF-0,5%,1/16W,CHIP,CS00002JB13   I231 @T6G_MB_LIB.T6G(SCH_1):PAGE141

UART_CPU0_UART0_R_TX @T6G_MB_LIB.T6G(SCH_1):UART_CPU0_UART0_R_TX
   U25 DJ34 UART0_TXD||AGPIO138 GENOA_SP5-SOCKET6096_13568-001,SMLF,IO,DGA^6000030   I227 @T6G_MB_LIB.T6G(SCH_1):PAGE27
  R405    2      B Q_RES_0402LF-0,5%,1/16W,CHIP,CS00002JB13   I279 @T6G_MB_LIB.T6G(SCH_1):PAGE27

UART_CPU0_UART0_TX @T6G_MB_LIB.T6G(SCH_1):UART_CPU0_UART0_TX
  R405    1      A Q_RES_0402LF-0,5%,1/16W,CHIP,CS00002JB13   I279 @T6G_MB_LIB.T6G(SCH_1):PAGE27
  U116    5     A3 SN74AVC4T774PWR-SN74AVC4T774PWR,SMLF,IC,AL04T774K00   I117 @T6G_MB_LIB.T6G(SCH_1):PAGE141
  R814    2      B Q_RES_0402LF-10K,5%,1/16W,EMPTY,CS31002JB08   I198 @T6G_MB_LIB.T6G(SCH_1):PAGE141

UART_LS_EN @T6G_MB_LIB.T6G(SCH_1):UART_LS_EN
   Q61    G   GATE MOSFET_N_GSD-NX138BK,SMLF,IC,BAM01380023    I89 @T6G_MB_LIB.T6G(SCH_1):PAGE141
 R1563    1      A Q_RES_0402LF-33,5%,1/16W,CHIP,CS03302JB10    I63 @T6G_MB_LIB.T6G(SCH_1):PAGE80

UART_LS_EN_N @T6G_MB_LIB.T6G(SCH_1):UART_LS_EN_N
  U116    9     OE SN74AVC4T774PWR-SN74AVC4T774PWR,SMLF,IC,AL04T774K00   I117 @T6G_MB_LIB.T6G(SCH_1):PAGE141
 R1253    1      A Q_RES_0402LF-33,5%,1/16W,CHIP,CS03302JB10   I211 @T6G_MB_LIB.T6G(SCH_1):PAGE141

UART_LS_EN_R_N @T6G_MB_LIB.T6G(SCH_1):UART_LS_EN_R_N
   Q61    D  DRAIN MOSFET_N_GSD-NX138BK,SMLF,IC,BAM01380023    I89 @T6G_MB_LIB.T6G(SCH_1):PAGE141
 R1419    2      B Q_RES_0402LF-4.7K,5%,1/16W,CHIP,CS24702JB10    I91 @T6G_MB_LIB.T6G(SCH_1):PAGE141
 R1253    2      B Q_RES_0402LF-33,5%,1/16W,CHIP,CS03302JB10   I211 @T6G_MB_LIB.T6G(SCH_1):PAGE141

UART_VCC_J13 @T6G_MB_LIB.T6G(SCH_1):UART_VCC_J13
  R821    2      B Q_RES_0402LF-10K,5%,1/16W,CHIP,CS31002JB08   I185 @T6G_MB_LIB.T6G(SCH_1):PAGE141
  R820    1      A Q_RES_0402LF-10K,5%,1/16W,EMPTY,CS31002JB08   I186 @T6G_MB_LIB.T6G(SCH_1):PAGE141
   J13    1      1 CONN4_HFK1040L0P1L7H-CONN4_HFK1040-L0P1L-7H,THLF,IA   I195 @T6G_MB_LIB.T6G(SCH_1):PAGE141

UART_VCC_J8 @T6G_MB_LIB.T6G(SCH_1):UART_VCC_J8
  R131    2      B Q_RES_0402LF-10K,5%,1/16W,CHIP,CS31002JB08   I116 @T6G_MB_LIB.T6G(SCH_1):PAGE349
    J8    1      1 CONN4_HFK1040L0P1L7H-CONN4_HFK1040-L0P1L-7H,THLF,IA   I148 @T6G_MB_LIB.T6G(SCH_1):PAGE349
  R130    1      A Q_RES_0402LF-10K,5%,1/16W,EMPTY,CS31002JB08   I113 @T6G_MB_LIB.T6G(SCH_1):PAGE349

USB2_CPU0_P0_DN @T6G_MB_LIB.T6G(SCH_1):USB2_CPU0_P0_DN
   U25  A25 USB00_DN GENOA_SP5-SOCKET6096_13568-001,SMLF,IO,DGA^6000030   I287 @T6G_MB_LIB.T6G(SCH_1):PAGE29
 R6193    1      A Q_RES_0201LF-0,5%,1/20W,CHIP,CS00001JE10     I4 @T6G_MB_LIB.T6G(SCH_1):PAGE158
 R6191    1      A Q_RES_0201LF-0,5%,1/20W,CHIP,CS00001JE10     I5 @T6G_MB_LIB.T6G(SCH_1):PAGE158
  R340    1      A Q_RES_0201LF-49.9,1%,1/20W,EMPTY,CS04991FE06   I121 @T6G_MB_LIB.T6G(SCH_1):PAGE158

USB2_CPU0_P0_DP @T6G_MB_LIB.T6G(SCH_1):USB2_CPU0_P0_DP
   U25  A26 USB00_DP GENOA_SP5-SOCKET6096_13568-001,SMLF,IO,DGA^6000030   I287 @T6G_MB_LIB.T6G(SCH_1):PAGE29
 R6192    1      A Q_RES_0201LF-0,5%,1/20W,CHIP,CS00001JE10     I3 @T6G_MB_LIB.T6G(SCH_1):PAGE158
 R6190    1      A Q_RES_0201LF-0,5%,1/20W,CHIP,CS00001JE10     I6 @T6G_MB_LIB.T6G(SCH_1):PAGE158
  R339    1      A Q_RES_0201LF-49.9,1%,1/20W,EMPTY,CS04991FE06   I120 @T6G_MB_LIB.T6G(SCH_1):PAGE158

USB2_CPU0_P0_HUB1_R_DN @T6G_MB_LIB.T6G(SCH_1):USB2_CPU0_P0_HUB1_R_DN
 U6001   59 DS1_DM CYUSB330468LTXI-CYUSB3304-68LTXI,SMLF,IC,AJ0330400A     I1 @T6G_MB_LIB.T6G(SCH_1):PAGE153
 R6195    1      A Q_RES_0201LF-0,5%,1/20W,CHIP,CS00001JE10    I71 @T6G_MB_LIB.T6G(SCH_1):PAGE158

USB2_CPU0_P0_HUB1_R_DP @T6G_MB_LIB.T6G(SCH_1):USB2_CPU0_P0_HUB1_R_DP
 U6001   60 DS1_DP CYUSB330468LTXI-CYUSB3304-68LTXI,SMLF,IC,AJ0330400A     I1 @T6G_MB_LIB.T6G(SCH_1):PAGE153
 R6194    1      A Q_RES_0201LF-0,5%,1/20W,CHIP,CS00001JE10    I72 @T6G_MB_LIB.T6G(SCH_1):PAGE158

USB2_CPU0_P0_HUB2_R_DN @T6G_MB_LIB.T6G(SCH_1):USB2_CPU0_P0_HUB2_R_DN
 R6197    1      A Q_RES_0201LF-0,5%,1/20W,CHIP,CS00001JE10    I74 @T6G_MB_LIB.T6G(SCH_1):PAGE158
 U6002   10 USB_DM_DN2 TUSB8042AIRGCR-TUSB8042AIRGCR,SMLF,IC,AL008042000   I101 @T6G_MB_LIB.T6G(SCH_1):PAGE155

USB2_CPU0_P0_HUB2_R_DP @T6G_MB_LIB.T6G(SCH_1):USB2_CPU0_P0_HUB2_R_DP
 R6196    1      A Q_RES_0201LF-0,5%,1/20W,CHIP,CS00001JE10    I73 @T6G_MB_LIB.T6G(SCH_1):PAGE158
 U6002    9 USB_DP_DN2 TUSB8042AIRGCR-TUSB8042AIRGCR,SMLF,IC,AL008042000   I101 @T6G_MB_LIB.T6G(SCH_1):PAGE155

USB2_CPU0_P0_R1_DN @T6G_MB_LIB.T6G(SCH_1):USB2_CPU0_P0_R1_DN
 U6001   58  US_DM CYUSB330468LTXI-CYUSB3304-68LTXI,SMLF,IC,AJ0330400A     I1 @T6G_MB_LIB.T6G(SCH_1):PAGE153
 R6191    2      B Q_RES_0201LF-0,5%,1/20W,CHIP,CS00001JE10     I5 @T6G_MB_LIB.T6G(SCH_1):PAGE158

USB2_CPU0_P0_R1_DP @T6G_MB_LIB.T6G(SCH_1):USB2_CPU0_P0_R1_DP
 U6001   57  US_DP CYUSB330468LTXI-CYUSB3304-68LTXI,SMLF,IC,AJ0330400A     I1 @T6G_MB_LIB.T6G(SCH_1):PAGE153
 R6190    2      B Q_RES_0201LF-0,5%,1/20W,CHIP,CS00001JE10     I6 @T6G_MB_LIB.T6G(SCH_1):PAGE158

USB2_CPU0_P0_R2_DN @T6G_MB_LIB.T6G(SCH_1):USB2_CPU0_P0_R2_DN
 R6193    2      B Q_RES_0201LF-0,5%,1/20W,CHIP,CS00001JE10     I4 @T6G_MB_LIB.T6G(SCH_1):PAGE158
  R345    1      A Q_RES_0201LF-49.9,1%,1/20W,EMPTY,CS04991FE06   I124 @T6G_MB_LIB.T6G(SCH_1):PAGE158
 U6002   54 USB_DM_UP TUSB8042AIRGCR-TUSB8042AIRGCR,SMLF,IC,AL008042000   I101 @T6G_MB_LIB.T6G(SCH_1):PAGE155

USB2_CPU0_P0_R2_DP @T6G_MB_LIB.T6G(SCH_1):USB2_CPU0_P0_R2_DP
 R6192    2      B Q_RES_0201LF-0,5%,1/20W,CHIP,CS00001JE10     I3 @T6G_MB_LIB.T6G(SCH_1):PAGE158
  R343    1      A Q_RES_0201LF-49.9,1%,1/20W,EMPTY,CS04991FE06   I125 @T6G_MB_LIB.T6G(SCH_1):PAGE158
 U6002   53 USB_DP_UP TUSB8042AIRGCR-TUSB8042AIRGCR,SMLF,IC,AL008042000   I101 @T6G_MB_LIB.T6G(SCH_1):PAGE155

USB2_CPU0_P10_DN @T6G_MB_LIB.T6G(SCH_1):USB2_CPU0_P10_DN
   U25 DH67 USB10_DN GENOA_SP5-SOCKET6096_13568-001,SMLF,IO,DGA^6000030   I287 @T6G_MB_LIB.T6G(SCH_1):PAGE29
 R3177    2      B Q_RES_0402LF-0,5%,1/16W,CHIP,CS00002JB13   I136 @T6G_MB_LIB.T6G(SCH_1):PAGE341

USB2_CPU0_P10_DP @T6G_MB_LIB.T6G(SCH_1):USB2_CPU0_P10_DP
   U25 DJ67 USB10_DP GENOA_SP5-SOCKET6096_13568-001,SMLF,IO,DGA^6000030   I287 @T6G_MB_LIB.T6G(SCH_1):PAGE29
 R3178    2      B Q_RES_0402LF-0,5%,1/16W,CHIP,CS00002JB13   I135 @T6G_MB_LIB.T6G(SCH_1):PAGE341

USB2_CPU0_P11_DN @T6G_MB_LIB.T6G(SCH_1):USB2_CPU0_P11_DN
   U25 DJ60 USB11_DN GENOA_SP5-SOCKET6096_13568-001,SMLF,IO,DGA^6000030   I287 @T6G_MB_LIB.T6G(SCH_1):PAGE29
   R42    2      B Q_RES_0402LF-0,5%,1/16W,CHIP,CS00002JB13   I166 @T6G_MB_LIB.T6G(SCH_1):PAGE335

USB2_CPU0_P11_DP @T6G_MB_LIB.T6G(SCH_1):USB2_CPU0_P11_DP
   U25 DH60 USB11_DP GENOA_SP5-SOCKET6096_13568-001,SMLF,IO,DGA^6000030   I287 @T6G_MB_LIB.T6G(SCH_1):PAGE29
   R46    2      B Q_RES_0402LF-0,5%,1/16W,CHIP,CS00002JB13   I108 @T6G_MB_LIB.T6G(SCH_1):PAGE335

USB2_CPU0_P1_DN @T6G_MB_LIB.T6G(SCH_1):USB2_CPU0_P1_DN
   U25  A29 USB01_DN GENOA_SP5-SOCKET6096_13568-001,SMLF,IO,DGA^6000030   I287 @T6G_MB_LIB.T6G(SCH_1):PAGE29
   J41  B54 PETP11 SCONN168_ME1016810202011-SCONN168_ME1016810202011,A   I176 @T6G_MB_LIB.T6G(SCH_1):PAGE348

USB2_CPU0_P1_DP @T6G_MB_LIB.T6G(SCH_1):USB2_CPU0_P1_DP
   U25  A28 USB01_DP GENOA_SP5-SOCKET6096_13568-001,SMLF,IO,DGA^6000030   I287 @T6G_MB_LIB.T6G(SCH_1):PAGE29
   J41  B53 PETN11 SCONN168_ME1016810202011-SCONN168_ME1016810202011,A   I176 @T6G_MB_LIB.T6G(SCH_1):PAGE348

USB2_HOST_BMC_B_BUF_DN @T6G_MB_LIB.T6G(SCH_1):USB2_HOST_BMC_B_BUF_DN
 R2791    2      B Q_RES_0402LF-0,5%,1/16W,EMPTY,CS00002JB13    I97 @T6G_MB_LIB.T6G(SCH_1):PAGE358
 R2789    1      A Q_RES_0402LF-0,5%,1/16W,EMPTY,CS00002JB13    I98 @T6G_MB_LIB.T6G(SCH_1):PAGE358
 R4483    1      A Q_RES_0402LF-49.9,1%,1/16W,EMPTY,CS04992FB07   I206 @T6G_MB_LIB.T6G(SCH_1):PAGE358

USB2_HOST_BMC_B_BUF_DP @T6G_MB_LIB.T6G(SCH_1):USB2_HOST_BMC_B_BUF_DP
 R2790    2      B Q_RES_0402LF-0,5%,1/16W,EMPTY,CS00002JB13    I96 @T6G_MB_LIB.T6G(SCH_1):PAGE358
 R2788    1      A Q_RES_0402LF-0,5%,1/16W,EMPTY,CS00002JB13    I99 @T6G_MB_LIB.T6G(SCH_1):PAGE358
 R4482    1      A Q_RES_0402LF-49.9,1%,1/16W,EMPTY,CS04992FB07   I208 @T6G_MB_LIB.T6G(SCH_1):PAGE358

USB2_HOST_BMC_B_DN @T6G_MB_LIB.T6G(SCH_1):USB2_HOST_BMC_B_DN
 R2791    1      A Q_RES_0402LF-0,5%,1/16W,EMPTY,CS00002JB13    I97 @T6G_MB_LIB.T6G(SCH_1):PAGE358
 R3652    2      B Q_RES_0402LF-0,5%,1/16W,CHIP,CS00002JB13   I137 @T6G_MB_LIB.T6G(SCH_1):PAGE358
 R4420    1      A Q_RES_0402LF-49.9,1%,1/16W,EMPTY,CS04992FB07   I202 @T6G_MB_LIB.T6G(SCH_1):PAGE358
   J41  B51 PETP10 SCONN168_ME1016810202011-SCONN168_ME1016810202011,A   I176 @T6G_MB_LIB.T6G(SCH_1):PAGE348

USB2_HOST_BMC_B_DP @T6G_MB_LIB.T6G(SCH_1):USB2_HOST_BMC_B_DP
 R2790    1      A Q_RES_0402LF-0,5%,1/16W,EMPTY,CS00002JB13    I96 @T6G_MB_LIB.T6G(SCH_1):PAGE358
 R3651    2      B Q_RES_0402LF-0,5%,1/16W,CHIP,CS00002JB13   I138 @T6G_MB_LIB.T6G(SCH_1):PAGE358
 R4419    1      A Q_RES_0402LF-49.9,1%,1/16W,EMPTY,CS04992FB07   I203 @T6G_MB_LIB.T6G(SCH_1):PAGE358
   J41  B50 PETN10 SCONN168_ME1016810202011-SCONN168_ME1016810202011,A   I176 @T6G_MB_LIB.T6G(SCH_1):PAGE348

USB2_HUB_BUF_SWB_DN @T6G_MB_LIB.T6G(SCH_1):USB2_HUB_BUF_SWB_DN
 R5236    2      B Q_RES_0402LF-0,5%,1/16W,CHIP,CS00002JB13    I90 @T6G_MB_LIB.T6G(SCH_1):PAGE358
  J112   R1     R1 CONN160_10131762101LF-CONN160_10131762-101LF,THLF,A   I102 @T6G_MB_LIB.T6G(SCH_1):PAGE329

USB2_HUB_BUF_SWB_DP @T6G_MB_LIB.T6G(SCH_1):USB2_HUB_BUF_SWB_DP
 R5234    2      B Q_RES_0402LF-0,5%,1/16W,CHIP,CS00002JB13    I91 @T6G_MB_LIB.T6G(SCH_1):PAGE358
  J112   S1     S1 CONN160_10131762101LF-CONN160_10131762-101LF,THLF,A   I102 @T6G_MB_LIB.T6G(SCH_1):PAGE329

USB2_HUB_BUF_SWB_R_DN @T6G_MB_LIB.T6G(SCH_1):USB2_HUB_BUF_SWB_R_DN
 R2787    2      B Q_RES_0402LF-0,5%,1/16W,CHIP,CS00002JB13    I78 @T6G_MB_LIB.T6G(SCH_1):PAGE358
 U5201    1    D1M TUSB211IRWBR-TUSB211IRWBR,SMLF,EMPTY,AL000211007    I84 @T6G_MB_LIB.T6G(SCH_1):PAGE358
 U5201    8    D2M TUSB211IRWBR-TUSB211IRWBR,SMLF,EMPTY,AL000211007    I84 @T6G_MB_LIB.T6G(SCH_1):PAGE358
 R5236    1      A Q_RES_0402LF-0,5%,1/16W,CHIP,CS00002JB13    I90 @T6G_MB_LIB.T6G(SCH_1):PAGE358
 R2789    2      B Q_RES_0402LF-0,5%,1/16W,EMPTY,CS00002JB13    I98 @T6G_MB_LIB.T6G(SCH_1):PAGE358

USB2_HUB_BUF_SWB_R_DP @T6G_MB_LIB.T6G(SCH_1):USB2_HUB_BUF_SWB_R_DP
 R2786    2      B Q_RES_0402LF-0,5%,1/16W,CHIP,CS00002JB13    I79 @T6G_MB_LIB.T6G(SCH_1):PAGE358
 U5201    2    D1P TUSB211IRWBR-TUSB211IRWBR,SMLF,EMPTY,AL000211007    I84 @T6G_MB_LIB.T6G(SCH_1):PAGE358
 U5201    7    D2P TUSB211IRWBR-TUSB211IRWBR,SMLF,EMPTY,AL000211007    I84 @T6G_MB_LIB.T6G(SCH_1):PAGE358
 R5234    1      A Q_RES_0402LF-0,5%,1/16W,CHIP,CS00002JB13    I91 @T6G_MB_LIB.T6G(SCH_1):PAGE358
 R2788    2      B Q_RES_0402LF-0,5%,1/16W,EMPTY,CS00002JB13    I99 @T6G_MB_LIB.T6G(SCH_1):PAGE358

USB2_HUB_EXT_DN @T6G_MB_LIB.T6G(SCH_1):USB2_HUB_EXT_DN
   J41  B57 PETP12 SCONN168_ME1016810202011-SCONN168_ME1016810202011,A   I176 @T6G_MB_LIB.T6G(SCH_1):PAGE348
 R6195    2      B Q_RES_0201LF-0,5%,1/20W,CHIP,CS00001JE10    I71 @T6G_MB_LIB.T6G(SCH_1):PAGE158
 R6197    2      B Q_RES_0201LF-0,5%,1/20W,CHIP,CS00001JE10    I74 @T6G_MB_LIB.T6G(SCH_1):PAGE158

USB2_HUB_EXT_DP @T6G_MB_LIB.T6G(SCH_1):USB2_HUB_EXT_DP
   J41  B56 PETN12 SCONN168_ME1016810202011-SCONN168_ME1016810202011,A   I176 @T6G_MB_LIB.T6G(SCH_1):PAGE348
 R6194    2      B Q_RES_0201LF-0,5%,1/20W,CHIP,CS00001JE10    I72 @T6G_MB_LIB.T6G(SCH_1):PAGE158
 R6196    2      B Q_RES_0201LF-0,5%,1/20W,CHIP,CS00001JE10    I73 @T6G_MB_LIB.T6G(SCH_1):PAGE158

USB2_HUB_SWB_DN @T6G_MB_LIB.T6G(SCH_1):USB2_HUB_SWB_DN
 R2787    1      A Q_RES_0402LF-0,5%,1/16W,CHIP,CS00002JB13    I78 @T6G_MB_LIB.T6G(SCH_1):PAGE358
  U268    3    DM1 GL852GOHY60-GL852G-OHY60,SMLF,IC,AL000852001   I100 @T6G_MB_LIB.T6G(SCH_1):PAGE358

USB2_HUB_SWB_DP @T6G_MB_LIB.T6G(SCH_1):USB2_HUB_SWB_DP
 R2786    1      A Q_RES_0402LF-0,5%,1/16W,CHIP,CS00002JB13    I79 @T6G_MB_LIB.T6G(SCH_1):PAGE358
  U268    4    DP1 GL852GOHY60-GL852G-OHY60,SMLF,IC,AL000852001   I100 @T6G_MB_LIB.T6G(SCH_1):PAGE358

USB2_P0_R_DN @T6G_MB_LIB.T6G(SCH_1):USB2_P0_R_DN
  U268    1    DM0 GL852GOHY60-GL852G-OHY60,SMLF,IC,AL000852001   I100 @T6G_MB_LIB.T6G(SCH_1):PAGE358
 R3652    1      A Q_RES_0402LF-0,5%,1/16W,CHIP,CS00002JB13   I137 @T6G_MB_LIB.T6G(SCH_1):PAGE358

USB2_P0_R_DP @T6G_MB_LIB.T6G(SCH_1):USB2_P0_R_DP
  U268    2    DP0 GL852GOHY60-GL852G-OHY60,SMLF,IC,AL000852001   I100 @T6G_MB_LIB.T6G(SCH_1):PAGE358
 R3651    1      A Q_RES_0402LF-0,5%,1/16W,CHIP,CS00002JB13   I138 @T6G_MB_LIB.T6G(SCH_1):PAGE358

USB2_P10_DN @T6G_MB_LIB.T6G(SCH_1):USB2_P10_DN
   J35  A68 USB_DATN SCONN168_ME1016810202011-SCONN168_ME1016810202011,A   I168 @T6G_MB_LIB.T6G(SCH_1):PAGE341
 R3177    1      A Q_RES_0402LF-0,5%,1/16W,CHIP,CS00002JB13   I136 @T6G_MB_LIB.T6G(SCH_1):PAGE341

USB2_P10_DP @T6G_MB_LIB.T6G(SCH_1):USB2_P10_DP
   J35  A69 USB_DATP SCONN168_ME1016810202011-SCONN168_ME1016810202011,A   I168 @T6G_MB_LIB.T6G(SCH_1):PAGE341
 R3178    1      A Q_RES_0402LF-0,5%,1/16W,CHIP,CS00002JB13   I135 @T6G_MB_LIB.T6G(SCH_1):PAGE341

USB2_P11_DN @T6G_MB_LIB.T6G(SCH_1):USB2_P11_DN
   J38  A68 USB_DATN SCONN168_ME1016810202011-SCONN168_ME1016810202011,A   I168 @T6G_MB_LIB.T6G(SCH_1):PAGE335
   R42    1      A Q_RES_0402LF-0,5%,1/16W,CHIP,CS00002JB13   I166 @T6G_MB_LIB.T6G(SCH_1):PAGE335

USB2_P11_DP @T6G_MB_LIB.T6G(SCH_1):USB2_P11_DP
   J38  A69 USB_DATP SCONN168_ME1016810202011-SCONN168_ME1016810202011,A   I168 @T6G_MB_LIB.T6G(SCH_1):PAGE335
   R46    1      A Q_RES_0402LF-0,5%,1/16W,CHIP,CS00002JB13   I108 @T6G_MB_LIB.T6G(SCH_1):PAGE335

USB3_CPU0_BMC_HUB1_TX_DN @T6G_MB_LIB.T6G(SCH_1):USB3_CPU0_BMC_HUB1_TX_DN
 U6001   48 DS1_TXM CYUSB330468LTXI-CYUSB3304-68LTXI,SMLF,IC,AJ0330400A     I1 @T6G_MB_LIB.T6G(SCH_1):PAGE153
 C6024    1      A Q_CAP_0402-0.1UF,25V,10%,X7R,CH4104K1B00   I138 @T6G_MB_LIB.T6G(SCH_1):PAGE158

USB3_CPU0_BMC_HUB1_TX_DP @T6G_MB_LIB.T6G(SCH_1):USB3_CPU0_BMC_HUB1_TX_DP
 U6001   47 DS1_TXP CYUSB330468LTXI-CYUSB3304-68LTXI,SMLF,IC,AJ0330400A     I1 @T6G_MB_LIB.T6G(SCH_1):PAGE153
 C6023    1      A Q_CAP_0402-0.1UF,25V,10%,X7R,CH4104K1B00   I137 @T6G_MB_LIB.T6G(SCH_1):PAGE158

USB3_CPU0_BMC_HUB2_TX_DN @T6G_MB_LIB.T6G(SCH_1):USB3_CPU0_BMC_HUB2_TX_DN
 C6026    1      A Q_CAP_0402-0.1UF,25V,10%,X7R,CH4104K1B00   I140 @T6G_MB_LIB.T6G(SCH_1):PAGE158
 U6002   12 USB_SSTXM_DN2 TUSB8042AIRGCR-TUSB8042AIRGCR,SMLF,IC,AL008042000   I101 @T6G_MB_LIB.T6G(SCH_1):PAGE155

USB3_CPU0_BMC_HUB2_TX_DP @T6G_MB_LIB.T6G(SCH_1):USB3_CPU0_BMC_HUB2_TX_DP
 C6025    1      A Q_CAP_0402-0.1UF,25V,10%,X7R,CH4104K1B00   I139 @T6G_MB_LIB.T6G(SCH_1):PAGE158
 U6002   11 USB_SSTXP_DN2 TUSB8042AIRGCR-TUSB8042AIRGCR,SMLF,IC,AL008042000   I101 @T6G_MB_LIB.T6G(SCH_1):PAGE155

USB3_CPU0_BMC_RX_C1_DN @T6G_MB_LIB.T6G(SCH_1):USB3_CPU0_BMC_RX_C1_DN
 U6001   50 DS1_RXM CYUSB330468LTXI-CYUSB3304-68LTXI,SMLF,IC,AJ0330400A     I1 @T6G_MB_LIB.T6G(SCH_1):PAGE153
 C6020    2      2 Q_CAP_DIFFBUS_C0402-DIFF BUS_0.33UF,6.3V,10%,X6S,SA    I86 @T6G_MB_LIB.T6G(SCH_1):PAGE158

USB3_CPU0_BMC_RX_C1_DP @T6G_MB_LIB.T6G(SCH_1):USB3_CPU0_BMC_RX_C1_DP
 U6001   51 DS1_RXP CYUSB330468LTXI-CYUSB3304-68LTXI,SMLF,IC,AJ0330400A     I1 @T6G_MB_LIB.T6G(SCH_1):PAGE153
 C6019    2      2 Q_CAP_DIFFBUS_C0402-DIFF BUS_0.33UF,6.3V,10%,X6S,SA    I85 @T6G_MB_LIB.T6G(SCH_1):PAGE158

USB3_CPU0_BMC_RX_C2_DN @T6G_MB_LIB.T6G(SCH_1):USB3_CPU0_BMC_RX_C2_DN
 C6022    2      2 Q_CAP_DIFFBUS_C0402-DIFF BUS_0.33UF,6.3V,10%,X6S,SA    I88 @T6G_MB_LIB.T6G(SCH_1):PAGE158
 U6002   15 USB_SSRXM_DN2 TUSB8042AIRGCR-TUSB8042AIRGCR,SMLF,IC,AL008042000   I101 @T6G_MB_LIB.T6G(SCH_1):PAGE155

USB3_CPU0_BMC_RX_C2_DP @T6G_MB_LIB.T6G(SCH_1):USB3_CPU0_BMC_RX_C2_DP
 C6021    2      2 Q_CAP_DIFFBUS_C0402-DIFF BUS_0.33UF,6.3V,10%,X6S,SA    I87 @T6G_MB_LIB.T6G(SCH_1):PAGE158
 U6002   14 USB_SSRXP_DN2 TUSB8042AIRGCR-TUSB8042AIRGCR,SMLF,IC,AL008042000   I101 @T6G_MB_LIB.T6G(SCH_1):PAGE155

USB3_CPU0_BMC_RX_DN @T6G_MB_LIB.T6G(SCH_1):USB3_CPU0_BMC_RX_DN
   J41  A60 PERP13 SCONN168_ME1016810202011-SCONN168_ME1016810202011,A   I176 @T6G_MB_LIB.T6G(SCH_1):PAGE348
 C6020    1      1 Q_CAP_DIFFBUS_C0402-DIFF BUS_0.33UF,6.3V,10%,X6S,SA    I86 @T6G_MB_LIB.T6G(SCH_1):PAGE158
 C6022    1      1 Q_CAP_DIFFBUS_C0402-DIFF BUS_0.33UF,6.3V,10%,X6S,SA    I88 @T6G_MB_LIB.T6G(SCH_1):PAGE158

USB3_CPU0_BMC_RX_DP @T6G_MB_LIB.T6G(SCH_1):USB3_CPU0_BMC_RX_DP
   J41  A59 PERN13 SCONN168_ME1016810202011-SCONN168_ME1016810202011,A   I176 @T6G_MB_LIB.T6G(SCH_1):PAGE348
 C6019    1      1 Q_CAP_DIFFBUS_C0402-DIFF BUS_0.33UF,6.3V,10%,X6S,SA    I85 @T6G_MB_LIB.T6G(SCH_1):PAGE158
 C6021    1      1 Q_CAP_DIFFBUS_C0402-DIFF BUS_0.33UF,6.3V,10%,X6S,SA    I87 @T6G_MB_LIB.T6G(SCH_1):PAGE158

USB3_CPU0_BMC_RX_HUB1_DN @T6G_MB_LIB.T6G(SCH_1):USB3_CPU0_BMC_RX_HUB1_DN
 U6001    5 US_TXM CYUSB330468LTXI-CYUSB3304-68LTXI,SMLF,IC,AJ0330400A     I1 @T6G_MB_LIB.T6G(SCH_1):PAGE153
 C6016    1      1 Q_CAP_DIFFBUS_C0402-DIFF BUS_0.33UF,6.3V,10%,X6S,SA    I50 @T6G_MB_LIB.T6G(SCH_1):PAGE158

USB3_CPU0_BMC_RX_HUB1_DP @T6G_MB_LIB.T6G(SCH_1):USB3_CPU0_BMC_RX_HUB1_DP
 U6001    6 US_TXP CYUSB330468LTXI-CYUSB3304-68LTXI,SMLF,IC,AJ0330400A     I1 @T6G_MB_LIB.T6G(SCH_1):PAGE153
 C6015    1      1 Q_CAP_DIFFBUS_C0402-DIFF BUS_0.33UF,6.3V,10%,X6S,SA    I49 @T6G_MB_LIB.T6G(SCH_1):PAGE158

USB3_CPU0_BMC_RX_HUB2_DN @T6G_MB_LIB.T6G(SCH_1):USB3_CPU0_BMC_RX_HUB2_DN
 U6002   56 USB_SSTXM_UP TUSB8042AIRGCR-TUSB8042AIRGCR,SMLF,IC,AL008042000   I101 @T6G_MB_LIB.T6G(SCH_1):PAGE155
 C6018    1      A Q_CAP_0402-0.1UF,25V,10%,X7R,CH4104K1B00   I147 @T6G_MB_LIB.T6G(SCH_1):PAGE158

USB3_CPU0_BMC_RX_HUB2_DP @T6G_MB_LIB.T6G(SCH_1):USB3_CPU0_BMC_RX_HUB2_DP
 U6002   55 USB_SSTXP_UP TUSB8042AIRGCR-TUSB8042AIRGCR,SMLF,IC,AL008042000   I101 @T6G_MB_LIB.T6G(SCH_1):PAGE155
 C6017    1      A Q_CAP_0402-0.1UF,25V,10%,X7R,CH4104K1B00   I148 @T6G_MB_LIB.T6G(SCH_1):PAGE158

USB3_CPU0_BMC_RX_HUB_C_DN @T6G_MB_LIB.T6G(SCH_1):USB3_CPU0_BMC_RX_HUB_C_DN
   U25  E26 USB00_RXN GENOA_SP5-SOCKET6096_13568-001,SMLF,IO,DGA^6000030   I287 @T6G_MB_LIB.T6G(SCH_1):PAGE29
 C6016    2      2 Q_CAP_DIFFBUS_C0402-DIFF BUS_0.33UF,6.3V,10%,X6S,SA    I50 @T6G_MB_LIB.T6G(SCH_1):PAGE158
 C6018    2      B Q_CAP_0402-0.1UF,25V,10%,X7R,CH4104K1B00   I147 @T6G_MB_LIB.T6G(SCH_1):PAGE158

USB3_CPU0_BMC_RX_HUB_C_DP @T6G_MB_LIB.T6G(SCH_1):USB3_CPU0_BMC_RX_HUB_C_DP
   U25  E27 USB00_RXP GENOA_SP5-SOCKET6096_13568-001,SMLF,IO,DGA^6000030   I287 @T6G_MB_LIB.T6G(SCH_1):PAGE29
 C6015    2      2 Q_CAP_DIFFBUS_C0402-DIFF BUS_0.33UF,6.3V,10%,X6S,SA    I49 @T6G_MB_LIB.T6G(SCH_1):PAGE158
 C6017    2      B Q_CAP_0402-0.1UF,25V,10%,X7R,CH4104K1B00   I148 @T6G_MB_LIB.T6G(SCH_1):PAGE158

USB3_CPU0_BMC_TX_BUF_C_DN @T6G_MB_LIB.T6G(SCH_1):USB3_CPU0_BMC_TX_BUF_C_DN
   J41  B60 PETP13 SCONN168_ME1016810202011-SCONN168_ME1016810202011,A   I176 @T6G_MB_LIB.T6G(SCH_1):PAGE348
 C6024    2      B Q_CAP_0402-0.1UF,25V,10%,X7R,CH4104K1B00   I138 @T6G_MB_LIB.T6G(SCH_1):PAGE158
 C6026    2      B Q_CAP_0402-0.1UF,25V,10%,X7R,CH4104K1B00   I140 @T6G_MB_LIB.T6G(SCH_1):PAGE158

USB3_CPU0_BMC_TX_BUF_C_DP @T6G_MB_LIB.T6G(SCH_1):USB3_CPU0_BMC_TX_BUF_C_DP
   J41  B59 PETN13 SCONN168_ME1016810202011-SCONN168_ME1016810202011,A   I176 @T6G_MB_LIB.T6G(SCH_1):PAGE348
 C6023    2      B Q_CAP_0402-0.1UF,25V,10%,X7R,CH4104K1B00   I137 @T6G_MB_LIB.T6G(SCH_1):PAGE158
 C6025    2      B Q_CAP_0402-0.1UF,25V,10%,X7R,CH4104K1B00   I139 @T6G_MB_LIB.T6G(SCH_1):PAGE158

USB3_CPU0_BMC_TX_C1_DN @T6G_MB_LIB.T6G(SCH_1):USB3_CPU0_BMC_TX_C1_DN
 U6001    8 US_RXM CYUSB330468LTXI-CYUSB3304-68LTXI,SMLF,IC,AJ0330400A     I1 @T6G_MB_LIB.T6G(SCH_1):PAGE153
 C6004    2      B Q_CAP_0402-0.1UF,25V,10%,X7R,CH4104K1B00   I143 @T6G_MB_LIB.T6G(SCH_1):PAGE158

USB3_CPU0_BMC_TX_C1_DP @T6G_MB_LIB.T6G(SCH_1):USB3_CPU0_BMC_TX_C1_DP
 U6001    9 US_RXP CYUSB330468LTXI-CYUSB3304-68LTXI,SMLF,IC,AJ0330400A     I1 @T6G_MB_LIB.T6G(SCH_1):PAGE153
 C6003    2      B Q_CAP_0402-0.1UF,25V,10%,X7R,CH4104K1B00   I144 @T6G_MB_LIB.T6G(SCH_1):PAGE158

USB3_CPU0_BMC_TX_C2_DN @T6G_MB_LIB.T6G(SCH_1):USB3_CPU0_BMC_TX_C2_DN
  R346    1      A Q_RES_0201LF-49.9,1%,1/20W,EMPTY,CS04991FE06   I126 @T6G_MB_LIB.T6G(SCH_1):PAGE158
 C6014    2      B Q_CAP_0402-0.1UF,25V,10%,X7R,CH4104K1B00   I141 @T6G_MB_LIB.T6G(SCH_1):PAGE158
 U6002   59 USB_SSRXM_UP TUSB8042AIRGCR-TUSB8042AIRGCR,SMLF,IC,AL008042000   I101 @T6G_MB_LIB.T6G(SCH_1):PAGE155

USB3_CPU0_BMC_TX_C2_DP @T6G_MB_LIB.T6G(SCH_1):USB3_CPU0_BMC_TX_C2_DP
  R344    1      A Q_RES_0201LF-49.9,1%,1/20W,EMPTY,CS04991FE06   I127 @T6G_MB_LIB.T6G(SCH_1):PAGE158
 C6013    2      B Q_CAP_0402-0.1UF,25V,10%,X7R,CH4104K1B00   I142 @T6G_MB_LIB.T6G(SCH_1):PAGE158
 U6002   58 USB_SSRXP_UP TUSB8042AIRGCR-TUSB8042AIRGCR,SMLF,IC,AL008042000   I101 @T6G_MB_LIB.T6G(SCH_1):PAGE155

USB3_CPU0_BMC_TX_DN @T6G_MB_LIB.T6G(SCH_1):USB3_CPU0_BMC_TX_DN
   U25  C26 USB00_TXN GENOA_SP5-SOCKET6096_13568-001,SMLF,IO,DGA^6000030   I287 @T6G_MB_LIB.T6G(SCH_1):PAGE29
 C6014    1      A Q_CAP_0402-0.1UF,25V,10%,X7R,CH4104K1B00   I141 @T6G_MB_LIB.T6G(SCH_1):PAGE158
 C6004    1      A Q_CAP_0402-0.1UF,25V,10%,X7R,CH4104K1B00   I143 @T6G_MB_LIB.T6G(SCH_1):PAGE158
  R342    1      A Q_RES_0402LF-51,5%,1/16W,EMPTY,CS05102JB04   I146 @T6G_MB_LIB.T6G(SCH_1):PAGE158

USB3_CPU0_BMC_TX_DP @T6G_MB_LIB.T6G(SCH_1):USB3_CPU0_BMC_TX_DP
   U25  C25 USB00_TXP GENOA_SP5-SOCKET6096_13568-001,SMLF,IO,DGA^6000030   I287 @T6G_MB_LIB.T6G(SCH_1):PAGE29
 C6013    1      A Q_CAP_0402-0.1UF,25V,10%,X7R,CH4104K1B00   I142 @T6G_MB_LIB.T6G(SCH_1):PAGE158
 C6003    1      A Q_CAP_0402-0.1UF,25V,10%,X7R,CH4104K1B00   I144 @T6G_MB_LIB.T6G(SCH_1):PAGE158
  R341    1      A Q_RES_0402LF-51,5%,1/16W,EMPTY,CS05102JB04   I145 @T6G_MB_LIB.T6G(SCH_1):PAGE158

USB_CPU0_ADD_A0 @T6G_MB_LIB.T6G(SCH_1):USB_CPU0_ADD_A0
 U6003    1     E0 M24128BWMN6TP-M24128-BWMN6TP,SMLF,IC,AKE30Z00613    I64 @T6G_MB_LIB.T6G(SCH_1):PAGE153
 R6222    2      B Q_RES_0402LF-10K,1%,1/16W,CHIP,CS31002FB08    I65 @T6G_MB_LIB.T6G(SCH_1):PAGE153
 R6217    1      A Q_RES_0402LF-10K,1%,1/16W,EMPTY,CS31002FB08    I68 @T6G_MB_LIB.T6G(SCH_1):PAGE153

USB_CPU0_ADD_A1 @T6G_MB_LIB.T6G(SCH_1):USB_CPU0_ADD_A1
 U6003    2     E1 M24128BWMN6TP-M24128-BWMN6TP,SMLF,IC,AKE30Z00613    I64 @T6G_MB_LIB.T6G(SCH_1):PAGE153
 R6219    1      A Q_RES_0402LF-10K,1%,1/16W,CHIP,CS31002FB08    I66 @T6G_MB_LIB.T6G(SCH_1):PAGE153
 R6218    2      B Q_RES_0402LF-10K,1%,1/16W,EMPTY,CS31002FB08    I69 @T6G_MB_LIB.T6G(SCH_1):PAGE153

USB_CPU0_ADD_A2 @T6G_MB_LIB.T6G(SCH_1):USB_CPU0_ADD_A2
 U6003    3     E2 M24128BWMN6TP-M24128-BWMN6TP,SMLF,IC,AKE30Z00613    I64 @T6G_MB_LIB.T6G(SCH_1):PAGE153
 R6221    1      A Q_RES_0402LF-10K,1%,1/16W,CHIP,CS31002FB08    I67 @T6G_MB_LIB.T6G(SCH_1):PAGE153
 R6220    2      B Q_RES_0402LF-10K,1%,1/16W,EMPTY,CS31002FB08    I70 @T6G_MB_LIB.T6G(SCH_1):PAGE153

USB_CPU0_HUB1_MODE_SEL0 @T6G_MB_LIB.T6G(SCH_1):USB_CPU0_HUB1_MODE_SEL0
 U6001   23 MODE_SEL0 CYUSB330468LTXI-CYUSB3304-68LTXI,SMLF,IC,AJ0330400A     I1 @T6G_MB_LIB.T6G(SCH_1):PAGE153
 R6215    2      B Q_RES_0402LF-10K,1%,1/16W,CHIP,CS31002FB08    I89 @T6G_MB_LIB.T6G(SCH_1):PAGE153
 R6216    1      A Q_RES_0402LF-10K,1%,1/16W,EMPTY,CS31002FB08    I90 @T6G_MB_LIB.T6G(SCH_1):PAGE153

USB_CPU0_HUB1_MODE_SEL1 @T6G_MB_LIB.T6G(SCH_1):USB_CPU0_HUB1_MODE_SEL1
 U6001   24 MODE_SEL1 CYUSB330468LTXI-CYUSB3304-68LTXI,SMLF,IC,AJ0330400A     I1 @T6G_MB_LIB.T6G(SCH_1):PAGE153
 R6213    2      B Q_RES_0402LF-10K,1%,1/16W,CHIP,CS31002FB08    I87 @T6G_MB_LIB.T6G(SCH_1):PAGE153
 R6214    1      A Q_RES_0402LF-10K,1%,1/16W,EMPTY,CS31002FB08    I88 @T6G_MB_LIB.T6G(SCH_1):PAGE153

USB_CPU0_HUB1_RREF_SS @T6G_MB_LIB.T6G(SCH_1):USB_CPU0_HUB1_RREF_SS
 U6001   26 RREF_SS CYUSB330468LTXI-CYUSB3304-68LTXI,SMLF,IC,AJ0330400A     I1 @T6G_MB_LIB.T6G(SCH_1):PAGE153
 R6202    2      B Q_RES_0402LF-200,1%,1/16W,CHIP,CS12002FB06    I37 @T6G_MB_LIB.T6G(SCH_1):PAGE153

USB_CPU0_HUB1_RREF_USB2 @T6G_MB_LIB.T6G(SCH_1):USB_CPU0_HUB1_RREF_USB2
 U6001    2 RREF_USB2 CYUSB330468LTXI-CYUSB3304-68LTXI,SMLF,IC,AJ0330400A     I1 @T6G_MB_LIB.T6G(SCH_1):PAGE153
 R6203    2      B Q_RES_0402LF-6.04K,1%,1/16W,CHIP,CS26042FB04    I39 @T6G_MB_LIB.T6G(SCH_1):PAGE153

USB_CPU0_HUB1_VBUS_DS @T6G_MB_LIB.T6G(SCH_1):USB_CPU0_HUB1_VBUS_DS
 U6001   18 VBUS_DS CYUSB330468LTXI-CYUSB3304-68LTXI,SMLF,IC,AJ0330400A     I1 @T6G_MB_LIB.T6G(SCH_1):PAGE153
 R4450    1      A Q_RES_0402LF-0,5%,1/16W,CHIP,CS00002JB13    I27 @T6G_MB_LIB.T6G(SCH_1):PAGE153

USB_CPU0_HUB1_VBUS_US @T6G_MB_LIB.T6G(SCH_1):USB_CPU0_HUB1_VBUS_US
 U6001   17 VBUS_US CYUSB330468LTXI-CYUSB3304-68LTXI,SMLF,IC,AJ0330400A     I1 @T6G_MB_LIB.T6G(SCH_1):PAGE153
 R6208    2      B Q_RES_0402LF-10K,1%,1/16W,CHIP,CS31002FB08    I47 @T6G_MB_LIB.T6G(SCH_1):PAGE153
 R6209    1      A Q_RES_0402LF-10K,1%,1/16W,CHIP,CS31002FB08    I48 @T6G_MB_LIB.T6G(SCH_1):PAGE153

USB_HUB2_MRP_CFG_BC_EN @T6G_MB_LIB.T6G(SCH_1):USB_HUB2_MRP_CFG_BC_EN
 R6303    2      B Q_RES_0402LF-200K,1%,1/16W,EMPTY,CS42002FB05   I169 @T6G_MB_LIB.T6G(SCH_1):PAGE155
 R6302    1      A Q_RES_0402LF-200K,1%,1/16W,CHIP,CS42002FB05   I175 @T6G_MB_LIB.T6G(SCH_1):PAGE155
 R6300    1      A Q_RES_0402LF-0,5%,1/16W,CHIP,CS00002JB13   I181 @T6G_MB_LIB.T6G(SCH_1):PAGE155

USB_HUB2_MRP_CFG_NON_REM @T6G_MB_LIB.T6G(SCH_1):USB_HUB2_MRP_CFG_NON_REM
 R6305    1      A Q_RES_0402LF-0,5%,1/16W,CHIP,CS00002JB13   I150 @T6G_MB_LIB.T6G(SCH_1):PAGE157
 R6308    2      B Q_RES_0402LF-200K,1%,1/16W,EMPTY,CS42002FB05   I153 @T6G_MB_LIB.T6G(SCH_1):PAGE157
 R6309    1      A Q_RES_0402LF-200K,1%,1/16W,CHIP,CS42002FB05   I158 @T6G_MB_LIB.T6G(SCH_1):PAGE157

USB_HUB2_MRP_CFG_STRAP @T6G_MB_LIB.T6G(SCH_1):USB_HUB2_MRP_CFG_STRAP
 R6271    2      B Q_RES_0402LF-0,5%,1/16W,CHIP,CS00002JB13   I102 @T6G_MB_LIB.T6G(SCH_1):PAGE155
 R6273    2      B Q_RES_0402LF-200K,1%,1/16W,EMPTY,CS42002FB05   I104 @T6G_MB_LIB.T6G(SCH_1):PAGE155
 R6272    1      A Q_RES_0402LF-200K,1%,1/16W,CHIP,CS42002FB05   I105 @T6G_MB_LIB.T6G(SCH_1):PAGE155

USB_HUB2_MRP_I2C_SLV_CFG0 @T6G_MB_LIB.T6G(SCH_1):USB_HUB2_MRP_I2C_SLV_CFG0
 R6291    2      B Q_RES_0402LF-0,5%,1/16W,CHIP,CS00002JB13    I75 @T6G_MB_LIB.T6G(SCH_1):PAGE157
 R6294    2      B Q_RES_0402LF-10K,1%,1/16W,CHIP,CS31002FB08    I81 @T6G_MB_LIB.T6G(SCH_1):PAGE157

USB_HUB2_MRP_I2C_SLV_CFG1 @T6G_MB_LIB.T6G(SCH_1):USB_HUB2_MRP_I2C_SLV_CFG1
 R6296    1      A Q_RES_0402LF-0,5%,1/16W,CHIP,CS00002JB13   I183 @T6G_MB_LIB.T6G(SCH_1):PAGE155
 R6298    2      B Q_RES_0402LF-10K,1%,1/16W,CHIP,CS31002FB08   I187 @T6G_MB_LIB.T6G(SCH_1):PAGE155

USB_HUB2_MRP_PROG_FUNC6 @T6G_MB_LIB.T6G(SCH_1):USB_HUB2_MRP_PROG_FUNC6
 R6326    1      A Q_RES_0402LF-4.7K,1%,1/16W,CHIP,CS24702FB06    I89 @T6G_MB_LIB.T6G(SCH_1):PAGE155
 R6327    2      B Q_RES_0402LF-4.7K,1%,1/16W,EMPTY,CS24702FB06    I91 @T6G_MB_LIB.T6G(SCH_1):PAGE155
 R6324    1      A Q_RES_0402LF-0,5%,1/16W,CHIP,CS00002JB13   I118 @T6G_MB_LIB.T6G(SCH_1):PAGE155

USB_HUB2_MRP_PRT_CTL4_GANGPWR @T6G_MB_LIB.T6G(SCH_1):USB_HUB2_MRP_PRT_CTL4_GANGPWR
 R6278    1      A Q_RES_0402LF-10K,1%,1/16W,EMPTY,CS31002FB08   I124 @T6G_MB_LIB.T6G(SCH_1):PAGE157
 R6276    2      B Q_RES_0402LF-0,5%,1/16W,CHIP,CS00002JB13   I125 @T6G_MB_LIB.T6G(SCH_1):PAGE157
 R6277    2      B Q_RES_0402LF-10K,1%,1/16W,EMPTY,CS31002FB08   I130 @T6G_MB_LIB.T6G(SCH_1):PAGE157

USB_HUB2_MRP_RESET_N @T6G_MB_LIB.T6G(SCH_1):USB_HUB2_MRP_RESET_N
 R6317    1      A Q_RES_0402LF-0,5%,1/16W,CHIP,CS00002JB13   I124 @T6G_MB_LIB.T6G(SCH_1):PAGE155
 C6088    1      A Q_CAP_C0805-10UF,16V,10%,X6S,CH6103KEA00   I127 @T6G_MB_LIB.T6G(SCH_1):PAGE155
 R6321    1      A Q_RES_0402LF-47K,0.1%,1/16W,EMPTY,CS34702BB05   I129 @T6G_MB_LIB.T6G(SCH_1):PAGE155
 R6322    2      B Q_RES_0402LF-0,5%,1/16W,CHIP,CS00002JB13   I131 @T6G_MB_LIB.T6G(SCH_1):PAGE155
 R6320    2      B Q_RES_0402LF-10K,1%,1/16W,EMPTY,CS31002FB08   I212 @T6G_MB_LIB.T6G(SCH_1):PAGE155

USB_HUB2_MRP_VBUS_DET @T6G_MB_LIB.T6G(SCH_1):USB_HUB2_MRP_VBUS_DET
 R6286    1      A Q_RES_0402LF-0,5%,1/16W,CHIP,CS00002JB13   I193 @T6G_MB_LIB.T6G(SCH_1):PAGE155
 R6289    2      B Q_RES_0402LF-10K,1%,1/16W,CHIP,CS31002FB08   I195 @T6G_MB_LIB.T6G(SCH_1):PAGE155

USB_HUB2_TI_FULLPWRMGMTZ_MRP_PROG_FUNC3 @T6G_MB_LIB.T6G(SCH_1):USB_HUB2_TI_FULLPWRMGMTZ_MRP_PROG_FUNC3
 R6283    2      B Q_RES_0402LF-1K,1%,1/16W,EMPTY,CS21002FB06    I63 @T6G_MB_LIB.T6G(SCH_1):PAGE157
 U6002   40 FULLPWRMGMTZ||FULLAUTOZ||SMBA1||SS_UP TUSB8042AIRGCR-TUSB8042AIRGCR,SMLF,IC,AL008042000   I119 @T6G_MB_LIB.T6G(SCH_1):PAGE157
 R6284    1      A Q_RES_0402LF-10,1%,1/16W,CHIP,CS01002FB07   I171 @T6G_MB_LIB.T6G(SCH_1):PAGE157

USB_HUB2_TI_GANGED @T6G_MB_LIB.T6G(SCH_1):USB_HUB2_TI_GANGED
 R6290    2      B Q_RES_0402LF-0,5%,1/16W,CHIP,CS00002JB13    I76 @T6G_MB_LIB.T6G(SCH_1):PAGE157
 R6292    2      B Q_RES_0402LF-1K,1%,1/16W,EMPTY,CS21002FB06    I77 @T6G_MB_LIB.T6G(SCH_1):PAGE157
 R6293    1      A Q_RES_0402LF-4.7K,1%,1/16W,CHIP,CS24702FB06    I79 @T6G_MB_LIB.T6G(SCH_1):PAGE157

USB_HUB2_TI_GANGED_MRP_I2C_SLV_CFG0 @T6G_MB_LIB.T6G(SCH_1):USB_HUB2_TI_GANGED_MRP_I2C_SLV_CFG0
 R6291    1      A Q_RES_0402LF-0,5%,1/16W,CHIP,CS00002JB13    I75 @T6G_MB_LIB.T6G(SCH_1):PAGE157
 R6290    1      A Q_RES_0402LF-0,5%,1/16W,CHIP,CS00002JB13    I76 @T6G_MB_LIB.T6G(SCH_1):PAGE157
 U6002   42 GANGED||SMBA2||HS_UP TUSB8042AIRGCR-TUSB8042AIRGCR,SMLF,IC,AL008042000   I119 @T6G_MB_LIB.T6G(SCH_1):PAGE157

USB_HUB2_TI_GRSTZ_MRP_PROG_FUNC1 @T6G_MB_LIB.T6G(SCH_1):USB_HUB2_TI_GRSTZ_MRP_PROG_FUNC1
 U6002   50  GRSTZ TUSB8042AIRGCR-TUSB8042AIRGCR,SMLF,IC,AL008042000   I101 @T6G_MB_LIB.T6G(SCH_1):PAGE155
 R6333    1      A Q_RES_0402LF-47K,0.1%,1/16W,EMPTY,CS34702BB05   I111 @T6G_MB_LIB.T6G(SCH_1):PAGE155
 R6328    2      B Q_RES_0402LF-0,5%,1/16W,CHIP,CS00002JB13   I114 @T6G_MB_LIB.T6G(SCH_1):PAGE155
 C6089    1      A Q_CAP_C0402-1UF,25V,10%,X6S,CH5104KEB02   I145 @T6G_MB_LIB.T6G(SCH_1):PAGE155
 R6329    2      B Q_RES_0402LF-10K,1%,1/16W,EMPTY,CS31002FB08   I213 @T6G_MB_LIB.T6G(SCH_1):PAGE155

USB_HUB2_TI_HS_SUSPEND @T6G_MB_LIB.T6G(SCH_1):USB_HUB2_TI_HS_SUSPEND
 R6304    1      A Q_RES_0402LF-0,5%,1/16W,CHIP,CS00002JB13   I151 @T6G_MB_LIB.T6G(SCH_1):PAGE157
 R6306    2      B Q_RES_0402LF-4.7K,1%,1/16W,CHIP,CS24702FB06   I155 @T6G_MB_LIB.T6G(SCH_1):PAGE157
 R6307    1      A Q_RES_0402LF-4.7K,1%,1/16W,EMPTY,CS24702FB06   I156 @T6G_MB_LIB.T6G(SCH_1):PAGE157

USB_HUB2_TI_HS_SUSPEND_MRP_CFG_NON_REM @T6G_MB_LIB.T6G(SCH_1):USB_HUB2_TI_HS_SUSPEND_MRP_CFG_NON_REM
 U6002   45 AUTOENZ||HS_SUSPEND TUSB8042AIRGCR-TUSB8042AIRGCR,SMLF,IC,AL008042000   I119 @T6G_MB_LIB.T6G(SCH_1):PAGE157
 R6305    2      B Q_RES_0402LF-0,5%,1/16W,CHIP,CS00002JB13   I150 @T6G_MB_LIB.T6G(SCH_1):PAGE157
 R6304    2      B Q_RES_0402LF-0,5%,1/16W,CHIP,CS00002JB13   I151 @T6G_MB_LIB.T6G(SCH_1):PAGE157

USB_HUB2_TI_NC_MRP_ATEST @T6G_MB_LIB.T6G(SCH_1):USB_HUB2_TI_NC_MRP_ATEST
 U6002   60   NC_1 TUSB8042AIRGCR-TUSB8042AIRGCR,SMLF,IC,AL008042000   I101 @T6G_MB_LIB.T6G(SCH_1):PAGE155
 R6330    2      B Q_RES_0402LF-4.7K,1%,1/16W,CHIP,CS24702FB06   I188 @T6G_MB_LIB.T6G(SCH_1):PAGE155

USB_HUB2_TI_OVERCCUR4 @T6G_MB_LIB.T6G(SCH_1):USB_HUB2_TI_OVERCCUR4
 R6295    1      A Q_RES_0402LF-0,5%,1/16W,CHIP,CS00002JB13   I182 @T6G_MB_LIB.T6G(SCH_1):PAGE155
 R6297    2      B Q_RES_0402LF-10K,1%,1/16W,CHIP,CS31002FB08   I185 @T6G_MB_LIB.T6G(SCH_1):PAGE155

USB_HUB2_TI_OVERCUR1 @T6G_MB_LIB.T6G(SCH_1):USB_HUB2_TI_OVERCUR1
 R6310    1      A Q_RES_0402LF-0,5%,1/16W,CHIP,CS00002JB13   I202 @T6G_MB_LIB.T6G(SCH_1):PAGE155
 R6312    2      B Q_RES_0402LF-10K,1%,1/16W,CHIP,CS31002FB08   I205 @T6G_MB_LIB.T6G(SCH_1):PAGE155

USB_HUB2_TI_OVERCUR1_MRP_PROG_FUNC4 @T6G_MB_LIB.T6G(SCH_1):USB_HUB2_TI_OVERCUR1_MRP_PROG_FUNC4
 U6002   46 OVERCUR1Z TUSB8042AIRGCR-TUSB8042AIRGCR,SMLF,IC,AL008042000   I101 @T6G_MB_LIB.T6G(SCH_1):PAGE155
 R6311    2      B Q_RES_0402LF-0,5%,1/16W,CHIP,CS00002JB13   I200 @T6G_MB_LIB.T6G(SCH_1):PAGE155
 R6310    2      B Q_RES_0402LF-0,5%,1/16W,CHIP,CS00002JB13   I202 @T6G_MB_LIB.T6G(SCH_1):PAGE155

USB_HUB2_TI_OVERCUR2 @T6G_MB_LIB.T6G(SCH_1):USB_HUB2_TI_OVERCUR2
 R6313    1      A Q_RES_0402LF-0,5%,1/16W,CHIP,CS00002JB13   I138 @T6G_MB_LIB.T6G(SCH_1):PAGE155
 R6315    2      B Q_RES_0402LF-10K,1%,1/16W,CHIP,CS31002FB08   I140 @T6G_MB_LIB.T6G(SCH_1):PAGE155

USB_HUB2_TI_OVERCUR2_MRP_PROG_FUNC5 @T6G_MB_LIB.T6G(SCH_1):USB_HUB2_TI_OVERCUR2_MRP_PROG_FUNC5
 U6002   47 OVERCUR2Z TUSB8042AIRGCR-TUSB8042AIRGCR,SMLF,IC,AL008042000   I101 @T6G_MB_LIB.T6G(SCH_1):PAGE155
 R6314    2      B Q_RES_0402LF-0,5%,1/16W,CHIP,CS00002JB13   I137 @T6G_MB_LIB.T6G(SCH_1):PAGE155
 R6313    2      B Q_RES_0402LF-0,5%,1/16W,CHIP,CS00002JB13   I138 @T6G_MB_LIB.T6G(SCH_1):PAGE155

USB_HUB2_TI_OVERCUR3 @T6G_MB_LIB.T6G(SCH_1):USB_HUB2_TI_OVERCUR3
 R6301    2      B Q_RES_0402LF-10K,1%,1/16W,CHIP,CS31002FB08   I179 @T6G_MB_LIB.T6G(SCH_1):PAGE155
 R6299    1      A Q_RES_0402LF-0,5%,1/16W,CHIP,CS00002JB13   I180 @T6G_MB_LIB.T6G(SCH_1):PAGE155

USB_HUB2_TI_OVERCUR3_MRP_CFG_BC_EN @T6G_MB_LIB.T6G(SCH_1):USB_HUB2_TI_OVERCUR3_MRP_CFG_BC_EN
 U6002   44 OVERCUR3Z TUSB8042AIRGCR-TUSB8042AIRGCR,SMLF,IC,AL008042000   I101 @T6G_MB_LIB.T6G(SCH_1):PAGE155
 R6299    2      B Q_RES_0402LF-0,5%,1/16W,CHIP,CS00002JB13   I180 @T6G_MB_LIB.T6G(SCH_1):PAGE155
 R6300    2      B Q_RES_0402LF-0,5%,1/16W,CHIP,CS00002JB13   I181 @T6G_MB_LIB.T6G(SCH_1):PAGE155

USB_HUB2_TI_OVERCUR4_MRP_I2C_SLV_CFG1 @T6G_MB_LIB.T6G(SCH_1):USB_HUB2_TI_OVERCUR4_MRP_I2C_SLV_CFG1
 U6002   43 OVERCUR4Z TUSB8042AIRGCR-TUSB8042AIRGCR,SMLF,IC,AL008042000   I101 @T6G_MB_LIB.T6G(SCH_1):PAGE155
 R6295    2      B Q_RES_0402LF-0,5%,1/16W,CHIP,CS00002JB13   I182 @T6G_MB_LIB.T6G(SCH_1):PAGE155
 R6296    2      B Q_RES_0402LF-0,5%,1/16W,CHIP,CS00002JB13   I183 @T6G_MB_LIB.T6G(SCH_1):PAGE155

USB_HUB2_TI_PWRCTL2_MRP_VDD12 @T6G_MB_LIB.T6G(SCH_1):USB_HUB2_TI_PWRCTL2_MRP_VDD12
 U6002   35 PWRCTL2||BATEN2 TUSB8042AIRGCR-TUSB8042AIRGCR,SMLF,IC,AL008042000   I101 @T6G_MB_LIB.T6G(SCH_1):PAGE155
 R6258    2      B Q_RES_0402LF-4.7K,5%,1/16W,EMPTY,CS24702JB10   I164 @T6G_MB_LIB.T6G(SCH_1):PAGE155
 R6259    2      B Q_RES_0402LF-0,5%,1/16W,CHIP,CS00002JB13   I166 @T6G_MB_LIB.T6G(SCH_1):PAGE155

USB_HUB2_TI_PWRCTL3_MRP_VDD33 @T6G_MB_LIB.T6G(SCH_1):USB_HUB2_TI_PWRCTL3_MRP_VDD33
 U6002   33 PWRCTL3||BATEN3 TUSB8042AIRGCR-TUSB8042AIRGCR,SMLF,IC,AL008042000   I101 @T6G_MB_LIB.T6G(SCH_1):PAGE155
 R6270    2      B Q_RES_0402LF-0,5%,1/16W,CHIP,CS00002JB13   I143 @T6G_MB_LIB.T6G(SCH_1):PAGE155

USB_HUB2_TI_PWRCTL_POL @T6G_MB_LIB.T6G(SCH_1):USB_HUB2_TI_PWRCTL_POL
 R6285    1      A Q_RES_0402LF-0,5%,1/16W,CHIP,CS00002JB13   I192 @T6G_MB_LIB.T6G(SCH_1):PAGE155
 R6287    2      B Q_RES_0402LF-1K,1%,1/16W,CHIP,CS21002FB06   I197 @T6G_MB_LIB.T6G(SCH_1):PAGE155
 R6288    1      A Q_RES_0402LF-1K,1%,1/16W,EMPTY,CS21002FB06   I198 @T6G_MB_LIB.T6G(SCH_1):PAGE155

USB_HUB2_TI_PWRCTL_POL_MRP_VBUS_DET @T6G_MB_LIB.T6G(SCH_1):USB_HUB2_TI_PWRCTL_POL_MRP_VBUS_DET
 U6002   41 PWRCTL_POL TUSB8042AIRGCR-TUSB8042AIRGCR,SMLF,IC,AL008042000   I101 @T6G_MB_LIB.T6G(SCH_1):PAGE155
 R6285    2      B Q_RES_0402LF-0,5%,1/16W,CHIP,CS00002JB13   I192 @T6G_MB_LIB.T6G(SCH_1):PAGE155
 R6286    2      B Q_RES_0402LF-0,5%,1/16W,CHIP,CS00002JB13   I193 @T6G_MB_LIB.T6G(SCH_1):PAGE155

USB_HUB2_TI_SMBUSZ_MRP_PROG_FUNC2 @T6G_MB_LIB.T6G(SCH_1):USB_HUB2_TI_SMBUSZ_MRP_PROG_FUNC2
 U6002   39 SMBUSZ||SS_SUSPEND TUSB8042AIRGCR-TUSB8042AIRGCR,SMLF,IC,AL008042000   I119 @T6G_MB_LIB.T6G(SCH_1):PAGE157
 R6282    2      B Q_RES_0402LF-1K,1%,1/16W,EMPTY,CS21002FB06   I138 @T6G_MB_LIB.T6G(SCH_1):PAGE157
 R6281    1      A Q_RES_0402LF-1K,1%,1/16W,EMPTY,CS21002FB06   I139 @T6G_MB_LIB.T6G(SCH_1):PAGE157

USB_HUB2_TI_TEST @T6G_MB_LIB.T6G(SCH_1):USB_HUB2_TI_TEST
 R6323    1      A Q_RES_0402LF-0,5%,1/16W,CHIP,CS00002JB13   I115 @T6G_MB_LIB.T6G(SCH_1):PAGE155
 R6325    1      A Q_RES_0402LF-10K,1%,1/16W,CHIP,CS31002FB08   I116 @T6G_MB_LIB.T6G(SCH_1):PAGE155

USB_HUB2_TI_TEST_MRP_PROG_FUNC6 @T6G_MB_LIB.T6G(SCH_1):USB_HUB2_TI_TEST_MRP_PROG_FUNC6
 U6002   49   TEST TUSB8042AIRGCR-TUSB8042AIRGCR,SMLF,IC,AL008042000   I101 @T6G_MB_LIB.T6G(SCH_1):PAGE155
 R6323    2      B Q_RES_0402LF-0,5%,1/16W,CHIP,CS00002JB13   I115 @T6G_MB_LIB.T6G(SCH_1):PAGE155
 R6324    2      B Q_RES_0402LF-0,5%,1/16W,CHIP,CS00002JB13   I118 @T6G_MB_LIB.T6G(SCH_1):PAGE155

USB_HUB2_TI_USB_DM_DN3_MRP_VDD33 @T6G_MB_LIB.T6G(SCH_1):USB_HUB2_TI_USB_DM_DN3_MRP_VDD33
 U6002   18 USB_DM_DN3 TUSB8042AIRGCR-TUSB8042AIRGCR,SMLF,IC,AL008042000   I101 @T6G_MB_LIB.T6G(SCH_1):PAGE155
 R6264    1      A Q_RES_0402LF-0,5%,1/16W,CHIP,CS00002JB13   I151 @T6G_MB_LIB.T6G(SCH_1):PAGE155

USB_HUB2_TI_USB_DP_DN1_MRP_CFG_STRAP @T6G_MB_LIB.T6G(SCH_1):USB_HUB2_TI_USB_DP_DN1_MRP_CFG_STRAP
 U6002    1 USB_DP_DN1 TUSB8042AIRGCR-TUSB8042AIRGCR,SMLF,IC,AL008042000   I101 @T6G_MB_LIB.T6G(SCH_1):PAGE155
 R6271    1      A Q_RES_0402LF-0,5%,1/16W,CHIP,CS00002JB13   I102 @T6G_MB_LIB.T6G(SCH_1):PAGE155

USB_HUB2_TI_USB_DP_DN3_MRP_VDD12 @T6G_MB_LIB.T6G(SCH_1):USB_HUB2_TI_USB_DP_DN3_MRP_VDD12
 U6002   17 USB_DP_DN3 TUSB8042AIRGCR-TUSB8042AIRGCR,SMLF,IC,AL008042000   I101 @T6G_MB_LIB.T6G(SCH_1):PAGE155
 R6263    1      A Q_RES_0402LF-0,5%,1/16W,CHIP,CS00002JB13   I155 @T6G_MB_LIB.T6G(SCH_1):PAGE155

USB_HUB2_TI_USB_R1_MRP_RBIAS @T6G_MB_LIB.T6G(SCH_1):USB_HUB2_TI_USB_R1_MRP_RBIAS
 U6002   64 USB_R1 TUSB8042AIRGCR-TUSB8042AIRGCR,SMLF,IC,AL008042000   I101 @T6G_MB_LIB.T6G(SCH_1):PAGE155
 R6331    1      A Q_RES_0402LF-9.53K,1%,1/16W,CHIP,CS29532FB06   I207 @T6G_MB_LIB.T6G(SCH_1):PAGE155
 R6332    1      A Q_RES_0402LF-12K,1%,1/16W,CHIP,CS31202FB04   I208 @T6G_MB_LIB.T6G(SCH_1):PAGE155

USB_HUB2_TI_USB_SSRXM_DN3_MRP_VDD12 @T6G_MB_LIB.T6G(SCH_1):USB_HUB2_TI_USB_SSRXM_DN3_MRP_VDD12
 U6002   23 USB_SSRXM_DN3 TUSB8042AIRGCR-TUSB8042AIRGCR,SMLF,IC,AL008042000   I101 @T6G_MB_LIB.T6G(SCH_1):PAGE155
 R6266    1      A Q_RES_0402LF-0,5%,1/16W,CHIP,CS00002JB13   I136 @T6G_MB_LIB.T6G(SCH_1):PAGE155

USB_HUB2_TI_USB_SSRXM_DN4_MRP_VDD12 @T6G_MB_LIB.T6G(SCH_1):USB_HUB2_TI_USB_SSRXM_DN4_MRP_VDD12
 U6002   30 USB_SSRXM_DN4 TUSB8042AIRGCR-TUSB8042AIRGCR,SMLF,IC,AL008042000   I101 @T6G_MB_LIB.T6G(SCH_1):PAGE155
 R6268    1      A Q_RES_0402LF-0,5%,1/16W,CHIP,CS00002JB13   I149 @T6G_MB_LIB.T6G(SCH_1):PAGE155

USB_HUB2_TI_USB_SSRXP_DN1_MRP_VDD12 @T6G_MB_LIB.T6G(SCH_1):USB_HUB2_TI_USB_SSRXP_DN1_MRP_VDD12
 U6002    6 USB_SSRXP_DN1 TUSB8042AIRGCR-TUSB8042AIRGCR,SMLF,IC,AL008042000   I101 @T6G_MB_LIB.T6G(SCH_1):PAGE155
 R6261    1      A Q_RES_0402LF-0,5%,1/16W,CHIP,CS00002JB13   I134 @T6G_MB_LIB.T6G(SCH_1):PAGE155

USB_HUB2_TI_USB_VBUS @T6G_MB_LIB.T6G(SCH_1):USB_HUB2_TI_USB_VBUS
 R6316    1      A Q_RES_0402LF-0,5%,1/16W,CHIP,CS00002JB13   I119 @T6G_MB_LIB.T6G(SCH_1):PAGE155
 R6319    1      A Q_RES_0402LF-10K,1%,1/16W,CHIP,CS31002FB08   I121 @T6G_MB_LIB.T6G(SCH_1):PAGE155
 R6318    2      B Q_RES_0402LF-90.9K,1%,1/16W,CHIP,CS39092FB04   I123 @T6G_MB_LIB.T6G(SCH_1):PAGE155

USB_HUB2_TI_USB_VBUS_MRP_RESET_N @T6G_MB_LIB.T6G(SCH_1):USB_HUB2_TI_USB_VBUS_MRP_RESET_N
 U6002   48 USB_VBUS TUSB8042AIRGCR-TUSB8042AIRGCR,SMLF,IC,AL008042000   I101 @T6G_MB_LIB.T6G(SCH_1):PAGE155
 R6316    2      B Q_RES_0402LF-0,5%,1/16W,CHIP,CS00002JB13   I119 @T6G_MB_LIB.T6G(SCH_1):PAGE155
 R6317    2      B Q_RES_0402LF-0,5%,1/16W,CHIP,CS00002JB13   I124 @T6G_MB_LIB.T6G(SCH_1):PAGE155

USB_HUB2_TI_VDD33_MRP_PROG_FUNC7 @T6G_MB_LIB.T6G(SCH_1):USB_HUB2_TI_VDD33_MRP_PROG_FUNC7
 U6002   16 VDD33_16 TUSB8042AIRGCR-TUSB8042AIRGCR,SMLF,IC,AL008042000   I119 @T6G_MB_LIB.T6G(SCH_1):PAGE157
 R6274    1      A Q_RES_0402LF-0,5%,1/16W,CHIP,CS00002JB13   I142 @T6G_MB_LIB.T6G(SCH_1):PAGE157

USB_HUB2_TI_VDD33_MRP_PRT_CTL4_GANGPWR @T6G_MB_LIB.T6G(SCH_1):USB_HUB2_TI_VDD33_MRP_PRT_CTL4_GANGPWR
 U6002   34 VDD33_34 TUSB8042AIRGCR-TUSB8042AIRGCR,SMLF,IC,AL008042000   I119 @T6G_MB_LIB.T6G(SCH_1):PAGE157
 R6276    1      A Q_RES_0402LF-0,5%,1/16W,CHIP,CS00002JB13   I125 @T6G_MB_LIB.T6G(SCH_1):PAGE157
 R6275    1      A Q_RES_0402LF-0,5%,1/16W,CHIP,CS00002JB13   I131 @T6G_MB_LIB.T6G(SCH_1):PAGE157

USB_HUB2_TI_VDD_MRP_USB3DN_RXDM1 @T6G_MB_LIB.T6G(SCH_1):USB_HUB2_TI_VDD_MRP_USB3DN_RXDM1
 U6002    8  VDD_8 TUSB8042AIRGCR-TUSB8042AIRGCR,SMLF,IC,AL008042000   I119 @T6G_MB_LIB.T6G(SCH_1):PAGE157
 R6262    1      A Q_RES_0402LF-0,5%,1/16W,CHIP,CS00002JB13   I134 @T6G_MB_LIB.T6G(SCH_1):PAGE157

USB_HUB2_TI_VDD_MRP_USB3DN_RXDP4 @T6G_MB_LIB.T6G(SCH_1):USB_HUB2_TI_VDD_MRP_USB3DN_RXDP4
 U6002   31 VDD_31 TUSB8042AIRGCR-TUSB8042AIRGCR,SMLF,IC,AL008042000   I119 @T6G_MB_LIB.T6G(SCH_1):PAGE157
 R6269    1      A Q_RES_0402LF-0,5%,1/16W,CHIP,CS00002JB13   I136 @T6G_MB_LIB.T6G(SCH_1):PAGE157

USB_HUB2_TI_VDD_MRP_USB3DN_TXDM1 @T6G_MB_LIB.T6G(SCH_1):USB_HUB2_TI_VDD_MRP_USB3DN_TXDM1
 U6002    5  VDD_5 TUSB8042AIRGCR-TUSB8042AIRGCR,SMLF,IC,AL008042000   I119 @T6G_MB_LIB.T6G(SCH_1):PAGE157
 R6260    1      A Q_RES_0402LF-0,5%,1/16W,CHIP,CS00002JB13   I170 @T6G_MB_LIB.T6G(SCH_1):PAGE157

USB_HUB2_TI_VDD_MRP_USB3DN_TXDP3 @T6G_MB_LIB.T6G(SCH_1):USB_HUB2_TI_VDD_MRP_USB3DN_TXDP3
 U6002   21 VDD_21 TUSB8042AIRGCR-TUSB8042AIRGCR,SMLF,IC,AL008042000   I119 @T6G_MB_LIB.T6G(SCH_1):PAGE157
 R6265    1      A Q_RES_0402LF-0,5%,1/16W,CHIP,CS00002JB13   I145 @T6G_MB_LIB.T6G(SCH_1):PAGE157

USB_HUB2_TI_VDD_MRP_USB3DN_TXDP4 @T6G_MB_LIB.T6G(SCH_1):USB_HUB2_TI_VDD_MRP_USB3DN_TXDP4
 U6002   28 VDD_28 TUSB8042AIRGCR-TUSB8042AIRGCR,SMLF,IC,AL008042000   I119 @T6G_MB_LIB.T6G(SCH_1):PAGE157
 R6267    1      A Q_RES_0402LF-0,5%,1/16W,CHIP,CS00002JB13   I122 @T6G_MB_LIB.T6G(SCH_1):PAGE157

USB_HUB_DVDD @T6G_MB_LIB.T6G(SCH_1):USB_HUB_DVDD
  U268   21   DVDD GL852GOHY60-GL852G-OHY60,SMLF,IC,AL000852001   I100 @T6G_MB_LIB.T6G(SCH_1):PAGE358
 R3662    2      B Q_RES_0402LF-0,5%,1/16W,CHIP,CS00002JB13   I167 @T6G_MB_LIB.T6G(SCH_1):PAGE358

USB_HUB_OVCUR1 @T6G_MB_LIB.T6G(SCH_1):USB_HUB_OVCUR1
  U268   25 OVCUR1#||SMC GL852GOHY60-GL852G-OHY60,SMLF,IC,AL000852001   I100 @T6G_MB_LIB.T6G(SCH_1):PAGE358
 R3656    2      B Q_RES_0402LF-10K,1%,1/16W,EMPTY,CS31002FB08   I194 @T6G_MB_LIB.T6G(SCH_1):PAGE358

USB_HUB_OVCUR2 @T6G_MB_LIB.T6G(SCH_1):USB_HUB_OVCUR2
  U268   24 OVCUR2#||SMD GL852GOHY60-GL852G-OHY60,SMLF,IC,AL000852001   I100 @T6G_MB_LIB.T6G(SCH_1):PAGE358
 R3657    2      B Q_RES_0402LF-10K,1%,1/16W,EMPTY,CS31002FB08   I195 @T6G_MB_LIB.T6G(SCH_1):PAGE358

USB_HUB_OVCUR3 @T6G_MB_LIB.T6G(SCH_1):USB_HUB_OVCUR3
  U268   20 OVCUR3# GL852GOHY60-GL852G-OHY60,SMLF,IC,AL000852001   I100 @T6G_MB_LIB.T6G(SCH_1):PAGE358
 R3658    2      B Q_RES_0402LF-10K,1%,1/16W,EMPTY,CS31002FB08   I196 @T6G_MB_LIB.T6G(SCH_1):PAGE358

USB_HUB_OVCUR4 @T6G_MB_LIB.T6G(SCH_1):USB_HUB_OVCUR4
  U268   19 OVCUR4# GL852GOHY60-GL852G-OHY60,SMLF,IC,AL000852001   I100 @T6G_MB_LIB.T6G(SCH_1):PAGE358
 R3659    2      B Q_RES_0402LF-10K,1%,1/16W,EMPTY,CS31002FB08   I198 @T6G_MB_LIB.T6G(SCH_1):PAGE358

USB_HUB_PGANG @T6G_MB_LIB.T6G(SCH_1):USB_HUB_PGANG
  U268   23  PGANG GL852GOHY60-GL852G-OHY60,SMLF,IC,AL000852001   I100 @T6G_MB_LIB.T6G(SCH_1):PAGE358
 R3665    1      A Q_RES_0402LF-100K,1%,1/16W,CHIP,CS41002FB09   I182 @T6G_MB_LIB.T6G(SCH_1):PAGE358

USB_HUB_PSELF @T6G_MB_LIB.T6G(SCH_1):USB_HUB_PSELF
  U268   22  PSELF GL852GOHY60-GL852G-OHY60,SMLF,IC,AL000852001   I100 @T6G_MB_LIB.T6G(SCH_1):PAGE358
 R3663    2      B Q_RES_0402LF-10K,1%,1/16W,CHIP,CS31002FB08   I186 @T6G_MB_LIB.T6G(SCH_1):PAGE358
 R3664    1      A Q_RES_0402LF-10K,1%,1/16W,EMPTY,CS31002FB08   I187 @T6G_MB_LIB.T6G(SCH_1):PAGE358

USB_HUB_RREF @T6G_MB_LIB.T6G(SCH_1):USB_HUB_RREF
  U268    8   RREF GL852GOHY60-GL852G-OHY60,SMLF,IC,AL000852001   I100 @T6G_MB_LIB.T6G(SCH_1):PAGE358
 R3653    1      A Q_RES_0402LF-680,1%,1/16W,CHIP,CS16802FB03   I139 @T6G_MB_LIB.T6G(SCH_1):PAGE358

USB_HUB_TEST @T6G_MB_LIB.T6G(SCH_1):USB_HUB_TEST
  U268   18 TEST||SCL GL852GOHY60-GL852G-OHY60,SMLF,IC,AL000852001   I100 @T6G_MB_LIB.T6G(SCH_1):PAGE358
 R3666    1      A Q_RES_0402LF-0,5%,1/16W,CHIP,CS00002JB13   I199 @T6G_MB_LIB.T6G(SCH_1):PAGE358

USB_HUB_XTAL_IN @T6G_MB_LIB.T6G(SCH_1):USB_HUB_XTAL_IN
  U268   10     X1 GL852GOHY60-GL852G-OHY60,SMLF,IC,AL000852001   I100 @T6G_MB_LIB.T6G(SCH_1):PAGE358
 Y8004    1     X1 Q_XTAL_4P_13BI_24GND-12MHZ,SMLF,MISC,BG6120000B0   I210 @T6G_MB_LIB.T6G(SCH_1):PAGE358
 C2029    1      A Q_CAP_0402-15PF,50V,5%,C0G,CH01506JB06   I212 @T6G_MB_LIB.T6G(SCH_1):PAGE358

USB_HUB_XTAL_OUT @T6G_MB_LIB.T6G(SCH_1):USB_HUB_XTAL_OUT
  U268   11     X2 GL852GOHY60-GL852G-OHY60,SMLF,IC,AL000852001   I100 @T6G_MB_LIB.T6G(SCH_1):PAGE358
 Y8004    3     X2 Q_XTAL_4P_13BI_24GND-12MHZ,SMLF,MISC,BG6120000B0   I210 @T6G_MB_LIB.T6G(SCH_1):PAGE358
 C2030    1      A Q_CAP_0402-15PF,50V,5%,C0G,CH01506JB06   I211 @T6G_MB_LIB.T6G(SCH_1):PAGE358

UV_ADR_P2V5_COMP @T6G_MB_LIB.T6G(SCH_1):UV_ADR_P2V5_COMP
 U8007    1     1+ LM4040AIM3X25NOPB-LM4040AIM3X-2.5/NOPB,SMLF,IC,AL4A    I51 @T6G_MB_LIB.T6G(SCH_1):PAGE372
 R8113    2      B Q_RES_0402LF-10K,1%,1/16W,CHIP,CS31002FB08    I52 @T6G_MB_LIB.T6G(SCH_1):PAGE372
 C8017    1      A Q_CAP_C0402-100NF,50V,10%,EMPTY,CH4106K1B01    I59 @T6G_MB_LIB.T6G(SCH_1):PAGE372
 U8008    1    IN- AP331AWG7-AP331AWG-7,SMLF,IC,AL000331011    I71 @T6G_MB_LIB.T6G(SCH_1):PAGE372

UV_ALERT_N @T6G_MB_LIB.T6G(SCH_1):UV_ALERT_N
 R6038    1      A Q_RES_0402LF-0,5%,1/16W,CHIP,CS00002JB13    I21 @T6G_MB_LIB.T6G(SCH_1):PAGE79
   U18  B10 PT23A||PCLKT0_1 LCMXO3LF9400C5BG484C-LCMXO3LF-9400C-5BG484C,SMLF,IA    I94 @T6G_MB_LIB.T6G(SCH_1):PAGE79

UV_P2V5_COMP @T6G_MB_LIB.T6G(SCH_1):UV_P2V5_COMP
 R8120    2      B Q_RES_0402LF-10K,1%,1/16W,CHIP,CS31002FB08    I72 @T6G_MB_LIB.T6G(SCH_1):PAGE372
 C8020    1      A Q_CAP_C0402-100NF,50V,10%,EMPTY,CH4106K1B01    I79 @T6G_MB_LIB.T6G(SCH_1):PAGE372
 U8010    1    IN- AP331AWG7-AP331AWG-7,SMLF,IC,AL000331011    I80 @T6G_MB_LIB.T6G(SCH_1):PAGE372
 U8009    1     1+ LM4040AIM3X25NOPB-LM4040AIM3X-2.5/NOPB,SMLF,IC,AL4A    I93 @T6G_MB_LIB.T6G(SCH_1):PAGE372

VFG3P3_CLK_GEN @T6G_MB_LIB.T6G(SCH_1):VFG3P3_CLK_GEN
   L17    2      2 Q_INDUCTOR_SMLF-FCM2012KF-601T/0.5A,IND,CX601T05003    I33 @T6G_MB_LIB.T6G(SCH_1):PAGE232
 C1883    1      A Q_CAP_C0805-10UF,25V,10%,X6S,CH6104KEA00    I36 @T6G_MB_LIB.T6G(SCH_1):PAGE232
 C2257    1      A Q_CAP_0402-0.1UF,25V,10%,X7R,CH4104K1B00    I37 @T6G_MB_LIB.T6G(SCH_1):PAGE232
 C1886    1      A Q_CAP_0402-0.1UF,25V,10%,X7R,CH4104K1B00    I40 @T6G_MB_LIB.T6G(SCH_1):PAGE232
 C1889    1      A Q_CAP_0402-0.1UF,25V,10%,X7R,CH4104K1B00    I41 @T6G_MB_LIB.T6G(SCH_1):PAGE232
   C95    1      A Q_CAP_0402-0.1UF,25V,10%,X7R,CH4104K1B00    I42 @T6G_MB_LIB.T6G(SCH_1):PAGE232
 R4077    1      A Q_RES_0402LF-1,1%,1/16W,CHIP,CS-1002FB04    I43 @T6G_MB_LIB.T6G(SCH_1):PAGE232
  U247   11 VDD3.3_11 9FGL0251DKILFT-9FGL0251DKILFT,SMLF,IC,AL000251002    I77 @T6G_MB_LIB.T6G(SCH_1):PAGE232
  U247   20 VDD3.3_20 9FGL0251DKILFT-9FGL0251DKILFT,SMLF,IC,AL000251002    I77 @T6G_MB_LIB.T6G(SCH_1):PAGE232
  U247    7 VDDDIG3.3 9FGL0251DKILFT-9FGL0251DKILFT,SMLF,IC,AL000251002    I77 @T6G_MB_LIB.T6G(SCH_1):PAGE232
  U247    3 VDDXTAL3.3 9FGL0251DKILFT-9FGL0251DKILFT,SMLF,IC,AL000251002    I77 @T6G_MB_LIB.T6G(SCH_1):PAGE232

VFG_3P3A_CLK_GEN @T6G_MB_LIB.T6G(SCH_1):VFG_3P3A_CLK_GEN
 R4077    2      B Q_RES_0402LF-1,1%,1/16W,CHIP,CS-1002FB04    I43 @T6G_MB_LIB.T6G(SCH_1):PAGE232
 C1884    1      A Q_CAP_C0402-1UF,25V,10%,X6S,CH5104KEB02    I68 @T6G_MB_LIB.T6G(SCH_1):PAGE232
   C97    1      A Q_CAP_0402-0.1UF,25V,10%,X7R,CH4104K1B00    I69 @T6G_MB_LIB.T6G(SCH_1):PAGE232
  U247   16 VDDA3.3 9FGL0251DKILFT-9FGL0251DKILFT,SMLF,IC,AL000251002    I77 @T6G_MB_LIB.T6G(SCH_1):PAGE232

VIRTUAL_RESEAT @T6G_MB_LIB.T6G(SCH_1):VIRTUAL_RESEAT
   J41 OA14 RBT_CLK_IN SCONN168_ME1016810202011-SCONN168_ME1016810202011,A   I176 @T6G_MB_LIB.T6G(SCH_1):PAGE348
   U18  F16 PT44C||INITN LCMXO3LF9400C5BG484C-LCMXO3LF-9400C-5BG484C,SMLF,IA    I25 @T6G_MB_LIB.T6G(SCH_1):PAGE79

VIRTUAL_RESEAT_FPGA_N @T6G_MB_LIB.T6G(SCH_1):VIRTUAL_RESEAT_FPGA_N
 R3996    1      A Q_RES_0402LF-0,5%,1/16W,CHIP,CS00002JB13    I17 @T6G_MB_LIB.T6G(SCH_1):PAGE350
 R6031    1      A Q_RES_0402LF-33,5%,1/16W,CHIP,CS03302JB10    I55 @T6G_MB_LIB.T6G(SCH_1):PAGE79

VIRTUAL_RESEAT_FPGA_R_N @T6G_MB_LIB.T6G(SCH_1):VIRTUAL_RESEAT_FPGA_R_N
   U18  E17 PT44D||DONE LCMXO3LF9400C5BG484C-LCMXO3LF-9400C-5BG484C,SMLF,IA    I25 @T6G_MB_LIB.T6G(SCH_1):PAGE79
 R6031    2      B Q_RES_0402LF-33,5%,1/16W,CHIP,CS03302JB10    I55 @T6G_MB_LIB.T6G(SCH_1):PAGE79

VR_P5V_EN @T6G_MB_LIB.T6G(SCH_1):VR_P5V_EN
  R333    2      B Q_RES_0402LF-0,5%,1/16W,CHIP,CS00002JB13     I4 @T6G_MB_LIB.T6G(SCH_1):PAGE273
   Q37    2     G1 MOSFET_NCH_DUAL-PJT138K,SMLF,IC,BAM138K0003     I9 @T6G_MB_LIB.T6G(SCH_1):PAGE273
  R334    1      A Q_RES_0402LF-100K,1%,1/16W,CHIP,CS41002FB09     I7 @T6G_MB_LIB.T6G(SCH_1):PAGE273

VR_P5V_EN_D @T6G_MB_LIB.T6G(SCH_1):VR_P5V_EN_D
 R4638    2      B Q_RES_1206LF-243,1%,1/4W,CHIP,CS12436F201    I45 @T6G_MB_LIB.T6G(SCH_1):PAGE273
  U324    D      D MOSFET_NCH_GDS_ESD_PROTECTED-2N7002K,SMLF,IC,BAM70A    I62 @T6G_MB_LIB.T6G(SCH_1):PAGE273
 R4639    2      B Q_RES_1206LF-243,1%,1/4W,CHIP,CS12436F201    I74 @T6G_MB_LIB.T6G(SCH_1):PAGE273
 R4640    2      B Q_RES_1206LF-243,1%,1/4W,CHIP,CS12436F201    I75 @T6G_MB_LIB.T6G(SCH_1):PAGE273
 R4641    2      B Q_RES_1206LF-243,1%,1/4W,CHIP,CS12436F201    I76 @T6G_MB_LIB.T6G(SCH_1):PAGE273

VR_P5V_EN_D_R @T6G_MB_LIB.T6G(SCH_1):VR_P5V_EN_D_R
 R1654    1      A Q_RES_0402LF-1K,1%,1/16W,CHIP,CS21002FB06    I22 @T6G_MB_LIB.T6G(SCH_1):PAGE273
  R335    2      B Q_RES_0402LF-10K,1%,1/16W,CHIP,CS31002FB08    I15 @T6G_MB_LIB.T6G(SCH_1):PAGE273
   Q57    4      4 MOSFET_NCH_1D3S-PSMNR58-30YLH,SMLF,IC,BAMNR580000    I23 @T6G_MB_LIB.T6G(SCH_1):PAGE273
 C9226    1      A Q_CAP_C0402-0.22UF,25V,10%,X7R,CH4224K1B01    I38 @T6G_MB_LIB.T6G(SCH_1):PAGE273

VR_P5V_EN_D_R1 @T6G_MB_LIB.T6G(SCH_1):VR_P5V_EN_D_R1
   Q37    3     D2 MOSFET_NCH_DUAL-PJT138K,SMLF,IC,BAM138K0003    I14 @T6G_MB_LIB.T6G(SCH_1):PAGE273
 R1654    2      B Q_RES_0402LF-1K,1%,1/16W,CHIP,CS21002FB06    I22 @T6G_MB_LIB.T6G(SCH_1):PAGE273

VR_P5V_EN_N @T6G_MB_LIB.T6G(SCH_1):VR_P5V_EN_N
   Q37    6     D1 MOSFET_NCH_DUAL-PJT138K,SMLF,IC,BAM138K0003     I9 @T6G_MB_LIB.T6G(SCH_1):PAGE273
  R336    2      B Q_RES_0402LF-100K,1%,1/16W,CHIP,CS41002FB09    I10 @T6G_MB_LIB.T6G(SCH_1):PAGE273
   Q37    5     G2 MOSFET_NCH_DUAL-PJT138K,SMLF,IC,BAM138K0003    I14 @T6G_MB_LIB.T6G(SCH_1):PAGE273
  U324    G      G MOSFET_NCH_GDS_ESD_PROTECTED-2N7002K,SMLF,IC,BAM70A    I62 @T6G_MB_LIB.T6G(SCH_1):PAGE273

VSENSE_P12V_INA230_3_INN @T6G_MB_LIB.T6G(SCH_1):VSENSE_P12V_INA230_3_INN
  U263   12   VINM ISL28022FRZT-ISL28022FRZ-T,SMLF,IC,AL028022003    I94 @T6G_MB_LIB.T6G(SCH_1):PAGE360
 C2020    2      B Q_CAP_0402-0.1UF,25V,10%,X7R,CH4104K1B00   I108 @T6G_MB_LIB.T6G(SCH_1):PAGE360
 R3571    2      B Q_RES_0402LF-10,1%,1/16W,CHIP,CS01002FB07   I110 @T6G_MB_LIB.T6G(SCH_1):PAGE360

VSENSE_P12V_INA230_3_INP @T6G_MB_LIB.T6G(SCH_1):VSENSE_P12V_INA230_3_INP
  U263   13   VINP ISL28022FRZT-ISL28022FRZ-T,SMLF,IC,AL028022003    I94 @T6G_MB_LIB.T6G(SCH_1):PAGE360
 C2020    1      A Q_CAP_0402-0.1UF,25V,10%,X7R,CH4104K1B00   I108 @T6G_MB_LIB.T6G(SCH_1):PAGE360
 R3570    2      B Q_RES_0402LF-10,1%,1/16W,CHIP,CS01002FB07   I109 @T6G_MB_LIB.T6G(SCH_1):PAGE360

VSENSE_P12V_INA230_4_INN @T6G_MB_LIB.T6G(SCH_1):VSENSE_P12V_INA230_4_INN
 R3575    2      B Q_RES_0402LF-10,1%,1/16W,CHIP,CS01002FB07    I33 @T6G_MB_LIB.T6G(SCH_1):PAGE360
  U264   12   VINM ISL28022FRZT-ISL28022FRZ-T,SMLF,IC,AL028022003    I46 @T6G_MB_LIB.T6G(SCH_1):PAGE360
 C2021    2      B Q_CAP_0402-0.1UF,25V,10%,X7R,CH4104K1B00    I71 @T6G_MB_LIB.T6G(SCH_1):PAGE360

VSENSE_P12V_INA230_4_INP @T6G_MB_LIB.T6G(SCH_1):VSENSE_P12V_INA230_4_INP
 R3574    2      B Q_RES_0402LF-10,1%,1/16W,CHIP,CS01002FB07    I35 @T6G_MB_LIB.T6G(SCH_1):PAGE360
  U264   13   VINP ISL28022FRZT-ISL28022FRZ-T,SMLF,IC,AL028022003    I46 @T6G_MB_LIB.T6G(SCH_1):PAGE360
 C2021    1      A Q_CAP_0402-0.1UF,25V,10%,X7R,CH4104K1B00    I71 @T6G_MB_LIB.T6G(SCH_1):PAGE360

VSENSE_P12V_INA230_5_INN @T6G_MB_LIB.T6G(SCH_1):VSENSE_P12V_INA230_5_INN
 R3579    2      B Q_RES_0402LF-10,1%,1/16W,CHIP,CS01002FB07    I56 @T6G_MB_LIB.T6G(SCH_1):PAGE360
  U265   12   VINM ISL28022FRZT-ISL28022FRZ-T,SMLF,IC,AL028022003    I69 @T6G_MB_LIB.T6G(SCH_1):PAGE360
 C2022    2      B Q_CAP_0402-0.1UF,25V,10%,X7R,CH4104K1B00    I72 @T6G_MB_LIB.T6G(SCH_1):PAGE360

VSENSE_P12V_INA230_5_INP @T6G_MB_LIB.T6G(SCH_1):VSENSE_P12V_INA230_5_INP
 R3578    2      B Q_RES_0402LF-10,1%,1/16W,CHIP,CS01002FB07    I58 @T6G_MB_LIB.T6G(SCH_1):PAGE360
  U265   13   VINP ISL28022FRZT-ISL28022FRZ-T,SMLF,IC,AL028022003    I69 @T6G_MB_LIB.T6G(SCH_1):PAGE360
 C2022    1      A Q_CAP_0402-0.1UF,25V,10%,X7R,CH4104K1B00    I72 @T6G_MB_LIB.T6G(SCH_1):PAGE360

VSENSE_P12V_INA230_6_INN @T6G_MB_LIB.T6G(SCH_1):VSENSE_P12V_INA230_6_INN
 R1301    2      B Q_RES_0402LF-10,1%,1/16W,CHIP,CS01002FB07    I11 @T6G_MB_LIB.T6G(SCH_1):PAGE466
 C1111    2      B Q_CAP_0402-0.1UF,25V,10%,X7R,CH4104K1B00    I15 @T6G_MB_LIB.T6G(SCH_1):PAGE466
   U55   12   VINM ISL28022FRZT-ISL28022FRZ-T,SMLF,IC,AL028022003    I28 @T6G_MB_LIB.T6G(SCH_1):PAGE466

VSENSE_P12V_INA230_6_INP @T6G_MB_LIB.T6G(SCH_1):VSENSE_P12V_INA230_6_INP
 R1284    2      B Q_RES_0402LF-10,1%,1/16W,CHIP,CS01002FB07    I10 @T6G_MB_LIB.T6G(SCH_1):PAGE466
 C1111    1      A Q_CAP_0402-0.1UF,25V,10%,X7R,CH4104K1B00    I15 @T6G_MB_LIB.T6G(SCH_1):PAGE466
   U55   13   VINP ISL28022FRZT-ISL28022FRZ-T,SMLF,IC,AL028022003    I28 @T6G_MB_LIB.T6G(SCH_1):PAGE466

VSENSE_P12V_INA230_7_INN @T6G_MB_LIB.T6G(SCH_1):VSENSE_P12V_INA230_7_INN
   U56   12   VINM ISL28022FRZT-ISL28022FRZ-T,SMLF,IC,AL028022003    I29 @T6G_MB_LIB.T6G(SCH_1):PAGE466
 C1112    2      B Q_CAP_0402-0.1UF,25V,10%,X7R,CH4104K1B00    I54 @T6G_MB_LIB.T6G(SCH_1):PAGE466
 R1302    2      B Q_RES_0402LF-10,1%,1/16W,CHIP,CS01002FB07    I55 @T6G_MB_LIB.T6G(SCH_1):PAGE466

VSENSE_P12V_INA230_7_INP @T6G_MB_LIB.T6G(SCH_1):VSENSE_P12V_INA230_7_INP
   U56   13   VINP ISL28022FRZT-ISL28022FRZ-T,SMLF,IC,AL028022003    I29 @T6G_MB_LIB.T6G(SCH_1):PAGE466
 R1291    2      B Q_RES_0402LF-10,1%,1/16W,CHIP,CS01002FB07    I43 @T6G_MB_LIB.T6G(SCH_1):PAGE466
 C1112    1      A Q_CAP_0402-0.1UF,25V,10%,X7R,CH4104K1B00    I54 @T6G_MB_LIB.T6G(SCH_1):PAGE466

VSENSE_P12V_INA230_8_INN @T6G_MB_LIB.T6G(SCH_1):VSENSE_P12V_INA230_8_INN
   U52   12   VINM ISL28022FRZT-ISL28022FRZ-T,SMLF,IC,AL028022003    I57 @T6G_MB_LIB.T6G(SCH_1):PAGE466
 C1110    2      B Q_CAP_0402-0.1UF,25V,10%,X7R,CH4104K1B00    I68 @T6G_MB_LIB.T6G(SCH_1):PAGE466
 R1292    2      B Q_RES_0402LF-10,1%,1/16W,CHIP,CS01002FB07    I75 @T6G_MB_LIB.T6G(SCH_1):PAGE466

VSENSE_P12V_INA230_8_INP @T6G_MB_LIB.T6G(SCH_1):VSENSE_P12V_INA230_8_INP
   U52   13   VINP ISL28022FRZT-ISL28022FRZ-T,SMLF,IC,AL028022003    I57 @T6G_MB_LIB.T6G(SCH_1):PAGE466
 C1110    1      A Q_CAP_0402-0.1UF,25V,10%,X7R,CH4104K1B00    I68 @T6G_MB_LIB.T6G(SCH_1):PAGE466
 R1283    2      B Q_RES_0402LF-10,1%,1/16W,CHIP,CS01002FB07    I74 @T6G_MB_LIB.T6G(SCH_1):PAGE466

VSENSE_P3V3_INA230_1_INN @T6G_MB_LIB.T6G(SCH_1):VSENSE_P3V3_INA230_1_INN
  U266   12   VINM ISL28022FRZT-ISL28022FRZ-T,SMLF,IC,AL028022003    I30 @T6G_MB_LIB.T6G(SCH_1):PAGE295
 R3603    2      B Q_RES_0402LF-10,1%,1/16W,CHIP,CS01002FB07    I43 @T6G_MB_LIB.T6G(SCH_1):PAGE295
 C2027    2      B Q_CAP_0402-0.1UF,25V,10%,X7R,CH4104K1B00    I77 @T6G_MB_LIB.T6G(SCH_1):PAGE295

VSENSE_P3V3_INA230_1_INP @T6G_MB_LIB.T6G(SCH_1):VSENSE_P3V3_INA230_1_INP
  U266   13   VINP ISL28022FRZT-ISL28022FRZ-T,SMLF,IC,AL028022003    I30 @T6G_MB_LIB.T6G(SCH_1):PAGE295
 R3602    2      B Q_RES_0402LF-10,1%,1/16W,CHIP,CS01002FB07    I41 @T6G_MB_LIB.T6G(SCH_1):PAGE295
 C2027    1      A Q_CAP_0402-0.1UF,25V,10%,X7R,CH4104K1B00    I77 @T6G_MB_LIB.T6G(SCH_1):PAGE295

VSENSE_P3V3_INA230_2_INN @T6G_MB_LIB.T6G(SCH_1):VSENSE_P3V3_INA230_2_INN
  U276   12   VINM ISL28022FRZT-ISL28022FRZ-T,SMLF,IC,AL028022003   I129 @T6G_MB_LIB.T6G(SCH_1):PAGE295
 C2071    2      B Q_CAP_0402-0.1UF,25V,10%,X7R,CH4104K1B00   I133 @T6G_MB_LIB.T6G(SCH_1):PAGE295
 R3760    2      B Q_RES_0402LF-10,1%,1/16W,CHIP,CS01002FB07   I134 @T6G_MB_LIB.T6G(SCH_1):PAGE295

VSENSE_P3V3_INA230_2_INP @T6G_MB_LIB.T6G(SCH_1):VSENSE_P3V3_INA230_2_INP
  U276   13   VINP ISL28022FRZT-ISL28022FRZ-T,SMLF,IC,AL028022003   I129 @T6G_MB_LIB.T6G(SCH_1):PAGE295
 R3758    2      B Q_RES_0402LF-10,1%,1/16W,CHIP,CS01002FB07   I132 @T6G_MB_LIB.T6G(SCH_1):PAGE295
 C2071    1      A Q_CAP_0402-0.1UF,25V,10%,X7R,CH4104K1B00   I133 @T6G_MB_LIB.T6G(SCH_1):PAGE295

VSENSE_PVDD11_S3_P0_DP @T6G_MB_LIB.T6G(SCH_1):VSENSE_PVDD11_S3_P0_DP
   U25  DH3 VDD_11_S3_SENSE GENOA_SP5-SOCKET6096_13568-001,SMLF,IO,DGA^6000030   I227 @T6G_MB_LIB.T6G(SCH_1):PAGE27
   TP8    1     TP TP_TP-NA,TP30   I356 @T6G_MB_LIB.T6G(SCH_1):PAGE27
 PR121    1      A Q_RES_0402LF-0,5%,1/16W,CHIP,CS00002JB13    I28 @T6G_MB_LIB.T6G(SCH_1):PAGE182
 PR114    2      B Q_RES_0402LF-49.9,1%,1/16W,CHIP,CS04992FB07    I30 @T6G_MB_LIB.T6G(SCH_1):PAGE182

VSENSE_PVDD11_S3_P0_R @T6G_MB_LIB.T6G(SCH_1):VSENSE_PVDD11_S3_P0_R
  PU21   21  VSEN0 RAA229621GNPHA0-RAA229621GNP#HA0,SMLF,IC,ARF0TGP40A    I24 @T6G_MB_LIB.T6G(SCH_1):PAGE182
 PR121    2      B Q_RES_0402LF-0,5%,1/16W,CHIP,CS00002JB13    I28 @T6G_MB_LIB.T6G(SCH_1):PAGE182
 PC194    1      A Q_CAP_0402-3300PF,50V,10%,X7R,TMP_QCH2336K1B12    I29 @T6G_MB_LIB.T6G(SCH_1):PAGE182

VSENSE_PVDD11_S3_P1_DP @T6G_MB_LIB.T6G(SCH_1):VSENSE_PVDD11_S3_P1_DP
   U26  DH3 VDD_11_S3_SENSE GENOA_SP5-SOCKET6096_13568-001,SMLF,IO,DGA^6000030   I190 @T6G_MB_LIB.T6G(SCH_1):PAGE54
  TP18    1     TP TP_TP-NA,TP30   I240 @T6G_MB_LIB.T6G(SCH_1):PAGE54
 PR384    1      A Q_RES_0402LF-0,5%,1/16W,CHIP,CS00002JB13    I27 @T6G_MB_LIB.T6G(SCH_1):PAGE199
 PR229    2      B Q_RES_0402LF-49.9,1%,1/16W,CHIP,CS04992FB07    I29 @T6G_MB_LIB.T6G(SCH_1):PAGE199

VSENSE_PVDD11_S3_P1_R @T6G_MB_LIB.T6G(SCH_1):VSENSE_PVDD11_S3_P1_R
 PR384    2      B Q_RES_0402LF-0,5%,1/16W,CHIP,CS00002JB13    I27 @T6G_MB_LIB.T6G(SCH_1):PAGE199
 PC639    1      A Q_CAP_0402-3300PF,50V,10%,X7R,TMP_QCH2336K1B12    I28 @T6G_MB_LIB.T6G(SCH_1):PAGE199
  PU54   21  VSEN0 RAA229621GNPHA0-RAA229621GNP#HA0,SMLF,IC,ARF0TGP40A    I86 @T6G_MB_LIB.T6G(SCH_1):PAGE199

VSENSE_PVDD18_S5_P0_DN @T6G_MB_LIB.T6G(SCH_1):VSENSE_PVDD18_S5_P0_DN
   U25  B73 VSS_SENSE_D GENOA_SP5-SOCKET6096_13568-001,SMLF,IO,DGA^6000030   I227 @T6G_MB_LIB.T6G(SCH_1):PAGE27
   TP4    1     TP TP_TP-NA,TP30   I360 @T6G_MB_LIB.T6G(SCH_1):PAGE27
 PR435    2      B Q_RES_0402LF-0,5%,1/16W,CHIP,CS00002JB13    I37 @T6G_MB_LIB.T6G(SCH_1):PAGE184

VSENSE_PVDD18_S5_P0_DP @T6G_MB_LIB.T6G(SCH_1):VSENSE_PVDD18_S5_P0_DP
   U25  C74 VDD_18_S5_SENSE GENOA_SP5-SOCKET6096_13568-001,SMLF,IO,DGA^6000030   I227 @T6G_MB_LIB.T6G(SCH_1):PAGE27
   TP9    1     TP TP_TP-NA,TP30   I355 @T6G_MB_LIB.T6G(SCH_1):PAGE27
 PR434    2      B Q_RES_0402LF-10,1%,1/16W,CHIP,CS01002FB07    I38 @T6G_MB_LIB.T6G(SCH_1):PAGE184

VSENSE_PVDD18_S5_P1_DN @T6G_MB_LIB.T6G(SCH_1):VSENSE_PVDD18_S5_P1_DN
   U26  B73 VSS_SENSE_D GENOA_SP5-SOCKET6096_13568-001,SMLF,IO,DGA^6000030   I190 @T6G_MB_LIB.T6G(SCH_1):PAGE54
  TP14    1     TP TP_TP-NA,TP30   I244 @T6G_MB_LIB.T6G(SCH_1):PAGE54
 PR401    2      B Q_RES_0402LF-0,5%,1/16W,CHIP,CS00002JB13    I35 @T6G_MB_LIB.T6G(SCH_1):PAGE201

VSENSE_PVDD18_S5_P1_DP @T6G_MB_LIB.T6G(SCH_1):VSENSE_PVDD18_S5_P1_DP
   U26  C74 VDD_18_S5_SENSE GENOA_SP5-SOCKET6096_13568-001,SMLF,IO,DGA^6000030   I190 @T6G_MB_LIB.T6G(SCH_1):PAGE54
  TP19    1     TP TP_TP-NA,TP30   I238 @T6G_MB_LIB.T6G(SCH_1):PAGE54
 PR400    2      B Q_RES_0402LF-10,1%,1/16W,CHIP,CS01002FB07    I36 @T6G_MB_LIB.T6G(SCH_1):PAGE201

VSENSE_PVDDCR_CPU0_P0_DP @T6G_MB_LIB.T6G(SCH_1):VSENSE_PVDDCR_CPU0_P0_DP
   U25   C2 VDDCR_CPU0_SENSE GENOA_SP5-SOCKET6096_13568-001,SMLF,IO,DGA^6000030   I227 @T6G_MB_LIB.T6G(SCH_1):PAGE27
   TP7    1     TP TP_TP-NA,TP30   I357 @T6G_MB_LIB.T6G(SCH_1):PAGE27
 PR306    1      A Q_RES_0402LF-0,5%,1/16W,CHIP,CS00002JB13    I61 @T6G_MB_LIB.T6G(SCH_1):PAGE168
 PR294    2      B Q_RES_0402LF-49.9,1%,1/16W,CHIP,CS04992FB07    I72 @T6G_MB_LIB.T6G(SCH_1):PAGE168

VSENSE_PVDDCR_CPU0_P0_VSEN0 @T6G_MB_LIB.T6G(SCH_1):VSENSE_PVDDCR_CPU0_P0_VSEN0
 PC463    1      A Q_CAP_0402-3300PF,50V,10%,X7R,TMP_QCH2336K1B12    I62 @T6G_MB_LIB.T6G(SCH_1):PAGE168
 PR306    2      B Q_RES_0402LF-0,5%,1/16W,CHIP,CS00002JB13    I61 @T6G_MB_LIB.T6G(SCH_1):PAGE168
  PU42   25  VSEN0 RAA229620GNPHA0-RAA229620GNP#HA0,SMLF,IC,ARF0TGP40A   I135 @T6G_MB_LIB.T6G(SCH_1):PAGE168

VSENSE_PVDDCR_CPU0_P1_DP @T6G_MB_LIB.T6G(SCH_1):VSENSE_PVDDCR_CPU0_P1_DP
   U26   C2 VDDCR_CPU0_SENSE GENOA_SP5-SOCKET6096_13568-001,SMLF,IO,DGA^6000030   I190 @T6G_MB_LIB.T6G(SCH_1):PAGE54
  TP17    1     TP TP_TP-NA,TP30   I241 @T6G_MB_LIB.T6G(SCH_1):PAGE54
 PR173    1      A Q_RES_0402LF-0,5%,1/16W,CHIP,CS00002JB13    I59 @T6G_MB_LIB.T6G(SCH_1):PAGE185
 PR161    2      B Q_RES_0402LF-49.9,1%,1/16W,CHIP,CS04992FB07    I70 @T6G_MB_LIB.T6G(SCH_1):PAGE185

VSENSE_PVDDCR_CPU0_P1_VSEN0 @T6G_MB_LIB.T6G(SCH_1):VSENSE_PVDDCR_CPU0_P1_VSEN0
 PR173    2      B Q_RES_0402LF-0,5%,1/16W,CHIP,CS00002JB13    I59 @T6G_MB_LIB.T6G(SCH_1):PAGE185
 PC244    1      A Q_CAP_0402-3300PF,50V,10%,X7R,TMP_QCH2336K1B12    I60 @T6G_MB_LIB.T6G(SCH_1):PAGE185
  PU25   25  VSEN0 RAA229620GNPHA0-RAA229620GNP#HA0,SMLF,IC,ARF0TGP40A   I133 @T6G_MB_LIB.T6G(SCH_1):PAGE185

VSENSE_PVDDCR_CPU1_P0_DP @T6G_MB_LIB.T6G(SCH_1):VSENSE_PVDDCR_CPU1_P0_DP
   U25  DG3 VDDCR_CPU1_SENSE GENOA_SP5-SOCKET6096_13568-001,SMLF,IO,DGA^6000030   I227 @T6G_MB_LIB.T6G(SCH_1):PAGE27
   TP6    1     TP TP_TP-NA,TP30   I358 @T6G_MB_LIB.T6G(SCH_1):PAGE27
  PR51    1      A Q_RES_0402LF-49.9,1%,1/16W,CHIP,CS04992FB07    I36 @T6G_MB_LIB.T6G(SCH_1):PAGE175
  PR68    1      A Q_RES_0402LF-0,5%,1/16W,CHIP,CS00002JB13    I78 @T6G_MB_LIB.T6G(SCH_1):PAGE175

VSENSE_PVDDCR_CPU1_P0_VSEN0 @T6G_MB_LIB.T6G(SCH_1):VSENSE_PVDDCR_CPU1_P0_VSEN0
  PR68    2      B Q_RES_0402LF-0,5%,1/16W,CHIP,CS00002JB13    I78 @T6G_MB_LIB.T6G(SCH_1):PAGE175
  PC68    1      A Q_CAP_0402-3300PF,50V,10%,X7R,TMP_QCH2336K1B12    I80 @T6G_MB_LIB.T6G(SCH_1):PAGE175
  PU12   25  VSEN0 RAA229620GNPHA0-RAA229620GNP#HA0,SMLF,IC,ARF0TGP40A   I128 @T6G_MB_LIB.T6G(SCH_1):PAGE175

VSENSE_PVDDCR_CPU1_P1_DP @T6G_MB_LIB.T6G(SCH_1):VSENSE_PVDDCR_CPU1_P1_DP
   U26  DG3 VDDCR_CPU1_SENSE GENOA_SP5-SOCKET6096_13568-001,SMLF,IO,DGA^6000030   I190 @T6G_MB_LIB.T6G(SCH_1):PAGE54
  TP16    1     TP TP_TP-NA,TP30   I242 @T6G_MB_LIB.T6G(SCH_1):PAGE54
 PR228    1      A Q_RES_0402LF-49.9,1%,1/16W,CHIP,CS04992FB07    I34 @T6G_MB_LIB.T6G(SCH_1):PAGE192
 PR245    1      A Q_RES_0402LF-0,5%,1/16W,CHIP,CS00002JB13    I77 @T6G_MB_LIB.T6G(SCH_1):PAGE192

VSENSE_PVDDCR_CPU1_P1_VSEN0 @T6G_MB_LIB.T6G(SCH_1):VSENSE_PVDDCR_CPU1_P1_VSEN0
 PR245    2      B Q_RES_0402LF-0,5%,1/16W,CHIP,CS00002JB13    I77 @T6G_MB_LIB.T6G(SCH_1):PAGE192
 PC358    1      A Q_CAP_0402-3300PF,50V,10%,X7R,TMP_QCH2336K1B12    I79 @T6G_MB_LIB.T6G(SCH_1):PAGE192
  PU34   25  VSEN0 RAA229620GNPHA0-RAA229620GNP#HA0,SMLF,IC,ARF0TGP40A   I128 @T6G_MB_LIB.T6G(SCH_1):PAGE192

VSENSE_PVDDCR_SOC_P0_DP @T6G_MB_LIB.T6G(SCH_1):VSENSE_PVDDCR_SOC_P0_DP
   U25   B3 VDDCR_SOC_SENSE GENOA_SP5-SOCKET6096_13568-001,SMLF,IO,DGA^6000030   I227 @T6G_MB_LIB.T6G(SCH_1):PAGE27
  TP10    1     TP TP_TP-NA,TP26   I403 @T6G_MB_LIB.T6G(SCH_1):PAGE27
 PR296    2      B Q_RES_0402LF-49.9,1%,1/16W,CHIP,CS04992FB07    I40 @T6G_MB_LIB.T6G(SCH_1):PAGE168
 PR307    1      A Q_RES_0402LF-0,5%,1/16W,CHIP,CS00002JB13    I59 @T6G_MB_LIB.T6G(SCH_1):PAGE168

VSENSE_PVDDCR_SOC_P0_VSEN1 @T6G_MB_LIB.T6G(SCH_1):VSENSE_PVDDCR_SOC_P0_VSEN1
 PR307    2      B Q_RES_0402LF-0,5%,1/16W,CHIP,CS00002JB13    I59 @T6G_MB_LIB.T6G(SCH_1):PAGE168
 PC464    1      A Q_CAP_0402-3300PF,50V,10%,X7R,TMP_QCH2336K1B12    I60 @T6G_MB_LIB.T6G(SCH_1):PAGE168
  PU42   40  VSEN1 RAA229620GNPHA0-RAA229620GNP#HA0,SMLF,IC,ARF0TGP40A   I135 @T6G_MB_LIB.T6G(SCH_1):PAGE168

VSENSE_PVDDCR_SOC_P1_DP @T6G_MB_LIB.T6G(SCH_1):VSENSE_PVDDCR_SOC_P1_DP
   U26   B3 VDDCR_SOC_SENSE GENOA_SP5-SOCKET6096_13568-001,SMLF,IO,DGA^6000030   I190 @T6G_MB_LIB.T6G(SCH_1):PAGE54
  TP20    1     TP TP_TP-NA,TP30   I237 @T6G_MB_LIB.T6G(SCH_1):PAGE54
 PR174    1      A Q_RES_0402LF-0,5%,1/16W,CHIP,CS00002JB13    I57 @T6G_MB_LIB.T6G(SCH_1):PAGE185
 PR163    2      B Q_RES_0402LF-49.9,1%,1/16W,CHIP,CS04992FB07    I39 @T6G_MB_LIB.T6G(SCH_1):PAGE185

VSENSE_PVDDCR_SOC_P1_VSEN1 @T6G_MB_LIB.T6G(SCH_1):VSENSE_PVDDCR_SOC_P1_VSEN1
 PR174    2      B Q_RES_0402LF-0,5%,1/16W,CHIP,CS00002JB13    I57 @T6G_MB_LIB.T6G(SCH_1):PAGE185
 PC245    1      A Q_CAP_0402-3300PF,50V,10%,X7R,TMP_QCH2336K1B12    I58 @T6G_MB_LIB.T6G(SCH_1):PAGE185
  PU25   40  VSEN1 RAA229620GNPHA0-RAA229620GNP#HA0,SMLF,IC,ARF0TGP40A   I133 @T6G_MB_LIB.T6G(SCH_1):PAGE185

VSENSE_PVDDIO_P0_DP @T6G_MB_LIB.T6G(SCH_1):VSENSE_PVDDIO_P0_DP
   U25 BR53 VDDIO_SENSE GENOA_SP5-SOCKET6096_13568-001,SMLF,IO,DGA^6000030   I227 @T6G_MB_LIB.T6G(SCH_1):PAGE27
   TP5    1     TP TP_TP-NA,TP30   I359 @T6G_MB_LIB.T6G(SCH_1):PAGE27
  PR52    1      A Q_RES_0402LF-49.9,1%,1/16W,CHIP,CS04992FB07    I22 @T6G_MB_LIB.T6G(SCH_1):PAGE175
  PR69    1      A Q_RES_0402LF-0,5%,1/16W,CHIP,CS00002JB13    I70 @T6G_MB_LIB.T6G(SCH_1):PAGE175

VSENSE_PVDDIO_P0_VSEN1 @T6G_MB_LIB.T6G(SCH_1):VSENSE_PVDDIO_P0_VSEN1
  PC71    1      A Q_CAP_0402-3300PF,50V,10%,X7R,TMP_QCH2336K1B12    I69 @T6G_MB_LIB.T6G(SCH_1):PAGE175
  PR69    2      B Q_RES_0402LF-0,5%,1/16W,CHIP,CS00002JB13    I70 @T6G_MB_LIB.T6G(SCH_1):PAGE175
  PU12   40  VSEN1 RAA229620GNPHA0-RAA229620GNP#HA0,SMLF,IC,ARF0TGP40A   I128 @T6G_MB_LIB.T6G(SCH_1):PAGE175

VSENSE_PVDDIO_P1_DP @T6G_MB_LIB.T6G(SCH_1):VSENSE_PVDDIO_P1_DP
   U26 BR53 VDDIO_SENSE GENOA_SP5-SOCKET6096_13568-001,SMLF,IO,DGA^6000030   I190 @T6G_MB_LIB.T6G(SCH_1):PAGE54
  TP15    1     TP TP_TP-NA,TP30   I243 @T6G_MB_LIB.T6G(SCH_1):PAGE54
 PR227    1      A Q_RES_0402LF-49.9,1%,1/16W,CHIP,CS04992FB07    I22 @T6G_MB_LIB.T6G(SCH_1):PAGE192
 PR246    1      A Q_RES_0402LF-0,5%,1/16W,CHIP,CS00002JB13    I69 @T6G_MB_LIB.T6G(SCH_1):PAGE192

VSENSE_PVDDIO_P1_VSEN1 @T6G_MB_LIB.T6G(SCH_1):VSENSE_PVDDIO_P1_VSEN1
 PC361    1      A Q_CAP_0402-3300PF,50V,10%,X7R,TMP_QCH2336K1B12    I67 @T6G_MB_LIB.T6G(SCH_1):PAGE192
 PR246    2      B Q_RES_0402LF-0,5%,1/16W,CHIP,CS00002JB13    I69 @T6G_MB_LIB.T6G(SCH_1):PAGE192
  PU34   40  VSEN1 RAA229620GNPHA0-RAA229620GNP#HA0,SMLF,IC,ARF0TGP40A   I128 @T6G_MB_LIB.T6G(SCH_1):PAGE192

VSENSE_VSS_SENSE_A_P0 @T6G_MB_LIB.T6G(SCH_1):VSENSE_VSS_SENSE_A_P0
   U25   C3 VSS_SENSE_A GENOA_SP5-SOCKET6096_13568-001,SMLF,IO,DGA^6000030   I227 @T6G_MB_LIB.T6G(SCH_1):PAGE27
   TP1    1     TP TP_TP-NA,TP26   I404 @T6G_MB_LIB.T6G(SCH_1):PAGE27
 PR297    1      A Q_RES_0402LF-49.9,1%,1/16W,CHIP,CS04992FB07    I36 @T6G_MB_LIB.T6G(SCH_1):PAGE168
 PC463    2      B Q_CAP_0402-3300PF,50V,10%,X7R,TMP_QCH2336K1B12    I62 @T6G_MB_LIB.T6G(SCH_1):PAGE168
 PR295    1      A Q_RES_0402LF-49.9,1%,1/16W,CHIP,CS04992FB07    I44 @T6G_MB_LIB.T6G(SCH_1):PAGE168
 PC464    2      B Q_CAP_0402-3300PF,50V,10%,X7R,TMP_QCH2336K1B12    I60 @T6G_MB_LIB.T6G(SCH_1):PAGE168
  PU42   26  RGND0 RAA229620GNPHA0-RAA229620GNP#HA0,SMLF,IC,ARF0TGP40A   I135 @T6G_MB_LIB.T6G(SCH_1):PAGE168
  PU42   39  RGND1 RAA229620GNPHA0-RAA229620GNP#HA0,SMLF,IC,ARF0TGP40A   I135 @T6G_MB_LIB.T6G(SCH_1):PAGE168

VSENSE_VSS_SENSE_A_P1 @T6G_MB_LIB.T6G(SCH_1):VSENSE_VSS_SENSE_A_P1
   U26   C3 VSS_SENSE_A GENOA_SP5-SOCKET6096_13568-001,SMLF,IO,DGA^6000030   I190 @T6G_MB_LIB.T6G(SCH_1):PAGE54
  TP11    1     TP TP_TP-NA,TP30   I273 @T6G_MB_LIB.T6G(SCH_1):PAGE54
 PR164    1      A Q_RES_0402LF-49.9,1%,1/16W,CHIP,CS04992FB07    I36 @T6G_MB_LIB.T6G(SCH_1):PAGE185
 PC245    2      B Q_CAP_0402-3300PF,50V,10%,X7R,TMP_QCH2336K1B12    I58 @T6G_MB_LIB.T6G(SCH_1):PAGE185
 PR162    1      A Q_RES_0402LF-49.9,1%,1/16W,CHIP,CS04992FB07    I45 @T6G_MB_LIB.T6G(SCH_1):PAGE185
 PC244    2      B Q_CAP_0402-3300PF,50V,10%,X7R,TMP_QCH2336K1B12    I60 @T6G_MB_LIB.T6G(SCH_1):PAGE185
  PU25   26  RGND0 RAA229620GNPHA0-RAA229620GNP#HA0,SMLF,IC,ARF0TGP40A   I133 @T6G_MB_LIB.T6G(SCH_1):PAGE185
  PU25   39  RGND1 RAA229620GNPHA0-RAA229620GNP#HA0,SMLF,IC,ARF0TGP40A   I133 @T6G_MB_LIB.T6G(SCH_1):PAGE185

VSENSE_VSS_SENSE_B_P0 @T6G_MB_LIB.T6G(SCH_1):VSENSE_VSS_SENSE_B_P0
   U25 BR54 VSS_SENSE_B GENOA_SP5-SOCKET6096_13568-001,SMLF,IO,DGA^6000030   I227 @T6G_MB_LIB.T6G(SCH_1):PAGE27
   TP2    1     TP TP_TP-NA,TP30   I362 @T6G_MB_LIB.T6G(SCH_1):PAGE27
  PR50    1      A Q_RES_0402LF-49.9,1%,1/16W,CHIP,CS04992FB07    I19 @T6G_MB_LIB.T6G(SCH_1):PAGE175
  PC71    2      B Q_CAP_0402-3300PF,50V,10%,X7R,TMP_QCH2336K1B12    I69 @T6G_MB_LIB.T6G(SCH_1):PAGE175
  PU12   39  RGND1 RAA229620GNPHA0-RAA229620GNP#HA0,SMLF,IC,ARF0TGP40A   I128 @T6G_MB_LIB.T6G(SCH_1):PAGE175

VSENSE_VSS_SENSE_B_P1 @T6G_MB_LIB.T6G(SCH_1):VSENSE_VSS_SENSE_B_P1
   U26 BR54 VSS_SENSE_B GENOA_SP5-SOCKET6096_13568-001,SMLF,IO,DGA^6000030   I190 @T6G_MB_LIB.T6G(SCH_1):PAGE54
  TP12    1     TP TP_TP-NA,TP30   I272 @T6G_MB_LIB.T6G(SCH_1):PAGE54
 PR460    1      A Q_RES_0402LF-49.9,1%,1/16W,CHIP,CS04992FB07    I19 @T6G_MB_LIB.T6G(SCH_1):PAGE192
 PC361    2      B Q_CAP_0402-3300PF,50V,10%,X7R,TMP_QCH2336K1B12    I67 @T6G_MB_LIB.T6G(SCH_1):PAGE192
  PU34   39  RGND1 RAA229620GNPHA0-RAA229620GNP#HA0,SMLF,IC,ARF0TGP40A   I128 @T6G_MB_LIB.T6G(SCH_1):PAGE192

VSENSE_VSS_SENSE_C_P0 @T6G_MB_LIB.T6G(SCH_1):VSENSE_VSS_SENSE_C_P0
   U25  DJ3 VSS_SENSE_C GENOA_SP5-SOCKET6096_13568-001,SMLF,IO,DGA^6000030   I227 @T6G_MB_LIB.T6G(SCH_1):PAGE27
   TP3    1     TP TP_TP-NA,TP30   I361 @T6G_MB_LIB.T6G(SCH_1):PAGE27
  PR49    1      A Q_RES_0402LF-49.9,1%,1/16W,CHIP,CS04992FB07    I23 @T6G_MB_LIB.T6G(SCH_1):PAGE175
  PC68    2      B Q_CAP_0402-3300PF,50V,10%,X7R,TMP_QCH2336K1B12    I80 @T6G_MB_LIB.T6G(SCH_1):PAGE175
  PU12   26  RGND0 RAA229620GNPHA0-RAA229620GNP#HA0,SMLF,IC,ARF0TGP40A   I128 @T6G_MB_LIB.T6G(SCH_1):PAGE175
 PR115    1      A Q_RES_0402LF-49.9,1%,1/16W,CHIP,CS04992FB07    I15 @T6G_MB_LIB.T6G(SCH_1):PAGE182
  PU21   22  RGND0 RAA229621GNPHA0-RAA229621GNP#HA0,SMLF,IC,ARF0TGP40A    I24 @T6G_MB_LIB.T6G(SCH_1):PAGE182
 PC194    2      B Q_CAP_0402-3300PF,50V,10%,X7R,TMP_QCH2336K1B12    I29 @T6G_MB_LIB.T6G(SCH_1):PAGE182

VSENSE_VSS_SENSE_C_P1 @T6G_MB_LIB.T6G(SCH_1):VSENSE_VSS_SENSE_C_P1
   U26  DJ3 VSS_SENSE_C GENOA_SP5-SOCKET6096_13568-001,SMLF,IO,DGA^6000030   I190 @T6G_MB_LIB.T6G(SCH_1):PAGE54
  TP13    1     TP TP_TP-NA,TP30   I245 @T6G_MB_LIB.T6G(SCH_1):PAGE54
 PR226    1      A Q_RES_0402LF-49.9,1%,1/16W,CHIP,CS04992FB07    I23 @T6G_MB_LIB.T6G(SCH_1):PAGE192
 PC358    2      B Q_CAP_0402-3300PF,50V,10%,X7R,TMP_QCH2336K1B12    I79 @T6G_MB_LIB.T6G(SCH_1):PAGE192
  PU34   26  RGND0 RAA229620GNPHA0-RAA229620GNP#HA0,SMLF,IC,ARF0TGP40A   I128 @T6G_MB_LIB.T6G(SCH_1):PAGE192
 PR288    1      A Q_RES_0402LF-49.9,1%,1/16W,CHIP,CS04992FB07    I15 @T6G_MB_LIB.T6G(SCH_1):PAGE199
 PC639    2      B Q_CAP_0402-3300PF,50V,10%,X7R,TMP_QCH2336K1B12    I28 @T6G_MB_LIB.T6G(SCH_1):PAGE199
  PU54   22  RGND0 RAA229621GNPHA0-RAA229621GNP#HA0,SMLF,IC,ARF0TGP40A    I86 @T6G_MB_LIB.T6G(SCH_1):PAGE199

WAFL_CPU0_TX0_CPU1_RX1_DN @T6G_MB_LIB.T6G(SCH_1):WAFL_CPU0_TX0_CPU1_RX1_DN
   U25  C51 WAFL_TXN0||P5_TXN0 GENOA_SP5-SOCKET6096_13568-001,SMLF,IO,DGA^6000030    I59 @T6G_MB_LIB.T6G(SCH_1):PAGE26
   U26  E47 WAFL_RXN1||P5_RXN1 GENOA_SP5-SOCKET6096_13568-001,SMLF,IO,DGA^6000030   I145 @T6G_MB_LIB.T6G(SCH_1):PAGE53

WAFL_CPU0_TX0_CPU1_RX1_DP @T6G_MB_LIB.T6G(SCH_1):WAFL_CPU0_TX0_CPU1_RX1_DP
   U25  C50 WAFL_TXP0||P5_TXP0 GENOA_SP5-SOCKET6096_13568-001,SMLF,IO,DGA^6000030    I59 @T6G_MB_LIB.T6G(SCH_1):PAGE26
   U26  E46 WAFL_RXP1||P5_RXP1 GENOA_SP5-SOCKET6096_13568-001,SMLF,IO,DGA^6000030   I145 @T6G_MB_LIB.T6G(SCH_1):PAGE53

WAFL_CPU1_TX1_CPU0_RX0_DN @T6G_MB_LIB.T6G(SCH_1):WAFL_CPU1_TX1_CPU0_RX0_DN
   U25  E50 WAFL_RXN0||P5_RXN0 GENOA_SP5-SOCKET6096_13568-001,SMLF,IO,DGA^6000030    I59 @T6G_MB_LIB.T6G(SCH_1):PAGE26
   U26  C48 WAFL_TXN1||P5_TXN1 GENOA_SP5-SOCKET6096_13568-001,SMLF,IO,DGA^6000030   I145 @T6G_MB_LIB.T6G(SCH_1):PAGE53

WAFL_CPU1_TX1_CPU0_RX0_DP @T6G_MB_LIB.T6G(SCH_1):WAFL_CPU1_TX1_CPU0_RX0_DP
   U25  E49 WAFL_RXP0||P5_RXP0 GENOA_SP5-SOCKET6096_13568-001,SMLF,IO,DGA^6000030    I59 @T6G_MB_LIB.T6G(SCH_1):PAGE26
   U26  C47 WAFL_TXP1||P5_TXP1 GENOA_SP5-SOCKET6096_13568-001,SMLF,IO,DGA^6000030   I145 @T6G_MB_LIB.T6G(SCH_1):PAGE53

XTAL_CPU0_X32K_X1 @T6G_MB_LIB.T6G(SCH_1):XTAL_CPU0_X32K_X1
    Y3    1      1 Q_CRYSTAL_SMLF-32.768KHZ,IC,BG632768012   I140 @T6G_MB_LIB.T6G(SCH_1):PAGE28
   U25 DJ14 X32K_X1 GENOA_SP5-SOCKET6096_13568-001,SMLF,IO,DGA^6000030   I188 @T6G_MB_LIB.T6G(SCH_1):PAGE28
  R433    1      A Q_RES_0402LF-20M,1%,1/16W,CHIP,CS62002FB01   I221 @T6G_MB_LIB.T6G(SCH_1):PAGE28
  C215    1      A Q_CAP_C0402-8.2PF,50V,0.1P,NP0,CH-8216TB09   I230 @T6G_MB_LIB.T6G(SCH_1):PAGE28

XTAL_CPU0_X32K_X2 @T6G_MB_LIB.T6G(SCH_1):XTAL_CPU0_X32K_X2
    Y3    2      2 Q_CRYSTAL_SMLF-32.768KHZ,IC,BG632768012   I140 @T6G_MB_LIB.T6G(SCH_1):PAGE28
   U25 DJ13 X32K_X2 GENOA_SP5-SOCKET6096_13568-001,SMLF,IO,DGA^6000030   I188 @T6G_MB_LIB.T6G(SCH_1):PAGE28
  R433    2      B Q_RES_0402LF-20M,1%,1/16W,CHIP,CS62002FB01   I221 @T6G_MB_LIB.T6G(SCH_1):PAGE28
  C216    1      A Q_CAP_C0402-8.2PF,50V,0.1P,NP0,CH-8216TB09   I231 @T6G_MB_LIB.T6G(SCH_1):PAGE28

XTAL_CPU0_X48M_X1 @T6G_MB_LIB.T6G(SCH_1):XTAL_CPU0_X48M_X1
    Y2    1     X1 Q_XTAL_4P_13BI_24GND-48MHZ,SMLF,MISC,BG648000076   I103 @T6G_MB_LIB.T6G(SCH_1):PAGE28
  R432    1      A Q_RES_0402LF-10M,1%,1/16W,CHIP,CS61002FB02   I104 @T6G_MB_LIB.T6G(SCH_1):PAGE28
   U25 DJ17 X48M_X1 GENOA_SP5-SOCKET6096_13568-001,SMLF,IO,DGA^6000030   I188 @T6G_MB_LIB.T6G(SCH_1):PAGE28
  C213    1      A Q_CAP_C0402-3.9P,50V,0.1P,NPO,CH-3916TB01   I232 @T6G_MB_LIB.T6G(SCH_1):PAGE28

XTAL_CPU0_X48M_X2 @T6G_MB_LIB.T6G(SCH_1):XTAL_CPU0_X48M_X2
   U25 DJ16 X48M_X2 GENOA_SP5-SOCKET6096_13568-001,SMLF,IO,DGA^6000030   I188 @T6G_MB_LIB.T6G(SCH_1):PAGE28
 R5102    1      A Q_RES_0402LF-49.9,1%,1/16W,CHIP,CS04992FB07   I195 @T6G_MB_LIB.T6G(SCH_1):PAGE28

XTAL_CPU0_X48M_X2_R @T6G_MB_LIB.T6G(SCH_1):XTAL_CPU0_X48M_X2_R
    Y2    3     X2 Q_XTAL_4P_13BI_24GND-48MHZ,SMLF,MISC,BG648000076   I103 @T6G_MB_LIB.T6G(SCH_1):PAGE28
  R432    2      B Q_RES_0402LF-10M,1%,1/16W,CHIP,CS61002FB02   I104 @T6G_MB_LIB.T6G(SCH_1):PAGE28
 R5102    2      B Q_RES_0402LF-49.9,1%,1/16W,CHIP,CS04992FB07   I195 @T6G_MB_LIB.T6G(SCH_1):PAGE28
  C214    1      A Q_CAP_C0402-3.9P,50V,0.1P,NPO,CH-3916TB01   I233 @T6G_MB_LIB.T6G(SCH_1):PAGE28

XTAL_CPU1_R_X32K_X1 @T6G_MB_LIB.T6G(SCH_1):XTAL_CPU1_R_X32K_X1
  C238    1      A Q_CAP_0402-10PF,50V,1%,NPO,TMP_QCH0106F0B00     I5 @T6G_MB_LIB.T6G(SCH_1):PAGE55
    Y5    1      1 Q_CRYSTAL_SMLF-32.768KHZ,EMPTY,BG632768012     I7 @T6G_MB_LIB.T6G(SCH_1):PAGE55
  R574    1      A Q_RES_0402LF-0,5%,1/16W,EMPTY,CS00002JB13    I24 @T6G_MB_LIB.T6G(SCH_1):PAGE55
  R572    1      A Q_RES_0402LF-20M,1%,1/16W,CHIP,CS62002FB01   I389 @T6G_MB_LIB.T6G(SCH_1):PAGE55

XTAL_CPU1_R_X32K_X2 @T6G_MB_LIB.T6G(SCH_1):XTAL_CPU1_R_X32K_X2
    Y5    2      2 Q_CRYSTAL_SMLF-32.768KHZ,EMPTY,BG632768012     I7 @T6G_MB_LIB.T6G(SCH_1):PAGE55
  C239    1      A Q_CAP_0402-10PF,50V,1%,NPO,TMP_QCH0106F0B00     I9 @T6G_MB_LIB.T6G(SCH_1):PAGE55
  R575    1      A Q_RES_0402LF-0,5%,1/16W,EMPTY,CS00002JB13   I296 @T6G_MB_LIB.T6G(SCH_1):PAGE55
  R572    2      B Q_RES_0402LF-20M,1%,1/16W,CHIP,CS62002FB01   I389 @T6G_MB_LIB.T6G(SCH_1):PAGE55

XTAL_CPU1_X32K_X1 @T6G_MB_LIB.T6G(SCH_1):XTAL_CPU1_X32K_X1
  R574    2      B Q_RES_0402LF-0,5%,1/16W,EMPTY,CS00002JB13    I24 @T6G_MB_LIB.T6G(SCH_1):PAGE55
  R573    2      B Q_RES_0402LF-0,5%,1/16W,CHIP,CS00002JB13    I26 @T6G_MB_LIB.T6G(SCH_1):PAGE55
   U26 DJ14 X32K_X1 GENOA_SP5-SOCKET6096_13568-001,SMLF,IO,DGA^6000030   I182 @T6G_MB_LIB.T6G(SCH_1):PAGE55

XTAL_CPU1_X32K_X2 @T6G_MB_LIB.T6G(SCH_1):XTAL_CPU1_X32K_X2
   U26 DJ13 X32K_X2 GENOA_SP5-SOCKET6096_13568-001,SMLF,IO,DGA^6000030   I182 @T6G_MB_LIB.T6G(SCH_1):PAGE55
  R575    2      B Q_RES_0402LF-0,5%,1/16W,EMPTY,CS00002JB13   I296 @T6G_MB_LIB.T6G(SCH_1):PAGE55

XTAL_CPU1_X48M_X1 @T6G_MB_LIB.T6G(SCH_1):XTAL_CPU1_X48M_X1
  C236    1      A Q_CAP_C0402-2.7PF,50V,0.1PF,NPO,CH-276B0B00     I3 @T6G_MB_LIB.T6G(SCH_1):PAGE55
  R571    1      A Q_RES_0402LF-10M,1%,1/16W,CHIP,CS61002FB02    I10 @T6G_MB_LIB.T6G(SCH_1):PAGE55
    Y4    1     X1 Q_XTAL_4P_13BI_24GND-48MHZ,SMLF,MISC,BG648000076    I12 @T6G_MB_LIB.T6G(SCH_1):PAGE55
   U26 DJ17 X48M_X1 GENOA_SP5-SOCKET6096_13568-001,SMLF,IO,DGA^6000030   I182 @T6G_MB_LIB.T6G(SCH_1):PAGE55

XTAL_CPU1_X48M_X2 @T6G_MB_LIB.T6G(SCH_1):XTAL_CPU1_X48M_X2
   U26 DJ16 X48M_X2 GENOA_SP5-SOCKET6096_13568-001,SMLF,IO,DGA^6000030   I182 @T6G_MB_LIB.T6G(SCH_1):PAGE55
 R5103    1      A Q_RES_0402LF-49.9,1%,1/16W,CHIP,CS04992FB07   I386 @T6G_MB_LIB.T6G(SCH_1):PAGE55

XTAL_CPU1_X48M_X2_R @T6G_MB_LIB.T6G(SCH_1):XTAL_CPU1_X48M_X2_R
  R571    2      B Q_RES_0402LF-10M,1%,1/16W,CHIP,CS61002FB02    I10 @T6G_MB_LIB.T6G(SCH_1):PAGE55
    Y4    3     X2 Q_XTAL_4P_13BI_24GND-48MHZ,SMLF,MISC,BG648000076    I12 @T6G_MB_LIB.T6G(SCH_1):PAGE55
  C237    1      A Q_CAP_C0402-2.7PF,50V,0.1PF,NPO,CH-276B0B00    I15 @T6G_MB_LIB.T6G(SCH_1):PAGE55
 R5103    2      B Q_RES_0402LF-49.9,1%,1/16W,CHIP,CS04992FB07   I386 @T6G_MB_LIB.T6G(SCH_1):PAGE55

XTAL_USB_CPU0_HUB1_XIN @T6G_MB_LIB.T6G(SCH_1):XTAL_USB_CPU0_HUB1_XIN
 U6001   55 XTL_IN CYUSB330468LTXI-CYUSB3304-68LTXI,SMLF,IC,AJ0330400A     I1 @T6G_MB_LIB.T6G(SCH_1):PAGE153
    Y9    1     X1 Q_XTAL_4P_13BI_24GND-26MHZ,SMLF,MISC,BG626000049    I14 @T6G_MB_LIB.T6G(SCH_1):PAGE153
   C91    1      A Q_CAP_C0402-12PF,50V,5%,C0G,CH01206JB05    I92 @T6G_MB_LIB.T6G(SCH_1):PAGE153

XTAL_USB_CPU0_HUB1_XOUT @T6G_MB_LIB.T6G(SCH_1):XTAL_USB_CPU0_HUB1_XOUT
 U6001   54 XTL_OUT CYUSB330468LTXI-CYUSB3304-68LTXI,SMLF,IC,AJ0330400A     I1 @T6G_MB_LIB.T6G(SCH_1):PAGE153
    Y9    3     X2 Q_XTAL_4P_13BI_24GND-26MHZ,SMLF,MISC,BG626000049    I14 @T6G_MB_LIB.T6G(SCH_1):PAGE153
   C93    1      A Q_CAP_0402-15PF,50V,5%,C0G,CH01506JB06    I91 @T6G_MB_LIB.T6G(SCH_1):PAGE153

XTAL_USB_CPU0_HUB2_XIN @T6G_MB_LIB.T6G(SCH_1):XTAL_USB_CPU0_HUB2_XIN
 U6002   62     XI TUSB8042AIRGCR-TUSB8042AIRGCR,SMLF,IC,AL008042000   I119 @T6G_MB_LIB.T6G(SCH_1):PAGE157
 R6257    2      B Q_RES_0402LF-1M,1%,1/16W,CHIP,CS51002FB05   I160 @T6G_MB_LIB.T6G(SCH_1):PAGE157
 Y6000    1     X1 Q_XTAL_4P_13BI_24GND-24MHZ,SMLF,MISC,BG624000101   I164 @T6G_MB_LIB.T6G(SCH_1):PAGE157
 C6091    1      A Q_CAP_0402-27PF,50V,5%,NPO,CH02706JB06   I175 @T6G_MB_LIB.T6G(SCH_1):PAGE157

XTAL_USB_CPU0_HUB2_XOUT @T6G_MB_LIB.T6G(SCH_1):XTAL_USB_CPU0_HUB2_XOUT
 U6002   61     XO TUSB8042AIRGCR-TUSB8042AIRGCR,SMLF,IC,AL008042000   I119 @T6G_MB_LIB.T6G(SCH_1):PAGE157
 R6257    1      A Q_RES_0402LF-1M,1%,1/16W,CHIP,CS51002FB05   I160 @T6G_MB_LIB.T6G(SCH_1):PAGE157
 Y6000    3     X2 Q_XTAL_4P_13BI_24GND-24MHZ,SMLF,MISC,BG624000101   I164 @T6G_MB_LIB.T6G(SCH_1):PAGE157
 C6090    1      A Q_CAP_0402-27PF,50V,5%,NPO,CH02706JB06   I174 @T6G_MB_LIB.T6G(SCH_1):PAGE157

END GLOBAL SIGNAL CROSS REFERENCE
GLOBAL PART CROSS REFERENCE - 14-Sep-2023 AT 16:11:04

 BT2 CONN2_AAABAT029Y19-CONN2_AAA-BAT-029-Y19,THLF,IO,DA
     1 P3V_BAT @T6G_MB_LIB.T6G(SCH_1):P3V_BAT    I86 @T6G_MB_LIB.T6G(SCH_1):PAGE156
     2    GND @T6G_MB_LIB.T6G(SCH_1):GND    I86 @T6G_MB_LIB.T6G(SCH_1):PAGE156

  C1 Q_CAP_0402-0.1UF,25V,10%,X7R,CH4104K1B00
     1 P3V3_AUX @T6G_MB_LIB.T6G(SCH_1):P3V3_AUX   I110 @T6G_MB_LIB.T6G(SCH_1):PAGE361
     2    GND @T6G_MB_LIB.T6G(SCH_1):GND   I110 @T6G_MB_LIB.T6G(SCH_1):PAGE361

  C2 Q_CAP_0402-0.1UF,25V,10%,X7R,CH4104K1B00
     1 P3V3_AUX @T6G_MB_LIB.T6G(SCH_1):P3V3_AUX    I59 @T6G_MB_LIB.T6G(SCH_1):PAGE137
     2    GND @T6G_MB_LIB.T6G(SCH_1):GND    I59 @T6G_MB_LIB.T6G(SCH_1):PAGE137

  C3 Q_CAP_0402-0.1UF,25V,10%,X7R,CH4104K1B00
     1 PVDD11_S3_P0 @T6G_MB_LIB.T6G(SCH_1):PVDD11_S3_P0    I56 @T6G_MB_LIB.T6G(SCH_1):PAGE137
     2    GND @T6G_MB_LIB.T6G(SCH_1):GND    I56 @T6G_MB_LIB.T6G(SCH_1):PAGE137

  C4 Q_CAP_0402-0.1UF,25V,10%,X7R,CH4104K1B00
     1 GPU_3V3IO_RSVD1_ISO @T6G_MB_LIB.T6G(SCH_1):GPU_3V3IO_RSVD1_ISO    I44 @T6G_MB_LIB.T6G(SCH_1):PAGE331
     2    GND @T6G_MB_LIB.T6G(SCH_1):GND    I44 @T6G_MB_LIB.T6G(SCH_1):PAGE331

  C5 Q_CAP_0402-0.1UF,25V,10%,X7R,CH4104K1B00
     1 GPU_3V3IO_RSVD4_ISO @T6G_MB_LIB.T6G(SCH_1):GPU_3V3IO_RSVD4_ISO    I33 @T6G_MB_LIB.T6G(SCH_1):PAGE331
     2    GND @T6G_MB_LIB.T6G(SCH_1):GND    I33 @T6G_MB_LIB.T6G(SCH_1):PAGE331

  C6 Q_CAP_0402-0.1UF,25V,10%,EMPTY,CH4104K1B00
     1 HGX_DETECT_N_ISO @T6G_MB_LIB.T6G(SCH_1):HGX_DETECT_N_ISO   I111 @T6G_MB_LIB.T6G(SCH_1):PAGE331
     2    GND @T6G_MB_LIB.T6G(SCH_1):GND   I111 @T6G_MB_LIB.T6G(SCH_1):PAGE331

  C7 Q_CAP_0402-0.1UF,25V,10%,X7R,CH4104K1B00
     1 GPU_3V3IO_RSVD3_ISO @T6G_MB_LIB.T6G(SCH_1):GPU_3V3IO_RSVD3_ISO    I42 @T6G_MB_LIB.T6G(SCH_1):PAGE331
     2    GND @T6G_MB_LIB.T6G(SCH_1):GND    I42 @T6G_MB_LIB.T6G(SCH_1):PAGE331

  C8 Q_CAP_0402-0.1UF,25V,10%,X7R,CH4104K1B00
     1 P3V3_AUX @T6G_MB_LIB.T6G(SCH_1):P3V3_AUX    I93 @T6G_MB_LIB.T6G(SCH_1):PAGE331
     2    GND @T6G_MB_LIB.T6G(SCH_1):GND    I93 @T6G_MB_LIB.T6G(SCH_1):PAGE331

  C9 Q_CAP_C0402-1UF,25V,10%,EMPTY,CH5104KEB02
     1 I3C_MUX_CPU0_VIO @T6G_MB_LIB.T6G(SCH_1):I3C_MUX_CPU0_VIO   I113 @T6G_MB_LIB.T6G(SCH_1):PAGE138
     2    GND @T6G_MB_LIB.T6G(SCH_1):GND   I113 @T6G_MB_LIB.T6G(SCH_1):PAGE138

 C10 Q_CAP_0402-0.1UF,25V,10%,X7R,CH4104K1B00
     1 P3V3_AUX @T6G_MB_LIB.T6G(SCH_1):P3V3_AUX    I61 @T6G_MB_LIB.T6G(SCH_1):PAGE337
     2    GND @T6G_MB_LIB.T6G(SCH_1):GND    I61 @T6G_MB_LIB.T6G(SCH_1):PAGE337

 C11 Q_CAP_0402-0.1UF,25V,10%,X7R,CH4104K1B00
     1 P3V3_AUX @T6G_MB_LIB.T6G(SCH_1):P3V3_AUX    I89 @T6G_MB_LIB.T6G(SCH_1):PAGE138
     2    GND @T6G_MB_LIB.T6G(SCH_1):GND    I89 @T6G_MB_LIB.T6G(SCH_1):PAGE138

 C12 Q_CAP_0402-0.1UF,25V,10%,X7R,CH4104K1B00
     1 GPU_3V3IO_RSVD0_FFU_ISO @T6G_MB_LIB.T6G(SCH_1):GPU_3V3IO_RSVD0_FFU_ISO    I75 @T6G_MB_LIB.T6G(SCH_1):PAGE332
     2    GND @T6G_MB_LIB.T6G(SCH_1):GND    I75 @T6G_MB_LIB.T6G(SCH_1):PAGE332

 C13 Q_CAP_0402-0.1UF,25V,10%,X7R,CH4104K1B00
     1 PRSNT_CABLE_GPU_B3_ISO_N @T6G_MB_LIB.T6G(SCH_1):PRSNT_CABLE_GPU_B3_ISO_N    I64 @T6G_MB_LIB.T6G(SCH_1):PAGE332
     2    GND @T6G_MB_LIB.T6G(SCH_1):GND    I64 @T6G_MB_LIB.T6G(SCH_1):PAGE332

 C14 Q_CAP_0402-0.1UF,25V,10%,X7R,CH4104K1B00
     1 GPU_3V3IO_RSVD1_FFU_ISO @T6G_MB_LIB.T6G(SCH_1):GPU_3V3IO_RSVD1_FFU_ISO    I73 @T6G_MB_LIB.T6G(SCH_1):PAGE332
     2    GND @T6G_MB_LIB.T6G(SCH_1):GND    I73 @T6G_MB_LIB.T6G(SCH_1):PAGE332

 C15 Q_CAP_0402-0.1UF,25V,10%,X7R,CH4104K1B00
     1 PRSNT_CABLE_GPU_A1_ISO_N @T6G_MB_LIB.T6G(SCH_1):PRSNT_CABLE_GPU_A1_ISO_N    I50 @T6G_MB_LIB.T6G(SCH_1):PAGE332
     2    GND @T6G_MB_LIB.T6G(SCH_1):GND    I50 @T6G_MB_LIB.T6G(SCH_1):PAGE332

 C16 Q_CAP_0402-0.1UF,25V,10%,X7R,CH4104K1B00
     1 GPU_3V3IO_RSVD3_FFU_ISO @T6G_MB_LIB.T6G(SCH_1):GPU_3V3IO_RSVD3_FFU_ISO   I130 @T6G_MB_LIB.T6G(SCH_1):PAGE332
     2    GND @T6G_MB_LIB.T6G(SCH_1):GND   I130 @T6G_MB_LIB.T6G(SCH_1):PAGE332

 C17 Q_CAP_0402-0.1UF,25V,10%,X7R,CH4104K1B00
     1 GPU_3V3IO_RSVD5_FFU_ISO @T6G_MB_LIB.T6G(SCH_1):GPU_3V3IO_RSVD5_FFU_ISO   I118 @T6G_MB_LIB.T6G(SCH_1):PAGE332
     2    GND @T6G_MB_LIB.T6G(SCH_1):GND   I118 @T6G_MB_LIB.T6G(SCH_1):PAGE332

 C18 Q_CAP_0402-0.1UF,25V,10%,X7R,CH4104K1B00
     1 SWB_HSC_PWRGD_ISO @T6G_MB_LIB.T6G(SCH_1):SWB_HSC_PWRGD_ISO    I61 @T6G_MB_LIB.T6G(SCH_1):PAGE332
     2    GND @T6G_MB_LIB.T6G(SCH_1):GND    I61 @T6G_MB_LIB.T6G(SCH_1):PAGE332

 C19 Q_CAP_0402-0.1UF,25V,10%,X7R,CH4104K1B00
     1 PRSNT_CABLE_GPU_A2_ISO_N @T6G_MB_LIB.T6G(SCH_1):PRSNT_CABLE_GPU_A2_ISO_N   I127 @T6G_MB_LIB.T6G(SCH_1):PAGE332
     2    GND @T6G_MB_LIB.T6G(SCH_1):GND   I127 @T6G_MB_LIB.T6G(SCH_1):PAGE332

 C20 Q_CAP_C0402-0.1UF,16V,10%,X7R,CH4103K1B08
     1 P3V3_AUX @T6G_MB_LIB.T6G(SCH_1):P3V3_AUX    I42 @T6G_MB_LIB.T6G(SCH_1):PAGE84
     2    GND @T6G_MB_LIB.T6G(SCH_1):GND    I42 @T6G_MB_LIB.T6G(SCH_1):PAGE84

 C21 Q_CAP_0402-0.1UF,25V,10%,X7R,CH4104K1B00
     1 P12V_OCP_SFF_R @T6G_MB_LIB.T6G(SCH_1):P12V_OCP_SFF_R    I89 @T6G_MB_LIB.T6G(SCH_1):PAGE335
     2    GND @T6G_MB_LIB.T6G(SCH_1):GND    I89 @T6G_MB_LIB.T6G(SCH_1):PAGE335

 C22 Q_CAP_C0402-0.01UF,50V,10%,EMPTY,CH31006KB18
     1  U9_NR @T6G_MB_LIB.T6G(SCH_1):U9_NR   I113 @T6G_MB_LIB.T6G(SCH_1):PAGE156
     2    GND @T6G_MB_LIB.T6G(SCH_1):GND   I113 @T6G_MB_LIB.T6G(SCH_1):PAGE156

 C23 Q_CAP_0402-0.1UF,25V,10%,X7R,CH4104K1B00
     1 P3V3_AUX @T6G_MB_LIB.T6G(SCH_1):P3V3_AUX    I26 @T6G_MB_LIB.T6G(SCH_1):PAGE137
     2    GND @T6G_MB_LIB.T6G(SCH_1):GND    I26 @T6G_MB_LIB.T6G(SCH_1):PAGE137

 C24 Q_CAP_C0402-10UF,6.3V,20%,EMPTY,CH6101MEB01
     1 PVDD18_S5_P0 @T6G_MB_LIB.T6G(SCH_1):PVDD18_S5_P0   I112 @T6G_MB_LIB.T6G(SCH_1):PAGE138
     2    GND @T6G_MB_LIB.T6G(SCH_1):GND   I112 @T6G_MB_LIB.T6G(SCH_1):PAGE138

 C25 Q_CAP_0402-0.1UF,25V,10%,X7R,CH4104K1B00
     1 P3V3_AUX @T6G_MB_LIB.T6G(SCH_1):P3V3_AUX    I69 @T6G_MB_LIB.T6G(SCH_1):PAGE138
     2    GND @T6G_MB_LIB.T6G(SCH_1):GND    I69 @T6G_MB_LIB.T6G(SCH_1):PAGE138

 C26 Q_CAP_0402-0.1UF,25V,10%,X7R,CH4104K1B00
     1   P3V3 @T6G_MB_LIB.T6G(SCH_1):P3V3    I29 @T6G_MB_LIB.T6G(SCH_1):PAGE137
     2    GND @T6G_MB_LIB.T6G(SCH_1):GND    I29 @T6G_MB_LIB.T6G(SCH_1):PAGE137

 C27 Q_CAP_0402-0.1UF,25V,10%,X7R,CH4104K1B00
     1 P12V_OCP_SFF_R @T6G_MB_LIB.T6G(SCH_1):P12V_OCP_SFF_R   I163 @T6G_MB_LIB.T6G(SCH_1):PAGE335
     2    GND @T6G_MB_LIB.T6G(SCH_1):GND   I163 @T6G_MB_LIB.T6G(SCH_1):PAGE335

 C28 Q_CAP_C0402-10UF,6.3V,20%,X6S,CH6101MEB01
     1 P3V3_9ZXL045_P1_VDD @T6G_MB_LIB.T6G(SCH_1):P3V3_9ZXL045_P1_VDD    I79 @T6G_MB_LIB.T6G(SCH_1):PAGE379
     2    GND @T6G_MB_LIB.T6G(SCH_1):GND    I79 @T6G_MB_LIB.T6G(SCH_1):PAGE379

 C29 Q_CAP_C0402-0.22UF,25V,10%,X7R,CH4224K1B01
     1 SW_P3V3_EN_ISO_R @T6G_MB_LIB.T6G(SCH_1):SW_P3V3_EN_ISO_R   I116 @T6G_MB_LIB.T6G(SCH_1):PAGE273
     2    GND @T6G_MB_LIB.T6G(SCH_1):GND   I116 @T6G_MB_LIB.T6G(SCH_1):PAGE273

 C30 Q_CAP_0402-0.1UF,25V,10%,X7R,CH4104K1B00
     1 P1V8_AUX @T6G_MB_LIB.T6G(SCH_1):P1V8_AUX   I379 @T6G_MB_LIB.T6G(SCH_1):PAGE29
     2    GND @T6G_MB_LIB.T6G(SCH_1):GND   I379 @T6G_MB_LIB.T6G(SCH_1):PAGE29

 C31 Q_CAP_0402-0.1UF,25V,10%,X7R,CH4104K1B00
     1 P3V3_AUX @T6G_MB_LIB.T6G(SCH_1):P3V3_AUX   I139 @T6G_MB_LIB.T6G(SCH_1):PAGE359
     2    GND @T6G_MB_LIB.T6G(SCH_1):GND   I139 @T6G_MB_LIB.T6G(SCH_1):PAGE359

 C32 Q_CAP_0402-0.1UF,25V,10%,X7R,CH4104K1B00
     1 P3V3_AUX @T6G_MB_LIB.T6G(SCH_1):P3V3_AUX   I119 @T6G_MB_LIB.T6G(SCH_1):PAGE359
     2    GND @T6G_MB_LIB.T6G(SCH_1):GND   I119 @T6G_MB_LIB.T6G(SCH_1):PAGE359

 C33 Q_CAP_0402-0.1UF,25V,10%,X7R,CH4104K1B00
     1 P12V_OCP_V3_2_ISENSE_TIC @T6G_MB_LIB.T6G(SCH_1):P12V_OCP_V3_2_ISENSE_TIC    I84 @T6G_MB_LIB.T6G(SCH_1):PAGE369
     2    GND @T6G_MB_LIB.T6G(SCH_1):GND    I84 @T6G_MB_LIB.T6G(SCH_1):PAGE369

 C34 Q_CAP_C0805-22UF,16V,20%,X6S,CH6223MEA00
     1 P12V_OCP_SFF_R @T6G_MB_LIB.T6G(SCH_1):P12V_OCP_SFF_R    I88 @T6G_MB_LIB.T6G(SCH_1):PAGE335
     2    GND @T6G_MB_LIB.T6G(SCH_1):GND    I88 @T6G_MB_LIB.T6G(SCH_1):PAGE335

 C35 Q_CAP_0402-100PF,50V,5%,EMPTY,CH11006JB18
     1 P12V_E1S_0_ISENSE_MAM @T6G_MB_LIB.T6G(SCH_1):P12V_E1S_0_ISENSE_MAM    I78 @T6G_MB_LIB.T6G(SCH_1):PAGE369
     2    GND @T6G_MB_LIB.T6G(SCH_1):GND    I78 @T6G_MB_LIB.T6G(SCH_1):PAGE369

 C36 Q_CAP_0402-0.1UF,25V,10%,X7R,CH4104K1B00
     1 P3V3_AUX @T6G_MB_LIB.T6G(SCH_1):P3V3_AUX    I33 @T6G_MB_LIB.T6G(SCH_1):PAGE337
     2    GND @T6G_MB_LIB.T6G(SCH_1):GND    I33 @T6G_MB_LIB.T6G(SCH_1):PAGE337

 C37 Q_CAP_0402-0.1UF,25V,10%,X7R,CH4104K1B00
     1 P12V_OCP_SFF_ISENSE_TIC @T6G_MB_LIB.T6G(SCH_1):P12V_OCP_SFF_ISENSE_TIC   I112 @T6G_MB_LIB.T6G(SCH_1):PAGE369
     2    GND @T6G_MB_LIB.T6G(SCH_1):GND   I112 @T6G_MB_LIB.T6G(SCH_1):PAGE369

 C38 Q_CAP_0402-0.1UF,25V,10%,X7R,CH4104K1B00
     1 P3V3_AUX @T6G_MB_LIB.T6G(SCH_1):P3V3_AUX    I47 @T6G_MB_LIB.T6G(SCH_1):PAGE342
     2    GND @T6G_MB_LIB.T6G(SCH_1):GND    I47 @T6G_MB_LIB.T6G(SCH_1):PAGE342

 C39 Q_CAP_C0402-1UF,25V,10%,X6S,CH5104KEB02
     1 P3V3_OCP_VCC_2 @T6G_MB_LIB.T6G(SCH_1):P3V3_OCP_VCC_2    I90 @T6G_MB_LIB.T6G(SCH_1):PAGE343
     2    GND @T6G_MB_LIB.T6G(SCH_1):GND    I90 @T6G_MB_LIB.T6G(SCH_1):PAGE343

 C40 Q_CAP_C0402-0.01UF,50V,10%,EMPTY,CH31006KB18
     1 P12V_OCP_V3_2 @T6G_MB_LIB.T6G(SCH_1):P12V_OCP_V3_2    I72 @T6G_MB_LIB.T6G(SCH_1):PAGE343
     2 P12V_OCP_GATE_2 @T6G_MB_LIB.T6G(SCH_1):P12V_OCP_GATE_2    I72 @T6G_MB_LIB.T6G(SCH_1):PAGE343

 C41 Q_CAP_DIFFBUS_C0201-DIFF BUS_0.22UF,6.3V,20%,X6S,SA
     1 P5E_CPU0_G3_TX_C_DN<12> @T6G_MB_LIB.T6G(SCH_1):P5E_CPU0_G3_TX_C_DN(12)   I268 @T6G_MB_LIB.T6G(SCH_1):PAGE353
     2 P5E_CPU0_G3_TX_DN<12> @T6G_MB_LIB.T6G(SCH_1):P5E_CPU0_G3_TX_DN(12)   I268 @T6G_MB_LIB.T6G(SCH_1):PAGE353

 C42 Q_CAP_0402-0.1UF,25V,10%,X7R,CH4104K1B00
     1 PVDD18_S5_P0 @T6G_MB_LIB.T6G(SCH_1):PVDD18_S5_P0    I44 @T6G_MB_LIB.T6G(SCH_1):PAGE34
     2    GND @T6G_MB_LIB.T6G(SCH_1):GND    I44 @T6G_MB_LIB.T6G(SCH_1):PAGE34

 C43 Q_CAP_0402-0.1UF,25V,10%,X7R,CH4104K1B00
     1 P3V3_AUX @T6G_MB_LIB.T6G(SCH_1):P3V3_AUX    I47 @T6G_MB_LIB.T6G(SCH_1):PAGE34
     2    GND @T6G_MB_LIB.T6G(SCH_1):GND    I47 @T6G_MB_LIB.T6G(SCH_1):PAGE34

 C44 Q_CAP_DIFFBUS_C0201-DIFF BUS_0.22UF,6.3V,20%,X6S,SA
     1 P5E_CPU0_G3_TX_C_DP<8> @T6G_MB_LIB.T6G(SCH_1):P5E_CPU0_G3_TX_C_DP(8)   I259 @T6G_MB_LIB.T6G(SCH_1):PAGE353
     2 P5E_CPU0_G3_TX_DP<8> @T6G_MB_LIB.T6G(SCH_1):P5E_CPU0_G3_TX_DP(8)   I259 @T6G_MB_LIB.T6G(SCH_1):PAGE353

 C45 Q_CAP_C0402-1UF,25V,10%,X6S,CH5104KEB02
     1 P1V5_BAT_IN @T6G_MB_LIB.T6G(SCH_1):P1V5_BAT_IN   I107 @T6G_MB_LIB.T6G(SCH_1):PAGE156
     2    GND @T6G_MB_LIB.T6G(SCH_1):GND   I107 @T6G_MB_LIB.T6G(SCH_1):PAGE156

 C46 Q_CAP_DIFFBUS_C0201-DIFF BUS_0.22UF,6.3V,20%,X6S,SA
     1 P5E_CPU0_G3_TX_C_DN<7> @T6G_MB_LIB.T6G(SCH_1):P5E_CPU0_G3_TX_C_DN(7)   I242 @T6G_MB_LIB.T6G(SCH_1):PAGE353
     2 P5E_CPU0_G3_TX_DN<7> @T6G_MB_LIB.T6G(SCH_1):P5E_CPU0_G3_TX_DN(7)   I242 @T6G_MB_LIB.T6G(SCH_1):PAGE353

 C47 Q_CAP_DIFFBUS_C0201-DIFF BUS_0.22UF,6.3V,20%,X6S,SA
     1 P5E_CPU0_G3_TX_C_DP<6> @T6G_MB_LIB.T6G(SCH_1):P5E_CPU0_G3_TX_C_DP(6)   I239 @T6G_MB_LIB.T6G(SCH_1):PAGE353
     2 P5E_CPU0_G3_TX_DP<6> @T6G_MB_LIB.T6G(SCH_1):P5E_CPU0_G3_TX_DP(6)   I239 @T6G_MB_LIB.T6G(SCH_1):PAGE353

 C48 Q_CAP_DIFFBUS_C0201-DIFF BUS_0.22UF,6.3V,20%,X6S,SA
     1 P5E_CPU1_P3_TX_C_DN<15> @T6G_MB_LIB.T6G(SCH_1):P5E_CPU1_P3_TX_C_DN(15)   I119 @T6G_MB_LIB.T6G(SCH_1):PAGE355
     2 P5E_CPU1_P3_TX_DN<15> @T6G_MB_LIB.T6G(SCH_1):P5E_CPU1_P3_TX_DN(15)   I119 @T6G_MB_LIB.T6G(SCH_1):PAGE355

 C49 Q_CAP_DIFFBUS_C0201-DIFF BUS_0.22UF,6.3V,20%,X6S,SA
     1 P5E_CPU1_P3_TX_C_DP<15> @T6G_MB_LIB.T6G(SCH_1):P5E_CPU1_P3_TX_C_DP(15)   I120 @T6G_MB_LIB.T6G(SCH_1):PAGE355
     2 P5E_CPU1_P3_TX_DP<15> @T6G_MB_LIB.T6G(SCH_1):P5E_CPU1_P3_TX_DP(15)   I120 @T6G_MB_LIB.T6G(SCH_1):PAGE355

 C50 Q_CAP_DIFFBUS_C0201-DIFF BUS_0.22UF,6.3V,20%,X6S,SA
     1 P5E_CPU1_P3_TX_C_DN<14> @T6G_MB_LIB.T6G(SCH_1):P5E_CPU1_P3_TX_C_DN(14)   I118 @T6G_MB_LIB.T6G(SCH_1):PAGE355
     2 P5E_CPU1_P3_TX_DN<14> @T6G_MB_LIB.T6G(SCH_1):P5E_CPU1_P3_TX_DN(14)   I118 @T6G_MB_LIB.T6G(SCH_1):PAGE355

 C51 Q_CAP_DIFFBUS_C0201-DIFF BUS_0.22UF,6.3V,20%,X6S,SA
     1 P5E_CPU1_P3_TX_C_DP<14> @T6G_MB_LIB.T6G(SCH_1):P5E_CPU1_P3_TX_C_DP(14)   I117 @T6G_MB_LIB.T6G(SCH_1):PAGE355
     2 P5E_CPU1_P3_TX_DP<14> @T6G_MB_LIB.T6G(SCH_1):P5E_CPU1_P3_TX_DP(14)   I117 @T6G_MB_LIB.T6G(SCH_1):PAGE355

 C52 Q_CAP_DIFFBUS_C0201-DIFF BUS_0.22UF,6.3V,20%,X6S,SA
     1 P5E_CPU1_P3_TX_C_DN<13> @T6G_MB_LIB.T6G(SCH_1):P5E_CPU1_P3_TX_C_DN(13)   I116 @T6G_MB_LIB.T6G(SCH_1):PAGE355
     2 P5E_CPU1_P3_TX_DN<13> @T6G_MB_LIB.T6G(SCH_1):P5E_CPU1_P3_TX_DN(13)   I116 @T6G_MB_LIB.T6G(SCH_1):PAGE355

 C53 Q_CAP_DIFFBUS_C0201-DIFF BUS_0.22UF,6.3V,20%,X6S,SA
     1 P5E_CPU1_P3_TX_C_DP<13> @T6G_MB_LIB.T6G(SCH_1):P5E_CPU1_P3_TX_C_DP(13)   I107 @T6G_MB_LIB.T6G(SCH_1):PAGE355
     2 P5E_CPU1_P3_TX_DP<13> @T6G_MB_LIB.T6G(SCH_1):P5E_CPU1_P3_TX_DP(13)   I107 @T6G_MB_LIB.T6G(SCH_1):PAGE355

 C54 Q_CAP_DIFFBUS_C0201-DIFF BUS_0.22UF,6.3V,20%,X6S,SA
     1 P5E_CPU1_P3_TX_C_DN<12> @T6G_MB_LIB.T6G(SCH_1):P5E_CPU1_P3_TX_C_DN(12)    I86 @T6G_MB_LIB.T6G(SCH_1):PAGE355
     2 P5E_CPU1_P3_TX_DN<12> @T6G_MB_LIB.T6G(SCH_1):P5E_CPU1_P3_TX_DN(12)    I86 @T6G_MB_LIB.T6G(SCH_1):PAGE355

 C55 Q_CAP_DIFFBUS_C0201-DIFF BUS_0.22UF,6.3V,20%,X6S,SA
     1 P5E_CPU1_P3_TX_C_DP<12> @T6G_MB_LIB.T6G(SCH_1):P5E_CPU1_P3_TX_C_DP(12)    I85 @T6G_MB_LIB.T6G(SCH_1):PAGE355
     2 P5E_CPU1_P3_TX_DP<12> @T6G_MB_LIB.T6G(SCH_1):P5E_CPU1_P3_TX_DP(12)    I85 @T6G_MB_LIB.T6G(SCH_1):PAGE355

 C56 Q_CAP_DIFFBUS_C0201-DIFF BUS_0.22UF,6.3V,20%,X6S,SA
     1 P5E_CPU1_G1_TX_C_DP<8> @T6G_MB_LIB.T6G(SCH_1):P5E_CPU1_G1_TX_C_DP(8)   I216 @T6G_MB_LIB.T6G(SCH_1):PAGE355
     2 P5E_CPU1_G1_TX_DP<8> @T6G_MB_LIB.T6G(SCH_1):P5E_CPU1_G1_TX_DP(8)   I216 @T6G_MB_LIB.T6G(SCH_1):PAGE355

 C57 Q_CAP_C0805-10UF,16V,10%,EMPTY,CH6103KEA00
     1 P5V_AUX @T6G_MB_LIB.T6G(SCH_1):P5V_AUX    I20 @T6G_MB_LIB.T6G(SCH_1):PAGE273
     2    GND @T6G_MB_LIB.T6G(SCH_1):GND    I20 @T6G_MB_LIB.T6G(SCH_1):PAGE273

 C58 Q_CAP_0402-0.1UF,25V,10%,X7R,CH4104K1B00
     1 P3V3_9ZXL045_P1_VDD @T6G_MB_LIB.T6G(SCH_1):P3V3_9ZXL045_P1_VDD    I34 @T6G_MB_LIB.T6G(SCH_1):PAGE379
     2    GND @T6G_MB_LIB.T6G(SCH_1):GND    I34 @T6G_MB_LIB.T6G(SCH_1):PAGE379

 C59 Q_CAP_0402-100PF,50V,5%,EMPTY,CH11006JB18
     1 P12V_OCP_V3_2_ISENSE_MAM @T6G_MB_LIB.T6G(SCH_1):P12V_OCP_V3_2_ISENSE_MAM    I87 @T6G_MB_LIB.T6G(SCH_1):PAGE369
     2    GND @T6G_MB_LIB.T6G(SCH_1):GND    I87 @T6G_MB_LIB.T6G(SCH_1):PAGE369

 C60 Q_CAP_C0805-10UF,16V,10%,EMPTY,CH6103KEA00
     1 P3V3_AUX @T6G_MB_LIB.T6G(SCH_1):P3V3_AUX    I51 @T6G_MB_LIB.T6G(SCH_1):PAGE273
     2    GND @T6G_MB_LIB.T6G(SCH_1):GND    I51 @T6G_MB_LIB.T6G(SCH_1):PAGE273

 C61 Q_CAP_C0402-100NF,50V,10%,X7R,CH4106K1B01
     1   P3V3 @T6G_MB_LIB.T6G(SCH_1):P3V3    I59 @T6G_MB_LIB.T6G(SCH_1):PAGE273
     2    GND @T6G_MB_LIB.T6G(SCH_1):GND    I59 @T6G_MB_LIB.T6G(SCH_1):PAGE273

 C62 Q_CAP_C0402-220PF,50V,5%,C0G,CH12206JB00
     1 UART_CPU0_SCM_LVC3_UART1_TX @T6G_MB_LIB.T6G(SCH_1):UART_CPU0_SCM_LVC3_UART1_TX    I69 @T6G_MB_LIB.T6G(SCH_1):PAGE349
     2    GND @T6G_MB_LIB.T6G(SCH_1):GND    I69 @T6G_MB_LIB.T6G(SCH_1):PAGE349

 C63 Q_CAP_C0402-220PF,50V,5%,C0G,CH12206JB00
     1 UART_CPU0_SCM_LVC3_UART1_R_RX @T6G_MB_LIB.T6G(SCH_1):UART_CPU0_SCM_LVC3_UART1_R_RX   I112 @T6G_MB_LIB.T6G(SCH_1):PAGE349
     2    GND @T6G_MB_LIB.T6G(SCH_1):GND   I112 @T6G_MB_LIB.T6G(SCH_1):PAGE349

 C64 Q_CAP_0402-0.1UF,25V,10%,EMPTY,CH4104K1B00
     1 PDB_PRSNT_N @T6G_MB_LIB.T6G(SCH_1):PDB_PRSNT_N   I453 @T6G_MB_LIB.T6G(SCH_1):PAGE363
     2    GND @T6G_MB_LIB.T6G(SCH_1):GND   I453 @T6G_MB_LIB.T6G(SCH_1):PAGE363

 C65 Q_CAP_0402-0.1UF,25V,10%,EMPTY,CH4104K1B00
     1 HPDB_HSC_PWRGD_R @T6G_MB_LIB.T6G(SCH_1):HPDB_HSC_PWRGD_R   I454 @T6G_MB_LIB.T6G(SCH_1):PAGE363
     2    GND @T6G_MB_LIB.T6G(SCH_1):GND   I454 @T6G_MB_LIB.T6G(SCH_1):PAGE363

 C66 Q_CAP_0402-0.1UF,25V,10%,EMPTY,CH4104K1B00
     1 FM_FAN_PWR_EN_R @T6G_MB_LIB.T6G(SCH_1):FM_FAN_PWR_EN_R   I455 @T6G_MB_LIB.T6G(SCH_1):PAGE363
     2    GND @T6G_MB_LIB.T6G(SCH_1):GND   I455 @T6G_MB_LIB.T6G(SCH_1):PAGE363

 C67 Q_CAP_0402-0.1UF,25V,10%,EMPTY,CH4104K1B00
     1 FM_GPU_HSC_EN_BUF_R1 @T6G_MB_LIB.T6G(SCH_1):FM_GPU_HSC_EN_BUF_R1   I456 @T6G_MB_LIB.T6G(SCH_1):PAGE363
     2    GND @T6G_MB_LIB.T6G(SCH_1):GND   I456 @T6G_MB_LIB.T6G(SCH_1):PAGE363

 C68 Q_CAP_0402-0.1UF,25V,10%,X7R,CH4104K1B00
     1 P3V3_9ZXL045_P1_VDDA @T6G_MB_LIB.T6G(SCH_1):P3V3_9ZXL045_P1_VDDA    I24 @T6G_MB_LIB.T6G(SCH_1):PAGE379
     2    GND @T6G_MB_LIB.T6G(SCH_1):GND    I24 @T6G_MB_LIB.T6G(SCH_1):PAGE379

 C69 Q_CAP_0402-0.1UF,25V,10%,X7R,CH4104K1B00
     1 P3V3_AUX @T6G_MB_LIB.T6G(SCH_1):P3V3_AUX    I40 @T6G_MB_LIB.T6G(SCH_1):PAGE364
     2    GND @T6G_MB_LIB.T6G(SCH_1):GND    I40 @T6G_MB_LIB.T6G(SCH_1):PAGE364

 C70 Q_CAP_0402-0.1UF,25V,10%,X7R,CH4104K1B00
     1 HPDB_HSC_PWRGD_ISO @T6G_MB_LIB.T6G(SCH_1):HPDB_HSC_PWRGD_ISO    I62 @T6G_MB_LIB.T6G(SCH_1):PAGE364
     2    GND @T6G_MB_LIB.T6G(SCH_1):GND    I62 @T6G_MB_LIB.T6G(SCH_1):PAGE364

 C71 Q_CAP_C0402-4.7PF,50V,0.1P,NPO,CH-4716TB06
     1 CLK_GEN2_XTAL_IN_R @T6G_MB_LIB.T6G(SCH_1):CLK_GEN2_XTAL_IN_R    I75 @T6G_MB_LIB.T6G(SCH_1):PAGE232
     2    GND @T6G_MB_LIB.T6G(SCH_1):GND    I75 @T6G_MB_LIB.T6G(SCH_1):PAGE232

 C72 Q_CAP_0402-0.1UF,25V,10%,X7R,CH4104K1B00
     1 P3V3_AUX @T6G_MB_LIB.T6G(SCH_1):P3V3_AUX    I40 @T6G_MB_LIB.T6G(SCH_1):PAGE337
     2    GND @T6G_MB_LIB.T6G(SCH_1):GND    I40 @T6G_MB_LIB.T6G(SCH_1):PAGE337

 C73 Q_CAP_0402-0.1UF,25V,10%,X7R,CH4104K1B00
     1 P3V3_AUX @T6G_MB_LIB.T6G(SCH_1):P3V3_AUX   I104 @T6G_MB_LIB.T6G(SCH_1):PAGE359
     2    GND @T6G_MB_LIB.T6G(SCH_1):GND   I104 @T6G_MB_LIB.T6G(SCH_1):PAGE359

 C74 Q_CAP_0402-0.1UF,25V,10%,EMPTY,CH4104K1B00
     1 RST_SMB_SWITCH_R_N @T6G_MB_LIB.T6G(SCH_1):RST_SMB_SWITCH_R_N   I452 @T6G_MB_LIB.T6G(SCH_1):PAGE363
     2    GND @T6G_MB_LIB.T6G(SCH_1):GND   I452 @T6G_MB_LIB.T6G(SCH_1):PAGE363

 C75 Q_CAP_0402-0.1UF,25V,10%,X7R,CH4104K1B00
     1 P3V3_9ZXL045_P1_VDD @T6G_MB_LIB.T6G(SCH_1):P3V3_9ZXL045_P1_VDD    I60 @T6G_MB_LIB.T6G(SCH_1):PAGE379
     2    GND @T6G_MB_LIB.T6G(SCH_1):GND    I60 @T6G_MB_LIB.T6G(SCH_1):PAGE379

 C76 Q_CAP_C0402-10UF,6.3V,20%,X6S,CH6101MEB01
     1 P3V3_9ZXL045_P0_VDDA @T6G_MB_LIB.T6G(SCH_1):P3V3_9ZXL045_P0_VDDA    I69 @T6G_MB_LIB.T6G(SCH_1):PAGE160
     2    GND @T6G_MB_LIB.T6G(SCH_1):GND    I69 @T6G_MB_LIB.T6G(SCH_1):PAGE160

 C77 Q_CAP_C0402-10UF,6.3V,20%,X6S,CH6101MEB01
     1 P3V3_9ZXL045_P0_VDDR @T6G_MB_LIB.T6G(SCH_1):P3V3_9ZXL045_P0_VDDR    I70 @T6G_MB_LIB.T6G(SCH_1):PAGE160
     2    GND @T6G_MB_LIB.T6G(SCH_1):GND    I70 @T6G_MB_LIB.T6G(SCH_1):PAGE160

 C78 Q_CAP_0402-0.1UF,25V,10%,X7R,CH4104K1B00
     1 P3V3_9ZXL045_P0_VDDR @T6G_MB_LIB.T6G(SCH_1):P3V3_9ZXL045_P0_VDDR    I18 @T6G_MB_LIB.T6G(SCH_1):PAGE160
     2    GND @T6G_MB_LIB.T6G(SCH_1):GND    I18 @T6G_MB_LIB.T6G(SCH_1):PAGE160

 C79 Q_CAP_0402-0.1UF,25V,10%,X7R,CH4104K1B00
     1 P3V3_9ZXL045_P0_VDD @T6G_MB_LIB.T6G(SCH_1):P3V3_9ZXL045_P0_VDD    I41 @T6G_MB_LIB.T6G(SCH_1):PAGE160
     2    GND @T6G_MB_LIB.T6G(SCH_1):GND    I41 @T6G_MB_LIB.T6G(SCH_1):PAGE160

 C80 Q_CAP_0402-0.1UF,25V,10%,X7R,CH4104K1B00
     1 P3V3_9ZXL045_P0_VDD @T6G_MB_LIB.T6G(SCH_1):P3V3_9ZXL045_P0_VDD    I44 @T6G_MB_LIB.T6G(SCH_1):PAGE160
     2    GND @T6G_MB_LIB.T6G(SCH_1):GND    I44 @T6G_MB_LIB.T6G(SCH_1):PAGE160

 C81 Q_CAP_0402-0.1UF,25V,10%,X7R,CH4104K1B00
     1 P3V3_9ZXL045_P0_VDD @T6G_MB_LIB.T6G(SCH_1):P3V3_9ZXL045_P0_VDD    I45 @T6G_MB_LIB.T6G(SCH_1):PAGE160
     2    GND @T6G_MB_LIB.T6G(SCH_1):GND    I45 @T6G_MB_LIB.T6G(SCH_1):PAGE160

 C82 Q_CAP_C0402-10UF,6.3V,20%,X6S,CH6101MEB01
     1 P3V3_9ZXL045_P1_VDDA @T6G_MB_LIB.T6G(SCH_1):P3V3_9ZXL045_P1_VDDA    I77 @T6G_MB_LIB.T6G(SCH_1):PAGE379
     2    GND @T6G_MB_LIB.T6G(SCH_1):GND    I77 @T6G_MB_LIB.T6G(SCH_1):PAGE379

 C83 Q_CAP_C0402-10UF,6.3V,20%,X6S,CH6101MEB01
     1 P3V3_9ZXL045_P1_VDDR @T6G_MB_LIB.T6G(SCH_1):P3V3_9ZXL045_P1_VDDR    I78 @T6G_MB_LIB.T6G(SCH_1):PAGE379
     2    GND @T6G_MB_LIB.T6G(SCH_1):GND    I78 @T6G_MB_LIB.T6G(SCH_1):PAGE379

 C84 Q_CAP_0402-0.1UF,25V,10%,X7R,CH4104K1B00
     1 P3V3_9ZXL045_P1_VDDR @T6G_MB_LIB.T6G(SCH_1):P3V3_9ZXL045_P1_VDDR    I26 @T6G_MB_LIB.T6G(SCH_1):PAGE379
     2    GND @T6G_MB_LIB.T6G(SCH_1):GND    I26 @T6G_MB_LIB.T6G(SCH_1):PAGE379

 C85 Q_CAP_C0402-0.001UF,50V,10%,X7R,CH30106KB19
     1 HDT_HDR_TRST_N @T6G_MB_LIB.T6G(SCH_1):HDT_HDR_TRST_N   I152 @T6G_MB_LIB.T6G(SCH_1):PAGE149
     2    GND @T6G_MB_LIB.T6G(SCH_1):GND   I152 @T6G_MB_LIB.T6G(SCH_1):PAGE149

 C86 Q_CAP_C0402-0.01UF,50V,10%,EMPTY,CH31006KB18
     1 JTAG_TDI @T6G_MB_LIB.T6G(SCH_1):JTAG_TDI   I161 @T6G_MB_LIB.T6G(SCH_1):PAGE149
     2    GND @T6G_MB_LIB.T6G(SCH_1):GND   I161 @T6G_MB_LIB.T6G(SCH_1):PAGE149

 C87 Q_CAP_C0402-0.001UF,50V,10%,X7R,CH30106KB19
     1 HDT_HDR_DBREQ_N @T6G_MB_LIB.T6G(SCH_1):HDT_HDR_DBREQ_N   I134 @T6G_MB_LIB.T6G(SCH_1):PAGE149
     2    GND @T6G_MB_LIB.T6G(SCH_1):GND   I134 @T6G_MB_LIB.T6G(SCH_1):PAGE149

 C88 Q_CAP_0402-0.1UF,25V,10%,X7R,CH4104K1B00
     1 P3V3_AUX @T6G_MB_LIB.T6G(SCH_1):P3V3_AUX   I523 @T6G_MB_LIB.T6G(SCH_1):PAGE85
     2    GND @T6G_MB_LIB.T6G(SCH_1):GND   I523 @T6G_MB_LIB.T6G(SCH_1):PAGE85

 C89 Q_CAP_C0805-10UF,25V,10%,X6S,CH6104KEA00
     1 P12V_MEM_CPU0 @T6G_MB_LIB.T6G(SCH_1):P12V_MEM_CPU0   I519 @T6G_MB_LIB.T6G(SCH_1):PAGE85
     2    GND @T6G_MB_LIB.T6G(SCH_1):GND   I519 @T6G_MB_LIB.T6G(SCH_1):PAGE85

 C90 Q_CAP_0402-0.1UF,25V,10%,X7R,CH4104K1B00
     1 P3V3_9ZXL045_P1_VDD @T6G_MB_LIB.T6G(SCH_1):P3V3_9ZXL045_P1_VDD    I35 @T6G_MB_LIB.T6G(SCH_1):PAGE379
     2    GND @T6G_MB_LIB.T6G(SCH_1):GND    I35 @T6G_MB_LIB.T6G(SCH_1):PAGE379

 C91 Q_CAP_C0402-12PF,50V,5%,C0G,CH01206JB05
     1 XTAL_USB_CPU0_HUB1_XIN @T6G_MB_LIB.T6G(SCH_1):XTAL_USB_CPU0_HUB1_XIN    I92 @T6G_MB_LIB.T6G(SCH_1):PAGE153
     2    GND @T6G_MB_LIB.T6G(SCH_1):GND    I92 @T6G_MB_LIB.T6G(SCH_1):PAGE153

 C92 Q_CAP_0402-0.1UF,25V,10%,X7R,CH4104K1B00
     1 P3V3_AUX @T6G_MB_LIB.T6G(SCH_1):P3V3_AUX   I362 @T6G_MB_LIB.T6G(SCH_1):PAGE86
     2    GND @T6G_MB_LIB.T6G(SCH_1):GND   I362 @T6G_MB_LIB.T6G(SCH_1):PAGE86

 C93 Q_CAP_0402-15PF,50V,5%,C0G,CH01506JB06
     1 XTAL_USB_CPU0_HUB1_XOUT @T6G_MB_LIB.T6G(SCH_1):XTAL_USB_CPU0_HUB1_XOUT    I91 @T6G_MB_LIB.T6G(SCH_1):PAGE153
     2    GND @T6G_MB_LIB.T6G(SCH_1):GND    I91 @T6G_MB_LIB.T6G(SCH_1):PAGE153

 C94 Q_CAP_C0402-4.7PF,50V,0.1P,NPO,CH-4716TB06
     1 CLK_GEN2_XTAL_OUT @T6G_MB_LIB.T6G(SCH_1):CLK_GEN2_XTAL_OUT    I76 @T6G_MB_LIB.T6G(SCH_1):PAGE232
     2    GND @T6G_MB_LIB.T6G(SCH_1):GND    I76 @T6G_MB_LIB.T6G(SCH_1):PAGE232

 C95 Q_CAP_0402-0.1UF,25V,10%,X7R,CH4104K1B00
     1 VFG3P3_CLK_GEN @T6G_MB_LIB.T6G(SCH_1):VFG3P3_CLK_GEN    I42 @T6G_MB_LIB.T6G(SCH_1):PAGE232
     2    GND @T6G_MB_LIB.T6G(SCH_1):GND    I42 @T6G_MB_LIB.T6G(SCH_1):PAGE232

 C96 Q_CAP_0402-0.1UF,25V,10%,X7R,CH4104K1B00
     1 P3V3_AUX @T6G_MB_LIB.T6G(SCH_1):P3V3_AUX   I362 @T6G_MB_LIB.T6G(SCH_1):PAGE87
     2    GND @T6G_MB_LIB.T6G(SCH_1):GND   I362 @T6G_MB_LIB.T6G(SCH_1):PAGE87

 C97 Q_CAP_0402-0.1UF,25V,10%,X7R,CH4104K1B00
     1 VFG_3P3A_CLK_GEN @T6G_MB_LIB.T6G(SCH_1):VFG_3P3A_CLK_GEN    I69 @T6G_MB_LIB.T6G(SCH_1):PAGE232
     2    GND @T6G_MB_LIB.T6G(SCH_1):GND    I69 @T6G_MB_LIB.T6G(SCH_1):PAGE232

 C98 Q_CAP_0402-0.1UF,25V,10%,X7R,CH4104K1B00
     1 P3V3_9ZXL045_P1_VDD @T6G_MB_LIB.T6G(SCH_1):P3V3_9ZXL045_P1_VDD    I36 @T6G_MB_LIB.T6G(SCH_1):PAGE379
     2    GND @T6G_MB_LIB.T6G(SCH_1):GND    I36 @T6G_MB_LIB.T6G(SCH_1):PAGE379

 C99 Q_CAP_0402-0.1UF,25V,10%,X7R,CH4104K1B00
     1 P3V3_9ZXL045_P1_VDD @T6G_MB_LIB.T6G(SCH_1):P3V3_9ZXL045_P1_VDD    I58 @T6G_MB_LIB.T6G(SCH_1):PAGE379
     2    GND @T6G_MB_LIB.T6G(SCH_1):GND    I58 @T6G_MB_LIB.T6G(SCH_1):PAGE379

C100 Q_CAP_0402-0.1UF,25V,10%,X7R,CH4104K1B00
     1 P3V3_AUX @T6G_MB_LIB.T6G(SCH_1):P3V3_AUX   I362 @T6G_MB_LIB.T6G(SCH_1):PAGE88
     2    GND @T6G_MB_LIB.T6G(SCH_1):GND   I362 @T6G_MB_LIB.T6G(SCH_1):PAGE88

C101 Q_CAP_0402-1000PF,50V,5%,EMPTY,TMP_QCH21006JB10
     1 PWRGD_P0V9_RETIMER_CPU0_R @T6G_MB_LIB.T6G(SCH_1):PWRGD_P0V9_RETIMER_CPU0_R   I118 @T6G_MB_LIB.T6G(SCH_1):PAGE475
     2    GND @T6G_MB_LIB.T6G(SCH_1):GND   I118 @T6G_MB_LIB.T6G(SCH_1):PAGE475

C102 Q_CAP_C0805-100UF,4V,20%,X6S,CH710KMEA01
     1 P1V8_CPU1_RT_1D @T6G_MB_LIB.T6G(SCH_1):P1V8_CPU1_RT_1D    I16 @T6G_MB_LIB.T6G(SCH_1):PAGE443
     2    GND @T6G_MB_LIB.T6G(SCH_1):GND    I16 @T6G_MB_LIB.T6G(SCH_1):PAGE443

C103 Q_CAP_C0805-100UF,4V,20%,X6S,CH710KMEA01
     1 P1V8_CPU1_RT1_1A @T6G_MB_LIB.T6G(SCH_1):P1V8_CPU1_RT1_1A    I13 @T6G_MB_LIB.T6G(SCH_1):PAGE443
     2    GND @T6G_MB_LIB.T6G(SCH_1):GND    I13 @T6G_MB_LIB.T6G(SCH_1):PAGE443

C104 Q_CAP_0402-0.1UF,25V,10%,X7R,CH4104K1B00
     1 P3V3_AUX @T6G_MB_LIB.T6G(SCH_1):P3V3_AUX   I360 @T6G_MB_LIB.T6G(SCH_1):PAGE89
     2    GND @T6G_MB_LIB.T6G(SCH_1):GND   I360 @T6G_MB_LIB.T6G(SCH_1):PAGE89

C105 Q_CAP_0402-0.1UF,25V,10%,EMPTY,CH4104K1B00
     1 P1V8_RETIMER_CPU1_EN @T6G_MB_LIB.T6G(SCH_1):P1V8_RETIMER_CPU1_EN     I5 @T6G_MB_LIB.T6G(SCH_1):PAGE470
     2    GND @T6G_MB_LIB.T6G(SCH_1):GND     I5 @T6G_MB_LIB.T6G(SCH_1):PAGE470

C106 Q_CAP_0402-0.1UF,25V,10%,X7R,CH4104K1B00
     1 P3V3_AUX @T6G_MB_LIB.T6G(SCH_1):P3V3_AUX    I34 @T6G_MB_LIB.T6G(SCH_1):PAGE252
     2    GND @T6G_MB_LIB.T6G(SCH_1):GND    I34 @T6G_MB_LIB.T6G(SCH_1):PAGE252

C107 Q_CAP_0402-1000PF,50V,5%,EMPTY,TMP_QCH21006JB10
     1 PWRGD_P0V9_RETIMER_CPU1_R @T6G_MB_LIB.T6G(SCH_1):PWRGD_P0V9_RETIMER_CPU1_R    I45 @T6G_MB_LIB.T6G(SCH_1):PAGE477
     2    GND @T6G_MB_LIB.T6G(SCH_1):GND    I45 @T6G_MB_LIB.T6G(SCH_1):PAGE477

C108 Q_CAP_0402-0.1UF,25V,10%,X7R,CH4104K1B00
     1 P3V3_AUX @T6G_MB_LIB.T6G(SCH_1):P3V3_AUX   I361 @T6G_MB_LIB.T6G(SCH_1):PAGE90
     2    GND @T6G_MB_LIB.T6G(SCH_1):GND   I361 @T6G_MB_LIB.T6G(SCH_1):PAGE90

C109 Q_CAP_0402-1000PF,50V,5%,X7R,TMP_QCH21006JB10
     1 FM_PWRGD_P1V8_RETIMER_CPU1 @T6G_MB_LIB.T6G(SCH_1):FM_PWRGD_P1V8_RETIMER_CPU1    I39 @T6G_MB_LIB.T6G(SCH_1):PAGE470
     2    GND @T6G_MB_LIB.T6G(SCH_1):GND    I39 @T6G_MB_LIB.T6G(SCH_1):PAGE470

C110 Q_CAP_C0402-22UF,4V,20%,X6S,CH622KMEB02
     1 P1V8_CPU1_RT_1D @T6G_MB_LIB.T6G(SCH_1):P1V8_CPU1_RT_1D    I24 @T6G_MB_LIB.T6G(SCH_1):PAGE443
     2    GND @T6G_MB_LIB.T6G(SCH_1):GND    I24 @T6G_MB_LIB.T6G(SCH_1):PAGE443

C111 Q_CAP_C0402-22UF,4V,20%,X6S,CH622KMEB02
     1 P1V8_CPU1_RT1_1A @T6G_MB_LIB.T6G(SCH_1):P1V8_CPU1_RT1_1A    I14 @T6G_MB_LIB.T6G(SCH_1):PAGE443
     2    GND @T6G_MB_LIB.T6G(SCH_1):GND    I14 @T6G_MB_LIB.T6G(SCH_1):PAGE443

C112 Q_CAP_0402-0.1UF,25V,10%,X7R,CH4104K1B00
     1 P3V3_AUX @T6G_MB_LIB.T6G(SCH_1):P3V3_AUX   I183 @T6G_MB_LIB.T6G(SCH_1):PAGE91
     2    GND @T6G_MB_LIB.T6G(SCH_1):GND   I183 @T6G_MB_LIB.T6G(SCH_1):PAGE91

C113 Q_CAP_C0805-100UF,4V,20%,X6S,CH710KMEA01
     1 P1V8_CPU1_RT_1D @T6G_MB_LIB.T6G(SCH_1):P1V8_CPU1_RT_1D    I12 @T6G_MB_LIB.T6G(SCH_1):PAGE398
     2    GND @T6G_MB_LIB.T6G(SCH_1):GND    I12 @T6G_MB_LIB.T6G(SCH_1):PAGE398

C114 Q_CAP_C0805-100UF,4V,20%,X6S,CH710KMEA01
     1 P1V8_CPU1_RT0_1A @T6G_MB_LIB.T6G(SCH_1):P1V8_CPU1_RT0_1A     I4 @T6G_MB_LIB.T6G(SCH_1):PAGE398
     2    GND @T6G_MB_LIB.T6G(SCH_1):GND     I4 @T6G_MB_LIB.T6G(SCH_1):PAGE398

C115 Q_CAP_C0402-22UF,4V,20%,X6S,CH622KMEB02
     1 P1V8_CPU1_RT_1D @T6G_MB_LIB.T6G(SCH_1):P1V8_CPU1_RT_1D    I21 @T6G_MB_LIB.T6G(SCH_1):PAGE398
     2    GND @T6G_MB_LIB.T6G(SCH_1):GND    I21 @T6G_MB_LIB.T6G(SCH_1):PAGE398

C116 Q_CAP_0402-0.1UF,25V,10%,X7R,CH4104K1B00
     1 P3V3_AUX @T6G_MB_LIB.T6G(SCH_1):P3V3_AUX   I186 @T6G_MB_LIB.T6G(SCH_1):PAGE92
     2    GND @T6G_MB_LIB.T6G(SCH_1):GND   I186 @T6G_MB_LIB.T6G(SCH_1):PAGE92

C117 Q_CAP_C0402-22UF,4V,20%,X6S,CH622KMEB02
     1 P1V8_CPU1_RT0_1A @T6G_MB_LIB.T6G(SCH_1):P1V8_CPU1_RT0_1A     I5 @T6G_MB_LIB.T6G(SCH_1):PAGE398
     2    GND @T6G_MB_LIB.T6G(SCH_1):GND     I5 @T6G_MB_LIB.T6G(SCH_1):PAGE398

C118 Q_CAP_C0402-10UF,6.3V,20%,X6S,CH6101MEB01
     1 P1V8_CPU1_RT_1D @T6G_MB_LIB.T6G(SCH_1):P1V8_CPU1_RT_1D    I14 @T6G_MB_LIB.T6G(SCH_1):PAGE398
     2    GND @T6G_MB_LIB.T6G(SCH_1):GND    I14 @T6G_MB_LIB.T6G(SCH_1):PAGE398

C119 Q_CAP_C0402-10UF,6.3V,20%,X6S,CH6101MEB01
     1 P1V8_CPU1_RT0_1A @T6G_MB_LIB.T6G(SCH_1):P1V8_CPU1_RT0_1A    I20 @T6G_MB_LIB.T6G(SCH_1):PAGE398
     2    GND @T6G_MB_LIB.T6G(SCH_1):GND    I20 @T6G_MB_LIB.T6G(SCH_1):PAGE398

C120 Q_CAP_0402-0.1UF,25V,10%,X7R,CH4104K1B00
     1 P3V3_AUX @T6G_MB_LIB.T6G(SCH_1):P3V3_AUX   I185 @T6G_MB_LIB.T6G(SCH_1):PAGE93
     2    GND @T6G_MB_LIB.T6G(SCH_1):GND   I185 @T6G_MB_LIB.T6G(SCH_1):PAGE93

C121 Q_CAP_0402-4.7UF,6.3V,20%,X6S,CH5471MEB01
     1 P1V8_CPU1_RT0_1A @T6G_MB_LIB.T6G(SCH_1):P1V8_CPU1_RT0_1A     I7 @T6G_MB_LIB.T6G(SCH_1):PAGE398
     2    GND @T6G_MB_LIB.T6G(SCH_1):GND     I7 @T6G_MB_LIB.T6G(SCH_1):PAGE398

C122 Q_CAP_0402-4.7UF,6.3V,20%,X6S,CH5471MEB01
     1 P1V8_CPU1_RT_1D @T6G_MB_LIB.T6G(SCH_1):P1V8_CPU1_RT_1D    I15 @T6G_MB_LIB.T6G(SCH_1):PAGE398
     2    GND @T6G_MB_LIB.T6G(SCH_1):GND    I15 @T6G_MB_LIB.T6G(SCH_1):PAGE398

C123 Q_CAP_0201-1UF,4V,20%,X6S,CH-10KMEE00
     1 P1V8_CPU1_RT0_1A @T6G_MB_LIB.T6G(SCH_1):P1V8_CPU1_RT0_1A    I18 @T6G_MB_LIB.T6G(SCH_1):PAGE398
     2    GND @T6G_MB_LIB.T6G(SCH_1):GND    I18 @T6G_MB_LIB.T6G(SCH_1):PAGE398

C124 Q_CAP_0402-0.1UF,25V,10%,X7R,CH4104K1B00
     1 P3V3_AUX @T6G_MB_LIB.T6G(SCH_1):P3V3_AUX   I185 @T6G_MB_LIB.T6G(SCH_1):PAGE94
     2    GND @T6G_MB_LIB.T6G(SCH_1):GND   I185 @T6G_MB_LIB.T6G(SCH_1):PAGE94

C125 Q_CAP_0201-1UF,4V,20%,X6S,CH-10KMEE00
     1 P1V8_CPU1_RT0_1A_1D @T6G_MB_LIB.T6G(SCH_1):P1V8_CPU1_RT0_1A_1D    I19 @T6G_MB_LIB.T6G(SCH_1):PAGE398
     2    GND @T6G_MB_LIB.T6G(SCH_1):GND    I19 @T6G_MB_LIB.T6G(SCH_1):PAGE398

C126 Q_CAP_0201-1UF,4V,20%,X6S,CH-10KMEE00
     1 P1V8_CPU1_RT0_1A @T6G_MB_LIB.T6G(SCH_1):P1V8_CPU1_RT0_1A     I9 @T6G_MB_LIB.T6G(SCH_1):PAGE398
     2    GND @T6G_MB_LIB.T6G(SCH_1):GND     I9 @T6G_MB_LIB.T6G(SCH_1):PAGE398

C127 Q_CAP_C0402-10UF,6.3V,20%,X6S,CH6101MEB01
     1 P1V8_CPU1_RT_1D @T6G_MB_LIB.T6G(SCH_1):P1V8_CPU1_RT_1D    I25 @T6G_MB_LIB.T6G(SCH_1):PAGE443
     2    GND @T6G_MB_LIB.T6G(SCH_1):GND    I25 @T6G_MB_LIB.T6G(SCH_1):PAGE443

C128 Q_CAP_0402-0.1UF,25V,10%,X7R,CH4104K1B00
     1 P3V3_AUX @T6G_MB_LIB.T6G(SCH_1):P3V3_AUX   I185 @T6G_MB_LIB.T6G(SCH_1):PAGE95
     2    GND @T6G_MB_LIB.T6G(SCH_1):GND   I185 @T6G_MB_LIB.T6G(SCH_1):PAGE95

C129 Q_CAP_C0201-0.1UF,10V,10%,X7S,CH4102K6E00
     1 P1V8_CPU1_RT0_1A @T6G_MB_LIB.T6G(SCH_1):P1V8_CPU1_RT0_1A    I23 @T6G_MB_LIB.T6G(SCH_1):PAGE398
     2    GND @T6G_MB_LIB.T6G(SCH_1):GND    I23 @T6G_MB_LIB.T6G(SCH_1):PAGE398

C130 Q_CAP_C0201-0.1UF,10V,10%,X7S,CH4102K6E00
     1 P1V8_CPU1_RT0_1A_1D @T6G_MB_LIB.T6G(SCH_1):P1V8_CPU1_RT0_1A_1D    I27 @T6G_MB_LIB.T6G(SCH_1):PAGE398
     2    GND @T6G_MB_LIB.T6G(SCH_1):GND    I27 @T6G_MB_LIB.T6G(SCH_1):PAGE398

C131 Q_CAP_C0201-0.1UF,10V,10%,X7S,CH4102K6E00
     1 P1V8_CPU1_RT0_1A @T6G_MB_LIB.T6G(SCH_1):P1V8_CPU1_RT0_1A    I24 @T6G_MB_LIB.T6G(SCH_1):PAGE398
     2    GND @T6G_MB_LIB.T6G(SCH_1):GND    I24 @T6G_MB_LIB.T6G(SCH_1):PAGE398

C132 Q_CAP_0402-0.1UF,25V,10%,X7R,CH4104K1B00
     1 P3V3_AUX @T6G_MB_LIB.T6G(SCH_1):P3V3_AUX   I185 @T6G_MB_LIB.T6G(SCH_1):PAGE96
     2    GND @T6G_MB_LIB.T6G(SCH_1):GND   I185 @T6G_MB_LIB.T6G(SCH_1):PAGE96

C133 Q_CAP_C0201-0.1UF,10V,10%,X7S,CH4102K6E00
     1 P1V8_CPU1_RT0_1A @T6G_MB_LIB.T6G(SCH_1):P1V8_CPU1_RT0_1A    I25 @T6G_MB_LIB.T6G(SCH_1):PAGE398
     2    GND @T6G_MB_LIB.T6G(SCH_1):GND    I25 @T6G_MB_LIB.T6G(SCH_1):PAGE398

C134 Q_CAP_C0201-0.1UF,10V,10%,X7S,CH4102K6E00
     1 P1V8_CPU1_RT0_1A @T6G_MB_LIB.T6G(SCH_1):P1V8_CPU1_RT0_1A    I26 @T6G_MB_LIB.T6G(SCH_1):PAGE398
     2    GND @T6G_MB_LIB.T6G(SCH_1):GND    I26 @T6G_MB_LIB.T6G(SCH_1):PAGE398

C135 Q_CAP_0201-1UF,4V,20%,X6S,CH-10KMEE00
     1 P0V9_CPU1_RT0_2A @T6G_MB_LIB.T6G(SCH_1):P0V9_CPU1_RT0_2A    I46 @T6G_MB_LIB.T6G(SCH_1):PAGE398
     2    GND @T6G_MB_LIB.T6G(SCH_1):GND    I46 @T6G_MB_LIB.T6G(SCH_1):PAGE398

C136 Q_CAP_0402-0.1UF,25V,10%,X7R,CH4104K1B00
     1 P3V3_AUX @T6G_MB_LIB.T6G(SCH_1):P3V3_AUX   I185 @T6G_MB_LIB.T6G(SCH_1):PAGE97
     2    GND @T6G_MB_LIB.T6G(SCH_1):GND   I185 @T6G_MB_LIB.T6G(SCH_1):PAGE97

C137 Q_CAP_C0201-0.1UF,10V,10%,X7S,CH4102K6E00
     1 P0V9_CPU1_RT_2D @T6G_MB_LIB.T6G(SCH_1):P0V9_CPU1_RT_2D    I78 @T6G_MB_LIB.T6G(SCH_1):PAGE398
     2    GND @T6G_MB_LIB.T6G(SCH_1):GND    I78 @T6G_MB_LIB.T6G(SCH_1):PAGE398

C138 Q_CAP_0201-1UF,4V,20%,X6S,CH-10KMEE00
     1 P0V9_CPU1_RT0_2A @T6G_MB_LIB.T6G(SCH_1):P0V9_CPU1_RT0_2A    I48 @T6G_MB_LIB.T6G(SCH_1):PAGE398
     2    GND @T6G_MB_LIB.T6G(SCH_1):GND    I48 @T6G_MB_LIB.T6G(SCH_1):PAGE398

C139 Q_CAP_C0201-0.1UF,10V,10%,X7S,CH4102K6E00
     1 P0V9_CPU1_RT_2D @T6G_MB_LIB.T6G(SCH_1):P0V9_CPU1_RT_2D    I77 @T6G_MB_LIB.T6G(SCH_1):PAGE398
     2    GND @T6G_MB_LIB.T6G(SCH_1):GND    I77 @T6G_MB_LIB.T6G(SCH_1):PAGE398

C140 Q_CAP_0402-0.1UF,25V,10%,X7R,CH4104K1B00
     1 P3V3_AUX @T6G_MB_LIB.T6G(SCH_1):P3V3_AUX   I185 @T6G_MB_LIB.T6G(SCH_1):PAGE98
     2    GND @T6G_MB_LIB.T6G(SCH_1):GND   I185 @T6G_MB_LIB.T6G(SCH_1):PAGE98

C141 Q_CAP_C0201-0.1UF,10V,10%,X7S,CH4102K6E00
     1 P0V9_CPU1_RT0_2A @T6G_MB_LIB.T6G(SCH_1):P0V9_CPU1_RT0_2A    I82 @T6G_MB_LIB.T6G(SCH_1):PAGE398
     2    GND @T6G_MB_LIB.T6G(SCH_1):GND    I82 @T6G_MB_LIB.T6G(SCH_1):PAGE398

C142 Q_CAP_C0805-10UF,25V,10%,X6S,CH6104KEA00
     1 P12V_MEM_CPU0 @T6G_MB_LIB.T6G(SCH_1):P12V_MEM_CPU0   I534 @T6G_MB_LIB.T6G(SCH_1):PAGE85
     2    GND @T6G_MB_LIB.T6G(SCH_1):GND   I534 @T6G_MB_LIB.T6G(SCH_1):PAGE85

C143 Q_CAP_C0805-10UF,25V,10%,X6S,CH6104KEA00
     1 P12V_MEM_CPU0 @T6G_MB_LIB.T6G(SCH_1):P12V_MEM_CPU0   I369 @T6G_MB_LIB.T6G(SCH_1):PAGE86
     2    GND @T6G_MB_LIB.T6G(SCH_1):GND   I369 @T6G_MB_LIB.T6G(SCH_1):PAGE86

C144 Q_CAP_0402-0.1UF,25V,10%,X7R,CH4104K1B00
     1 P3V3_AUX @T6G_MB_LIB.T6G(SCH_1):P3V3_AUX   I185 @T6G_MB_LIB.T6G(SCH_1):PAGE99
     2    GND @T6G_MB_LIB.T6G(SCH_1):GND   I185 @T6G_MB_LIB.T6G(SCH_1):PAGE99

C145 Q_CAP_C0805-10UF,25V,10%,X6S,CH6104KEA00
     1 P12V_MEM_CPU0 @T6G_MB_LIB.T6G(SCH_1):P12V_MEM_CPU0   I370 @T6G_MB_LIB.T6G(SCH_1):PAGE86
     2    GND @T6G_MB_LIB.T6G(SCH_1):GND   I370 @T6G_MB_LIB.T6G(SCH_1):PAGE86

C146 Q_CAP_C0805-10UF,25V,10%,X6S,CH6104KEA00
     1 P12V_MEM_CPU0 @T6G_MB_LIB.T6G(SCH_1):P12V_MEM_CPU0   I413 @T6G_MB_LIB.T6G(SCH_1):PAGE87
     2    GND @T6G_MB_LIB.T6G(SCH_1):GND   I413 @T6G_MB_LIB.T6G(SCH_1):PAGE87

C147 Q_CAP_C0805-10UF,25V,10%,X6S,CH6104KEA00
     1 P12V_MEM_CPU0 @T6G_MB_LIB.T6G(SCH_1):P12V_MEM_CPU0   I414 @T6G_MB_LIB.T6G(SCH_1):PAGE87
     2    GND @T6G_MB_LIB.T6G(SCH_1):GND   I414 @T6G_MB_LIB.T6G(SCH_1):PAGE87

C148 Q_CAP_0402-0.1UF,25V,10%,X7R,CH4104K1B00
     1 P3V3_AUX @T6G_MB_LIB.T6G(SCH_1):P3V3_AUX   I185 @T6G_MB_LIB.T6G(SCH_1):PAGE100
     2    GND @T6G_MB_LIB.T6G(SCH_1):GND   I185 @T6G_MB_LIB.T6G(SCH_1):PAGE100

C149 Q_CAP_C0805-10UF,25V,10%,X6S,CH6104KEA00
     1 P12V_MEM_CPU0 @T6G_MB_LIB.T6G(SCH_1):P12V_MEM_CPU0   I417 @T6G_MB_LIB.T6G(SCH_1):PAGE88
     2    GND @T6G_MB_LIB.T6G(SCH_1):GND   I417 @T6G_MB_LIB.T6G(SCH_1):PAGE88

C150 Q_CAP_C0805-10UF,25V,10%,X6S,CH6104KEA00
     1 P12V_MEM_CPU0 @T6G_MB_LIB.T6G(SCH_1):P12V_MEM_CPU0   I418 @T6G_MB_LIB.T6G(SCH_1):PAGE88
     2    GND @T6G_MB_LIB.T6G(SCH_1):GND   I418 @T6G_MB_LIB.T6G(SCH_1):PAGE88

C151 Q_CAP_C0805-10UF,25V,10%,X6S,CH6104KEA00
     1 P12V_MEM_CPU0 @T6G_MB_LIB.T6G(SCH_1):P12V_MEM_CPU0   I412 @T6G_MB_LIB.T6G(SCH_1):PAGE89
     2    GND @T6G_MB_LIB.T6G(SCH_1):GND   I412 @T6G_MB_LIB.T6G(SCH_1):PAGE89

C152 Q_CAP_0402-0.1UF,25V,10%,X7R,CH4104K1B00
     1 P3V3_AUX @T6G_MB_LIB.T6G(SCH_1):P3V3_AUX   I185 @T6G_MB_LIB.T6G(SCH_1):PAGE101
     2    GND @T6G_MB_LIB.T6G(SCH_1):GND   I185 @T6G_MB_LIB.T6G(SCH_1):PAGE101

C153 Q_CAP_C0805-10UF,25V,10%,X6S,CH6104KEA00
     1 P12V_MEM_CPU0 @T6G_MB_LIB.T6G(SCH_1):P12V_MEM_CPU0   I413 @T6G_MB_LIB.T6G(SCH_1):PAGE89
     2    GND @T6G_MB_LIB.T6G(SCH_1):GND   I413 @T6G_MB_LIB.T6G(SCH_1):PAGE89

C154 Q_CAP_C0805-10UF,25V,10%,X6S,CH6104KEA00
     1 P12V_MEM_CPU0 @T6G_MB_LIB.T6G(SCH_1):P12V_MEM_CPU0   I414 @T6G_MB_LIB.T6G(SCH_1):PAGE90
     2    GND @T6G_MB_LIB.T6G(SCH_1):GND   I414 @T6G_MB_LIB.T6G(SCH_1):PAGE90

C155 Q_CAP_C0805-10UF,25V,10%,X6S,CH6104KEA00
     1 P12V_MEM_CPU0 @T6G_MB_LIB.T6G(SCH_1):P12V_MEM_CPU0   I415 @T6G_MB_LIB.T6G(SCH_1):PAGE90
     2    GND @T6G_MB_LIB.T6G(SCH_1):GND   I415 @T6G_MB_LIB.T6G(SCH_1):PAGE90

C156 Q_CAP_0402-0.1UF,25V,10%,X7R,CH4104K1B00
     1 P3V3_AUX @T6G_MB_LIB.T6G(SCH_1):P3V3_AUX   I185 @T6G_MB_LIB.T6G(SCH_1):PAGE102
     2    GND @T6G_MB_LIB.T6G(SCH_1):GND   I185 @T6G_MB_LIB.T6G(SCH_1):PAGE102

C157 Q_CAP_C0805-10UF,25V,10%,X6S,CH6104KEA00
     1 P12V_MEM_CPU0 @T6G_MB_LIB.T6G(SCH_1):P12V_MEM_CPU0   I238 @T6G_MB_LIB.T6G(SCH_1):PAGE91
     2    GND @T6G_MB_LIB.T6G(SCH_1):GND   I238 @T6G_MB_LIB.T6G(SCH_1):PAGE91

C158 Q_CAP_C0805-10UF,25V,10%,X6S,CH6104KEA00
     1 P12V_MEM_CPU0 @T6G_MB_LIB.T6G(SCH_1):P12V_MEM_CPU0   I239 @T6G_MB_LIB.T6G(SCH_1):PAGE91
     2    GND @T6G_MB_LIB.T6G(SCH_1):GND   I239 @T6G_MB_LIB.T6G(SCH_1):PAGE91

C159 Q_CAP_C0805-10UF,25V,10%,X6S,CH6104KEA00
     1 P12V_MEM_CPU0 @T6G_MB_LIB.T6G(SCH_1):P12V_MEM_CPU0   I239 @T6G_MB_LIB.T6G(SCH_1):PAGE92
     2    GND @T6G_MB_LIB.T6G(SCH_1):GND   I239 @T6G_MB_LIB.T6G(SCH_1):PAGE92

C160 Q_CAP_0402-0.1UF,25V,10%,X7R,CH4104K1B00
     1 P3V3_AUX @T6G_MB_LIB.T6G(SCH_1):P3V3_AUX   I185 @T6G_MB_LIB.T6G(SCH_1):PAGE103
     2    GND @T6G_MB_LIB.T6G(SCH_1):GND   I185 @T6G_MB_LIB.T6G(SCH_1):PAGE103

C161 Q_CAP_C0805-10UF,25V,10%,X6S,CH6104KEA00
     1 P12V_MEM_CPU0 @T6G_MB_LIB.T6G(SCH_1):P12V_MEM_CPU0   I240 @T6G_MB_LIB.T6G(SCH_1):PAGE92
     2    GND @T6G_MB_LIB.T6G(SCH_1):GND   I240 @T6G_MB_LIB.T6G(SCH_1):PAGE92

C162 Q_CAP_C0805-10UF,25V,10%,X6S,CH6104KEA00
     1 P12V_MEM_CPU0 @T6G_MB_LIB.T6G(SCH_1):P12V_MEM_CPU0   I238 @T6G_MB_LIB.T6G(SCH_1):PAGE93
     2    GND @T6G_MB_LIB.T6G(SCH_1):GND   I238 @T6G_MB_LIB.T6G(SCH_1):PAGE93

C163 Q_CAP_C0805-10UF,25V,10%,X6S,CH6104KEA00
     1 P12V_MEM_CPU0 @T6G_MB_LIB.T6G(SCH_1):P12V_MEM_CPU0   I239 @T6G_MB_LIB.T6G(SCH_1):PAGE93
     2    GND @T6G_MB_LIB.T6G(SCH_1):GND   I239 @T6G_MB_LIB.T6G(SCH_1):PAGE93

C164 Q_CAP_0402-0.1UF,25V,10%,X7R,CH4104K1B00
     1 P3V3_AUX @T6G_MB_LIB.T6G(SCH_1):P3V3_AUX   I185 @T6G_MB_LIB.T6G(SCH_1):PAGE104
     2    GND @T6G_MB_LIB.T6G(SCH_1):GND   I185 @T6G_MB_LIB.T6G(SCH_1):PAGE104

C165 Q_CAP_C0805-10UF,25V,10%,X6S,CH6104KEA00
     1 P12V_MEM_CPU0 @T6G_MB_LIB.T6G(SCH_1):P12V_MEM_CPU0   I238 @T6G_MB_LIB.T6G(SCH_1):PAGE94
     2    GND @T6G_MB_LIB.T6G(SCH_1):GND   I238 @T6G_MB_LIB.T6G(SCH_1):PAGE94

C166 Q_CAP_C0805-10UF,25V,10%,X6S,CH6104KEA00
     1 P12V_MEM_CPU0 @T6G_MB_LIB.T6G(SCH_1):P12V_MEM_CPU0   I239 @T6G_MB_LIB.T6G(SCH_1):PAGE94
     2    GND @T6G_MB_LIB.T6G(SCH_1):GND   I239 @T6G_MB_LIB.T6G(SCH_1):PAGE94

C167 Q_CAP_C0805-10UF,25V,10%,X6S,CH6104KEA00
     1 P12V_MEM_CPU0 @T6G_MB_LIB.T6G(SCH_1):P12V_MEM_CPU0   I238 @T6G_MB_LIB.T6G(SCH_1):PAGE95
     2    GND @T6G_MB_LIB.T6G(SCH_1):GND   I238 @T6G_MB_LIB.T6G(SCH_1):PAGE95

C168 Q_CAP_0402-0.1UF,25V,10%,X7R,CH4104K1B00
     1 P3V3_AUX @T6G_MB_LIB.T6G(SCH_1):P3V3_AUX   I185 @T6G_MB_LIB.T6G(SCH_1):PAGE105
     2    GND @T6G_MB_LIB.T6G(SCH_1):GND   I185 @T6G_MB_LIB.T6G(SCH_1):PAGE105

C169 Q_CAP_C0805-10UF,25V,10%,X6S,CH6104KEA00
     1 P12V_MEM_CPU0 @T6G_MB_LIB.T6G(SCH_1):P12V_MEM_CPU0   I239 @T6G_MB_LIB.T6G(SCH_1):PAGE95
     2    GND @T6G_MB_LIB.T6G(SCH_1):GND   I239 @T6G_MB_LIB.T6G(SCH_1):PAGE95

C170 Q_CAP_C0805-10UF,25V,10%,X6S,CH6104KEA00
     1 P12V_MEM_CPU0 @T6G_MB_LIB.T6G(SCH_1):P12V_MEM_CPU0   I238 @T6G_MB_LIB.T6G(SCH_1):PAGE96
     2    GND @T6G_MB_LIB.T6G(SCH_1):GND   I238 @T6G_MB_LIB.T6G(SCH_1):PAGE96

C171 Q_CAP_C0805-10UF,25V,10%,X6S,CH6104KEA00
     1 P12V_MEM_CPU0 @T6G_MB_LIB.T6G(SCH_1):P12V_MEM_CPU0   I239 @T6G_MB_LIB.T6G(SCH_1):PAGE96
     2    GND @T6G_MB_LIB.T6G(SCH_1):GND   I239 @T6G_MB_LIB.T6G(SCH_1):PAGE96

C172 Q_CAP_0402-0.1UF,25V,10%,X7R,CH4104K1B00
     1 P3V3_AUX @T6G_MB_LIB.T6G(SCH_1):P3V3_AUX   I185 @T6G_MB_LIB.T6G(SCH_1):PAGE106
     2    GND @T6G_MB_LIB.T6G(SCH_1):GND   I185 @T6G_MB_LIB.T6G(SCH_1):PAGE106

C173 Q_CAP_C0805-10UF,25V,10%,X6S,CH6104KEA00
     1 P12V_MEM_CPU1 @T6G_MB_LIB.T6G(SCH_1):P12V_MEM_CPU1   I240 @T6G_MB_LIB.T6G(SCH_1):PAGE97
     2    GND @T6G_MB_LIB.T6G(SCH_1):GND   I240 @T6G_MB_LIB.T6G(SCH_1):PAGE97

C174 Q_CAP_C0805-10UF,25V,10%,X6S,CH6104KEA00
     1 P12V_MEM_CPU1 @T6G_MB_LIB.T6G(SCH_1):P12V_MEM_CPU1   I241 @T6G_MB_LIB.T6G(SCH_1):PAGE97
     2    GND @T6G_MB_LIB.T6G(SCH_1):GND   I241 @T6G_MB_LIB.T6G(SCH_1):PAGE97

C175 Q_CAP_C0805-10UF,25V,10%,X6S,CH6104KEA00
     1 P12V_MEM_CPU1 @T6G_MB_LIB.T6G(SCH_1):P12V_MEM_CPU1   I238 @T6G_MB_LIB.T6G(SCH_1):PAGE98
     2    GND @T6G_MB_LIB.T6G(SCH_1):GND   I238 @T6G_MB_LIB.T6G(SCH_1):PAGE98

C176 Q_CAP_0402-0.1UF,25V,10%,X7R,CH4104K1B00
     1 P3V3_AUX @T6G_MB_LIB.T6G(SCH_1):P3V3_AUX   I185 @T6G_MB_LIB.T6G(SCH_1):PAGE107
     2    GND @T6G_MB_LIB.T6G(SCH_1):GND   I185 @T6G_MB_LIB.T6G(SCH_1):PAGE107

C177 Q_CAP_C0805-10UF,25V,10%,X6S,CH6104KEA00
     1 P12V_MEM_CPU1 @T6G_MB_LIB.T6G(SCH_1):P12V_MEM_CPU1   I239 @T6G_MB_LIB.T6G(SCH_1):PAGE98
     2    GND @T6G_MB_LIB.T6G(SCH_1):GND   I239 @T6G_MB_LIB.T6G(SCH_1):PAGE98

C178 Q_CAP_C0805-10UF,25V,10%,X6S,CH6104KEA00
     1 P12V_MEM_CPU1 @T6G_MB_LIB.T6G(SCH_1):P12V_MEM_CPU1   I238 @T6G_MB_LIB.T6G(SCH_1):PAGE99
     2    GND @T6G_MB_LIB.T6G(SCH_1):GND   I238 @T6G_MB_LIB.T6G(SCH_1):PAGE99

C179 Q_CAP_C0805-10UF,25V,10%,X6S,CH6104KEA00
     1 P12V_MEM_CPU1 @T6G_MB_LIB.T6G(SCH_1):P12V_MEM_CPU1   I239 @T6G_MB_LIB.T6G(SCH_1):PAGE99
     2    GND @T6G_MB_LIB.T6G(SCH_1):GND   I239 @T6G_MB_LIB.T6G(SCH_1):PAGE99

C180 Q_CAP_0402-0.1UF,25V,10%,X7R,CH4104K1B00
     1 P3V3_AUX @T6G_MB_LIB.T6G(SCH_1):P3V3_AUX   I185 @T6G_MB_LIB.T6G(SCH_1):PAGE108
     2    GND @T6G_MB_LIB.T6G(SCH_1):GND   I185 @T6G_MB_LIB.T6G(SCH_1):PAGE108

C181 Q_CAP_C0805-10UF,25V,10%,X6S,CH6104KEA00
     1 P12V_MEM_CPU1 @T6G_MB_LIB.T6G(SCH_1):P12V_MEM_CPU1   I238 @T6G_MB_LIB.T6G(SCH_1):PAGE100
     2    GND @T6G_MB_LIB.T6G(SCH_1):GND   I238 @T6G_MB_LIB.T6G(SCH_1):PAGE100

C182 Q_CAP_C0805-10UF,25V,10%,X6S,CH6104KEA00
     1 P12V_MEM_CPU1 @T6G_MB_LIB.T6G(SCH_1):P12V_MEM_CPU1   I239 @T6G_MB_LIB.T6G(SCH_1):PAGE100
     2    GND @T6G_MB_LIB.T6G(SCH_1):GND   I239 @T6G_MB_LIB.T6G(SCH_1):PAGE100

C183 Q_CAP_C0805-10UF,25V,10%,X6S,CH6104KEA00
     1 P12V_MEM_CPU1 @T6G_MB_LIB.T6G(SCH_1):P12V_MEM_CPU1   I238 @T6G_MB_LIB.T6G(SCH_1):PAGE101
     2    GND @T6G_MB_LIB.T6G(SCH_1):GND   I238 @T6G_MB_LIB.T6G(SCH_1):PAGE101

C184 Q_CAP_C0201-0.1UF,10V,10%,X7S,CH4102K6E00
     1 P0V9_CPU1_RT0_2A @T6G_MB_LIB.T6G(SCH_1):P0V9_CPU1_RT0_2A    I85 @T6G_MB_LIB.T6G(SCH_1):PAGE398
     2    GND @T6G_MB_LIB.T6G(SCH_1):GND    I85 @T6G_MB_LIB.T6G(SCH_1):PAGE398

C185 Q_CAP_0201-1UF,4V,20%,X6S,CH-10KMEE00
     1 P0V9_CPU1_RT_2D @T6G_MB_LIB.T6G(SCH_1):P0V9_CPU1_RT_2D    I40 @T6G_MB_LIB.T6G(SCH_1):PAGE398
     2    GND @T6G_MB_LIB.T6G(SCH_1):GND    I40 @T6G_MB_LIB.T6G(SCH_1):PAGE398

C186 Q_CAP_0201-1UF,4V,20%,X6S,CH-10KMEE00
     1 P0V9_CPU1_RT0_2A @T6G_MB_LIB.T6G(SCH_1):P0V9_CPU1_RT0_2A    I58 @T6G_MB_LIB.T6G(SCH_1):PAGE398
     2    GND @T6G_MB_LIB.T6G(SCH_1):GND    I58 @T6G_MB_LIB.T6G(SCH_1):PAGE398

C187 Q_CAP_0201-1UF,4V,20%,X6S,CH-10KMEE00
     1 P0V9_CPU1_RT0_2A_2D @T6G_MB_LIB.T6G(SCH_1):P0V9_CPU1_RT0_2A_2D    I99 @T6G_MB_LIB.T6G(SCH_1):PAGE398
     2    GND @T6G_MB_LIB.T6G(SCH_1):GND    I99 @T6G_MB_LIB.T6G(SCH_1):PAGE398

C188 Q_CAP_0201-1UF,4V,20%,X6S,CH-10KMEE00
     1 P0V9_CPU1_RT0_2A @T6G_MB_LIB.T6G(SCH_1):P0V9_CPU1_RT0_2A    I55 @T6G_MB_LIB.T6G(SCH_1):PAGE398
     2    GND @T6G_MB_LIB.T6G(SCH_1):GND    I55 @T6G_MB_LIB.T6G(SCH_1):PAGE398

C189 Q_CAP_C0201-0.1UF,10V,10%,X7S,CH4102K6E00
     1 P0V9_CPU1_RT_2D @T6G_MB_LIB.T6G(SCH_1):P0V9_CPU1_RT_2D    I75 @T6G_MB_LIB.T6G(SCH_1):PAGE398
     2    GND @T6G_MB_LIB.T6G(SCH_1):GND    I75 @T6G_MB_LIB.T6G(SCH_1):PAGE398

C190 Q_CAP_0201-1UF,4V,20%,X6S,CH-10KMEE00
     1 P0V9_CPU1_RT0_2A @T6G_MB_LIB.T6G(SCH_1):P0V9_CPU1_RT0_2A    I62 @T6G_MB_LIB.T6G(SCH_1):PAGE398
     2    GND @T6G_MB_LIB.T6G(SCH_1):GND    I62 @T6G_MB_LIB.T6G(SCH_1):PAGE398

C191 Q_CAP_C0201-0.1UF,10V,10%,X7S,CH4102K6E00
     1 P0V9_CPU1_RT0_2A_2D @T6G_MB_LIB.T6G(SCH_1):P0V9_CPU1_RT0_2A_2D    I93 @T6G_MB_LIB.T6G(SCH_1):PAGE398
     2    GND @T6G_MB_LIB.T6G(SCH_1):GND    I93 @T6G_MB_LIB.T6G(SCH_1):PAGE398

C192 Q_CAP_C0201-0.1UF,10V,10%,X7S,CH4102K6E00
     1 P0V9_CPU1_RT0_2A @T6G_MB_LIB.T6G(SCH_1):P0V9_CPU1_RT0_2A    I83 @T6G_MB_LIB.T6G(SCH_1):PAGE398
     2    GND @T6G_MB_LIB.T6G(SCH_1):GND    I83 @T6G_MB_LIB.T6G(SCH_1):PAGE398

C193 Q_CAP_C0402-100NF,50V,10%,X7R,CH4106K1B01
     1 P1V5_BAT_IN @T6G_MB_LIB.T6G(SCH_1):P1V5_BAT_IN   I108 @T6G_MB_LIB.T6G(SCH_1):PAGE156
     2    GND @T6G_MB_LIB.T6G(SCH_1):GND   I108 @T6G_MB_LIB.T6G(SCH_1):PAGE156

C194 Q_CAP_C0402-0.1UF,16V,10%,X7R,CH4103K1B08
     1 P3V3_AUX @T6G_MB_LIB.T6G(SCH_1):P3V3_AUX   I299 @T6G_MB_LIB.T6G(SCH_1):PAGE148
     2    GND @T6G_MB_LIB.T6G(SCH_1):GND   I299 @T6G_MB_LIB.T6G(SCH_1):PAGE148

C195 Q_CAP_0402-4.7UF,6.3V,20%,X6S,CH5471MEB01
     1 P1V8_CPU1_RT1_1A @T6G_MB_LIB.T6G(SCH_1):P1V8_CPU1_RT1_1A    I18 @T6G_MB_LIB.T6G(SCH_1):PAGE443
     2    GND @T6G_MB_LIB.T6G(SCH_1):GND    I18 @T6G_MB_LIB.T6G(SCH_1):PAGE443

C196 Q_CAP_0402-1000PF,50V,5%,EMPTY,TMP_QCH21006JB10
     1 PWRGD_PVDD11_S3_P0_R @T6G_MB_LIB.T6G(SCH_1):PWRGD_PVDD11_S3_P0_R    I47 @T6G_MB_LIB.T6G(SCH_1):PAGE182
     2    GND @T6G_MB_LIB.T6G(SCH_1):GND    I47 @T6G_MB_LIB.T6G(SCH_1):PAGE182

C197 Q_CAP_0402-1000PF,50V,5%,X7R,TMP_QCH21006JB10
     1 PVDD11_S3_P0_EN_R @T6G_MB_LIB.T6G(SCH_1):PVDD11_S3_P0_EN_R    I45 @T6G_MB_LIB.T6G(SCH_1):PAGE182
     2    GND @T6G_MB_LIB.T6G(SCH_1):GND    I45 @T6G_MB_LIB.T6G(SCH_1):PAGE182

C198 Q_CAP_C0201-0.1UF,10V,10%,X7S,CH4102K6E00
     1 P0V9_CPU1_RT0_2A_2D @T6G_MB_LIB.T6G(SCH_1):P0V9_CPU1_RT0_2A_2D    I92 @T6G_MB_LIB.T6G(SCH_1):PAGE398
     2    GND @T6G_MB_LIB.T6G(SCH_1):GND    I92 @T6G_MB_LIB.T6G(SCH_1):PAGE398

C199 Q_CAP_C0402-10UF,6.3V,20%,X6S,CH6101MEB01
     1 P1V8_CPU1_RT1_1A @T6G_MB_LIB.T6G(SCH_1):P1V8_CPU1_RT1_1A    I17 @T6G_MB_LIB.T6G(SCH_1):PAGE443
     2    GND @T6G_MB_LIB.T6G(SCH_1):GND    I17 @T6G_MB_LIB.T6G(SCH_1):PAGE443

C200 Q_CAP_0402-4.7UF,6.3V,20%,X6S,CH5471MEB01
     1 P1V8_CPU1_RT_1D @T6G_MB_LIB.T6G(SCH_1):P1V8_CPU1_RT_1D    I26 @T6G_MB_LIB.T6G(SCH_1):PAGE443
     2    GND @T6G_MB_LIB.T6G(SCH_1):GND    I26 @T6G_MB_LIB.T6G(SCH_1):PAGE443

C201 Q_CAP_0201-1UF,4V,20%,X6S,CH-10KMEE00
     1 P0V9_CPU1_RT0_2A_2D @T6G_MB_LIB.T6G(SCH_1):P0V9_CPU1_RT0_2A_2D   I100 @T6G_MB_LIB.T6G(SCH_1):PAGE398
     2    GND @T6G_MB_LIB.T6G(SCH_1):GND   I100 @T6G_MB_LIB.T6G(SCH_1):PAGE398

C202 Q_CAP_0201-1UF,4V,20%,X6S,CH-10KMEE00
     1 P1V8_CPU1_RT1_1A @T6G_MB_LIB.T6G(SCH_1):P1V8_CPU1_RT1_1A    I20 @T6G_MB_LIB.T6G(SCH_1):PAGE443
     2    GND @T6G_MB_LIB.T6G(SCH_1):GND    I20 @T6G_MB_LIB.T6G(SCH_1):PAGE443

C203 Q_CAP_0201-1UF,4V,20%,X6S,CH-10KMEE00
     1 P1V8_CPU1_RT1_1A_1D @T6G_MB_LIB.T6G(SCH_1):P1V8_CPU1_RT1_1A_1D     I8 @T6G_MB_LIB.T6G(SCH_1):PAGE443
     2    GND @T6G_MB_LIB.T6G(SCH_1):GND     I8 @T6G_MB_LIB.T6G(SCH_1):PAGE443

C204 Q_CAP_0201-1UF,4V,20%,X6S,CH-10KMEE00
     1 P1V8_CPU1_RT1_1A @T6G_MB_LIB.T6G(SCH_1):P1V8_CPU1_RT1_1A    I22 @T6G_MB_LIB.T6G(SCH_1):PAGE443
     2    GND @T6G_MB_LIB.T6G(SCH_1):GND    I22 @T6G_MB_LIB.T6G(SCH_1):PAGE443

C205 Q_CAP_C0201-0.1UF,10V,10%,X7S,CH4102K6E00
     1 P1V8_CPU1_RT1_1A @T6G_MB_LIB.T6G(SCH_1):P1V8_CPU1_RT1_1A    I23 @T6G_MB_LIB.T6G(SCH_1):PAGE443
     2    GND @T6G_MB_LIB.T6G(SCH_1):GND    I23 @T6G_MB_LIB.T6G(SCH_1):PAGE443

C206 Q_CAP_C0201-0.1UF,10V,10%,X7S,CH4102K6E00
     1 P1V8_CPU1_RT1_1A_1D @T6G_MB_LIB.T6G(SCH_1):P1V8_CPU1_RT1_1A_1D     I9 @T6G_MB_LIB.T6G(SCH_1):PAGE443
     2    GND @T6G_MB_LIB.T6G(SCH_1):GND     I9 @T6G_MB_LIB.T6G(SCH_1):PAGE443

C207 Q_CAP_C0402-0.001UF,50V,10%,EMPTY,CH30106KB19
     1 JTAG_CPU0_TDO @T6G_MB_LIB.T6G(SCH_1):JTAG_CPU0_TDO   I307 @T6G_MB_LIB.T6G(SCH_1):PAGE27
     2    GND @T6G_MB_LIB.T6G(SCH_1):GND   I307 @T6G_MB_LIB.T6G(SCH_1):PAGE27

C208 Q_CAP_C0402-0.001UF,50V,10%,EMPTY,CH30106KB19
     1 JTAG_CPU0_TDI @T6G_MB_LIB.T6G(SCH_1):JTAG_CPU0_TDI   I306 @T6G_MB_LIB.T6G(SCH_1):PAGE27
     2    GND @T6G_MB_LIB.T6G(SCH_1):GND   I306 @T6G_MB_LIB.T6G(SCH_1):PAGE27

C209 Q_CAP_C0402-0.001UF,50V,10%,EMPTY,CH30106KB19
     1 JTAG_CPU0_TRST_N @T6G_MB_LIB.T6G(SCH_1):JTAG_CPU0_TRST_N   I303 @T6G_MB_LIB.T6G(SCH_1):PAGE27
     2    GND @T6G_MB_LIB.T6G(SCH_1):GND   I303 @T6G_MB_LIB.T6G(SCH_1):PAGE27

C210 Q_CAP_C0402-0.001UF,50V,10%,EMPTY,CH30106KB19
     1 JTAG_CPU0_TCK @T6G_MB_LIB.T6G(SCH_1):JTAG_CPU0_TCK   I302 @T6G_MB_LIB.T6G(SCH_1):PAGE27
     2    GND @T6G_MB_LIB.T6G(SCH_1):GND   I302 @T6G_MB_LIB.T6G(SCH_1):PAGE27

C211 Q_CAP_C0402-0.001UF,50V,10%,EMPTY,CH30106KB19
     1 JTAG_CPU0_TMS @T6G_MB_LIB.T6G(SCH_1):JTAG_CPU0_TMS   I297 @T6G_MB_LIB.T6G(SCH_1):PAGE27
     2    GND @T6G_MB_LIB.T6G(SCH_1):GND   I297 @T6G_MB_LIB.T6G(SCH_1):PAGE27

C212 Q_CAP_C0402-0.001UF,50V,10%,EMPTY,CH30106KB19
     1 JTAG_CPU0_DBREQ_N @T6G_MB_LIB.T6G(SCH_1):JTAG_CPU0_DBREQ_N   I295 @T6G_MB_LIB.T6G(SCH_1):PAGE27
     2    GND @T6G_MB_LIB.T6G(SCH_1):GND   I295 @T6G_MB_LIB.T6G(SCH_1):PAGE27

C213 Q_CAP_C0402-3.9P,50V,0.1P,NPO,CH-3916TB01
     1 XTAL_CPU0_X48M_X1 @T6G_MB_LIB.T6G(SCH_1):XTAL_CPU0_X48M_X1   I232 @T6G_MB_LIB.T6G(SCH_1):PAGE28
     2    GND @T6G_MB_LIB.T6G(SCH_1):GND   I232 @T6G_MB_LIB.T6G(SCH_1):PAGE28

C214 Q_CAP_C0402-3.9P,50V,0.1P,NPO,CH-3916TB01
     1 XTAL_CPU0_X48M_X2_R @T6G_MB_LIB.T6G(SCH_1):XTAL_CPU0_X48M_X2_R   I233 @T6G_MB_LIB.T6G(SCH_1):PAGE28
     2    GND @T6G_MB_LIB.T6G(SCH_1):GND   I233 @T6G_MB_LIB.T6G(SCH_1):PAGE28

C215 Q_CAP_C0402-8.2PF,50V,0.1P,NP0,CH-8216TB09
     1 XTAL_CPU0_X32K_X1 @T6G_MB_LIB.T6G(SCH_1):XTAL_CPU0_X32K_X1   I230 @T6G_MB_LIB.T6G(SCH_1):PAGE28
     2    GND @T6G_MB_LIB.T6G(SCH_1):GND   I230 @T6G_MB_LIB.T6G(SCH_1):PAGE28

C216 Q_CAP_C0402-8.2PF,50V,0.1P,NP0,CH-8216TB09
     1 XTAL_CPU0_X32K_X2 @T6G_MB_LIB.T6G(SCH_1):XTAL_CPU0_X32K_X2   I231 @T6G_MB_LIB.T6G(SCH_1):PAGE28
     2    GND @T6G_MB_LIB.T6G(SCH_1):GND   I231 @T6G_MB_LIB.T6G(SCH_1):PAGE28

C217 Q_CAP_C0201-0.1UF,10V,10%,X7S,CH4102K6E00
     1 P1V8_CPU1_RT1_1A @T6G_MB_LIB.T6G(SCH_1):P1V8_CPU1_RT1_1A    I27 @T6G_MB_LIB.T6G(SCH_1):PAGE443
     2    GND @T6G_MB_LIB.T6G(SCH_1):GND    I27 @T6G_MB_LIB.T6G(SCH_1):PAGE443

C218 Q_CAP_0402-0.1UF,25V,10%,X7R,CH4104K1B00
     1 P1V8_AUX @T6G_MB_LIB.T6G(SCH_1):P1V8_AUX    I24 @T6G_MB_LIB.T6G(SCH_1):PAGE143
     2    GND @T6G_MB_LIB.T6G(SCH_1):GND    I24 @T6G_MB_LIB.T6G(SCH_1):PAGE143

C219 Q_CAP_0402-0.1UF,25V,10%,X7R,CH4104K1B00
     1 P1V8_AUX @T6G_MB_LIB.T6G(SCH_1):P1V8_AUX    I29 @T6G_MB_LIB.T6G(SCH_1):PAGE143
     2    GND @T6G_MB_LIB.T6G(SCH_1):GND    I29 @T6G_MB_LIB.T6G(SCH_1):PAGE143

C220 Q_CAP_C0805-100UF,4V,20%,X6S,CH710KMEA01
     1 P0V9_CPU1_RT0_2A @T6G_MB_LIB.T6G(SCH_1):P0V9_CPU1_RT0_2A    I44 @T6G_MB_LIB.T6G(SCH_1):PAGE398
     2    GND @T6G_MB_LIB.T6G(SCH_1):GND    I44 @T6G_MB_LIB.T6G(SCH_1):PAGE398

C221 Q_CAP_0402-4.7UF,6.3V,20%,X6S,CH5471MEB01
     1 P0V9_CPU1_RT0_2A @T6G_MB_LIB.T6G(SCH_1):P0V9_CPU1_RT0_2A    I50 @T6G_MB_LIB.T6G(SCH_1):PAGE398
     2    GND @T6G_MB_LIB.T6G(SCH_1):GND    I50 @T6G_MB_LIB.T6G(SCH_1):PAGE398

C222 Q_CAP_0201-1UF,4V,20%,X6S,CH-10KMEE00
     1 P0V9_CPU1_RT0_2A @T6G_MB_LIB.T6G(SCH_1):P0V9_CPU1_RT0_2A    I42 @T6G_MB_LIB.T6G(SCH_1):PAGE398
     2    GND @T6G_MB_LIB.T6G(SCH_1):GND    I42 @T6G_MB_LIB.T6G(SCH_1):PAGE398

C223 Q_CAP_0402-0.1UF,25V,10%,X7R,CH4104K1B00
     1 P1V8_AUX @T6G_MB_LIB.T6G(SCH_1):P1V8_AUX    I11 @T6G_MB_LIB.T6G(SCH_1):PAGE77
     2    GND @T6G_MB_LIB.T6G(SCH_1):GND    I11 @T6G_MB_LIB.T6G(SCH_1):PAGE77

C224 Q_CAP_0402-0.1UF,25V,10%,X7R,CH4104K1B00
     1 P1V8_AUX @T6G_MB_LIB.T6G(SCH_1):P1V8_AUX    I19 @T6G_MB_LIB.T6G(SCH_1):PAGE77
     2    GND @T6G_MB_LIB.T6G(SCH_1):GND    I19 @T6G_MB_LIB.T6G(SCH_1):PAGE77

C225 Q_CAP_C0805-100UF,4V,20%,X6S,CH710KMEA01
     1 P0V9_CPU1_RT0_2A @T6G_MB_LIB.T6G(SCH_1):P0V9_CPU1_RT0_2A    I52 @T6G_MB_LIB.T6G(SCH_1):PAGE398
     2    GND @T6G_MB_LIB.T6G(SCH_1):GND    I52 @T6G_MB_LIB.T6G(SCH_1):PAGE398

C226 Q_CAP_0402-0.1UF,25V,10%,X7R,CH4104K1B00
     1 PVDD18_S5_P0 @T6G_MB_LIB.T6G(SCH_1):PVDD18_S5_P0    I59 @T6G_MB_LIB.T6G(SCH_1):PAGE34
     2    GND @T6G_MB_LIB.T6G(SCH_1):GND    I59 @T6G_MB_LIB.T6G(SCH_1):PAGE34

C227 Q_CAP_0402-4.7UF,6.3V,20%,X6S,CH5471MEB01
     1 P0V9_CPU1_RT0_2A @T6G_MB_LIB.T6G(SCH_1):P0V9_CPU1_RT0_2A    I57 @T6G_MB_LIB.T6G(SCH_1):PAGE398
     2    GND @T6G_MB_LIB.T6G(SCH_1):GND    I57 @T6G_MB_LIB.T6G(SCH_1):PAGE398

C228 Q_CAP_C0201-0.1UF,10V,10%,X7S,CH4102K6E00
     1 P0V9_CPU1_RT0_2A @T6G_MB_LIB.T6G(SCH_1):P0V9_CPU1_RT0_2A    I87 @T6G_MB_LIB.T6G(SCH_1):PAGE398
     2    GND @T6G_MB_LIB.T6G(SCH_1):GND    I87 @T6G_MB_LIB.T6G(SCH_1):PAGE398

C229 Q_CAP_C0805-100UF,4V,20%,X6S,CH710KMEA01
     1 P0V9_CPU1_RT_2D @T6G_MB_LIB.T6G(SCH_1):P0V9_CPU1_RT_2D    I34 @T6G_MB_LIB.T6G(SCH_1):PAGE398
     2    GND @T6G_MB_LIB.T6G(SCH_1):GND    I34 @T6G_MB_LIB.T6G(SCH_1):PAGE398

C230 Q_CAP_C0402-0.001UF,50V,10%,EMPTY,CH30106KB19
     1 JTAG_CPU1_TDO @T6G_MB_LIB.T6G(SCH_1):JTAG_CPU1_TDO   I325 @T6G_MB_LIB.T6G(SCH_1):PAGE54
     2    GND @T6G_MB_LIB.T6G(SCH_1):GND   I325 @T6G_MB_LIB.T6G(SCH_1):PAGE54

C231 Q_CAP_C0402-0.001UF,50V,10%,EMPTY,CH30106KB19
     1 JTAG_CPU1_TDI @T6G_MB_LIB.T6G(SCH_1):JTAG_CPU1_TDI   I319 @T6G_MB_LIB.T6G(SCH_1):PAGE54
     2    GND @T6G_MB_LIB.T6G(SCH_1):GND   I319 @T6G_MB_LIB.T6G(SCH_1):PAGE54

C232 Q_CAP_C0402-0.001UF,50V,10%,EMPTY,CH30106KB19
     1 JTAG_CPU1_TRST_N @T6G_MB_LIB.T6G(SCH_1):JTAG_CPU1_TRST_N   I318 @T6G_MB_LIB.T6G(SCH_1):PAGE54
     2    GND @T6G_MB_LIB.T6G(SCH_1):GND   I318 @T6G_MB_LIB.T6G(SCH_1):PAGE54

C233 Q_CAP_C0402-0.001UF,50V,10%,EMPTY,CH30106KB19
     1 JTAG_CPU1_TCK @T6G_MB_LIB.T6G(SCH_1):JTAG_CPU1_TCK   I315 @T6G_MB_LIB.T6G(SCH_1):PAGE54
     2    GND @T6G_MB_LIB.T6G(SCH_1):GND   I315 @T6G_MB_LIB.T6G(SCH_1):PAGE54

C234 Q_CAP_C0402-0.001UF,50V,10%,EMPTY,CH30106KB19
     1 JTAG_CPU1_TMS @T6G_MB_LIB.T6G(SCH_1):JTAG_CPU1_TMS   I311 @T6G_MB_LIB.T6G(SCH_1):PAGE54
     2    GND @T6G_MB_LIB.T6G(SCH_1):GND   I311 @T6G_MB_LIB.T6G(SCH_1):PAGE54

C235 Q_CAP_C0402-0.001UF,50V,10%,EMPTY,CH30106KB19
     1 JTAG_CPU1_DBREQ_N @T6G_MB_LIB.T6G(SCH_1):JTAG_CPU1_DBREQ_N   I310 @T6G_MB_LIB.T6G(SCH_1):PAGE54
     2    GND @T6G_MB_LIB.T6G(SCH_1):GND   I310 @T6G_MB_LIB.T6G(SCH_1):PAGE54

C236 Q_CAP_C0402-2.7PF,50V,0.1PF,NPO,CH-276B0B00
     1 XTAL_CPU1_X48M_X1 @T6G_MB_LIB.T6G(SCH_1):XTAL_CPU1_X48M_X1     I3 @T6G_MB_LIB.T6G(SCH_1):PAGE55
     2    GND @T6G_MB_LIB.T6G(SCH_1):GND     I3 @T6G_MB_LIB.T6G(SCH_1):PAGE55

C237 Q_CAP_C0402-2.7PF,50V,0.1PF,NPO,CH-276B0B00
     1 XTAL_CPU1_X48M_X2_R @T6G_MB_LIB.T6G(SCH_1):XTAL_CPU1_X48M_X2_R    I15 @T6G_MB_LIB.T6G(SCH_1):PAGE55
     2    GND @T6G_MB_LIB.T6G(SCH_1):GND    I15 @T6G_MB_LIB.T6G(SCH_1):PAGE55

C238 Q_CAP_0402-10PF,50V,1%,NPO,TMP_QCH0106F0B00
     1 XTAL_CPU1_R_X32K_X1 @T6G_MB_LIB.T6G(SCH_1):XTAL_CPU1_R_X32K_X1     I5 @T6G_MB_LIB.T6G(SCH_1):PAGE55
     2    GND @T6G_MB_LIB.T6G(SCH_1):GND     I5 @T6G_MB_LIB.T6G(SCH_1):PAGE55

C239 Q_CAP_0402-10PF,50V,1%,NPO,TMP_QCH0106F0B00
     1 XTAL_CPU1_R_X32K_X2 @T6G_MB_LIB.T6G(SCH_1):XTAL_CPU1_R_X32K_X2     I9 @T6G_MB_LIB.T6G(SCH_1):PAGE55
     2    GND @T6G_MB_LIB.T6G(SCH_1):GND     I9 @T6G_MB_LIB.T6G(SCH_1):PAGE55

C240 Q_CAP_C0805-100UF,4V,20%,X6S,CH710KMEA01
     1 P0V9_CPU1_RT0_2A @T6G_MB_LIB.T6G(SCH_1):P0V9_CPU1_RT0_2A    I53 @T6G_MB_LIB.T6G(SCH_1):PAGE398
     2    GND @T6G_MB_LIB.T6G(SCH_1):GND    I53 @T6G_MB_LIB.T6G(SCH_1):PAGE398

C241 Q_CAP_0402-4.7UF,6.3V,20%,X6S,CH5471MEB01
     1 P0V9_CPU1_RT0_2A @T6G_MB_LIB.T6G(SCH_1):P0V9_CPU1_RT0_2A    I72 @T6G_MB_LIB.T6G(SCH_1):PAGE398
     2    GND @T6G_MB_LIB.T6G(SCH_1):GND    I72 @T6G_MB_LIB.T6G(SCH_1):PAGE398

C242 Q_CAP_0402-1000PF,50V,5%,X7R,TMP_QCH21006JB10
     1 PVDDCR_SOC_P1_EN_RC @T6G_MB_LIB.T6G(SCH_1):PVDDCR_SOC_P1_EN_RC    I13 @T6G_MB_LIB.T6G(SCH_1):PAGE185
     2    GND @T6G_MB_LIB.T6G(SCH_1):GND    I13 @T6G_MB_LIB.T6G(SCH_1):PAGE185

C243 Q_CAP_0201-1UF,4V,20%,X6S,CH-10KMEE00
     1 P0V9_CPU1_RT0_2A @T6G_MB_LIB.T6G(SCH_1):P0V9_CPU1_RT0_2A    I47 @T6G_MB_LIB.T6G(SCH_1):PAGE398
     2    GND @T6G_MB_LIB.T6G(SCH_1):GND    I47 @T6G_MB_LIB.T6G(SCH_1):PAGE398

C244 Q_CAP_C0402-22UF,4V,20%,X6S,CH622KMEB02
     1 P0V9_CPU1_RT_2D @T6G_MB_LIB.T6G(SCH_1):P0V9_CPU1_RT_2D    I35 @T6G_MB_LIB.T6G(SCH_1):PAGE398
     2    GND @T6G_MB_LIB.T6G(SCH_1):GND    I35 @T6G_MB_LIB.T6G(SCH_1):PAGE398

C245 Q_CAP_C0402-22UF,4V,20%,X6S,CH622KMEB02
     1 PVDDCR_CPU0_P0 @T6G_MB_LIB.T6G(SCH_1):PVDDCR_CPU0_P0    I14 @T6G_MB_LIB.T6G(SCH_1):PAGE68
     2    GND @T6G_MB_LIB.T6G(SCH_1):GND    I14 @T6G_MB_LIB.T6G(SCH_1):PAGE68

C246 Q_CAP_C0402-22UF,4V,20%,X6S,CH622KMEB02
     1 PVDDCR_CPU0_P0 @T6G_MB_LIB.T6G(SCH_1):PVDDCR_CPU0_P0    I10 @T6G_MB_LIB.T6G(SCH_1):PAGE68
     2    GND @T6G_MB_LIB.T6G(SCH_1):GND    I10 @T6G_MB_LIB.T6G(SCH_1):PAGE68

C247 Q_CAP_C0805-100UF,4V,20%,X6S,CH710KMEA01
     1 P0V9_CPU1_RT0_2A @T6G_MB_LIB.T6G(SCH_1):P0V9_CPU1_RT0_2A    I73 @T6G_MB_LIB.T6G(SCH_1):PAGE398
     2    GND @T6G_MB_LIB.T6G(SCH_1):GND    I73 @T6G_MB_LIB.T6G(SCH_1):PAGE398

C248 Q_CAP_0402-1000PF,50V,5%,EMPTY,TMP_QCH21006JB10
     1 PWRGD_PVDDCR_CPU0_P1_R @T6G_MB_LIB.T6G(SCH_1):PWRGD_PVDDCR_CPU0_P1_R    I88 @T6G_MB_LIB.T6G(SCH_1):PAGE185
     2    GND @T6G_MB_LIB.T6G(SCH_1):GND    I88 @T6G_MB_LIB.T6G(SCH_1):PAGE185

C249 Q_CAP_0402-1000PF,50V,5%,X7R,TMP_QCH21006JB10
     1 PVDDCR_CPU0_P1_EN_R @T6G_MB_LIB.T6G(SCH_1):PVDDCR_CPU0_P1_EN_R    I86 @T6G_MB_LIB.T6G(SCH_1):PAGE185
     2    GND @T6G_MB_LIB.T6G(SCH_1):GND    I86 @T6G_MB_LIB.T6G(SCH_1):PAGE185

C250 Q_CAP_C0402-10UF,6.3V,20%,X6S,CH6101MEB01
     1 P0V9_CPU1_RT0_2A @T6G_MB_LIB.T6G(SCH_1):P0V9_CPU1_RT0_2A    I70 @T6G_MB_LIB.T6G(SCH_1):PAGE398
     2    GND @T6G_MB_LIB.T6G(SCH_1):GND    I70 @T6G_MB_LIB.T6G(SCH_1):PAGE398

C251 Q_CAP_C0402-22UF,4V,20%,X6S,CH622KMEB02
     1 PVDDCR_CPU0_P0 @T6G_MB_LIB.T6G(SCH_1):PVDDCR_CPU0_P0    I15 @T6G_MB_LIB.T6G(SCH_1):PAGE68
     2    GND @T6G_MB_LIB.T6G(SCH_1):GND    I15 @T6G_MB_LIB.T6G(SCH_1):PAGE68

C252 Q_CAP_C0402-22UF,4V,20%,X6S,CH622KMEB02
     1 PVDDCR_CPU0_P0 @T6G_MB_LIB.T6G(SCH_1):PVDDCR_CPU0_P0    I12 @T6G_MB_LIB.T6G(SCH_1):PAGE68
     2    GND @T6G_MB_LIB.T6G(SCH_1):GND    I12 @T6G_MB_LIB.T6G(SCH_1):PAGE68

C253 Q_CAP_C0201-0.1UF,10V,10%,X7S,CH4102K6E00
     1 P0V9_CPU1_RT0_2A @T6G_MB_LIB.T6G(SCH_1):P0V9_CPU1_RT0_2A    I86 @T6G_MB_LIB.T6G(SCH_1):PAGE398
     2    GND @T6G_MB_LIB.T6G(SCH_1):GND    I86 @T6G_MB_LIB.T6G(SCH_1):PAGE398

C254 Q_CAP_C0402-10UF,6.3V,20%,X6S,CH6101MEB01
     1 P0V9_CPU1_RT0_2A @T6G_MB_LIB.T6G(SCH_1):P0V9_CPU1_RT0_2A    I67 @T6G_MB_LIB.T6G(SCH_1):PAGE398
     2    GND @T6G_MB_LIB.T6G(SCH_1):GND    I67 @T6G_MB_LIB.T6G(SCH_1):PAGE398

C255 Q_CAP_C0402-22UF,4V,20%,X6S,CH622KMEB02
     1 P0V9_CPU1_RT0_2A @T6G_MB_LIB.T6G(SCH_1):P0V9_CPU1_RT0_2A    I64 @T6G_MB_LIB.T6G(SCH_1):PAGE398
     2    GND @T6G_MB_LIB.T6G(SCH_1):GND    I64 @T6G_MB_LIB.T6G(SCH_1):PAGE398

C256 Q_CAP_0402-4.7UF,6.3V,20%,X6S,CH5471MEB01
     1 P0V9_CPU1_RT_2D @T6G_MB_LIB.T6G(SCH_1):P0V9_CPU1_RT_2D    I39 @T6G_MB_LIB.T6G(SCH_1):PAGE398
     2    GND @T6G_MB_LIB.T6G(SCH_1):GND    I39 @T6G_MB_LIB.T6G(SCH_1):PAGE398

C257 Q_CAP_0201-1UF,4V,20%,X6S,CH-10KMEE00
     1 P0V9_CPU1_RT0_2A @T6G_MB_LIB.T6G(SCH_1):P0V9_CPU1_RT0_2A    I49 @T6G_MB_LIB.T6G(SCH_1):PAGE398
     2    GND @T6G_MB_LIB.T6G(SCH_1):GND    I49 @T6G_MB_LIB.T6G(SCH_1):PAGE398

C258 Q_CAP_0402-4.7UF,6.3V,20%,X6S,CH5471MEB01
     1 P0V9_CPU1_RT0_2A @T6G_MB_LIB.T6G(SCH_1):P0V9_CPU1_RT0_2A    I51 @T6G_MB_LIB.T6G(SCH_1):PAGE398
     2    GND @T6G_MB_LIB.T6G(SCH_1):GND    I51 @T6G_MB_LIB.T6G(SCH_1):PAGE398

C259 Q_CAP_C0402-22UF,4V,20%,X6S,CH622KMEB02
     1 P0V9_CPU1_RT0_2A @T6G_MB_LIB.T6G(SCH_1):P0V9_CPU1_RT0_2A    I66 @T6G_MB_LIB.T6G(SCH_1):PAGE398
     2    GND @T6G_MB_LIB.T6G(SCH_1):GND    I66 @T6G_MB_LIB.T6G(SCH_1):PAGE398

C260 Q_CAP_C0201-0.1UF,10V,10%,X7S,CH4102K6E00
     1 P0V9_CPU1_RT0_2A @T6G_MB_LIB.T6G(SCH_1):P0V9_CPU1_RT0_2A    I84 @T6G_MB_LIB.T6G(SCH_1):PAGE398
     2    GND @T6G_MB_LIB.T6G(SCH_1):GND    I84 @T6G_MB_LIB.T6G(SCH_1):PAGE398

C261 Q_CAP_C0402-10UF,6.3V,20%,X6S,CH6101MEB01
     1 P0V9_CPU1_RT_2D @T6G_MB_LIB.T6G(SCH_1):P0V9_CPU1_RT_2D    I36 @T6G_MB_LIB.T6G(SCH_1):PAGE398
     2    GND @T6G_MB_LIB.T6G(SCH_1):GND    I36 @T6G_MB_LIB.T6G(SCH_1):PAGE398

C262 Q_CAP_C0402-22UF,4V,20%,X6S,CH622KMEB02
     1 P0V9_CPU1_RT0_2A @T6G_MB_LIB.T6G(SCH_1):P0V9_CPU1_RT0_2A    I65 @T6G_MB_LIB.T6G(SCH_1):PAGE398
     2    GND @T6G_MB_LIB.T6G(SCH_1):GND    I65 @T6G_MB_LIB.T6G(SCH_1):PAGE398

C263 Q_CAP_C0402-22UF,4V,20%,X6S,CH622KMEB02
     1 PVDDCR_CPU0_P0 @T6G_MB_LIB.T6G(SCH_1):PVDDCR_CPU0_P0    I46 @T6G_MB_LIB.T6G(SCH_1):PAGE68
     2    GND @T6G_MB_LIB.T6G(SCH_1):GND    I46 @T6G_MB_LIB.T6G(SCH_1):PAGE68

C264 Q_CAP_C0201-0.1UF,10V,10%,X7S,CH4102K6E00
     1 P0V9_CPU1_RT0_2A @T6G_MB_LIB.T6G(SCH_1):P0V9_CPU1_RT0_2A    I81 @T6G_MB_LIB.T6G(SCH_1):PAGE398
     2    GND @T6G_MB_LIB.T6G(SCH_1):GND    I81 @T6G_MB_LIB.T6G(SCH_1):PAGE398

C265 Q_CAP_0201-1UF,4V,20%,X6S,CH-10KMEE00
     1 P0V9_CPU1_RT0_2A @T6G_MB_LIB.T6G(SCH_1):P0V9_CPU1_RT0_2A    I56 @T6G_MB_LIB.T6G(SCH_1):PAGE398
     2    GND @T6G_MB_LIB.T6G(SCH_1):GND    I56 @T6G_MB_LIB.T6G(SCH_1):PAGE398

C266 Q_CAP_C0201-0.1UF,10V,10%,X7S,CH4102K6E00
     1 P0V9_CPU1_RT_2D @T6G_MB_LIB.T6G(SCH_1):P0V9_CPU1_RT_2D    I76 @T6G_MB_LIB.T6G(SCH_1):PAGE398
     2    GND @T6G_MB_LIB.T6G(SCH_1):GND    I76 @T6G_MB_LIB.T6G(SCH_1):PAGE398

C267 Q_CAP_C0402-22UF,4V,20%,X6S,CH622KMEB02
     1 PVDDCR_CPU0_P0 @T6G_MB_LIB.T6G(SCH_1):PVDDCR_CPU0_P0    I50 @T6G_MB_LIB.T6G(SCH_1):PAGE68
     2    GND @T6G_MB_LIB.T6G(SCH_1):GND    I50 @T6G_MB_LIB.T6G(SCH_1):PAGE68

C268 Q_CAP_C0402-22UF,4V,20%,X6S,CH622KMEB02
     1 PVDDCR_CPU0_P0 @T6G_MB_LIB.T6G(SCH_1):PVDDCR_CPU0_P0    I49 @T6G_MB_LIB.T6G(SCH_1):PAGE68
     2    GND @T6G_MB_LIB.T6G(SCH_1):GND    I49 @T6G_MB_LIB.T6G(SCH_1):PAGE68

C269 Q_CAP_C0402-10UF,6.3V,20%,X6S,CH6101MEB01
     1 P0V9_CPU1_RT0_2A @T6G_MB_LIB.T6G(SCH_1):P0V9_CPU1_RT0_2A    I71 @T6G_MB_LIB.T6G(SCH_1):PAGE398
     2    GND @T6G_MB_LIB.T6G(SCH_1):GND    I71 @T6G_MB_LIB.T6G(SCH_1):PAGE398

C270 Q_CAP_C0402-22UF,4V,20%,X6S,CH622KMEB02
     1 PVDDCR_CPU0_P0 @T6G_MB_LIB.T6G(SCH_1):PVDDCR_CPU0_P0    I53 @T6G_MB_LIB.T6G(SCH_1):PAGE68
     2    GND @T6G_MB_LIB.T6G(SCH_1):GND    I53 @T6G_MB_LIB.T6G(SCH_1):PAGE68

C271 Q_CAP_C0402-22UF,4V,20%,X6S,CH622KMEB02
     1 PVDDCR_CPU0_P0 @T6G_MB_LIB.T6G(SCH_1):PVDDCR_CPU0_P0    I51 @T6G_MB_LIB.T6G(SCH_1):PAGE68
     2    GND @T6G_MB_LIB.T6G(SCH_1):GND    I51 @T6G_MB_LIB.T6G(SCH_1):PAGE68

C272 Q_CAP_C0402-22UF,4V,20%,X6S,CH622KMEB02
     1 PVDDCR_CPU0_P0 @T6G_MB_LIB.T6G(SCH_1):PVDDCR_CPU0_P0   I110 @T6G_MB_LIB.T6G(SCH_1):PAGE68
     2    GND @T6G_MB_LIB.T6G(SCH_1):GND   I110 @T6G_MB_LIB.T6G(SCH_1):PAGE68

C273 Q_CAP_C0402-22UF,4V,20%,X6S,CH622KMEB02
     1 PVDDCR_CPU0_P0 @T6G_MB_LIB.T6G(SCH_1):PVDDCR_CPU0_P0    I52 @T6G_MB_LIB.T6G(SCH_1):PAGE68
     2    GND @T6G_MB_LIB.T6G(SCH_1):GND    I52 @T6G_MB_LIB.T6G(SCH_1):PAGE68

C274 Q_CAP_C0402-22UF,4V,20%,X6S,CH622KMEB02
     1 PVDDCR_CPU0_P0 @T6G_MB_LIB.T6G(SCH_1):PVDDCR_CPU0_P0    I56 @T6G_MB_LIB.T6G(SCH_1):PAGE68
     2    GND @T6G_MB_LIB.T6G(SCH_1):GND    I56 @T6G_MB_LIB.T6G(SCH_1):PAGE68

C275 Q_CAP_C0402-22UF,4V,20%,X6S,CH622KMEB02
     1 PVDDCR_CPU0_P0 @T6G_MB_LIB.T6G(SCH_1):PVDDCR_CPU0_P0    I54 @T6G_MB_LIB.T6G(SCH_1):PAGE68
     2    GND @T6G_MB_LIB.T6G(SCH_1):GND    I54 @T6G_MB_LIB.T6G(SCH_1):PAGE68

C276 Q_CAP_C0402-22UF,4V,20%,X6S,CH622KMEB02
     1 PVDDCR_CPU0_P0 @T6G_MB_LIB.T6G(SCH_1):PVDDCR_CPU0_P0    I57 @T6G_MB_LIB.T6G(SCH_1):PAGE68
     2    GND @T6G_MB_LIB.T6G(SCH_1):GND    I57 @T6G_MB_LIB.T6G(SCH_1):PAGE68

C277 Q_CAP_C0402-22UF,4V,20%,X6S,CH622KMEB02
     1 PVDDCR_CPU0_P0 @T6G_MB_LIB.T6G(SCH_1):PVDDCR_CPU0_P0    I55 @T6G_MB_LIB.T6G(SCH_1):PAGE68
     2    GND @T6G_MB_LIB.T6G(SCH_1):GND    I55 @T6G_MB_LIB.T6G(SCH_1):PAGE68

C278 Q_CAP_C0402-22UF,4V,20%,X6S,CH622KMEB02
     1 PVDDCR_CPU0_P0 @T6G_MB_LIB.T6G(SCH_1):PVDDCR_CPU0_P0    I62 @T6G_MB_LIB.T6G(SCH_1):PAGE68
     2    GND @T6G_MB_LIB.T6G(SCH_1):GND    I62 @T6G_MB_LIB.T6G(SCH_1):PAGE68

C279 Q_CAP_C0402-22UF,4V,20%,X6S,CH622KMEB02
     1 PVDDCR_CPU0_P0 @T6G_MB_LIB.T6G(SCH_1):PVDDCR_CPU0_P0    I58 @T6G_MB_LIB.T6G(SCH_1):PAGE68
     2    GND @T6G_MB_LIB.T6G(SCH_1):GND    I58 @T6G_MB_LIB.T6G(SCH_1):PAGE68

C280 Q_CAP_0201-1UF,4V,20%,X6S,CH-10KMEE00
     1 P0V9_CPU1_RT0_2A @T6G_MB_LIB.T6G(SCH_1):P0V9_CPU1_RT0_2A    I59 @T6G_MB_LIB.T6G(SCH_1):PAGE398
     2    GND @T6G_MB_LIB.T6G(SCH_1):GND    I59 @T6G_MB_LIB.T6G(SCH_1):PAGE398

C281 Q_CAP_C0201-0.1UF,10V,10%,X7S,CH4102K6E00
     1 P0V9_CPU1_RT0_2A @T6G_MB_LIB.T6G(SCH_1):P0V9_CPU1_RT0_2A   I101 @T6G_MB_LIB.T6G(SCH_1):PAGE398
     2    GND @T6G_MB_LIB.T6G(SCH_1):GND   I101 @T6G_MB_LIB.T6G(SCH_1):PAGE398

C282 Q_CAP_C0201-0.1UF,10V,10%,X7S,CH4102K6E00
     1 P0V9_CPU1_RT0_2A @T6G_MB_LIB.T6G(SCH_1):P0V9_CPU1_RT0_2A    I80 @T6G_MB_LIB.T6G(SCH_1):PAGE398
     2    GND @T6G_MB_LIB.T6G(SCH_1):GND    I80 @T6G_MB_LIB.T6G(SCH_1):PAGE398

C283 Q_CAP_C0201-0.1UF,10V,10%,X7S,CH4102K6E00
     1 P0V9_CPU1_RT0_2A @T6G_MB_LIB.T6G(SCH_1):P0V9_CPU1_RT0_2A   I102 @T6G_MB_LIB.T6G(SCH_1):PAGE398
     2    GND @T6G_MB_LIB.T6G(SCH_1):GND   I102 @T6G_MB_LIB.T6G(SCH_1):PAGE398

C284 Q_CAP_C0402-22UF,4V,20%,X6S,CH622KMEB02
     1 P0V9_CPU1_RT0_2A @T6G_MB_LIB.T6G(SCH_1):P0V9_CPU1_RT0_2A    I54 @T6G_MB_LIB.T6G(SCH_1):PAGE398
     2    GND @T6G_MB_LIB.T6G(SCH_1):GND    I54 @T6G_MB_LIB.T6G(SCH_1):PAGE398

C285 Q_CAP_0201-1UF,4V,20%,X6S,CH-10KMEE00
     1 P0V9_CPU1_RT0_2A @T6G_MB_LIB.T6G(SCH_1):P0V9_CPU1_RT0_2A    I63 @T6G_MB_LIB.T6G(SCH_1):PAGE398
     2    GND @T6G_MB_LIB.T6G(SCH_1):GND    I63 @T6G_MB_LIB.T6G(SCH_1):PAGE398

C286 Q_CAP_C0402-10UF,6.3V,20%,X6S,CH6101MEB01
     1 P0V9_CPU1_RT0_2A @T6G_MB_LIB.T6G(SCH_1):P0V9_CPU1_RT0_2A    I68 @T6G_MB_LIB.T6G(SCH_1):PAGE398
     2    GND @T6G_MB_LIB.T6G(SCH_1):GND    I68 @T6G_MB_LIB.T6G(SCH_1):PAGE398

C287 Q_CAP_C0201-0.1UF,10V,10%,X7S,CH4102K6E00
     1 P1V8_CPU1_RT1_1A @T6G_MB_LIB.T6G(SCH_1):P1V8_CPU1_RT1_1A    I28 @T6G_MB_LIB.T6G(SCH_1):PAGE443
     2    GND @T6G_MB_LIB.T6G(SCH_1):GND    I28 @T6G_MB_LIB.T6G(SCH_1):PAGE443

C288 Q_CAP_C0201-0.1UF,10V,10%,X7S,CH4102K6E00
     1 P1V8_CPU1_RT1_1A @T6G_MB_LIB.T6G(SCH_1):P1V8_CPU1_RT1_1A    I29 @T6G_MB_LIB.T6G(SCH_1):PAGE443
     2    GND @T6G_MB_LIB.T6G(SCH_1):GND    I29 @T6G_MB_LIB.T6G(SCH_1):PAGE443

C289 Q_CAP_0201-1UF,4V,20%,X6S,CH-10KMEE00
     1 P0V9_CPU1_RT1_2A @T6G_MB_LIB.T6G(SCH_1):P0V9_CPU1_RT1_2A    I65 @T6G_MB_LIB.T6G(SCH_1):PAGE443
     2    GND @T6G_MB_LIB.T6G(SCH_1):GND    I65 @T6G_MB_LIB.T6G(SCH_1):PAGE443

C290 Q_CAP_C0201-0.1UF,10V,10%,X7S,CH4102K6E00
     1 P0V9_CPU1_RT_2D @T6G_MB_LIB.T6G(SCH_1):P0V9_CPU1_RT_2D    I86 @T6G_MB_LIB.T6G(SCH_1):PAGE443
     2    GND @T6G_MB_LIB.T6G(SCH_1):GND    I86 @T6G_MB_LIB.T6G(SCH_1):PAGE443

C291 Q_CAP_C0201-0.1UF,10V,10%,X7S,CH4102K6E00
     1 P0V9_CPU1_RT1_2A @T6G_MB_LIB.T6G(SCH_1):P0V9_CPU1_RT1_2A    I50 @T6G_MB_LIB.T6G(SCH_1):PAGE443
     2    GND @T6G_MB_LIB.T6G(SCH_1):GND    I50 @T6G_MB_LIB.T6G(SCH_1):PAGE443

C292 Q_CAP_C0201-0.1UF,10V,10%,X7S,CH4102K6E00
     1 P0V9_CPU1_RT_2D @T6G_MB_LIB.T6G(SCH_1):P0V9_CPU1_RT_2D    I85 @T6G_MB_LIB.T6G(SCH_1):PAGE443
     2    GND @T6G_MB_LIB.T6G(SCH_1):GND    I85 @T6G_MB_LIB.T6G(SCH_1):PAGE443

C293 Q_CAP_0201-1UF,4V,20%,X6S,CH-10KMEE00
     1 P0V9_CPU1_RT1_2A @T6G_MB_LIB.T6G(SCH_1):P0V9_CPU1_RT1_2A    I58 @T6G_MB_LIB.T6G(SCH_1):PAGE443
     2    GND @T6G_MB_LIB.T6G(SCH_1):GND    I58 @T6G_MB_LIB.T6G(SCH_1):PAGE443

C294 Q_CAP_0201-1UF,4V,20%,X6S,CH-10KMEE00
     1 P0V9_CPU1_RT1_2A @T6G_MB_LIB.T6G(SCH_1):P0V9_CPU1_RT1_2A    I40 @T6G_MB_LIB.T6G(SCH_1):PAGE443
     2    GND @T6G_MB_LIB.T6G(SCH_1):GND    I40 @T6G_MB_LIB.T6G(SCH_1):PAGE443

C295 Q_CAP_0402-10PF,50V,5%,EMPTY,CH01006JB08
     1 SVID_PVDDCR_CPU0_P1_SVTO @T6G_MB_LIB.T6G(SCH_1):SVID_PVDDCR_CPU0_P1_SVTO    I62 @T6G_MB_LIB.T6G(SCH_1):PAGE185
     2    GND @T6G_MB_LIB.T6G(SCH_1):GND    I62 @T6G_MB_LIB.T6G(SCH_1):PAGE185

C296 Q_CAP_0402-10PF,50V,5%,EMPTY,CH01006JB08
     1 SVID_PVDDCR_CPU0_P1_SVD_R @T6G_MB_LIB.T6G(SCH_1):SVID_PVDDCR_CPU0_P1_SVD_R    I64 @T6G_MB_LIB.T6G(SCH_1):PAGE185
     2    GND @T6G_MB_LIB.T6G(SCH_1):GND    I64 @T6G_MB_LIB.T6G(SCH_1):PAGE185

C297 Q_CAP_0402-10PF,50V,5%,EMPTY,CH01006JB08
     1 SVID_PVDDCR_CPU0_P1_SVC_R @T6G_MB_LIB.T6G(SCH_1):SVID_PVDDCR_CPU0_P1_SVC_R    I66 @T6G_MB_LIB.T6G(SCH_1):PAGE185
     2    GND @T6G_MB_LIB.T6G(SCH_1):GND    I66 @T6G_MB_LIB.T6G(SCH_1):PAGE185

C298 Q_CAP_0402-10PF,50V,5%,EMPTY,CH01006JB08
     1 SVID_PVDDCR_CPU0_P0_SVTO @T6G_MB_LIB.T6G(SCH_1):SVID_PVDDCR_CPU0_P0_SVTO    I64 @T6G_MB_LIB.T6G(SCH_1):PAGE168
     2    GND @T6G_MB_LIB.T6G(SCH_1):GND    I64 @T6G_MB_LIB.T6G(SCH_1):PAGE168

C299 Q_CAP_0402-10PF,50V,5%,EMPTY,CH01006JB08
     1 SVID_PVDDCR_CPU0_P0_SVD_R @T6G_MB_LIB.T6G(SCH_1):SVID_PVDDCR_CPU0_P0_SVD_R    I66 @T6G_MB_LIB.T6G(SCH_1):PAGE168
     2    GND @T6G_MB_LIB.T6G(SCH_1):GND    I66 @T6G_MB_LIB.T6G(SCH_1):PAGE168

C300 Q_CAP_C0201-0.1UF,10V,10%,X7S,CH4102K6E00
     1 P0V9_CPU1_RT_2D @T6G_MB_LIB.T6G(SCH_1):P0V9_CPU1_RT_2D    I82 @T6G_MB_LIB.T6G(SCH_1):PAGE443
     2    GND @T6G_MB_LIB.T6G(SCH_1):GND    I82 @T6G_MB_LIB.T6G(SCH_1):PAGE443

C301 Q_CAP_0201-1UF,4V,20%,X6S,CH-10KMEE00
     1 P0V9_CPU1_RT1_2A @T6G_MB_LIB.T6G(SCH_1):P0V9_CPU1_RT1_2A    I59 @T6G_MB_LIB.T6G(SCH_1):PAGE443
     2    GND @T6G_MB_LIB.T6G(SCH_1):GND    I59 @T6G_MB_LIB.T6G(SCH_1):PAGE443

C302 Q_CAP_0402-10PF,50V,5%,EMPTY,CH01006JB08
     1 SVID_PVDDCR_CPU0_P0_SVC_R @T6G_MB_LIB.T6G(SCH_1):SVID_PVDDCR_CPU0_P0_SVC_R    I68 @T6G_MB_LIB.T6G(SCH_1):PAGE168
     2    GND @T6G_MB_LIB.T6G(SCH_1):GND    I68 @T6G_MB_LIB.T6G(SCH_1):PAGE168

C303 Q_CAP_0402-10PF,50V,5%,EMPTY,CH01006JB08
     1 SVID_PVDDCR_CPU1_P0_SVTO @T6G_MB_LIB.T6G(SCH_1):SVID_PVDDCR_CPU1_P0_SVTO    I33 @T6G_MB_LIB.T6G(SCH_1):PAGE175
     2    GND @T6G_MB_LIB.T6G(SCH_1):GND    I33 @T6G_MB_LIB.T6G(SCH_1):PAGE175

C304 Q_CAP_0402-10PF,50V,5%,EMPTY,CH01006JB08
     1 SVID_PVDDCR_CPU1_P0_SVD_R @T6G_MB_LIB.T6G(SCH_1):SVID_PVDDCR_CPU1_P0_SVD_R    I34 @T6G_MB_LIB.T6G(SCH_1):PAGE175
     2    GND @T6G_MB_LIB.T6G(SCH_1):GND    I34 @T6G_MB_LIB.T6G(SCH_1):PAGE175

C305 Q_CAP_0402-10PF,50V,5%,EMPTY,CH01006JB08
     1 SVID_PVDDCR_CPU1_P0_SVC_R @T6G_MB_LIB.T6G(SCH_1):SVID_PVDDCR_CPU1_P0_SVC_R    I35 @T6G_MB_LIB.T6G(SCH_1):PAGE175
     2    GND @T6G_MB_LIB.T6G(SCH_1):GND    I35 @T6G_MB_LIB.T6G(SCH_1):PAGE175

C306 Q_CAP_0201-1UF,4V,20%,X6S,CH-10KMEE00
     1 P0V9_CPU1_RT1_2A_2D @T6G_MB_LIB.T6G(SCH_1):P0V9_CPU1_RT1_2A_2D    I90 @T6G_MB_LIB.T6G(SCH_1):PAGE443
     2    GND @T6G_MB_LIB.T6G(SCH_1):GND    I90 @T6G_MB_LIB.T6G(SCH_1):PAGE443

C307 Q_CAP_0201-1UF,4V,20%,X6S,CH-10KMEE00
     1 P0V9_CPU1_RT1_2A @T6G_MB_LIB.T6G(SCH_1):P0V9_CPU1_RT1_2A    I42 @T6G_MB_LIB.T6G(SCH_1):PAGE443
     2    GND @T6G_MB_LIB.T6G(SCH_1):GND    I42 @T6G_MB_LIB.T6G(SCH_1):PAGE443

C308 Q_CAP_0402-10PF,50V,5%,EMPTY,CH01006JB08
     1 SVID_PVDDCR_CPU1_P1_SVTO @T6G_MB_LIB.T6G(SCH_1):SVID_PVDDCR_CPU1_P1_SVTO    I31 @T6G_MB_LIB.T6G(SCH_1):PAGE192
     2    GND @T6G_MB_LIB.T6G(SCH_1):GND    I31 @T6G_MB_LIB.T6G(SCH_1):PAGE192

C309 Q_CAP_0402-10PF,50V,5%,EMPTY,CH01006JB08
     1 SVID_PVDDCR_CPU1_P1_SVD_R @T6G_MB_LIB.T6G(SCH_1):SVID_PVDDCR_CPU1_P1_SVD_R    I32 @T6G_MB_LIB.T6G(SCH_1):PAGE192
     2    GND @T6G_MB_LIB.T6G(SCH_1):GND    I32 @T6G_MB_LIB.T6G(SCH_1):PAGE192

C310 Q_CAP_0402-10PF,50V,5%,EMPTY,CH01006JB08
     1 SVID_PVDDCR_CPU1_P1_SVC_R @T6G_MB_LIB.T6G(SCH_1):SVID_PVDDCR_CPU1_P1_SVC_R    I33 @T6G_MB_LIB.T6G(SCH_1):PAGE192
     2    GND @T6G_MB_LIB.T6G(SCH_1):GND    I33 @T6G_MB_LIB.T6G(SCH_1):PAGE192

C311 Q_CAP_C0201-0.1UF,10V,10%,X7S,CH4102K6E00
     1 P0V9_CPU1_RT_2D @T6G_MB_LIB.T6G(SCH_1):P0V9_CPU1_RT_2D    I84 @T6G_MB_LIB.T6G(SCH_1):PAGE443
     2    GND @T6G_MB_LIB.T6G(SCH_1):GND    I84 @T6G_MB_LIB.T6G(SCH_1):PAGE443

C312 Q_CAP_C0201-0.1UF,10V,10%,X7S,CH4102K6E00
     1 P0V9_CPU1_RT1_2A @T6G_MB_LIB.T6G(SCH_1):P0V9_CPU1_RT1_2A    I48 @T6G_MB_LIB.T6G(SCH_1):PAGE443
     2    GND @T6G_MB_LIB.T6G(SCH_1):GND    I48 @T6G_MB_LIB.T6G(SCH_1):PAGE443

C313 Q_CAP_C0201-0.1UF,10V,10%,X7S,CH4102K6E00
     1 P0V9_CPU1_RT1_2A_2D @T6G_MB_LIB.T6G(SCH_1):P0V9_CPU1_RT1_2A_2D    I34 @T6G_MB_LIB.T6G(SCH_1):PAGE443
     2    GND @T6G_MB_LIB.T6G(SCH_1):GND    I34 @T6G_MB_LIB.T6G(SCH_1):PAGE443

C314 Q_CAP_0201-1UF,4V,20%,X6S,CH-10KMEE00
     1 P0V9_CPU1_RT1_2A @T6G_MB_LIB.T6G(SCH_1):P0V9_CPU1_RT1_2A    I52 @T6G_MB_LIB.T6G(SCH_1):PAGE443
     2    GND @T6G_MB_LIB.T6G(SCH_1):GND    I52 @T6G_MB_LIB.T6G(SCH_1):PAGE443

C315 Q_CAP_0201-1UF,4V,20%,X6S,CH-10KMEE00
     1 P0V9_CPU1_RT1_2A_2D @T6G_MB_LIB.T6G(SCH_1):P0V9_CPU1_RT1_2A_2D    I91 @T6G_MB_LIB.T6G(SCH_1):PAGE443
     2    GND @T6G_MB_LIB.T6G(SCH_1):GND    I91 @T6G_MB_LIB.T6G(SCH_1):PAGE443

C316 Q_CAP_C0201-0.1UF,10V,10%,X7S,CH4102K6E00
     1 P0V9_CPU1_RT1_2A_2D @T6G_MB_LIB.T6G(SCH_1):P0V9_CPU1_RT1_2A_2D    I37 @T6G_MB_LIB.T6G(SCH_1):PAGE443
     2    GND @T6G_MB_LIB.T6G(SCH_1):GND    I37 @T6G_MB_LIB.T6G(SCH_1):PAGE443

C317 Q_CAP_C0805-100UF,4V,20%,X6S,CH710KMEA01
     1 P0V9_CPU1_RT1_2A @T6G_MB_LIB.T6G(SCH_1):P0V9_CPU1_RT1_2A    I67 @T6G_MB_LIB.T6G(SCH_1):PAGE443
     2    GND @T6G_MB_LIB.T6G(SCH_1):GND    I67 @T6G_MB_LIB.T6G(SCH_1):PAGE443

C318 Q_CAP_C0402-22UF,4V,20%,X6S,CH622KMEB02
     1 P0V9_CPU1_RT1_2A @T6G_MB_LIB.T6G(SCH_1):P0V9_CPU1_RT1_2A    I77 @T6G_MB_LIB.T6G(SCH_1):PAGE443
     2    GND @T6G_MB_LIB.T6G(SCH_1):GND    I77 @T6G_MB_LIB.T6G(SCH_1):PAGE443

C319 Q_CAP_C0201-0.1UF,10V,10%,X7S,CH4102K6E00
     1 P0V9_CPU1_RT1_2A @T6G_MB_LIB.T6G(SCH_1):P0V9_CPU1_RT1_2A    I51 @T6G_MB_LIB.T6G(SCH_1):PAGE443
     2    GND @T6G_MB_LIB.T6G(SCH_1):GND    I51 @T6G_MB_LIB.T6G(SCH_1):PAGE443

C320 Q_CAP_C0805-100UF,4V,20%,X6S,CH710KMEA01
     1 P0V9_CPU1_RT1_2A @T6G_MB_LIB.T6G(SCH_1):P0V9_CPU1_RT1_2A    I69 @T6G_MB_LIB.T6G(SCH_1):PAGE443
     2    GND @T6G_MB_LIB.T6G(SCH_1):GND    I69 @T6G_MB_LIB.T6G(SCH_1):PAGE443

C321 Q_CAP_C0402-10UF,6.3V,20%,X6S,CH6101MEB01
     1 P0V9_CPU1_RT1_2A @T6G_MB_LIB.T6G(SCH_1):P0V9_CPU1_RT1_2A    I44 @T6G_MB_LIB.T6G(SCH_1):PAGE443
     2    GND @T6G_MB_LIB.T6G(SCH_1):GND    I44 @T6G_MB_LIB.T6G(SCH_1):PAGE443

C322 Q_CAP_C0201-0.1UF,10V,10%,X7S,CH4102K6E00
     1 P0V9_CPU1_RT1_2A @T6G_MB_LIB.T6G(SCH_1):P0V9_CPU1_RT1_2A    I60 @T6G_MB_LIB.T6G(SCH_1):PAGE443
     2    GND @T6G_MB_LIB.T6G(SCH_1):GND    I60 @T6G_MB_LIB.T6G(SCH_1):PAGE443

C323 Q_CAP_C0805-100UF,4V,20%,X6S,CH710KMEA01
     1 P0V9_CPU1_RT_2D @T6G_MB_LIB.T6G(SCH_1):P0V9_CPU1_RT_2D    I72 @T6G_MB_LIB.T6G(SCH_1):PAGE443
     2    GND @T6G_MB_LIB.T6G(SCH_1):GND    I72 @T6G_MB_LIB.T6G(SCH_1):PAGE443

C324 Q_CAP_C0805-100UF,4V,20%,X6S,CH710KMEA01
     1 P0V9_CPU1_RT1_2A @T6G_MB_LIB.T6G(SCH_1):P0V9_CPU1_RT1_2A    I70 @T6G_MB_LIB.T6G(SCH_1):PAGE443
     2    GND @T6G_MB_LIB.T6G(SCH_1):GND    I70 @T6G_MB_LIB.T6G(SCH_1):PAGE443

C325 Q_CAP_0402-4.7UF,6.3V,20%,X6S,CH5471MEB01
     1 P0V9_CPU1_RT1_2A @T6G_MB_LIB.T6G(SCH_1):P0V9_CPU1_RT1_2A    I45 @T6G_MB_LIB.T6G(SCH_1):PAGE443
     2    GND @T6G_MB_LIB.T6G(SCH_1):GND    I45 @T6G_MB_LIB.T6G(SCH_1):PAGE443

C326 Q_CAP_0201-1UF,4V,20%,X6S,CH-10KMEE00
     1 P0V9_CPU1_RT1_2A @T6G_MB_LIB.T6G(SCH_1):P0V9_CPU1_RT1_2A    I43 @T6G_MB_LIB.T6G(SCH_1):PAGE443
     2    GND @T6G_MB_LIB.T6G(SCH_1):GND    I43 @T6G_MB_LIB.T6G(SCH_1):PAGE443

C327 Q_CAP_C0402-22UF,4V,20%,X6S,CH622KMEB02
     1 P0V9_CPU1_RT_2D @T6G_MB_LIB.T6G(SCH_1):P0V9_CPU1_RT_2D    I73 @T6G_MB_LIB.T6G(SCH_1):PAGE443
     2    GND @T6G_MB_LIB.T6G(SCH_1):GND    I73 @T6G_MB_LIB.T6G(SCH_1):PAGE443

C328 Q_CAP_C0805-100UF,4V,20%,X6S,CH710KMEA01
     1 P0V9_CPU1_RT1_2A @T6G_MB_LIB.T6G(SCH_1):P0V9_CPU1_RT1_2A    I71 @T6G_MB_LIB.T6G(SCH_1):PAGE443
     2    GND @T6G_MB_LIB.T6G(SCH_1):GND    I71 @T6G_MB_LIB.T6G(SCH_1):PAGE443

C329 Q_CAP_C0402-22UF,4V,20%,X6S,CH622KMEB02
     1 P0V9_CPU1_RT1_2A @T6G_MB_LIB.T6G(SCH_1):P0V9_CPU1_RT1_2A    I74 @T6G_MB_LIB.T6G(SCH_1):PAGE443
     2    GND @T6G_MB_LIB.T6G(SCH_1):GND    I74 @T6G_MB_LIB.T6G(SCH_1):PAGE443

C330 Q_CAP_0201-1UF,4V,20%,X6S,CH-10KMEE00
     1 P0V9_CPU1_RT1_2A @T6G_MB_LIB.T6G(SCH_1):P0V9_CPU1_RT1_2A    I47 @T6G_MB_LIB.T6G(SCH_1):PAGE443
     2    GND @T6G_MB_LIB.T6G(SCH_1):GND    I47 @T6G_MB_LIB.T6G(SCH_1):PAGE443

C331 Q_CAP_0402-4.7UF,6.3V,20%,X6S,CH5471MEB01
     1 P0V9_CPU1_RT1_2A @T6G_MB_LIB.T6G(SCH_1):P0V9_CPU1_RT1_2A    I46 @T6G_MB_LIB.T6G(SCH_1):PAGE443
     2    GND @T6G_MB_LIB.T6G(SCH_1):GND    I46 @T6G_MB_LIB.T6G(SCH_1):PAGE443

C332 Q_CAP_C0402-10UF,6.3V,20%,X6S,CH6101MEB01
     1 P0V9_CPU1_RT1_2A @T6G_MB_LIB.T6G(SCH_1):P0V9_CPU1_RT1_2A    I41 @T6G_MB_LIB.T6G(SCH_1):PAGE443
     2    GND @T6G_MB_LIB.T6G(SCH_1):GND    I41 @T6G_MB_LIB.T6G(SCH_1):PAGE443

C333 Q_CAP_C0402-10UF,6.3V,20%,X6S,CH6101MEB01
     1 P0V9_CPU1_RT_2D @T6G_MB_LIB.T6G(SCH_1):P0V9_CPU1_RT_2D    I87 @T6G_MB_LIB.T6G(SCH_1):PAGE443
     2    GND @T6G_MB_LIB.T6G(SCH_1):GND    I87 @T6G_MB_LIB.T6G(SCH_1):PAGE443

C334 Q_CAP_C0201-0.1UF,10V,10%,X7S,CH4102K6E00
     1 P0V9_CPU1_RT1_2A @T6G_MB_LIB.T6G(SCH_1):P0V9_CPU1_RT1_2A    I62 @T6G_MB_LIB.T6G(SCH_1):PAGE443
     2    GND @T6G_MB_LIB.T6G(SCH_1):GND    I62 @T6G_MB_LIB.T6G(SCH_1):PAGE443

C335 Q_CAP_C0402-22UF,4V,20%,X6S,CH622KMEB02
     1 P0V9_CPU1_RT1_2A @T6G_MB_LIB.T6G(SCH_1):P0V9_CPU1_RT1_2A    I75 @T6G_MB_LIB.T6G(SCH_1):PAGE443
     2    GND @T6G_MB_LIB.T6G(SCH_1):GND    I75 @T6G_MB_LIB.T6G(SCH_1):PAGE443

C336 Q_CAP_0402-4.7UF,6.3V,20%,X6S,CH5471MEB01
     1 P0V9_CPU1_RT1_2A @T6G_MB_LIB.T6G(SCH_1):P0V9_CPU1_RT1_2A    I55 @T6G_MB_LIB.T6G(SCH_1):PAGE443
     2    GND @T6G_MB_LIB.T6G(SCH_1):GND    I55 @T6G_MB_LIB.T6G(SCH_1):PAGE443

C337 Q_CAP_0201-1UF,4V,20%,X6S,CH-10KMEE00
     1 P0V9_CPU1_RT1_2A @T6G_MB_LIB.T6G(SCH_1):P0V9_CPU1_RT1_2A    I53 @T6G_MB_LIB.T6G(SCH_1):PAGE443
     2    GND @T6G_MB_LIB.T6G(SCH_1):GND    I53 @T6G_MB_LIB.T6G(SCH_1):PAGE443

C338 Q_CAP_0402-4.7UF,6.3V,20%,X6S,CH5471MEB01
     1 P0V9_CPU1_RT_2D @T6G_MB_LIB.T6G(SCH_1):P0V9_CPU1_RT_2D    I78 @T6G_MB_LIB.T6G(SCH_1):PAGE443
     2    GND @T6G_MB_LIB.T6G(SCH_1):GND    I78 @T6G_MB_LIB.T6G(SCH_1):PAGE443

C339 Q_CAP_C0402-10UF,6.3V,20%,X6S,CH6101MEB01
     1 P0V9_CPU1_RT1_2A @T6G_MB_LIB.T6G(SCH_1):P0V9_CPU1_RT1_2A    I80 @T6G_MB_LIB.T6G(SCH_1):PAGE443
     2    GND @T6G_MB_LIB.T6G(SCH_1):GND    I80 @T6G_MB_LIB.T6G(SCH_1):PAGE443

C340 Q_CAP_C0201-0.1UF,10V,10%,X7S,CH4102K6E00
     1 P0V9_CPU1_RT1_2A @T6G_MB_LIB.T6G(SCH_1):P0V9_CPU1_RT1_2A    I38 @T6G_MB_LIB.T6G(SCH_1):PAGE443
     2    GND @T6G_MB_LIB.T6G(SCH_1):GND    I38 @T6G_MB_LIB.T6G(SCH_1):PAGE443

C341 Q_CAP_C0201-0.1UF,10V,10%,X7S,CH4102K6E00
     1 P0V9_CPU1_RT1_2A @T6G_MB_LIB.T6G(SCH_1):P0V9_CPU1_RT1_2A    I92 @T6G_MB_LIB.T6G(SCH_1):PAGE443
     2    GND @T6G_MB_LIB.T6G(SCH_1):GND    I92 @T6G_MB_LIB.T6G(SCH_1):PAGE443

C342 Q_CAP_0201-1UF,4V,20%,X6S,CH-10KMEE00
     1 P0V9_CPU1_RT_2D @T6G_MB_LIB.T6G(SCH_1):P0V9_CPU1_RT_2D    I79 @T6G_MB_LIB.T6G(SCH_1):PAGE443
     2    GND @T6G_MB_LIB.T6G(SCH_1):GND    I79 @T6G_MB_LIB.T6G(SCH_1):PAGE443

C343 Q_CAP_0402-4.7UF,6.3V,20%,X6S,CH5471MEB01
     1 P0V9_CPU1_RT1_2A @T6G_MB_LIB.T6G(SCH_1):P0V9_CPU1_RT1_2A    I54 @T6G_MB_LIB.T6G(SCH_1):PAGE443
     2    GND @T6G_MB_LIB.T6G(SCH_1):GND    I54 @T6G_MB_LIB.T6G(SCH_1):PAGE443

C344 Q_CAP_C0201-0.1UF,10V,10%,X7S,CH4102K6E00
     1 P0V9_CPU1_RT1_2A @T6G_MB_LIB.T6G(SCH_1):P0V9_CPU1_RT1_2A    I39 @T6G_MB_LIB.T6G(SCH_1):PAGE443
     2    GND @T6G_MB_LIB.T6G(SCH_1):GND    I39 @T6G_MB_LIB.T6G(SCH_1):PAGE443

C345 Q_CAP_0402-0.1UF,25V,10%,EMPTY,CH4104K1B00
     1 P1V8_AUX_ENABLE @T6G_MB_LIB.T6G(SCH_1):P1V8_AUX_ENABLE    I41 @T6G_MB_LIB.T6G(SCH_1):PAGE315
     2    GND @T6G_MB_LIB.T6G(SCH_1):GND    I41 @T6G_MB_LIB.T6G(SCH_1):PAGE315

C346 Q_CAP_0201-1UF,4V,20%,X6S,CH-10KMEE00
     1 P0V9_CPU1_RT1_2A @T6G_MB_LIB.T6G(SCH_1):P0V9_CPU1_RT1_2A    I57 @T6G_MB_LIB.T6G(SCH_1):PAGE443
     2    GND @T6G_MB_LIB.T6G(SCH_1):GND    I57 @T6G_MB_LIB.T6G(SCH_1):PAGE443

C347 Q_CAP_0402-0.1UF,25V,10%,X7R,CH4104K1B00
     1 P1V8_AUX @T6G_MB_LIB.T6G(SCH_1):P1V8_AUX    I47 @T6G_MB_LIB.T6G(SCH_1):PAGE264
     2    GND @T6G_MB_LIB.T6G(SCH_1):GND    I47 @T6G_MB_LIB.T6G(SCH_1):PAGE264

C348 Q_CAP_0402-0.1UF,25V,10%,EMPTY,CH4104K1B00
     1 PVDD33_S5_EN @T6G_MB_LIB.T6G(SCH_1):PVDD33_S5_EN     I5 @T6G_MB_LIB.T6G(SCH_1):PAGE167
     2    GND @T6G_MB_LIB.T6G(SCH_1):GND     I5 @T6G_MB_LIB.T6G(SCH_1):PAGE167

C349 Q_CAP_C0201-0.1UF,10V,10%,X7S,CH4102K6E00
     1 P0V9_CPU1_RT1_2A @T6G_MB_LIB.T6G(SCH_1):P0V9_CPU1_RT1_2A    I49 @T6G_MB_LIB.T6G(SCH_1):PAGE443
     2    GND @T6G_MB_LIB.T6G(SCH_1):GND    I49 @T6G_MB_LIB.T6G(SCH_1):PAGE443

C350 Q_CAP_C0201-0.1UF,10V,10%,X7S,CH4102K6E00
     1 P0V9_CPU1_RT1_2A @T6G_MB_LIB.T6G(SCH_1):P0V9_CPU1_RT1_2A    I93 @T6G_MB_LIB.T6G(SCH_1):PAGE443
     2    GND @T6G_MB_LIB.T6G(SCH_1):GND    I93 @T6G_MB_LIB.T6G(SCH_1):PAGE443

C351 Q_CAP_C0402-22UF,4V,20%,X6S,CH622KMEB02
     1 P0V9_CPU1_RT1_2A @T6G_MB_LIB.T6G(SCH_1):P0V9_CPU1_RT1_2A    I76 @T6G_MB_LIB.T6G(SCH_1):PAGE443
     2    GND @T6G_MB_LIB.T6G(SCH_1):GND    I76 @T6G_MB_LIB.T6G(SCH_1):PAGE443

C352 Q_CAP_C0402-0.1UF,16V,10%,X7R,CH4103K1B08
     1 P1V8_AUX @T6G_MB_LIB.T6G(SCH_1):P1V8_AUX    I83 @T6G_MB_LIB.T6G(SCH_1):PAGE82
     2    GND @T6G_MB_LIB.T6G(SCH_1):GND    I83 @T6G_MB_LIB.T6G(SCH_1):PAGE82

C353 Q_CAP_0201-1UF,4V,20%,X6S,CH-10KMEE00
     1 P0V9_CPU1_RT1_2A @T6G_MB_LIB.T6G(SCH_1):P0V9_CPU1_RT1_2A    I66 @T6G_MB_LIB.T6G(SCH_1):PAGE443
     2    GND @T6G_MB_LIB.T6G(SCH_1):GND    I66 @T6G_MB_LIB.T6G(SCH_1):PAGE443

C354 Q_CAP_C0402-10UF,6.3V,20%,X6S,CH6101MEB01
     1 P0V9_CPU1_RT1_2A @T6G_MB_LIB.T6G(SCH_1):P0V9_CPU1_RT1_2A    I81 @T6G_MB_LIB.T6G(SCH_1):PAGE443
     2    GND @T6G_MB_LIB.T6G(SCH_1):GND    I81 @T6G_MB_LIB.T6G(SCH_1):PAGE443

C355 Q_CAP_C0402-0.1UF,16V,10%,X7R,CH4103K1B08
     1 P3V3_AUX @T6G_MB_LIB.T6G(SCH_1):P3V3_AUX   I108 @T6G_MB_LIB.T6G(SCH_1):PAGE82
     2    GND @T6G_MB_LIB.T6G(SCH_1):GND   I108 @T6G_MB_LIB.T6G(SCH_1):PAGE82

C356 Q_CAP_C0402-0.1UF,16V,10%,X7R,CH4103K1B08
     1 P3V3_AUX @T6G_MB_LIB.T6G(SCH_1):P3V3_AUX   I107 @T6G_MB_LIB.T6G(SCH_1):PAGE82
     2    GND @T6G_MB_LIB.T6G(SCH_1):GND   I107 @T6G_MB_LIB.T6G(SCH_1):PAGE82

C357 Q_CAP_C0402-0.1UF,16V,10%,X7R,CH4103K1B08
     1 P3V3_AUX @T6G_MB_LIB.T6G(SCH_1):P3V3_AUX   I106 @T6G_MB_LIB.T6G(SCH_1):PAGE82
     2    GND @T6G_MB_LIB.T6G(SCH_1):GND   I106 @T6G_MB_LIB.T6G(SCH_1):PAGE82

C358 Q_CAP_C0402-0.1UF,16V,10%,X7R,CH4103K1B08
     1 P3V3_AUX @T6G_MB_LIB.T6G(SCH_1):P3V3_AUX   I105 @T6G_MB_LIB.T6G(SCH_1):PAGE82
     2    GND @T6G_MB_LIB.T6G(SCH_1):GND   I105 @T6G_MB_LIB.T6G(SCH_1):PAGE82

C359 Q_CAP_C0402-0.1UF,16V,10%,X7R,CH4103K1B08
     1 P3V3_AUX @T6G_MB_LIB.T6G(SCH_1):P3V3_AUX   I135 @T6G_MB_LIB.T6G(SCH_1):PAGE82
     2    GND @T6G_MB_LIB.T6G(SCH_1):GND   I135 @T6G_MB_LIB.T6G(SCH_1):PAGE82

C360 Q_CAP_C0402-0.1UF,16V,10%,X7R,CH4103K1B08
     1 P3V3_AUX @T6G_MB_LIB.T6G(SCH_1):P3V3_AUX   I103 @T6G_MB_LIB.T6G(SCH_1):PAGE82
     2    GND @T6G_MB_LIB.T6G(SCH_1):GND   I103 @T6G_MB_LIB.T6G(SCH_1):PAGE82

C361 Q_CAP_C0402-0.1UF,16V,10%,X7R,CH4103K1B08
     1 P3V3_AUX @T6G_MB_LIB.T6G(SCH_1):P3V3_AUX   I104 @T6G_MB_LIB.T6G(SCH_1):PAGE82
     2    GND @T6G_MB_LIB.T6G(SCH_1):GND   I104 @T6G_MB_LIB.T6G(SCH_1):PAGE82

C362 Q_CAP_C0402-0.1UF,16V,10%,X7R,CH4103K1B08
     1 P3V3_AUX @T6G_MB_LIB.T6G(SCH_1):P3V3_AUX   I102 @T6G_MB_LIB.T6G(SCH_1):PAGE82
     2    GND @T6G_MB_LIB.T6G(SCH_1):GND   I102 @T6G_MB_LIB.T6G(SCH_1):PAGE82

C363 Q_CAP_C0402-220PF,50V,5%,C0G,CH12206JB00
     1 UART_CPU0_LVC3_UART0_TX @T6G_MB_LIB.T6G(SCH_1):UART_CPU0_LVC3_UART0_TX   I190 @T6G_MB_LIB.T6G(SCH_1):PAGE141
     2    GND @T6G_MB_LIB.T6G(SCH_1):GND   I190 @T6G_MB_LIB.T6G(SCH_1):PAGE141

C364 Q_CAP_C0402-220PF,50V,5%,C0G,CH12206JB00
     1 UART_CPU0_LVC3_UART0_RX @T6G_MB_LIB.T6G(SCH_1):UART_CPU0_LVC3_UART0_RX   I187 @T6G_MB_LIB.T6G(SCH_1):PAGE141
     2    GND @T6G_MB_LIB.T6G(SCH_1):GND   I187 @T6G_MB_LIB.T6G(SCH_1):PAGE141

C365 Q_CAP_C0201-0.1UF,10V,10%,X7S,CH4102K6E00
     1 P1V8_AUX @T6G_MB_LIB.T6G(SCH_1):P1V8_AUX    I55 @T6G_MB_LIB.T6G(SCH_1):PAGE377
     2    GND @T6G_MB_LIB.T6G(SCH_1):GND    I55 @T6G_MB_LIB.T6G(SCH_1):PAGE377

C366 Q_CAP_C0805-100UF,4V,20%,X6S,CH710KMEA01
     1 P1V8_CPU1_RT_1D @T6G_MB_LIB.T6G(SCH_1):P1V8_CPU1_RT_1D    I24 @T6G_MB_LIB.T6G(SCH_1):PAGE454
     2    GND @T6G_MB_LIB.T6G(SCH_1):GND    I24 @T6G_MB_LIB.T6G(SCH_1):PAGE454

C367 Q_CAP_C0805-100UF,4V,20%,X6S,CH710KMEA01
     1 P1V8_CPU1_RT2_1A @T6G_MB_LIB.T6G(SCH_1):P1V8_CPU1_RT2_1A     I5 @T6G_MB_LIB.T6G(SCH_1):PAGE454
     2    GND @T6G_MB_LIB.T6G(SCH_1):GND     I5 @T6G_MB_LIB.T6G(SCH_1):PAGE454

C368 Q_CAP_C0402-22UF,4V,20%,X6S,CH622KMEB02
     1 P1V8_CPU1_RT_1D @T6G_MB_LIB.T6G(SCH_1):P1V8_CPU1_RT_1D    I25 @T6G_MB_LIB.T6G(SCH_1):PAGE454
     2    GND @T6G_MB_LIB.T6G(SCH_1):GND    I25 @T6G_MB_LIB.T6G(SCH_1):PAGE454

C369 Q_CAP_C0402-22UF,4V,20%,X6S,CH622KMEB02
     1 P1V8_CPU1_RT2_1A @T6G_MB_LIB.T6G(SCH_1):P1V8_CPU1_RT2_1A    I10 @T6G_MB_LIB.T6G(SCH_1):PAGE454
     2    GND @T6G_MB_LIB.T6G(SCH_1):GND    I10 @T6G_MB_LIB.T6G(SCH_1):PAGE454

C370 Q_CAP_C0402-10UF,6.3V,20%,X6S,CH6101MEB01
     1 P1V8_CPU1_RT_1D @T6G_MB_LIB.T6G(SCH_1):P1V8_CPU1_RT_1D    I27 @T6G_MB_LIB.T6G(SCH_1):PAGE454
     2    GND @T6G_MB_LIB.T6G(SCH_1):GND    I27 @T6G_MB_LIB.T6G(SCH_1):PAGE454

C371 Q_CAP_0402-4.7UF,6.3V,20%,X6S,CH5471MEB01
     1 P1V8_CPU1_RT2_1A @T6G_MB_LIB.T6G(SCH_1):P1V8_CPU1_RT2_1A    I12 @T6G_MB_LIB.T6G(SCH_1):PAGE454
     2    GND @T6G_MB_LIB.T6G(SCH_1):GND    I12 @T6G_MB_LIB.T6G(SCH_1):PAGE454

C372 Q_CAP_C0402-10UF,6.3V,20%,X6S,CH6101MEB01
     1 P1V8_CPU1_RT2_1A @T6G_MB_LIB.T6G(SCH_1):P1V8_CPU1_RT2_1A    I11 @T6G_MB_LIB.T6G(SCH_1):PAGE454
     2    GND @T6G_MB_LIB.T6G(SCH_1):GND    I11 @T6G_MB_LIB.T6G(SCH_1):PAGE454

C373 Q_CAP_0402-4.7UF,6.3V,20%,X6S,CH5471MEB01
     1 P1V8_CPU1_RT_1D @T6G_MB_LIB.T6G(SCH_1):P1V8_CPU1_RT_1D    I28 @T6G_MB_LIB.T6G(SCH_1):PAGE454
     2    GND @T6G_MB_LIB.T6G(SCH_1):GND    I28 @T6G_MB_LIB.T6G(SCH_1):PAGE454

C374 Q_CAP_0201-1UF,4V,20%,X6S,CH-10KMEE00
     1 P1V8_CPU1_RT2_1A @T6G_MB_LIB.T6G(SCH_1):P1V8_CPU1_RT2_1A    I13 @T6G_MB_LIB.T6G(SCH_1):PAGE454
     2    GND @T6G_MB_LIB.T6G(SCH_1):GND    I13 @T6G_MB_LIB.T6G(SCH_1):PAGE454

C375 Q_CAP_0201-1UF,4V,20%,X6S,CH-10KMEE00
     1 P1V8_CPU1_RT2_1A_1D @T6G_MB_LIB.T6G(SCH_1):P1V8_CPU1_RT2_1A_1D     I6 @T6G_MB_LIB.T6G(SCH_1):PAGE454
     2    GND @T6G_MB_LIB.T6G(SCH_1):GND     I6 @T6G_MB_LIB.T6G(SCH_1):PAGE454

C376 Q_CAP_0201-1UF,4V,20%,X6S,CH-10KMEE00
     1 P1V8_CPU1_RT2_1A @T6G_MB_LIB.T6G(SCH_1):P1V8_CPU1_RT2_1A    I15 @T6G_MB_LIB.T6G(SCH_1):PAGE454
     2    GND @T6G_MB_LIB.T6G(SCH_1):GND    I15 @T6G_MB_LIB.T6G(SCH_1):PAGE454

C377 Q_CAP_C0201-0.1UF,10V,10%,X7S,CH4102K6E00
     1 P1V8_CPU1_RT2_1A @T6G_MB_LIB.T6G(SCH_1):P1V8_CPU1_RT2_1A    I16 @T6G_MB_LIB.T6G(SCH_1):PAGE454
     2    GND @T6G_MB_LIB.T6G(SCH_1):GND    I16 @T6G_MB_LIB.T6G(SCH_1):PAGE454

C378 Q_CAP_C0201-0.1UF,10V,10%,X7S,CH4102K6E00
     1 P1V8_CPU1_RT2_1A_1D @T6G_MB_LIB.T6G(SCH_1):P1V8_CPU1_RT2_1A_1D     I8 @T6G_MB_LIB.T6G(SCH_1):PAGE454
     2    GND @T6G_MB_LIB.T6G(SCH_1):GND     I8 @T6G_MB_LIB.T6G(SCH_1):PAGE454

C379 Q_CAP_C0201-0.1UF,10V,10%,X7S,CH4102K6E00
     1 P1V8_CPU1_RT2_1A @T6G_MB_LIB.T6G(SCH_1):P1V8_CPU1_RT2_1A    I17 @T6G_MB_LIB.T6G(SCH_1):PAGE454
     2    GND @T6G_MB_LIB.T6G(SCH_1):GND    I17 @T6G_MB_LIB.T6G(SCH_1):PAGE454

C380 Q_CAP_C0201-0.1UF,10V,10%,X7S,CH4102K6E00
     1 P1V8_CPU1_RT2_1A @T6G_MB_LIB.T6G(SCH_1):P1V8_CPU1_RT2_1A    I18 @T6G_MB_LIB.T6G(SCH_1):PAGE454
     2    GND @T6G_MB_LIB.T6G(SCH_1):GND    I18 @T6G_MB_LIB.T6G(SCH_1):PAGE454

C381 Q_CAP_C0201-0.1UF,10V,10%,X7S,CH4102K6E00
     1 P1V8_CPU1_RT2_1A @T6G_MB_LIB.T6G(SCH_1):P1V8_CPU1_RT2_1A    I19 @T6G_MB_LIB.T6G(SCH_1):PAGE454
     2    GND @T6G_MB_LIB.T6G(SCH_1):GND    I19 @T6G_MB_LIB.T6G(SCH_1):PAGE454

C382 Q_CAP_0201-1UF,4V,20%,X6S,CH-10KMEE00
     1 P0V9_CPU1_RT2_2A @T6G_MB_LIB.T6G(SCH_1):P0V9_CPU1_RT2_2A    I71 @T6G_MB_LIB.T6G(SCH_1):PAGE454
     2    GND @T6G_MB_LIB.T6G(SCH_1):GND    I71 @T6G_MB_LIB.T6G(SCH_1):PAGE454

C383 Q_CAP_C0201-0.1UF,10V,10%,X7S,CH4102K6E00
     1 P0V9_CPU1_RT_2D @T6G_MB_LIB.T6G(SCH_1):P0V9_CPU1_RT_2D    I82 @T6G_MB_LIB.T6G(SCH_1):PAGE454
     2    GND @T6G_MB_LIB.T6G(SCH_1):GND    I82 @T6G_MB_LIB.T6G(SCH_1):PAGE454

C384 Q_CAP_0201-1UF,4V,20%,X6S,CH-10KMEE00
     1 P0V9_CPU1_RT2_2A @T6G_MB_LIB.T6G(SCH_1):P0V9_CPU1_RT2_2A    I42 @T6G_MB_LIB.T6G(SCH_1):PAGE454
     2    GND @T6G_MB_LIB.T6G(SCH_1):GND    I42 @T6G_MB_LIB.T6G(SCH_1):PAGE454

C385 Q_CAP_C0201-0.1UF,10V,10%,X7S,CH4102K6E00
     1 P0V9_CPU1_RT_2D @T6G_MB_LIB.T6G(SCH_1):P0V9_CPU1_RT_2D    I83 @T6G_MB_LIB.T6G(SCH_1):PAGE454
     2    GND @T6G_MB_LIB.T6G(SCH_1):GND    I83 @T6G_MB_LIB.T6G(SCH_1):PAGE454

C386 Q_CAP_0201-1UF,4V,20%,X6S,CH-10KMEE00
     1 P0V9_CPU1_RT2_2A @T6G_MB_LIB.T6G(SCH_1):P0V9_CPU1_RT2_2A    I58 @T6G_MB_LIB.T6G(SCH_1):PAGE454
     2    GND @T6G_MB_LIB.T6G(SCH_1):GND    I58 @T6G_MB_LIB.T6G(SCH_1):PAGE454

C387 Q_CAP_0201-1UF,4V,20%,X6S,CH-10KMEE00
     1 P0V9_CPU1_RT2_2A @T6G_MB_LIB.T6G(SCH_1):P0V9_CPU1_RT2_2A    I43 @T6G_MB_LIB.T6G(SCH_1):PAGE454
     2    GND @T6G_MB_LIB.T6G(SCH_1):GND    I43 @T6G_MB_LIB.T6G(SCH_1):PAGE454

C388 Q_CAP_C0201-0.1UF,10V,10%,X7S,CH4102K6E00
     1 P0V9_CPU1_RT_2D @T6G_MB_LIB.T6G(SCH_1):P0V9_CPU1_RT_2D    I84 @T6G_MB_LIB.T6G(SCH_1):PAGE454
     2    GND @T6G_MB_LIB.T6G(SCH_1):GND    I84 @T6G_MB_LIB.T6G(SCH_1):PAGE454

C389 Q_CAP_0201-1UF,4V,20%,X6S,CH-10KMEE00
     1 P0V9_CPU1_RT2_2A @T6G_MB_LIB.T6G(SCH_1):P0V9_CPU1_RT2_2A    I68 @T6G_MB_LIB.T6G(SCH_1):PAGE454
     2    GND @T6G_MB_LIB.T6G(SCH_1):GND    I68 @T6G_MB_LIB.T6G(SCH_1):PAGE454

C390 Q_CAP_0201-1UF,4V,20%,X6S,CH-10KMEE00
     1 P0V9_CPU1_RT2_2A_2D @T6G_MB_LIB.T6G(SCH_1):P0V9_CPU1_RT2_2A_2D    I90 @T6G_MB_LIB.T6G(SCH_1):PAGE454
     2    GND @T6G_MB_LIB.T6G(SCH_1):GND    I90 @T6G_MB_LIB.T6G(SCH_1):PAGE454

C391 Q_CAP_0201-1UF,4V,20%,X6S,CH-10KMEE00
     1 P0V9_CPU1_RT2_2A @T6G_MB_LIB.T6G(SCH_1):P0V9_CPU1_RT2_2A    I50 @T6G_MB_LIB.T6G(SCH_1):PAGE454
     2    GND @T6G_MB_LIB.T6G(SCH_1):GND    I50 @T6G_MB_LIB.T6G(SCH_1):PAGE454

C392 Q_CAP_C0201-0.1UF,10V,10%,X7S,CH4102K6E00
     1 P0V9_CPU1_RT_2D @T6G_MB_LIB.T6G(SCH_1):P0V9_CPU1_RT_2D    I85 @T6G_MB_LIB.T6G(SCH_1):PAGE454
     2    GND @T6G_MB_LIB.T6G(SCH_1):GND    I85 @T6G_MB_LIB.T6G(SCH_1):PAGE454

C393 Q_CAP_C0201-0.1UF,10V,10%,X7S,CH4102K6E00
     1 P0V9_CPU1_RT2_2A @T6G_MB_LIB.T6G(SCH_1):P0V9_CPU1_RT2_2A    I38 @T6G_MB_LIB.T6G(SCH_1):PAGE454
     2    GND @T6G_MB_LIB.T6G(SCH_1):GND    I38 @T6G_MB_LIB.T6G(SCH_1):PAGE454

C394 Q_CAP_0201-1UF,4V,20%,X6S,CH-10KMEE00
     1 P0V9_CPU1_RT2_2A_2D @T6G_MB_LIB.T6G(SCH_1):P0V9_CPU1_RT2_2A_2D    I91 @T6G_MB_LIB.T6G(SCH_1):PAGE454
     2    GND @T6G_MB_LIB.T6G(SCH_1):GND    I91 @T6G_MB_LIB.T6G(SCH_1):PAGE454

C395 Q_CAP_C0201-0.1UF,10V,10%,X7S,CH4102K6E00
     1 P0V9_CPU1_RT2_2A @T6G_MB_LIB.T6G(SCH_1):P0V9_CPU1_RT2_2A    I64 @T6G_MB_LIB.T6G(SCH_1):PAGE454
     2    GND @T6G_MB_LIB.T6G(SCH_1):GND    I64 @T6G_MB_LIB.T6G(SCH_1):PAGE454

C396 Q_CAP_C0201-0.1UF,10V,10%,X7S,CH4102K6E00
     1 P0V9_CPU1_RT2_2A_2D @T6G_MB_LIB.T6G(SCH_1):P0V9_CPU1_RT2_2A_2D    I35 @T6G_MB_LIB.T6G(SCH_1):PAGE454
     2    GND @T6G_MB_LIB.T6G(SCH_1):GND    I35 @T6G_MB_LIB.T6G(SCH_1):PAGE454

C397 Q_CAP_C0201-0.1UF,10V,10%,X7S,CH4102K6E00
     1 P0V9_CPU1_RT2_2A_2D @T6G_MB_LIB.T6G(SCH_1):P0V9_CPU1_RT2_2A_2D    I36 @T6G_MB_LIB.T6G(SCH_1):PAGE454
     2    GND @T6G_MB_LIB.T6G(SCH_1):GND    I36 @T6G_MB_LIB.T6G(SCH_1):PAGE454

C398 Q_CAP_C0805-100UF,4V,20%,X6S,CH710KMEA01
     1 P0V9_CPU1_RT2_2A @T6G_MB_LIB.T6G(SCH_1):P0V9_CPU1_RT2_2A    I46 @T6G_MB_LIB.T6G(SCH_1):PAGE454
     2    GND @T6G_MB_LIB.T6G(SCH_1):GND    I46 @T6G_MB_LIB.T6G(SCH_1):PAGE454

C399 Q_CAP_C0402-22UF,4V,20%,X6S,CH622KMEB02
     1 P0V9_CPU1_RT2_2A @T6G_MB_LIB.T6G(SCH_1):P0V9_CPU1_RT2_2A    I59 @T6G_MB_LIB.T6G(SCH_1):PAGE454
     2    GND @T6G_MB_LIB.T6G(SCH_1):GND    I59 @T6G_MB_LIB.T6G(SCH_1):PAGE454

C400 Q_CAP_C0201-0.1UF,10V,10%,X7S,CH4102K6E00
     1 P0V9_CPU1_RT2_2A @T6G_MB_LIB.T6G(SCH_1):P0V9_CPU1_RT2_2A    I40 @T6G_MB_LIB.T6G(SCH_1):PAGE454
     2    GND @T6G_MB_LIB.T6G(SCH_1):GND    I40 @T6G_MB_LIB.T6G(SCH_1):PAGE454

C401 Q_CAP_C0805-100UF,4V,20%,X6S,CH710KMEA01
     1 P0V9_CPU1_RT2_2A @T6G_MB_LIB.T6G(SCH_1):P0V9_CPU1_RT2_2A    I47 @T6G_MB_LIB.T6G(SCH_1):PAGE454
     2    GND @T6G_MB_LIB.T6G(SCH_1):GND    I47 @T6G_MB_LIB.T6G(SCH_1):PAGE454

C402 Q_CAP_C0402-22UF,4V,20%,X6S,CH622KMEB02
     1 P0V9_CPU1_RT2_2A @T6G_MB_LIB.T6G(SCH_1):P0V9_CPU1_RT2_2A    I60 @T6G_MB_LIB.T6G(SCH_1):PAGE454
     2    GND @T6G_MB_LIB.T6G(SCH_1):GND    I60 @T6G_MB_LIB.T6G(SCH_1):PAGE454

C403 Q_CAP_C0201-0.1UF,10V,10%,X7S,CH4102K6E00
     1 P0V9_CPU1_RT2_2A @T6G_MB_LIB.T6G(SCH_1):P0V9_CPU1_RT2_2A    I61 @T6G_MB_LIB.T6G(SCH_1):PAGE454
     2    GND @T6G_MB_LIB.T6G(SCH_1):GND    I61 @T6G_MB_LIB.T6G(SCH_1):PAGE454

C404 Q_CAP_C0805-100UF,4V,20%,X6S,CH710KMEA01
     1 P0V9_CPU1_RT_2D @T6G_MB_LIB.T6G(SCH_1):P0V9_CPU1_RT_2D    I76 @T6G_MB_LIB.T6G(SCH_1):PAGE454
     2    GND @T6G_MB_LIB.T6G(SCH_1):GND    I76 @T6G_MB_LIB.T6G(SCH_1):PAGE454

C405 Q_CAP_C0805-100UF,4V,20%,X6S,CH710KMEA01
     1 P0V9_CPU1_RT2_2A @T6G_MB_LIB.T6G(SCH_1):P0V9_CPU1_RT2_2A    I86 @T6G_MB_LIB.T6G(SCH_1):PAGE454
     2    GND @T6G_MB_LIB.T6G(SCH_1):GND    I86 @T6G_MB_LIB.T6G(SCH_1):PAGE454

C406 Q_CAP_0402-4.7UF,6.3V,20%,X6S,CH5471MEB01
     1 P0V9_CPU1_RT2_2A @T6G_MB_LIB.T6G(SCH_1):P0V9_CPU1_RT2_2A    I48 @T6G_MB_LIB.T6G(SCH_1):PAGE454
     2    GND @T6G_MB_LIB.T6G(SCH_1):GND    I48 @T6G_MB_LIB.T6G(SCH_1):PAGE454

C407 Q_CAP_0201-1UF,4V,20%,X6S,CH-10KMEE00
     1 P0V9_CPU1_RT2_2A @T6G_MB_LIB.T6G(SCH_1):P0V9_CPU1_RT2_2A    I49 @T6G_MB_LIB.T6G(SCH_1):PAGE454
     2    GND @T6G_MB_LIB.T6G(SCH_1):GND    I49 @T6G_MB_LIB.T6G(SCH_1):PAGE454

C408 Q_CAP_C0402-22UF,4V,20%,X6S,CH622KMEB02
     1 P0V9_CPU1_RT_2D @T6G_MB_LIB.T6G(SCH_1):P0V9_CPU1_RT_2D    I77 @T6G_MB_LIB.T6G(SCH_1):PAGE454
     2    GND @T6G_MB_LIB.T6G(SCH_1):GND    I77 @T6G_MB_LIB.T6G(SCH_1):PAGE454

C409 Q_CAP_C0805-100UF,4V,20%,X6S,CH710KMEA01
     1 P0V9_CPU1_RT2_2A @T6G_MB_LIB.T6G(SCH_1):P0V9_CPU1_RT2_2A    I87 @T6G_MB_LIB.T6G(SCH_1):PAGE454
     2    GND @T6G_MB_LIB.T6G(SCH_1):GND    I87 @T6G_MB_LIB.T6G(SCH_1):PAGE454

C410 Q_CAP_C0402-10UF,6.3V,20%,X6S,CH6101MEB01
     1 P0V9_CPU1_RT2_2A @T6G_MB_LIB.T6G(SCH_1):P0V9_CPU1_RT2_2A    I44 @T6G_MB_LIB.T6G(SCH_1):PAGE454
     2    GND @T6G_MB_LIB.T6G(SCH_1):GND    I44 @T6G_MB_LIB.T6G(SCH_1):PAGE454

C411 Q_CAP_C0201-0.1UF,10V,10%,X7S,CH4102K6E00
     1 P0V9_CPU1_RT2_2A @T6G_MB_LIB.T6G(SCH_1):P0V9_CPU1_RT2_2A    I62 @T6G_MB_LIB.T6G(SCH_1):PAGE454
     2    GND @T6G_MB_LIB.T6G(SCH_1):GND    I62 @T6G_MB_LIB.T6G(SCH_1):PAGE454

C412 Q_CAP_0402-4.7UF,6.3V,20%,X6S,CH5471MEB01
     1 P0V9_CPU1_RT2_2A @T6G_MB_LIB.T6G(SCH_1):P0V9_CPU1_RT2_2A    I57 @T6G_MB_LIB.T6G(SCH_1):PAGE454
     2    GND @T6G_MB_LIB.T6G(SCH_1):GND    I57 @T6G_MB_LIB.T6G(SCH_1):PAGE454

C413 Q_CAP_0402-4.7UF,6.3V,20%,X6S,CH5471MEB01
     1 P0V9_CPU1_RT2_2A @T6G_MB_LIB.T6G(SCH_1):P0V9_CPU1_RT2_2A    I55 @T6G_MB_LIB.T6G(SCH_1):PAGE454
     2    GND @T6G_MB_LIB.T6G(SCH_1):GND    I55 @T6G_MB_LIB.T6G(SCH_1):PAGE454

C414 Q_CAP_C0402-10UF,6.3V,20%,X6S,CH6101MEB01
     1 P0V9_CPU1_RT_2D @T6G_MB_LIB.T6G(SCH_1):P0V9_CPU1_RT_2D    I78 @T6G_MB_LIB.T6G(SCH_1):PAGE454
     2    GND @T6G_MB_LIB.T6G(SCH_1):GND    I78 @T6G_MB_LIB.T6G(SCH_1):PAGE454

C415 Q_CAP_0201-1UF,4V,20%,X6S,CH-10KMEE00
     1 P0V9_CPU1_RT2_2A @T6G_MB_LIB.T6G(SCH_1):P0V9_CPU1_RT2_2A    I51 @T6G_MB_LIB.T6G(SCH_1):PAGE454
     2    GND @T6G_MB_LIB.T6G(SCH_1):GND    I51 @T6G_MB_LIB.T6G(SCH_1):PAGE454

C416 Q_CAP_0402-4.7UF,6.3V,20%,X6S,CH5471MEB01
     1 P0V9_CPU1_RT2_2A @T6G_MB_LIB.T6G(SCH_1):P0V9_CPU1_RT2_2A    I54 @T6G_MB_LIB.T6G(SCH_1):PAGE454
     2    GND @T6G_MB_LIB.T6G(SCH_1):GND    I54 @T6G_MB_LIB.T6G(SCH_1):PAGE454

C417 Q_CAP_C0402-22UF,4V,20%,X6S,CH622KMEB02
     1 P0V9_CPU1_RT2_2A @T6G_MB_LIB.T6G(SCH_1):P0V9_CPU1_RT2_2A    I56 @T6G_MB_LIB.T6G(SCH_1):PAGE454
     2    GND @T6G_MB_LIB.T6G(SCH_1):GND    I56 @T6G_MB_LIB.T6G(SCH_1):PAGE454

C418 Q_CAP_0201-1UF,4V,20%,X6S,CH-10KMEE00
     1 P0V9_CPU1_RT2_2A @T6G_MB_LIB.T6G(SCH_1):P0V9_CPU1_RT2_2A    I52 @T6G_MB_LIB.T6G(SCH_1):PAGE454
     2    GND @T6G_MB_LIB.T6G(SCH_1):GND    I52 @T6G_MB_LIB.T6G(SCH_1):PAGE454

C419 Q_CAP_0402-4.7UF,6.3V,20%,X6S,CH5471MEB01
     1 P0V9_CPU1_RT_2D @T6G_MB_LIB.T6G(SCH_1):P0V9_CPU1_RT_2D    I79 @T6G_MB_LIB.T6G(SCH_1):PAGE454
     2    GND @T6G_MB_LIB.T6G(SCH_1):GND    I79 @T6G_MB_LIB.T6G(SCH_1):PAGE454

C420 Q_CAP_C0402-10UF,6.3V,20%,X6S,CH6101MEB01
     1 P0V9_CPU1_RT2_2A @T6G_MB_LIB.T6G(SCH_1):P0V9_CPU1_RT2_2A    I45 @T6G_MB_LIB.T6G(SCH_1):PAGE454
     2    GND @T6G_MB_LIB.T6G(SCH_1):GND    I45 @T6G_MB_LIB.T6G(SCH_1):PAGE454

C421 Q_CAP_C0201-0.1UF,10V,10%,X7S,CH4102K6E00
     1 P0V9_CPU1_RT2_2A @T6G_MB_LIB.T6G(SCH_1):P0V9_CPU1_RT2_2A    I31 @T6G_MB_LIB.T6G(SCH_1):PAGE454
     2    GND @T6G_MB_LIB.T6G(SCH_1):GND    I31 @T6G_MB_LIB.T6G(SCH_1):PAGE454

C422 Q_CAP_0201-1UF,4V,20%,X6S,CH-10KMEE00
     1 P0V9_CPU1_RT2_2A @T6G_MB_LIB.T6G(SCH_1):P0V9_CPU1_RT2_2A    I53 @T6G_MB_LIB.T6G(SCH_1):PAGE454
     2    GND @T6G_MB_LIB.T6G(SCH_1):GND    I53 @T6G_MB_LIB.T6G(SCH_1):PAGE454

C423 Q_CAP_0201-1UF,4V,20%,X6S,CH-10KMEE00
     1 P0V9_CPU1_RT_2D @T6G_MB_LIB.T6G(SCH_1):P0V9_CPU1_RT_2D    I80 @T6G_MB_LIB.T6G(SCH_1):PAGE454
     2    GND @T6G_MB_LIB.T6G(SCH_1):GND    I80 @T6G_MB_LIB.T6G(SCH_1):PAGE454

C424 Q_CAP_C0402-22UF,4V,20%,X6S,CH622KMEB02
     1 P0V9_CPU1_RT2_2A @T6G_MB_LIB.T6G(SCH_1):P0V9_CPU1_RT2_2A    I69 @T6G_MB_LIB.T6G(SCH_1):PAGE454
     2    GND @T6G_MB_LIB.T6G(SCH_1):GND    I69 @T6G_MB_LIB.T6G(SCH_1):PAGE454

C425 Q_CAP_0201-1UF,4V,20%,X6S,CH-10KMEE00
     1 P0V9_CPU1_RT2_2A @T6G_MB_LIB.T6G(SCH_1):P0V9_CPU1_RT2_2A    I67 @T6G_MB_LIB.T6G(SCH_1):PAGE454
     2    GND @T6G_MB_LIB.T6G(SCH_1):GND    I67 @T6G_MB_LIB.T6G(SCH_1):PAGE454

C426 Q_CAP_C0201-0.1UF,10V,10%,X7S,CH4102K6E00
     1 P0V9_CPU1_RT2_2A @T6G_MB_LIB.T6G(SCH_1):P0V9_CPU1_RT2_2A    I92 @T6G_MB_LIB.T6G(SCH_1):PAGE454
     2    GND @T6G_MB_LIB.T6G(SCH_1):GND    I92 @T6G_MB_LIB.T6G(SCH_1):PAGE454

C427 Q_CAP_C0201-0.1UF,10V,10%,X7S,CH4102K6E00
     1 P0V9_CPU1_RT2_2A @T6G_MB_LIB.T6G(SCH_1):P0V9_CPU1_RT2_2A    I37 @T6G_MB_LIB.T6G(SCH_1):PAGE454
     2    GND @T6G_MB_LIB.T6G(SCH_1):GND    I37 @T6G_MB_LIB.T6G(SCH_1):PAGE454

C428 Q_CAP_C0201-0.1UF,10V,10%,X7S,CH4102K6E00
     1 P0V9_CPU1_RT2_2A @T6G_MB_LIB.T6G(SCH_1):P0V9_CPU1_RT2_2A    I93 @T6G_MB_LIB.T6G(SCH_1):PAGE454
     2    GND @T6G_MB_LIB.T6G(SCH_1):GND    I93 @T6G_MB_LIB.T6G(SCH_1):PAGE454

C429 Q_CAP_C0402-10UF,6.3V,20%,X6S,CH6101MEB01
     1 P0V9_CPU1_RT2_2A @T6G_MB_LIB.T6G(SCH_1):P0V9_CPU1_RT2_2A    I70 @T6G_MB_LIB.T6G(SCH_1):PAGE454
     2    GND @T6G_MB_LIB.T6G(SCH_1):GND    I70 @T6G_MB_LIB.T6G(SCH_1):PAGE454

C430 Q_CAP_C0201-0.1UF,10V,10%,X7S,CH4102K6E00
     1 P0V9_CPU1_RT2_2A @T6G_MB_LIB.T6G(SCH_1):P0V9_CPU1_RT2_2A    I39 @T6G_MB_LIB.T6G(SCH_1):PAGE454
     2    GND @T6G_MB_LIB.T6G(SCH_1):GND    I39 @T6G_MB_LIB.T6G(SCH_1):PAGE454

C431 Q_CAP_C0402-10UF,6.3V,20%,X6S,CH6101MEB01
     1 P0V9_CPU1_RT2_2A @T6G_MB_LIB.T6G(SCH_1):P0V9_CPU1_RT2_2A    I72 @T6G_MB_LIB.T6G(SCH_1):PAGE454
     2    GND @T6G_MB_LIB.T6G(SCH_1):GND    I72 @T6G_MB_LIB.T6G(SCH_1):PAGE454

C432 Q_CAP_C0805-100UF,4V,20%,X6S,CH710KMEA01
     1 P1V8_CPU1_RT_1D @T6G_MB_LIB.T6G(SCH_1):P1V8_CPU1_RT_1D    I17 @T6G_MB_LIB.T6G(SCH_1):PAGE465
     2    GND @T6G_MB_LIB.T6G(SCH_1):GND    I17 @T6G_MB_LIB.T6G(SCH_1):PAGE465

C433 Q_CAP_C0805-100UF,4V,20%,X6S,CH710KMEA01
     1 P1V8_CPU1_RT3_1A @T6G_MB_LIB.T6G(SCH_1):P1V8_CPU1_RT3_1A    I14 @T6G_MB_LIB.T6G(SCH_1):PAGE465
     2    GND @T6G_MB_LIB.T6G(SCH_1):GND    I14 @T6G_MB_LIB.T6G(SCH_1):PAGE465

C434 Q_CAP_C0402-22UF,4V,20%,X6S,CH622KMEB02
     1 P1V8_CPU1_RT_1D @T6G_MB_LIB.T6G(SCH_1):P1V8_CPU1_RT_1D    I18 @T6G_MB_LIB.T6G(SCH_1):PAGE465
     2    GND @T6G_MB_LIB.T6G(SCH_1):GND    I18 @T6G_MB_LIB.T6G(SCH_1):PAGE465

C435 Q_CAP_C0402-22UF,4V,20%,X6S,CH622KMEB02
     1 P1V8_CPU1_RT3_1A @T6G_MB_LIB.T6G(SCH_1):P1V8_CPU1_RT3_1A    I15 @T6G_MB_LIB.T6G(SCH_1):PAGE465
     2    GND @T6G_MB_LIB.T6G(SCH_1):GND    I15 @T6G_MB_LIB.T6G(SCH_1):PAGE465

C436 Q_CAP_C0402-10UF,6.3V,20%,X6S,CH6101MEB01
     1 P1V8_CPU1_RT_1D @T6G_MB_LIB.T6G(SCH_1):P1V8_CPU1_RT_1D    I21 @T6G_MB_LIB.T6G(SCH_1):PAGE465
     2    GND @T6G_MB_LIB.T6G(SCH_1):GND    I21 @T6G_MB_LIB.T6G(SCH_1):PAGE465

C437 Q_CAP_C0402-10UF,6.3V,20%,X6S,CH6101MEB01
     1 P1V8_CPU1_RT3_1A @T6G_MB_LIB.T6G(SCH_1):P1V8_CPU1_RT3_1A    I16 @T6G_MB_LIB.T6G(SCH_1):PAGE465
     2    GND @T6G_MB_LIB.T6G(SCH_1):GND    I16 @T6G_MB_LIB.T6G(SCH_1):PAGE465

C438 Q_CAP_0402-4.7UF,6.3V,20%,X6S,CH5471MEB01
     1 P1V8_CPU1_RT3_1A @T6G_MB_LIB.T6G(SCH_1):P1V8_CPU1_RT3_1A    I19 @T6G_MB_LIB.T6G(SCH_1):PAGE465
     2    GND @T6G_MB_LIB.T6G(SCH_1):GND    I19 @T6G_MB_LIB.T6G(SCH_1):PAGE465

C439 Q_CAP_0402-4.7UF,6.3V,20%,X6S,CH5471MEB01
     1 P1V8_CPU1_RT_1D @T6G_MB_LIB.T6G(SCH_1):P1V8_CPU1_RT_1D    I23 @T6G_MB_LIB.T6G(SCH_1):PAGE465
     2    GND @T6G_MB_LIB.T6G(SCH_1):GND    I23 @T6G_MB_LIB.T6G(SCH_1):PAGE465

C440 Q_CAP_0201-1UF,4V,20%,X6S,CH-10KMEE00
     1 P1V8_CPU1_RT3_1A @T6G_MB_LIB.T6G(SCH_1):P1V8_CPU1_RT3_1A    I20 @T6G_MB_LIB.T6G(SCH_1):PAGE465
     2    GND @T6G_MB_LIB.T6G(SCH_1):GND    I20 @T6G_MB_LIB.T6G(SCH_1):PAGE465

C441 Q_CAP_0201-1UF,4V,20%,X6S,CH-10KMEE00
     1 P1V8_CPU1_RT3_1A_1D @T6G_MB_LIB.T6G(SCH_1):P1V8_CPU1_RT3_1A_1D     I4 @T6G_MB_LIB.T6G(SCH_1):PAGE465
     2    GND @T6G_MB_LIB.T6G(SCH_1):GND     I4 @T6G_MB_LIB.T6G(SCH_1):PAGE465

C442 Q_CAP_0201-1UF,4V,20%,X6S,CH-10KMEE00
     1 P1V8_CPU1_RT3_1A @T6G_MB_LIB.T6G(SCH_1):P1V8_CPU1_RT3_1A    I24 @T6G_MB_LIB.T6G(SCH_1):PAGE465
     2    GND @T6G_MB_LIB.T6G(SCH_1):GND    I24 @T6G_MB_LIB.T6G(SCH_1):PAGE465

C443 Q_CAP_C0201-0.1UF,10V,10%,X7S,CH4102K6E00
     1 P1V8_CPU1_RT3_1A @T6G_MB_LIB.T6G(SCH_1):P1V8_CPU1_RT3_1A    I25 @T6G_MB_LIB.T6G(SCH_1):PAGE465
     2    GND @T6G_MB_LIB.T6G(SCH_1):GND    I25 @T6G_MB_LIB.T6G(SCH_1):PAGE465

C444 Q_CAP_C0201-0.1UF,10V,10%,X7S,CH4102K6E00
     1 P1V8_CPU1_RT3_1A_1D @T6G_MB_LIB.T6G(SCH_1):P1V8_CPU1_RT3_1A_1D     I6 @T6G_MB_LIB.T6G(SCH_1):PAGE465
     2    GND @T6G_MB_LIB.T6G(SCH_1):GND     I6 @T6G_MB_LIB.T6G(SCH_1):PAGE465

C445 Q_CAP_C0201-0.1UF,10V,10%,X7S,CH4102K6E00
     1 P1V8_CPU1_RT3_1A @T6G_MB_LIB.T6G(SCH_1):P1V8_CPU1_RT3_1A    I26 @T6G_MB_LIB.T6G(SCH_1):PAGE465
     2    GND @T6G_MB_LIB.T6G(SCH_1):GND    I26 @T6G_MB_LIB.T6G(SCH_1):PAGE465

C446 Q_CAP_C0201-0.1UF,10V,10%,X7S,CH4102K6E00
     1 P1V8_CPU1_RT3_1A @T6G_MB_LIB.T6G(SCH_1):P1V8_CPU1_RT3_1A    I27 @T6G_MB_LIB.T6G(SCH_1):PAGE465
     2    GND @T6G_MB_LIB.T6G(SCH_1):GND    I27 @T6G_MB_LIB.T6G(SCH_1):PAGE465

C447 Q_CAP_C0201-0.1UF,10V,10%,X7S,CH4102K6E00
     1 P1V8_CPU1_RT3_1A @T6G_MB_LIB.T6G(SCH_1):P1V8_CPU1_RT3_1A    I28 @T6G_MB_LIB.T6G(SCH_1):PAGE465
     2    GND @T6G_MB_LIB.T6G(SCH_1):GND    I28 @T6G_MB_LIB.T6G(SCH_1):PAGE465

C448 Q_CAP_0201-1UF,4V,20%,X6S,CH-10KMEE00
     1 P0V9_CPU1_RT3_2A @T6G_MB_LIB.T6G(SCH_1):P0V9_CPU1_RT3_2A    I44 @T6G_MB_LIB.T6G(SCH_1):PAGE465
     2    GND @T6G_MB_LIB.T6G(SCH_1):GND    I44 @T6G_MB_LIB.T6G(SCH_1):PAGE465

C449 Q_CAP_C0201-0.1UF,10V,10%,X7S,CH4102K6E00
     1 P0V9_CPU1_RT_2D @T6G_MB_LIB.T6G(SCH_1):P0V9_CPU1_RT_2D    I78 @T6G_MB_LIB.T6G(SCH_1):PAGE465
     2    GND @T6G_MB_LIB.T6G(SCH_1):GND    I78 @T6G_MB_LIB.T6G(SCH_1):PAGE465

C450 Q_CAP_C0201-0.1UF,10V,10%,X7S,CH4102K6E00
     1 P0V9_CPU1_RT3_2A @T6G_MB_LIB.T6G(SCH_1):P0V9_CPU1_RT3_2A    I47 @T6G_MB_LIB.T6G(SCH_1):PAGE465
     2    GND @T6G_MB_LIB.T6G(SCH_1):GND    I47 @T6G_MB_LIB.T6G(SCH_1):PAGE465

C451 Q_CAP_C0201-0.1UF,10V,10%,X7S,CH4102K6E00
     1 P0V9_CPU1_RT_2D @T6G_MB_LIB.T6G(SCH_1):P0V9_CPU1_RT_2D    I79 @T6G_MB_LIB.T6G(SCH_1):PAGE465
     2    GND @T6G_MB_LIB.T6G(SCH_1):GND    I79 @T6G_MB_LIB.T6G(SCH_1):PAGE465

C452 Q_CAP_0201-1UF,4V,20%,X6S,CH-10KMEE00
     1 P0V9_CPU1_RT3_2A @T6G_MB_LIB.T6G(SCH_1):P0V9_CPU1_RT3_2A    I84 @T6G_MB_LIB.T6G(SCH_1):PAGE465
     2    GND @T6G_MB_LIB.T6G(SCH_1):GND    I84 @T6G_MB_LIB.T6G(SCH_1):PAGE465

C453 Q_CAP_0201-1UF,4V,20%,X6S,CH-10KMEE00
     1 P0V9_CPU1_RT3_2A @T6G_MB_LIB.T6G(SCH_1):P0V9_CPU1_RT3_2A    I45 @T6G_MB_LIB.T6G(SCH_1):PAGE465
     2    GND @T6G_MB_LIB.T6G(SCH_1):GND    I45 @T6G_MB_LIB.T6G(SCH_1):PAGE465

C454 Q_CAP_0201-1UF,4V,20%,X6S,CH-10KMEE00
     1 P0V9_CPU1_RT_2D @T6G_MB_LIB.T6G(SCH_1):P0V9_CPU1_RT_2D    I74 @T6G_MB_LIB.T6G(SCH_1):PAGE465
     2    GND @T6G_MB_LIB.T6G(SCH_1):GND    I74 @T6G_MB_LIB.T6G(SCH_1):PAGE465

C455 Q_CAP_0201-1UF,4V,20%,X6S,CH-10KMEE00
     1 P0V9_CPU1_RT3_2A @T6G_MB_LIB.T6G(SCH_1):P0V9_CPU1_RT3_2A    I61 @T6G_MB_LIB.T6G(SCH_1):PAGE465
     2    GND @T6G_MB_LIB.T6G(SCH_1):GND    I61 @T6G_MB_LIB.T6G(SCH_1):PAGE465

C456 Q_CAP_0201-1UF,4V,20%,X6S,CH-10KMEE00
     1 P0V9_CPU1_RT3_2A_2D @T6G_MB_LIB.T6G(SCH_1):P0V9_CPU1_RT3_2A_2D    I90 @T6G_MB_LIB.T6G(SCH_1):PAGE465
     2    GND @T6G_MB_LIB.T6G(SCH_1):GND    I90 @T6G_MB_LIB.T6G(SCH_1):PAGE465

C457 Q_CAP_C0201-0.1UF,10V,10%,X7S,CH4102K6E00
     1 P0V9_CPU1_RT3_2A @T6G_MB_LIB.T6G(SCH_1):P0V9_CPU1_RT3_2A    I57 @T6G_MB_LIB.T6G(SCH_1):PAGE465
     2    GND @T6G_MB_LIB.T6G(SCH_1):GND    I57 @T6G_MB_LIB.T6G(SCH_1):PAGE465

C458 Q_CAP_C0201-0.1UF,10V,10%,X7S,CH4102K6E00
     1 P0V9_CPU1_RT_2D @T6G_MB_LIB.T6G(SCH_1):P0V9_CPU1_RT_2D    I82 @T6G_MB_LIB.T6G(SCH_1):PAGE465
     2    GND @T6G_MB_LIB.T6G(SCH_1):GND    I82 @T6G_MB_LIB.T6G(SCH_1):PAGE465

C459 Q_CAP_0201-1UF,4V,20%,X6S,CH-10KMEE00
     1 P0V9_CPU1_RT3_2A @T6G_MB_LIB.T6G(SCH_1):P0V9_CPU1_RT3_2A    I39 @T6G_MB_LIB.T6G(SCH_1):PAGE465
     2    GND @T6G_MB_LIB.T6G(SCH_1):GND    I39 @T6G_MB_LIB.T6G(SCH_1):PAGE465

C460 Q_CAP_0201-1UF,4V,20%,X6S,CH-10KMEE00
     1 P0V9_CPU1_RT3_2A_2D @T6G_MB_LIB.T6G(SCH_1):P0V9_CPU1_RT3_2A_2D    I91 @T6G_MB_LIB.T6G(SCH_1):PAGE465
     2    GND @T6G_MB_LIB.T6G(SCH_1):GND    I91 @T6G_MB_LIB.T6G(SCH_1):PAGE465

C461 Q_CAP_0402-1000PF,50V,5%,X7R,TMP_QCH21006JB10
     1 PVDDCR_SOC_P0_EN_RC @T6G_MB_LIB.T6G(SCH_1):PVDDCR_SOC_P0_EN_RC    I13 @T6G_MB_LIB.T6G(SCH_1):PAGE168
     2    GND @T6G_MB_LIB.T6G(SCH_1):GND    I13 @T6G_MB_LIB.T6G(SCH_1):PAGE168

C462 Q_CAP_C0201-0.1UF,10V,10%,X7S,CH4102K6E00
     1 P0V9_CPU1_RT3_2A @T6G_MB_LIB.T6G(SCH_1):P0V9_CPU1_RT3_2A    I83 @T6G_MB_LIB.T6G(SCH_1):PAGE465
     2    GND @T6G_MB_LIB.T6G(SCH_1):GND    I83 @T6G_MB_LIB.T6G(SCH_1):PAGE465

C463 Q_CAP_C0201-0.1UF,10V,10%,X7S,CH4102K6E00
     1 P0V9_CPU1_RT3_2A_2D @T6G_MB_LIB.T6G(SCH_1):P0V9_CPU1_RT3_2A_2D    I34 @T6G_MB_LIB.T6G(SCH_1):PAGE465
     2    GND @T6G_MB_LIB.T6G(SCH_1):GND    I34 @T6G_MB_LIB.T6G(SCH_1):PAGE465

C464 Q_CAP_C0201-0.1UF,10V,10%,X7S,CH4102K6E00
     1 P0V9_CPU1_RT3_2A_2D @T6G_MB_LIB.T6G(SCH_1):P0V9_CPU1_RT3_2A_2D    I35 @T6G_MB_LIB.T6G(SCH_1):PAGE465
     2    GND @T6G_MB_LIB.T6G(SCH_1):GND    I35 @T6G_MB_LIB.T6G(SCH_1):PAGE465

C465 Q_CAP_0402-1000PF,50V,5%,EMPTY,TMP_QCH21006JB10
     1 PWRGD_PVDDCR_SOC_P0_R @T6G_MB_LIB.T6G(SCH_1):PWRGD_PVDDCR_SOC_P0_R    I51 @T6G_MB_LIB.T6G(SCH_1):PAGE168
     2    GND @T6G_MB_LIB.T6G(SCH_1):GND    I51 @T6G_MB_LIB.T6G(SCH_1):PAGE168

C466 Q_CAP_C0805-100UF,4V,20%,X6S,CH710KMEA01
     1 P0V9_CPU1_RT3_2A @T6G_MB_LIB.T6G(SCH_1):P0V9_CPU1_RT3_2A    I64 @T6G_MB_LIB.T6G(SCH_1):PAGE465
     2    GND @T6G_MB_LIB.T6G(SCH_1):GND    I64 @T6G_MB_LIB.T6G(SCH_1):PAGE465

C467 Q_CAP_0402-1000PF,50V,5%,EMPTY,TMP_QCH21006JB10
     1 PWRGD_PVDDCR_CPU0_P0_R @T6G_MB_LIB.T6G(SCH_1):PWRGD_PVDDCR_CPU0_P0_R    I92 @T6G_MB_LIB.T6G(SCH_1):PAGE168
     2    GND @T6G_MB_LIB.T6G(SCH_1):GND    I92 @T6G_MB_LIB.T6G(SCH_1):PAGE168

C468 Q_CAP_0402-1000PF,50V,5%,X7R,TMP_QCH21006JB10
     1 PVDDCR_CPU0_P0_EN_R @T6G_MB_LIB.T6G(SCH_1):PVDDCR_CPU0_P0_EN_R    I90 @T6G_MB_LIB.T6G(SCH_1):PAGE168
     2    GND @T6G_MB_LIB.T6G(SCH_1):GND    I90 @T6G_MB_LIB.T6G(SCH_1):PAGE168

C469 Q_CAP_0402-4.7UF,6.3V,20%,X6S,CH5471MEB01
     1 P0V9_CPU1_RT3_2A @T6G_MB_LIB.T6G(SCH_1):P0V9_CPU1_RT3_2A    I51 @T6G_MB_LIB.T6G(SCH_1):PAGE465
     2    GND @T6G_MB_LIB.T6G(SCH_1):GND    I51 @T6G_MB_LIB.T6G(SCH_1):PAGE465

C470 Q_CAP_0201-1UF,4V,20%,X6S,CH-10KMEE00
     1 P0V9_CPU1_RT3_2A @T6G_MB_LIB.T6G(SCH_1):P0V9_CPU1_RT3_2A    I38 @T6G_MB_LIB.T6G(SCH_1):PAGE465
     2    GND @T6G_MB_LIB.T6G(SCH_1):GND    I38 @T6G_MB_LIB.T6G(SCH_1):PAGE465

C471 Q_CAP_C0805-100UF,4V,20%,X6S,CH710KMEA01
     1 P0V9_CPU1_RT3_2A @T6G_MB_LIB.T6G(SCH_1):P0V9_CPU1_RT3_2A    I65 @T6G_MB_LIB.T6G(SCH_1):PAGE465
     2    GND @T6G_MB_LIB.T6G(SCH_1):GND    I65 @T6G_MB_LIB.T6G(SCH_1):PAGE465

C472 Q_CAP_0402-4.7UF,6.3V,20%,X6S,CH5471MEB01
     1 P0V9_CPU1_RT3_2A @T6G_MB_LIB.T6G(SCH_1):P0V9_CPU1_RT3_2A    I50 @T6G_MB_LIB.T6G(SCH_1):PAGE465
     2    GND @T6G_MB_LIB.T6G(SCH_1):GND    I50 @T6G_MB_LIB.T6G(SCH_1):PAGE465

C473 Q_CAP_C0201-0.1UF,10V,10%,X7S,CH4102K6E00
     1 P0V9_CPU1_RT3_2A @T6G_MB_LIB.T6G(SCH_1):P0V9_CPU1_RT3_2A    I43 @T6G_MB_LIB.T6G(SCH_1):PAGE465
     2    GND @T6G_MB_LIB.T6G(SCH_1):GND    I43 @T6G_MB_LIB.T6G(SCH_1):PAGE465

C474 Q_CAP_C0805-100UF,4V,20%,X6S,CH710KMEA01
     1 P0V9_CPU1_RT_2D @T6G_MB_LIB.T6G(SCH_1):P0V9_CPU1_RT_2D    I67 @T6G_MB_LIB.T6G(SCH_1):PAGE465
     2    GND @T6G_MB_LIB.T6G(SCH_1):GND    I67 @T6G_MB_LIB.T6G(SCH_1):PAGE465

C475 Q_CAP_C0805-100UF,4V,20%,X6S,CH710KMEA01
     1 P0V9_CPU1_RT3_2A @T6G_MB_LIB.T6G(SCH_1):P0V9_CPU1_RT3_2A    I69 @T6G_MB_LIB.T6G(SCH_1):PAGE465
     2    GND @T6G_MB_LIB.T6G(SCH_1):GND    I69 @T6G_MB_LIB.T6G(SCH_1):PAGE465

C476 Q_CAP_C0402-22UF,4V,20%,X6S,CH622KMEB02
     1 P0V9_CPU1_RT3_2A @T6G_MB_LIB.T6G(SCH_1):P0V9_CPU1_RT3_2A    I71 @T6G_MB_LIB.T6G(SCH_1):PAGE465
     2    GND @T6G_MB_LIB.T6G(SCH_1):GND    I71 @T6G_MB_LIB.T6G(SCH_1):PAGE465

C477 Q_CAP_C0201-0.1UF,10V,10%,X7S,CH4102K6E00
     1 P0V9_CPU1_RT3_2A @T6G_MB_LIB.T6G(SCH_1):P0V9_CPU1_RT3_2A    I46 @T6G_MB_LIB.T6G(SCH_1):PAGE465
     2    GND @T6G_MB_LIB.T6G(SCH_1):GND    I46 @T6G_MB_LIB.T6G(SCH_1):PAGE465

C478 Q_CAP_C0402-22UF,4V,20%,X6S,CH622KMEB02
     1 P0V9_CPU1_RT_2D @T6G_MB_LIB.T6G(SCH_1):P0V9_CPU1_RT_2D    I68 @T6G_MB_LIB.T6G(SCH_1):PAGE465
     2    GND @T6G_MB_LIB.T6G(SCH_1):GND    I68 @T6G_MB_LIB.T6G(SCH_1):PAGE465

C479 Q_CAP_C0805-100UF,4V,20%,X6S,CH710KMEA01
     1 P0V9_CPU1_RT3_2A @T6G_MB_LIB.T6G(SCH_1):P0V9_CPU1_RT3_2A    I87 @T6G_MB_LIB.T6G(SCH_1):PAGE465
     2    GND @T6G_MB_LIB.T6G(SCH_1):GND    I87 @T6G_MB_LIB.T6G(SCH_1):PAGE465

C480 Q_CAP_C0402-10UF,6.3V,20%,X6S,CH6101MEB01
     1 P0V9_CPU1_RT3_2A @T6G_MB_LIB.T6G(SCH_1):P0V9_CPU1_RT3_2A    I40 @T6G_MB_LIB.T6G(SCH_1):PAGE465
     2    GND @T6G_MB_LIB.T6G(SCH_1):GND    I40 @T6G_MB_LIB.T6G(SCH_1):PAGE465

C481 Q_CAP_C0201-0.1UF,10V,10%,X7S,CH4102K6E00
     1 P0V9_CPU1_RT3_2A @T6G_MB_LIB.T6G(SCH_1):P0V9_CPU1_RT3_2A    I56 @T6G_MB_LIB.T6G(SCH_1):PAGE465
     2    GND @T6G_MB_LIB.T6G(SCH_1):GND    I56 @T6G_MB_LIB.T6G(SCH_1):PAGE465

C482 Q_CAP_C0402-10UF,6.3V,20%,X6S,CH6101MEB01
     1 P0V9_CPU1_RT3_2A @T6G_MB_LIB.T6G(SCH_1):P0V9_CPU1_RT3_2A    I77 @T6G_MB_LIB.T6G(SCH_1):PAGE465
     2    GND @T6G_MB_LIB.T6G(SCH_1):GND    I77 @T6G_MB_LIB.T6G(SCH_1):PAGE465

C483 Q_CAP_0402-4.7UF,6.3V,20%,X6S,CH5471MEB01
     1 P0V9_CPU1_RT3_2A @T6G_MB_LIB.T6G(SCH_1):P0V9_CPU1_RT3_2A    I86 @T6G_MB_LIB.T6G(SCH_1):PAGE465
     2    GND @T6G_MB_LIB.T6G(SCH_1):GND    I86 @T6G_MB_LIB.T6G(SCH_1):PAGE465

C484 Q_CAP_0402-4.7UF,6.3V,20%,X6S,CH5471MEB01
     1 P0V9_CPU1_RT_2D @T6G_MB_LIB.T6G(SCH_1):P0V9_CPU1_RT_2D    I73 @T6G_MB_LIB.T6G(SCH_1):PAGE465
     2    GND @T6G_MB_LIB.T6G(SCH_1):GND    I73 @T6G_MB_LIB.T6G(SCH_1):PAGE465

C485 Q_CAP_0201-1UF,4V,20%,X6S,CH-10KMEE00
     1 P0V9_CPU1_RT3_2A @T6G_MB_LIB.T6G(SCH_1):P0V9_CPU1_RT3_2A    I48 @T6G_MB_LIB.T6G(SCH_1):PAGE465
     2    GND @T6G_MB_LIB.T6G(SCH_1):GND    I48 @T6G_MB_LIB.T6G(SCH_1):PAGE465

C486 Q_CAP_C0402-22UF,4V,20%,X6S,CH622KMEB02
     1 P0V9_CPU1_RT3_2A @T6G_MB_LIB.T6G(SCH_1):P0V9_CPU1_RT3_2A    I85 @T6G_MB_LIB.T6G(SCH_1):PAGE465
     2    GND @T6G_MB_LIB.T6G(SCH_1):GND    I85 @T6G_MB_LIB.T6G(SCH_1):PAGE465

C487 Q_CAP_C0402-22UF,4V,20%,X6S,CH622KMEB02
     1 P0V9_CPU1_RT3_2A @T6G_MB_LIB.T6G(SCH_1):P0V9_CPU1_RT3_2A    I75 @T6G_MB_LIB.T6G(SCH_1):PAGE465
     2    GND @T6G_MB_LIB.T6G(SCH_1):GND    I75 @T6G_MB_LIB.T6G(SCH_1):PAGE465

C488 Q_CAP_0201-1UF,4V,20%,X6S,CH-10KMEE00
     1 P0V9_CPU1_RT3_2A @T6G_MB_LIB.T6G(SCH_1):P0V9_CPU1_RT3_2A    I49 @T6G_MB_LIB.T6G(SCH_1):PAGE465
     2    GND @T6G_MB_LIB.T6G(SCH_1):GND    I49 @T6G_MB_LIB.T6G(SCH_1):PAGE465

C489 Q_CAP_C0402-10UF,6.3V,20%,X6S,CH6101MEB01
     1 P0V9_CPU1_RT_2D @T6G_MB_LIB.T6G(SCH_1):P0V9_CPU1_RT_2D    I72 @T6G_MB_LIB.T6G(SCH_1):PAGE465
     2    GND @T6G_MB_LIB.T6G(SCH_1):GND    I72 @T6G_MB_LIB.T6G(SCH_1):PAGE465

C490 Q_CAP_C0402-10UF,6.3V,20%,X6S,CH6101MEB01
     1 P0V9_CPU1_RT3_2A @T6G_MB_LIB.T6G(SCH_1):P0V9_CPU1_RT3_2A    I41 @T6G_MB_LIB.T6G(SCH_1):PAGE465
     2    GND @T6G_MB_LIB.T6G(SCH_1):GND    I41 @T6G_MB_LIB.T6G(SCH_1):PAGE465

C491 Q_CAP_0201-1UF,4V,20%,X6S,CH-10KMEE00
     1 P0V9_CPU1_RT3_2A @T6G_MB_LIB.T6G(SCH_1):P0V9_CPU1_RT3_2A    I53 @T6G_MB_LIB.T6G(SCH_1):PAGE465
     2    GND @T6G_MB_LIB.T6G(SCH_1):GND    I53 @T6G_MB_LIB.T6G(SCH_1):PAGE465

C492 Q_CAP_0201-1UF,4V,20%,X6S,CH-10KMEE00
     1 P0V9_CPU1_RT3_2A @T6G_MB_LIB.T6G(SCH_1):P0V9_CPU1_RT3_2A    I54 @T6G_MB_LIB.T6G(SCH_1):PAGE465
     2    GND @T6G_MB_LIB.T6G(SCH_1):GND    I54 @T6G_MB_LIB.T6G(SCH_1):PAGE465

C493 Q_CAP_C0201-0.1UF,10V,10%,X7S,CH4102K6E00
     1 P0V9_CPU1_RT_2D @T6G_MB_LIB.T6G(SCH_1):P0V9_CPU1_RT_2D    I80 @T6G_MB_LIB.T6G(SCH_1):PAGE465
     2    GND @T6G_MB_LIB.T6G(SCH_1):GND    I80 @T6G_MB_LIB.T6G(SCH_1):PAGE465

C494 Q_CAP_0402-4.7UF,6.3V,20%,X6S,CH5471MEB01
     1 P0V9_CPU1_RT3_2A @T6G_MB_LIB.T6G(SCH_1):P0V9_CPU1_RT3_2A    I52 @T6G_MB_LIB.T6G(SCH_1):PAGE465
     2    GND @T6G_MB_LIB.T6G(SCH_1):GND    I52 @T6G_MB_LIB.T6G(SCH_1):PAGE465

C495 Q_CAP_C0201-0.1UF,10V,10%,X7S,CH4102K6E00
     1 P0V9_CPU1_RT3_2A @T6G_MB_LIB.T6G(SCH_1):P0V9_CPU1_RT3_2A    I37 @T6G_MB_LIB.T6G(SCH_1):PAGE465
     2    GND @T6G_MB_LIB.T6G(SCH_1):GND    I37 @T6G_MB_LIB.T6G(SCH_1):PAGE465

C496 Q_CAP_C0201-0.1UF,10V,10%,X7S,CH4102K6E00
     1 P0V9_CPU1_RT3_2A @T6G_MB_LIB.T6G(SCH_1):P0V9_CPU1_RT3_2A    I92 @T6G_MB_LIB.T6G(SCH_1):PAGE465
     2    GND @T6G_MB_LIB.T6G(SCH_1):GND    I92 @T6G_MB_LIB.T6G(SCH_1):PAGE465

C497 Q_CAP_0201-1UF,4V,20%,X6S,CH-10KMEE00
     1 P0V9_CPU1_RT3_2A @T6G_MB_LIB.T6G(SCH_1):P0V9_CPU1_RT3_2A    I60 @T6G_MB_LIB.T6G(SCH_1):PAGE465
     2    GND @T6G_MB_LIB.T6G(SCH_1):GND    I60 @T6G_MB_LIB.T6G(SCH_1):PAGE465

C498 Q_CAP_C0201-0.1UF,10V,10%,X7S,CH4102K6E00
     1 P0V9_CPU1_RT3_2A @T6G_MB_LIB.T6G(SCH_1):P0V9_CPU1_RT3_2A    I93 @T6G_MB_LIB.T6G(SCH_1):PAGE465
     2    GND @T6G_MB_LIB.T6G(SCH_1):GND    I93 @T6G_MB_LIB.T6G(SCH_1):PAGE465

C499 Q_CAP_C0402-10UF,6.3V,20%,X6S,CH6101MEB01
     1 P0V9_CPU1_RT3_2A @T6G_MB_LIB.T6G(SCH_1):P0V9_CPU1_RT3_2A    I76 @T6G_MB_LIB.T6G(SCH_1):PAGE465
     2    GND @T6G_MB_LIB.T6G(SCH_1):GND    I76 @T6G_MB_LIB.T6G(SCH_1):PAGE465

C500 Q_CAP_C0201-0.1UF,10V,10%,X7S,CH4102K6E00
     1 P0V9_CPU1_RT3_2A @T6G_MB_LIB.T6G(SCH_1):P0V9_CPU1_RT3_2A    I42 @T6G_MB_LIB.T6G(SCH_1):PAGE465
     2    GND @T6G_MB_LIB.T6G(SCH_1):GND    I42 @T6G_MB_LIB.T6G(SCH_1):PAGE465

C501 Q_CAP_C0402-22UF,4V,20%,X6S,CH622KMEB02
     1 P0V9_CPU1_RT3_2A @T6G_MB_LIB.T6G(SCH_1):P0V9_CPU1_RT3_2A    I70 @T6G_MB_LIB.T6G(SCH_1):PAGE465
     2    GND @T6G_MB_LIB.T6G(SCH_1):GND    I70 @T6G_MB_LIB.T6G(SCH_1):PAGE465

C502 Q_CAP_C0805-100UF,4V,20%,X6S,CH710KMEA01
     1 P1V8_CPU0_RT_1D @T6G_MB_LIB.T6G(SCH_1):P1V8_CPU0_RT_1D    I16 @T6G_MB_LIB.T6G(SCH_1):PAGE388
     2    GND @T6G_MB_LIB.T6G(SCH_1):GND    I16 @T6G_MB_LIB.T6G(SCH_1):PAGE388

C503 Q_CAP_C0805-100UF,4V,20%,X6S,CH710KMEA01
     1 P1V8_CPU0_RT0_1A @T6G_MB_LIB.T6G(SCH_1):P1V8_CPU0_RT0_1A    I13 @T6G_MB_LIB.T6G(SCH_1):PAGE388
     2    GND @T6G_MB_LIB.T6G(SCH_1):GND    I13 @T6G_MB_LIB.T6G(SCH_1):PAGE388

C504 Q_CAP_C0402-22UF,4V,20%,X6S,CH622KMEB02
     1 P1V8_CPU0_RT_1D @T6G_MB_LIB.T6G(SCH_1):P1V8_CPU0_RT_1D    I24 @T6G_MB_LIB.T6G(SCH_1):PAGE388
     2    GND @T6G_MB_LIB.T6G(SCH_1):GND    I24 @T6G_MB_LIB.T6G(SCH_1):PAGE388

C505 Q_CAP_C0402-22UF,4V,20%,X6S,CH622KMEB02
     1 P1V8_CPU0_RT0_1A @T6G_MB_LIB.T6G(SCH_1):P1V8_CPU0_RT0_1A    I14 @T6G_MB_LIB.T6G(SCH_1):PAGE388
     2    GND @T6G_MB_LIB.T6G(SCH_1):GND    I14 @T6G_MB_LIB.T6G(SCH_1):PAGE388

C506 Q_CAP_C0402-10UF,6.3V,20%,X6S,CH6101MEB01
     1 P1V8_CPU0_RT_1D @T6G_MB_LIB.T6G(SCH_1):P1V8_CPU0_RT_1D    I25 @T6G_MB_LIB.T6G(SCH_1):PAGE388
     2    GND @T6G_MB_LIB.T6G(SCH_1):GND    I25 @T6G_MB_LIB.T6G(SCH_1):PAGE388

C507 Q_CAP_C0402-10UF,6.3V,20%,X6S,CH6101MEB01
     1 P1V8_CPU0_RT0_1A @T6G_MB_LIB.T6G(SCH_1):P1V8_CPU0_RT0_1A    I17 @T6G_MB_LIB.T6G(SCH_1):PAGE388
     2    GND @T6G_MB_LIB.T6G(SCH_1):GND    I17 @T6G_MB_LIB.T6G(SCH_1):PAGE388

C508 Q_CAP_0402-0.1UF,25V,10%,X7R,CH4104K1B00
     1 P3V3_E1S_0 @T6G_MB_LIB.T6G(SCH_1):P3V3_E1S_0    I99 @T6G_MB_LIB.T6G(SCH_1):PAGE297
     2    GND @T6G_MB_LIB.T6G(SCH_1):GND    I99 @T6G_MB_LIB.T6G(SCH_1):PAGE297

C509 Q_CAP_C0805-10UF,25V,10%,X6S,CH6104KEA00
     1 P12V_MEM_CPU1 @T6G_MB_LIB.T6G(SCH_1):P12V_MEM_CPU1   I239 @T6G_MB_LIB.T6G(SCH_1):PAGE101
     2    GND @T6G_MB_LIB.T6G(SCH_1):GND   I239 @T6G_MB_LIB.T6G(SCH_1):PAGE101

C510 Q_CAP_0402-4.7UF,6.3V,20%,X6S,CH5471MEB01
     1 P1V8_CPU0_RT0_1A @T6G_MB_LIB.T6G(SCH_1):P1V8_CPU0_RT0_1A    I18 @T6G_MB_LIB.T6G(SCH_1):PAGE388
     2    GND @T6G_MB_LIB.T6G(SCH_1):GND    I18 @T6G_MB_LIB.T6G(SCH_1):PAGE388

C511 Q_CAP_0402-4.7UF,6.3V,20%,X6S,CH5471MEB01
     1 P1V8_CPU0_RT_1D @T6G_MB_LIB.T6G(SCH_1):P1V8_CPU0_RT_1D    I26 @T6G_MB_LIB.T6G(SCH_1):PAGE388
     2    GND @T6G_MB_LIB.T6G(SCH_1):GND    I26 @T6G_MB_LIB.T6G(SCH_1):PAGE388

C512 Q_CAP_0201-1UF,4V,20%,X6S,CH-10KMEE00
     1 P1V8_CPU0_RT0_1A @T6G_MB_LIB.T6G(SCH_1):P1V8_CPU0_RT0_1A    I19 @T6G_MB_LIB.T6G(SCH_1):PAGE388
     2    GND @T6G_MB_LIB.T6G(SCH_1):GND    I19 @T6G_MB_LIB.T6G(SCH_1):PAGE388

C513 Q_CAP_0201-1UF,4V,20%,X6S,CH-10KMEE00
     1 P1V8_CPU0_RT0_1A_1D @T6G_MB_LIB.T6G(SCH_1):P1V8_CPU0_RT0_1A_1D     I8 @T6G_MB_LIB.T6G(SCH_1):PAGE388
     2    GND @T6G_MB_LIB.T6G(SCH_1):GND     I8 @T6G_MB_LIB.T6G(SCH_1):PAGE388

C514 Q_CAP_0201-1UF,4V,20%,X6S,CH-10KMEE00
     1 P1V8_CPU0_RT0_1A @T6G_MB_LIB.T6G(SCH_1):P1V8_CPU0_RT0_1A    I22 @T6G_MB_LIB.T6G(SCH_1):PAGE388
     2    GND @T6G_MB_LIB.T6G(SCH_1):GND    I22 @T6G_MB_LIB.T6G(SCH_1):PAGE388

C515 Q_CAP_C0201-0.1UF,10V,10%,X7S,CH4102K6E00
     1 P1V8_CPU0_RT0_1A @T6G_MB_LIB.T6G(SCH_1):P1V8_CPU0_RT0_1A    I23 @T6G_MB_LIB.T6G(SCH_1):PAGE388
     2    GND @T6G_MB_LIB.T6G(SCH_1):GND    I23 @T6G_MB_LIB.T6G(SCH_1):PAGE388

C516 Q_CAP_C0201-0.1UF,10V,10%,X7S,CH4102K6E00
     1 P1V8_CPU0_RT0_1A_1D @T6G_MB_LIB.T6G(SCH_1):P1V8_CPU0_RT0_1A_1D     I9 @T6G_MB_LIB.T6G(SCH_1):PAGE388
     2    GND @T6G_MB_LIB.T6G(SCH_1):GND     I9 @T6G_MB_LIB.T6G(SCH_1):PAGE388

C517 Q_CAP_C0201-0.1UF,10V,10%,X7S,CH4102K6E00
     1 P1V8_CPU0_RT0_1A @T6G_MB_LIB.T6G(SCH_1):P1V8_CPU0_RT0_1A    I27 @T6G_MB_LIB.T6G(SCH_1):PAGE388
     2    GND @T6G_MB_LIB.T6G(SCH_1):GND    I27 @T6G_MB_LIB.T6G(SCH_1):PAGE388

C518 Q_CAP_C0805-10UF,25V,10%,X6S,CH6104KEA00
     1 P12V_MEM_CPU1 @T6G_MB_LIB.T6G(SCH_1):P12V_MEM_CPU1   I238 @T6G_MB_LIB.T6G(SCH_1):PAGE102
     2    GND @T6G_MB_LIB.T6G(SCH_1):GND   I238 @T6G_MB_LIB.T6G(SCH_1):PAGE102

C519 Q_CAP_C0201-0.1UF,10V,10%,X7S,CH4102K6E00
     1 P1V8_CPU0_RT0_1A @T6G_MB_LIB.T6G(SCH_1):P1V8_CPU0_RT0_1A    I28 @T6G_MB_LIB.T6G(SCH_1):PAGE388
     2    GND @T6G_MB_LIB.T6G(SCH_1):GND    I28 @T6G_MB_LIB.T6G(SCH_1):PAGE388

C520 Q_CAP_C0201-0.1UF,10V,10%,X7S,CH4102K6E00
     1 P1V8_CPU0_RT0_1A @T6G_MB_LIB.T6G(SCH_1):P1V8_CPU0_RT0_1A    I29 @T6G_MB_LIB.T6G(SCH_1):PAGE388
     2    GND @T6G_MB_LIB.T6G(SCH_1):GND    I29 @T6G_MB_LIB.T6G(SCH_1):PAGE388

C521 Q_CAP_0201-1UF,4V,20%,X6S,CH-10KMEE00
     1 P0V9_CPU0_RT0_2A @T6G_MB_LIB.T6G(SCH_1):P0V9_CPU0_RT0_2A    I65 @T6G_MB_LIB.T6G(SCH_1):PAGE388
     2    GND @T6G_MB_LIB.T6G(SCH_1):GND    I65 @T6G_MB_LIB.T6G(SCH_1):PAGE388

C522 Q_CAP_C0201-0.1UF,10V,10%,X7S,CH4102K6E00
     1 P0V9_CPU0_RT_2D @T6G_MB_LIB.T6G(SCH_1):P0V9_CPU0_RT_2D    I81 @T6G_MB_LIB.T6G(SCH_1):PAGE388
     2    GND @T6G_MB_LIB.T6G(SCH_1):GND    I81 @T6G_MB_LIB.T6G(SCH_1):PAGE388

C523 Q_CAP_C0201-0.1UF,10V,10%,X7S,CH4102K6E00
     1 P0V9_CPU0_RT0_2A @T6G_MB_LIB.T6G(SCH_1):P0V9_CPU0_RT0_2A    I50 @T6G_MB_LIB.T6G(SCH_1):PAGE388
     2    GND @T6G_MB_LIB.T6G(SCH_1):GND    I50 @T6G_MB_LIB.T6G(SCH_1):PAGE388

C524 Q_CAP_C0201-0.1UF,10V,10%,X7S,CH4102K6E00
     1 P0V9_CPU0_RT_2D @T6G_MB_LIB.T6G(SCH_1):P0V9_CPU0_RT_2D    I84 @T6G_MB_LIB.T6G(SCH_1):PAGE388
     2    GND @T6G_MB_LIB.T6G(SCH_1):GND    I84 @T6G_MB_LIB.T6G(SCH_1):PAGE388

C525 Q_CAP_0201-1UF,4V,20%,X6S,CH-10KMEE00
     1 P0V9_CPU0_RT0_2A @T6G_MB_LIB.T6G(SCH_1):P0V9_CPU0_RT0_2A    I58 @T6G_MB_LIB.T6G(SCH_1):PAGE388
     2    GND @T6G_MB_LIB.T6G(SCH_1):GND    I58 @T6G_MB_LIB.T6G(SCH_1):PAGE388

C526 Q_CAP_0201-1UF,4V,20%,X6S,CH-10KMEE00
     1 P0V9_CPU0_RT0_2A @T6G_MB_LIB.T6G(SCH_1):P0V9_CPU0_RT0_2A    I66 @T6G_MB_LIB.T6G(SCH_1):PAGE388
     2    GND @T6G_MB_LIB.T6G(SCH_1):GND    I66 @T6G_MB_LIB.T6G(SCH_1):PAGE388

C527 Q_CAP_C0805-10UF,25V,10%,X6S,CH6104KEA00
     1 P12V_MEM_CPU1 @T6G_MB_LIB.T6G(SCH_1):P12V_MEM_CPU1   I239 @T6G_MB_LIB.T6G(SCH_1):PAGE102
     2    GND @T6G_MB_LIB.T6G(SCH_1):GND   I239 @T6G_MB_LIB.T6G(SCH_1):PAGE102

C528 Q_CAP_0201-1UF,4V,20%,X6S,CH-10KMEE00
     1 P0V9_CPU0_RT_2D @T6G_MB_LIB.T6G(SCH_1):P0V9_CPU0_RT_2D    I80 @T6G_MB_LIB.T6G(SCH_1):PAGE388
     2    GND @T6G_MB_LIB.T6G(SCH_1):GND    I80 @T6G_MB_LIB.T6G(SCH_1):PAGE388

C529 Q_CAP_0201-1UF,4V,20%,X6S,CH-10KMEE00
     1 P0V9_CPU0_RT0_2A @T6G_MB_LIB.T6G(SCH_1):P0V9_CPU0_RT0_2A    I59 @T6G_MB_LIB.T6G(SCH_1):PAGE388
     2    GND @T6G_MB_LIB.T6G(SCH_1):GND    I59 @T6G_MB_LIB.T6G(SCH_1):PAGE388

C530 Q_CAP_C0805-10UF,25V,10%,X6S,CH6104KEA00
     1 P12V_MEM_CPU1 @T6G_MB_LIB.T6G(SCH_1):P12V_MEM_CPU1   I240 @T6G_MB_LIB.T6G(SCH_1):PAGE103
     2    GND @T6G_MB_LIB.T6G(SCH_1):GND   I240 @T6G_MB_LIB.T6G(SCH_1):PAGE103

C531 Q_CAP_C0805-10UF,25V,10%,X6S,CH6104KEA00
     1 P12V_MEM_CPU1 @T6G_MB_LIB.T6G(SCH_1):P12V_MEM_CPU1   I241 @T6G_MB_LIB.T6G(SCH_1):PAGE103
     2    GND @T6G_MB_LIB.T6G(SCH_1):GND   I241 @T6G_MB_LIB.T6G(SCH_1):PAGE103

C532 Q_CAP_C0805-10UF,25V,10%,X6S,CH6104KEA00
     1 P12V_MEM_CPU1 @T6G_MB_LIB.T6G(SCH_1):P12V_MEM_CPU1   I240 @T6G_MB_LIB.T6G(SCH_1):PAGE104
     2    GND @T6G_MB_LIB.T6G(SCH_1):GND   I240 @T6G_MB_LIB.T6G(SCH_1):PAGE104

C533 Q_CAP_C0805-10UF,25V,10%,X6S,CH6104KEA00
     1 P12V_MEM_CPU1 @T6G_MB_LIB.T6G(SCH_1):P12V_MEM_CPU1   I241 @T6G_MB_LIB.T6G(SCH_1):PAGE104
     2    GND @T6G_MB_LIB.T6G(SCH_1):GND   I241 @T6G_MB_LIB.T6G(SCH_1):PAGE104

C534 Q_CAP_C0805-10UF,25V,10%,X6S,CH6104KEA00
     1 P12V_MEM_CPU1 @T6G_MB_LIB.T6G(SCH_1):P12V_MEM_CPU1   I238 @T6G_MB_LIB.T6G(SCH_1):PAGE105
     2    GND @T6G_MB_LIB.T6G(SCH_1):GND   I238 @T6G_MB_LIB.T6G(SCH_1):PAGE105

C535 Q_CAP_C0805-10UF,25V,10%,X6S,CH6104KEA00
     1 P12V_MEM_CPU1 @T6G_MB_LIB.T6G(SCH_1):P12V_MEM_CPU1   I239 @T6G_MB_LIB.T6G(SCH_1):PAGE105
     2    GND @T6G_MB_LIB.T6G(SCH_1):GND   I239 @T6G_MB_LIB.T6G(SCH_1):PAGE105

C536 Q_CAP_C0805-10UF,25V,10%,X6S,CH6104KEA00
     1 P12V_MEM_CPU1 @T6G_MB_LIB.T6G(SCH_1):P12V_MEM_CPU1   I238 @T6G_MB_LIB.T6G(SCH_1):PAGE106
     2    GND @T6G_MB_LIB.T6G(SCH_1):GND   I238 @T6G_MB_LIB.T6G(SCH_1):PAGE106

C537 Q_CAP_C0805-10UF,25V,10%,X6S,CH6104KEA00
     1 P12V_MEM_CPU1 @T6G_MB_LIB.T6G(SCH_1):P12V_MEM_CPU1   I239 @T6G_MB_LIB.T6G(SCH_1):PAGE106
     2    GND @T6G_MB_LIB.T6G(SCH_1):GND   I239 @T6G_MB_LIB.T6G(SCH_1):PAGE106

C538 Q_CAP_C0201-0.1UF,10V,10%,X7S,CH4102K6E00
     1 P0V9_CPU0_RT0_2A_2D @T6G_MB_LIB.T6G(SCH_1):P0V9_CPU0_RT0_2A_2D    I32 @T6G_MB_LIB.T6G(SCH_1):PAGE388
     2    GND @T6G_MB_LIB.T6G(SCH_1):GND    I32 @T6G_MB_LIB.T6G(SCH_1):PAGE388

C539 Q_CAP_0201-1UF,4V,20%,X6S,CH-10KMEE00
     1 P0V9_CPU0_RT0_2A @T6G_MB_LIB.T6G(SCH_1):P0V9_CPU0_RT0_2A    I42 @T6G_MB_LIB.T6G(SCH_1):PAGE388
     2    GND @T6G_MB_LIB.T6G(SCH_1):GND    I42 @T6G_MB_LIB.T6G(SCH_1):PAGE388

C540 Q_CAP_C0201-0.1UF,10V,10%,X7S,CH4102K6E00
     1 P0V9_CPU0_RT_2D @T6G_MB_LIB.T6G(SCH_1):P0V9_CPU0_RT_2D    I87 @T6G_MB_LIB.T6G(SCH_1):PAGE388
     2    GND @T6G_MB_LIB.T6G(SCH_1):GND    I87 @T6G_MB_LIB.T6G(SCH_1):PAGE388

C541 Q_CAP_C0201-0.1UF,10V,10%,X7S,CH4102K6E00
     1 P0V9_CPU0_RT0_2A @T6G_MB_LIB.T6G(SCH_1):P0V9_CPU0_RT0_2A    I48 @T6G_MB_LIB.T6G(SCH_1):PAGE388
     2    GND @T6G_MB_LIB.T6G(SCH_1):GND    I48 @T6G_MB_LIB.T6G(SCH_1):PAGE388

C542 Q_CAP_0201-1UF,4V,20%,X6S,CH-10KMEE00
     1 P0V9_CPU0_RT0_2A_2D @T6G_MB_LIB.T6G(SCH_1):P0V9_CPU0_RT0_2A_2D    I90 @T6G_MB_LIB.T6G(SCH_1):PAGE388
     2    GND @T6G_MB_LIB.T6G(SCH_1):GND    I90 @T6G_MB_LIB.T6G(SCH_1):PAGE388

C543 Q_CAP_C0201-0.1UF,10V,10%,X7S,CH4102K6E00
     1 P0V9_CPU0_RT0_2A @T6G_MB_LIB.T6G(SCH_1):P0V9_CPU0_RT0_2A    I62 @T6G_MB_LIB.T6G(SCH_1):PAGE388
     2    GND @T6G_MB_LIB.T6G(SCH_1):GND    I62 @T6G_MB_LIB.T6G(SCH_1):PAGE388

C544 Q_CAP_C0201-0.1UF,10V,10%,X7S,CH4102K6E00
     1 P0V9_CPU0_RT0_2A_2D @T6G_MB_LIB.T6G(SCH_1):P0V9_CPU0_RT0_2A_2D    I36 @T6G_MB_LIB.T6G(SCH_1):PAGE388
     2    GND @T6G_MB_LIB.T6G(SCH_1):GND    I36 @T6G_MB_LIB.T6G(SCH_1):PAGE388

C545 Q_CAP_0201-1UF,4V,20%,X6S,CH-10KMEE00
     1 P0V9_CPU0_RT0_2A_2D @T6G_MB_LIB.T6G(SCH_1):P0V9_CPU0_RT0_2A_2D    I91 @T6G_MB_LIB.T6G(SCH_1):PAGE388
     2    GND @T6G_MB_LIB.T6G(SCH_1):GND    I91 @T6G_MB_LIB.T6G(SCH_1):PAGE388

C546 Q_CAP_C0805-10UF,25V,10%,X6S,CH6104KEA00
     1 P12V_MEM_CPU1 @T6G_MB_LIB.T6G(SCH_1):P12V_MEM_CPU1   I237 @T6G_MB_LIB.T6G(SCH_1):PAGE107
     2    GND @T6G_MB_LIB.T6G(SCH_1):GND   I237 @T6G_MB_LIB.T6G(SCH_1):PAGE107

C547 Q_CAP_C0805-10UF,25V,10%,X6S,CH6104KEA00
     1 P12V_MEM_CPU1 @T6G_MB_LIB.T6G(SCH_1):P12V_MEM_CPU1   I238 @T6G_MB_LIB.T6G(SCH_1):PAGE107
     2    GND @T6G_MB_LIB.T6G(SCH_1):GND   I238 @T6G_MB_LIB.T6G(SCH_1):PAGE107

C548 Q_CAP_C0805-10UF,25V,10%,X6S,CH6104KEA00
     1 P12V_MEM_CPU1 @T6G_MB_LIB.T6G(SCH_1):P12V_MEM_CPU1   I237 @T6G_MB_LIB.T6G(SCH_1):PAGE108
     2    GND @T6G_MB_LIB.T6G(SCH_1):GND   I237 @T6G_MB_LIB.T6G(SCH_1):PAGE108

C549 Q_CAP_C0805-10UF,25V,10%,X6S,CH6104KEA00
     1 P12V_MEM_CPU1 @T6G_MB_LIB.T6G(SCH_1):P12V_MEM_CPU1   I238 @T6G_MB_LIB.T6G(SCH_1):PAGE108
     2    GND @T6G_MB_LIB.T6G(SCH_1):GND   I238 @T6G_MB_LIB.T6G(SCH_1):PAGE108

C550 Q_CAP_C0805-100UF,4V,20%,X6S,CH710KMEA01
     1 P0V9_CPU0_RT0_2A @T6G_MB_LIB.T6G(SCH_1):P0V9_CPU0_RT0_2A    I67 @T6G_MB_LIB.T6G(SCH_1):PAGE388
     2    GND @T6G_MB_LIB.T6G(SCH_1):GND    I67 @T6G_MB_LIB.T6G(SCH_1):PAGE388

C551 Q_CAP_C0402-0.01UF,50V,10%,X7R,CH31006KB18
     1 CPU0_HDT_CONN_TESTEN @T6G_MB_LIB.T6G(SCH_1):CPU0_HDT_CONN_TESTEN   I123 @T6G_MB_LIB.T6G(SCH_1):PAGE149
     2    GND @T6G_MB_LIB.T6G(SCH_1):GND   I123 @T6G_MB_LIB.T6G(SCH_1):PAGE149

C552 Q_CAP_0402-0.1UF,25V,10%,X7R,CH4104K1B00
     1 P1V8_AUX @T6G_MB_LIB.T6G(SCH_1):P1V8_AUX    I24 @T6G_MB_LIB.T6G(SCH_1):PAGE83
     2    GND @T6G_MB_LIB.T6G(SCH_1):GND    I24 @T6G_MB_LIB.T6G(SCH_1):PAGE83

C553 Q_CAP_0402-0.1UF,25V,10%,X7R,CH4104K1B00
     1 P3V3_AUX @T6G_MB_LIB.T6G(SCH_1):P3V3_AUX   I342 @T6G_MB_LIB.T6G(SCH_1):PAGE148
     2    GND @T6G_MB_LIB.T6G(SCH_1):GND   I342 @T6G_MB_LIB.T6G(SCH_1):PAGE148

C554 Q_CAP_0402-4.7UF,6.3V,20%,X6S,CH5471MEB01
     1 P0V9_CPU0_RT0_2A @T6G_MB_LIB.T6G(SCH_1):P0V9_CPU0_RT0_2A    I45 @T6G_MB_LIB.T6G(SCH_1):PAGE388
     2    GND @T6G_MB_LIB.T6G(SCH_1):GND    I45 @T6G_MB_LIB.T6G(SCH_1):PAGE388

C555 Q_CAP_0201-1UF,4V,20%,X6S,CH-10KMEE00
     1 P0V9_CPU0_RT0_2A @T6G_MB_LIB.T6G(SCH_1):P0V9_CPU0_RT0_2A    I40 @T6G_MB_LIB.T6G(SCH_1):PAGE388
     2    GND @T6G_MB_LIB.T6G(SCH_1):GND    I40 @T6G_MB_LIB.T6G(SCH_1):PAGE388

C556 Q_CAP_C0805-100UF,4V,20%,X6S,CH710KMEA01
     1 P0V9_CPU0_RT0_2A @T6G_MB_LIB.T6G(SCH_1):P0V9_CPU0_RT0_2A    I69 @T6G_MB_LIB.T6G(SCH_1):PAGE388
     2    GND @T6G_MB_LIB.T6G(SCH_1):GND    I69 @T6G_MB_LIB.T6G(SCH_1):PAGE388

C557 Q_CAP_0402-4.7UF,6.3V,20%,X6S,CH5471MEB01
     1 P0V9_CPU0_RT0_2A @T6G_MB_LIB.T6G(SCH_1):P0V9_CPU0_RT0_2A    I54 @T6G_MB_LIB.T6G(SCH_1):PAGE388
     2    GND @T6G_MB_LIB.T6G(SCH_1):GND    I54 @T6G_MB_LIB.T6G(SCH_1):PAGE388

C558 Q_CAP_C0201-0.1UF,10V,10%,X7S,CH4102K6E00
     1 P0V9_CPU0_RT0_2A @T6G_MB_LIB.T6G(SCH_1):P0V9_CPU0_RT0_2A    I60 @T6G_MB_LIB.T6G(SCH_1):PAGE388
     2    GND @T6G_MB_LIB.T6G(SCH_1):GND    I60 @T6G_MB_LIB.T6G(SCH_1):PAGE388

C559 Q_CAP_C0805-100UF,4V,20%,X6S,CH710KMEA01
     1 P0V9_CPU0_RT_2D @T6G_MB_LIB.T6G(SCH_1):P0V9_CPU0_RT_2D    I72 @T6G_MB_LIB.T6G(SCH_1):PAGE388
     2    GND @T6G_MB_LIB.T6G(SCH_1):GND    I72 @T6G_MB_LIB.T6G(SCH_1):PAGE388

C560 Q_CAP_C0805-100UF,4V,20%,X6S,CH710KMEA01
     1 P0V9_CPU0_RT0_2A @T6G_MB_LIB.T6G(SCH_1):P0V9_CPU0_RT0_2A    I70 @T6G_MB_LIB.T6G(SCH_1):PAGE388
     2    GND @T6G_MB_LIB.T6G(SCH_1):GND    I70 @T6G_MB_LIB.T6G(SCH_1):PAGE388

C561 Q_CAP_C0402-10UF,6.3V,20%,X6S,CH6101MEB01
     1 P0V9_CPU0_RT0_2A @T6G_MB_LIB.T6G(SCH_1):P0V9_CPU0_RT0_2A    I41 @T6G_MB_LIB.T6G(SCH_1):PAGE388
     2    GND @T6G_MB_LIB.T6G(SCH_1):GND    I41 @T6G_MB_LIB.T6G(SCH_1):PAGE388

C562 Q_CAP_0201-1UF,4V,20%,X6S,CH-10KMEE00
     1 P0V9_CPU0_RT0_2A @T6G_MB_LIB.T6G(SCH_1):P0V9_CPU0_RT0_2A    I43 @T6G_MB_LIB.T6G(SCH_1):PAGE388
     2    GND @T6G_MB_LIB.T6G(SCH_1):GND    I43 @T6G_MB_LIB.T6G(SCH_1):PAGE388

C563 Q_CAP_C0402-22UF,4V,20%,X6S,CH622KMEB02
     1 P0V9_CPU0_RT_2D @T6G_MB_LIB.T6G(SCH_1):P0V9_CPU0_RT_2D    I74 @T6G_MB_LIB.T6G(SCH_1):PAGE388
     2    GND @T6G_MB_LIB.T6G(SCH_1):GND    I74 @T6G_MB_LIB.T6G(SCH_1):PAGE388

C564 Q_CAP_C0805-100UF,4V,20%,X6S,CH710KMEA01
     1 P0V9_CPU0_RT0_2A @T6G_MB_LIB.T6G(SCH_1):P0V9_CPU0_RT0_2A    I71 @T6G_MB_LIB.T6G(SCH_1):PAGE388
     2    GND @T6G_MB_LIB.T6G(SCH_1):GND    I71 @T6G_MB_LIB.T6G(SCH_1):PAGE388

C565 Q_CAP_C0402-22UF,4V,20%,X6S,CH622KMEB02
     1 P0V9_CPU0_RT0_2A @T6G_MB_LIB.T6G(SCH_1):P0V9_CPU0_RT0_2A    I76 @T6G_MB_LIB.T6G(SCH_1):PAGE388
     2    GND @T6G_MB_LIB.T6G(SCH_1):GND    I76 @T6G_MB_LIB.T6G(SCH_1):PAGE388

C566 Q_CAP_C0201-0.1UF,10V,10%,X7S,CH4102K6E00
     1 P0V9_CPU0_RT0_2A @T6G_MB_LIB.T6G(SCH_1):P0V9_CPU0_RT0_2A    I94 @T6G_MB_LIB.T6G(SCH_1):PAGE388
     2    GND @T6G_MB_LIB.T6G(SCH_1):GND    I94 @T6G_MB_LIB.T6G(SCH_1):PAGE388

C567 Q_CAP_C0402-10UF,6.3V,20%,X6S,CH6101MEB01
     1 P0V9_CPU0_RT0_2A @T6G_MB_LIB.T6G(SCH_1):P0V9_CPU0_RT0_2A    I83 @T6G_MB_LIB.T6G(SCH_1):PAGE388
     2    GND @T6G_MB_LIB.T6G(SCH_1):GND    I83 @T6G_MB_LIB.T6G(SCH_1):PAGE388

C568 Q_CAP_C0402-22UF,4V,20%,X6S,CH622KMEB02
     1 P0V9_CPU0_RT0_2A @T6G_MB_LIB.T6G(SCH_1):P0V9_CPU0_RT0_2A    I78 @T6G_MB_LIB.T6G(SCH_1):PAGE388
     2    GND @T6G_MB_LIB.T6G(SCH_1):GND    I78 @T6G_MB_LIB.T6G(SCH_1):PAGE388

C569 Q_CAP_0402-4.7UF,6.3V,20%,X6S,CH5471MEB01
     1 P0V9_CPU0_RT_2D @T6G_MB_LIB.T6G(SCH_1):P0V9_CPU0_RT_2D    I79 @T6G_MB_LIB.T6G(SCH_1):PAGE388
     2    GND @T6G_MB_LIB.T6G(SCH_1):GND    I79 @T6G_MB_LIB.T6G(SCH_1):PAGE388

C570 Q_CAP_0201-1UF,4V,20%,X6S,CH-10KMEE00
     1 P0V9_CPU0_RT0_2A @T6G_MB_LIB.T6G(SCH_1):P0V9_CPU0_RT0_2A    I52 @T6G_MB_LIB.T6G(SCH_1):PAGE388
     2    GND @T6G_MB_LIB.T6G(SCH_1):GND    I52 @T6G_MB_LIB.T6G(SCH_1):PAGE388

C571 Q_CAP_0402-4.7UF,6.3V,20%,X6S,CH5471MEB01
     1 P0V9_CPU0_RT0_2A @T6G_MB_LIB.T6G(SCH_1):P0V9_CPU0_RT0_2A    I46 @T6G_MB_LIB.T6G(SCH_1):PAGE388
     2    GND @T6G_MB_LIB.T6G(SCH_1):GND    I46 @T6G_MB_LIB.T6G(SCH_1):PAGE388

C572 Q_CAP_0402-4.7UF,6.3V,20%,X6S,CH5471MEB01
     1 P0V9_CPU0_RT0_2A @T6G_MB_LIB.T6G(SCH_1):P0V9_CPU0_RT0_2A    I55 @T6G_MB_LIB.T6G(SCH_1):PAGE388
     2    GND @T6G_MB_LIB.T6G(SCH_1):GND    I55 @T6G_MB_LIB.T6G(SCH_1):PAGE388

C573 Q_CAP_0201-1UF,4V,20%,X6S,CH-10KMEE00
     1 P0V9_CPU0_RT0_2A @T6G_MB_LIB.T6G(SCH_1):P0V9_CPU0_RT0_2A    I53 @T6G_MB_LIB.T6G(SCH_1):PAGE388
     2    GND @T6G_MB_LIB.T6G(SCH_1):GND    I53 @T6G_MB_LIB.T6G(SCH_1):PAGE388

C574 Q_CAP_C0402-10UF,6.3V,20%,X6S,CH6101MEB01
     1 P0V9_CPU0_RT_2D @T6G_MB_LIB.T6G(SCH_1):P0V9_CPU0_RT_2D    I73 @T6G_MB_LIB.T6G(SCH_1):PAGE388
     2    GND @T6G_MB_LIB.T6G(SCH_1):GND    I73 @T6G_MB_LIB.T6G(SCH_1):PAGE388

C575 Q_CAP_C0402-22UF,4V,20%,X6S,CH622KMEB02
     1 P0V9_CPU0_RT0_2A @T6G_MB_LIB.T6G(SCH_1):P0V9_CPU0_RT0_2A    I77 @T6G_MB_LIB.T6G(SCH_1):PAGE388
     2    GND @T6G_MB_LIB.T6G(SCH_1):GND    I77 @T6G_MB_LIB.T6G(SCH_1):PAGE388

C576 Q_CAP_C0201-0.1UF,10V,10%,X7S,CH4102K6E00
     1 P0V9_CPU0_RT0_2A @T6G_MB_LIB.T6G(SCH_1):P0V9_CPU0_RT0_2A    I38 @T6G_MB_LIB.T6G(SCH_1):PAGE388
     2    GND @T6G_MB_LIB.T6G(SCH_1):GND    I38 @T6G_MB_LIB.T6G(SCH_1):PAGE388

C577 Q_CAP_0201-1UF,4V,20%,X6S,CH-10KMEE00
     1 P0V9_CPU0_RT0_2A @T6G_MB_LIB.T6G(SCH_1):P0V9_CPU0_RT0_2A    I56 @T6G_MB_LIB.T6G(SCH_1):PAGE388
     2    GND @T6G_MB_LIB.T6G(SCH_1):GND    I56 @T6G_MB_LIB.T6G(SCH_1):PAGE388

C578 Q_CAP_C0201-0.1UF,10V,10%,X7S,CH4102K6E00
     1 P0V9_CPU0_RT_2D @T6G_MB_LIB.T6G(SCH_1):P0V9_CPU0_RT_2D    I85 @T6G_MB_LIB.T6G(SCH_1):PAGE388
     2    GND @T6G_MB_LIB.T6G(SCH_1):GND    I85 @T6G_MB_LIB.T6G(SCH_1):PAGE388

C579 Q_CAP_C0402-10UF,6.3V,20%,X6S,CH6101MEB01
     1 P0V9_CPU0_RT0_2A @T6G_MB_LIB.T6G(SCH_1):P0V9_CPU0_RT0_2A    I44 @T6G_MB_LIB.T6G(SCH_1):PAGE388
     2    GND @T6G_MB_LIB.T6G(SCH_1):GND    I44 @T6G_MB_LIB.T6G(SCH_1):PAGE388

C580 Q_CAP_C0201-0.1UF,10V,10%,X7S,CH4102K6E00
     1 P0V9_CPU0_RT0_2A @T6G_MB_LIB.T6G(SCH_1):P0V9_CPU0_RT0_2A    I39 @T6G_MB_LIB.T6G(SCH_1):PAGE388
     2    GND @T6G_MB_LIB.T6G(SCH_1):GND    I39 @T6G_MB_LIB.T6G(SCH_1):PAGE388

C581 Q_CAP_0201-1UF,4V,20%,X6S,CH-10KMEE00
     1 P0V9_CPU0_RT0_2A @T6G_MB_LIB.T6G(SCH_1):P0V9_CPU0_RT0_2A    I57 @T6G_MB_LIB.T6G(SCH_1):PAGE388
     2    GND @T6G_MB_LIB.T6G(SCH_1):GND    I57 @T6G_MB_LIB.T6G(SCH_1):PAGE388

C582 Q_CAP_C0201-0.1UF,10V,10%,X7S,CH4102K6E00
     1 P0V9_CPU0_RT0_2A @T6G_MB_LIB.T6G(SCH_1):P0V9_CPU0_RT0_2A    I49 @T6G_MB_LIB.T6G(SCH_1):PAGE388
     2    GND @T6G_MB_LIB.T6G(SCH_1):GND    I49 @T6G_MB_LIB.T6G(SCH_1):PAGE388

C583 Q_CAP_C0201-0.1UF,10V,10%,X7S,CH4102K6E00
     1 P0V9_CPU0_RT0_2A @T6G_MB_LIB.T6G(SCH_1):P0V9_CPU0_RT0_2A    I93 @T6G_MB_LIB.T6G(SCH_1):PAGE388
     2    GND @T6G_MB_LIB.T6G(SCH_1):GND    I93 @T6G_MB_LIB.T6G(SCH_1):PAGE388

C584 Q_CAP_C0402-10UF,6.3V,20%,X6S,CH6101MEB01
     1 P0V9_CPU0_RT0_2A @T6G_MB_LIB.T6G(SCH_1):P0V9_CPU0_RT0_2A    I82 @T6G_MB_LIB.T6G(SCH_1):PAGE388
     2    GND @T6G_MB_LIB.T6G(SCH_1):GND    I82 @T6G_MB_LIB.T6G(SCH_1):PAGE388

C585 Q_CAP_C0201-0.1UF,10V,10%,X7S,CH4102K6E00
     1 P0V9_CPU0_RT0_2A @T6G_MB_LIB.T6G(SCH_1):P0V9_CPU0_RT0_2A    I51 @T6G_MB_LIB.T6G(SCH_1):PAGE388
     2    GND @T6G_MB_LIB.T6G(SCH_1):GND    I51 @T6G_MB_LIB.T6G(SCH_1):PAGE388

C586 Q_CAP_C0402-22UF,4V,20%,X6S,CH622KMEB02
     1 P0V9_CPU0_RT0_2A @T6G_MB_LIB.T6G(SCH_1):P0V9_CPU0_RT0_2A    I75 @T6G_MB_LIB.T6G(SCH_1):PAGE388
     2    GND @T6G_MB_LIB.T6G(SCH_1):GND    I75 @T6G_MB_LIB.T6G(SCH_1):PAGE388

C587 Q_CAP_C0805-100UF,4V,20%,X6S,CH710KMEA01
     1 P1V8_CPU0_RT_1D @T6G_MB_LIB.T6G(SCH_1):P1V8_CPU0_RT_1D    I17 @T6G_MB_LIB.T6G(SCH_1):PAGE411
     2    GND @T6G_MB_LIB.T6G(SCH_1):GND    I17 @T6G_MB_LIB.T6G(SCH_1):PAGE411

C588 Q_CAP_C0805-100UF,4V,20%,X6S,CH710KMEA01
     1 P1V8_CPU0_RT1_1A @T6G_MB_LIB.T6G(SCH_1):P1V8_CPU0_RT1_1A    I12 @T6G_MB_LIB.T6G(SCH_1):PAGE411
     2    GND @T6G_MB_LIB.T6G(SCH_1):GND    I12 @T6G_MB_LIB.T6G(SCH_1):PAGE411

C589 Q_CAP_C0402-22UF,4V,20%,X6S,CH622KMEB02
     1 P1V8_CPU0_RT_1D @T6G_MB_LIB.T6G(SCH_1):P1V8_CPU0_RT_1D    I18 @T6G_MB_LIB.T6G(SCH_1):PAGE411
     2    GND @T6G_MB_LIB.T6G(SCH_1):GND    I18 @T6G_MB_LIB.T6G(SCH_1):PAGE411

C590 Q_CAP_C0402-22UF,4V,20%,X6S,CH622KMEB02
     1 P1V8_CPU0_RT1_1A @T6G_MB_LIB.T6G(SCH_1):P1V8_CPU0_RT1_1A    I15 @T6G_MB_LIB.T6G(SCH_1):PAGE411
     2    GND @T6G_MB_LIB.T6G(SCH_1):GND    I15 @T6G_MB_LIB.T6G(SCH_1):PAGE411

C591 Q_CAP_C0402-10UF,6.3V,20%,X6S,CH6101MEB01
     1 P1V8_CPU0_RT_1D @T6G_MB_LIB.T6G(SCH_1):P1V8_CPU0_RT_1D    I22 @T6G_MB_LIB.T6G(SCH_1):PAGE411
     2    GND @T6G_MB_LIB.T6G(SCH_1):GND    I22 @T6G_MB_LIB.T6G(SCH_1):PAGE411

C592 Q_CAP_0402-0.1UF,25V,10%,X7R,CH4104K1B00
     1 P3V3_AUX @T6G_MB_LIB.T6G(SCH_1):P3V3_AUX    I33 @T6G_MB_LIB.T6G(SCH_1):PAGE338
     2    GND @T6G_MB_LIB.T6G(SCH_1):GND    I33 @T6G_MB_LIB.T6G(SCH_1):PAGE338

C593 Q_CAP_0402-0.1UF,25V,10%,X7R,CH4104K1B00
     1 P3V3_AUX @T6G_MB_LIB.T6G(SCH_1):P3V3_AUX    I30 @T6G_MB_LIB.T6G(SCH_1):PAGE338
     2    GND @T6G_MB_LIB.T6G(SCH_1):GND    I30 @T6G_MB_LIB.T6G(SCH_1):PAGE338

C594 Q_CAP_0402-4.7UF,6.3V,20%,X6S,CH5471MEB01
     1 P1V8_CPU0_RT1_1A @T6G_MB_LIB.T6G(SCH_1):P1V8_CPU0_RT1_1A    I19 @T6G_MB_LIB.T6G(SCH_1):PAGE411
     2    GND @T6G_MB_LIB.T6G(SCH_1):GND    I19 @T6G_MB_LIB.T6G(SCH_1):PAGE411

C595 Q_CAP_C0402-10UF,6.3V,20%,X6S,CH6101MEB01
     1 P1V8_CPU0_RT1_1A @T6G_MB_LIB.T6G(SCH_1):P1V8_CPU0_RT1_1A    I16 @T6G_MB_LIB.T6G(SCH_1):PAGE411
     2    GND @T6G_MB_LIB.T6G(SCH_1):GND    I16 @T6G_MB_LIB.T6G(SCH_1):PAGE411

C596 Q_CAP_0402-4.7UF,6.3V,20%,X6S,CH5471MEB01
     1 P1V8_CPU0_RT_1D @T6G_MB_LIB.T6G(SCH_1):P1V8_CPU0_RT_1D    I24 @T6G_MB_LIB.T6G(SCH_1):PAGE411
     2    GND @T6G_MB_LIB.T6G(SCH_1):GND    I24 @T6G_MB_LIB.T6G(SCH_1):PAGE411

C597 Q_CAP_0201-1UF,4V,20%,X6S,CH-10KMEE00
     1 P1V8_CPU0_RT1_1A @T6G_MB_LIB.T6G(SCH_1):P1V8_CPU0_RT1_1A    I20 @T6G_MB_LIB.T6G(SCH_1):PAGE411
     2    GND @T6G_MB_LIB.T6G(SCH_1):GND    I20 @T6G_MB_LIB.T6G(SCH_1):PAGE411

C598 Q_CAP_0201-1UF,4V,20%,X6S,CH-10KMEE00
     1 P1V8_CPU0_RT1_1A_1D @T6G_MB_LIB.T6G(SCH_1):P1V8_CPU0_RT1_1A_1D     I5 @T6G_MB_LIB.T6G(SCH_1):PAGE411
     2    GND @T6G_MB_LIB.T6G(SCH_1):GND     I5 @T6G_MB_LIB.T6G(SCH_1):PAGE411

C599 Q_CAP_0201-1UF,4V,20%,X6S,CH-10KMEE00
     1 P1V8_CPU0_RT1_1A @T6G_MB_LIB.T6G(SCH_1):P1V8_CPU0_RT1_1A    I21 @T6G_MB_LIB.T6G(SCH_1):PAGE411
     2    GND @T6G_MB_LIB.T6G(SCH_1):GND    I21 @T6G_MB_LIB.T6G(SCH_1):PAGE411

C600 Q_CAP_C0201-0.1UF,10V,10%,X7S,CH4102K6E00
     1 P1V8_CPU0_RT1_1A @T6G_MB_LIB.T6G(SCH_1):P1V8_CPU0_RT1_1A    I25 @T6G_MB_LIB.T6G(SCH_1):PAGE411
     2    GND @T6G_MB_LIB.T6G(SCH_1):GND    I25 @T6G_MB_LIB.T6G(SCH_1):PAGE411

C601 Q_CAP_C0201-0.1UF,10V,10%,X7S,CH4102K6E00
     1 P1V8_CPU0_RT1_1A_1D @T6G_MB_LIB.T6G(SCH_1):P1V8_CPU0_RT1_1A_1D     I7 @T6G_MB_LIB.T6G(SCH_1):PAGE411
     2    GND @T6G_MB_LIB.T6G(SCH_1):GND     I7 @T6G_MB_LIB.T6G(SCH_1):PAGE411

C602 Q_CAP_C0201-0.1UF,10V,10%,X7S,CH4102K6E00
     1 P1V8_CPU0_RT1_1A @T6G_MB_LIB.T6G(SCH_1):P1V8_CPU0_RT1_1A    I26 @T6G_MB_LIB.T6G(SCH_1):PAGE411
     2    GND @T6G_MB_LIB.T6G(SCH_1):GND    I26 @T6G_MB_LIB.T6G(SCH_1):PAGE411

C603 Q_CAP_C0201-0.1UF,10V,10%,X7S,CH4102K6E00
     1 P1V8_CPU0_RT1_1A @T6G_MB_LIB.T6G(SCH_1):P1V8_CPU0_RT1_1A    I27 @T6G_MB_LIB.T6G(SCH_1):PAGE411
     2    GND @T6G_MB_LIB.T6G(SCH_1):GND    I27 @T6G_MB_LIB.T6G(SCH_1):PAGE411

C604 Q_CAP_C0402-0.001UF,50V,10%,X7R,CH30106KB19
     1 HDT_HDR_TCK @T6G_MB_LIB.T6G(SCH_1):HDT_HDR_TCK   I140 @T6G_MB_LIB.T6G(SCH_1):PAGE149
     2    GND @T6G_MB_LIB.T6G(SCH_1):GND   I140 @T6G_MB_LIB.T6G(SCH_1):PAGE149

C605 Q_CAP_C0402-0.001UF,50V,10%,X7R,CH30106KB19
     1 HDT_HDR_TDI @T6G_MB_LIB.T6G(SCH_1):HDT_HDR_TDI   I137 @T6G_MB_LIB.T6G(SCH_1):PAGE149
     2    GND @T6G_MB_LIB.T6G(SCH_1):GND   I137 @T6G_MB_LIB.T6G(SCH_1):PAGE149

C606 Q_CAP_C0201-0.1UF,10V,10%,X7S,CH4102K6E00
     1 P1V8_CPU0_RT1_1A @T6G_MB_LIB.T6G(SCH_1):P1V8_CPU0_RT1_1A    I28 @T6G_MB_LIB.T6G(SCH_1):PAGE411
     2    GND @T6G_MB_LIB.T6G(SCH_1):GND    I28 @T6G_MB_LIB.T6G(SCH_1):PAGE411

C607 Q_CAP_0201-1UF,4V,20%,X6S,CH-10KMEE00
     1 P0V9_CPU0_RT1_2A @T6G_MB_LIB.T6G(SCH_1):P0V9_CPU0_RT1_2A    I44 @T6G_MB_LIB.T6G(SCH_1):PAGE411
     2    GND @T6G_MB_LIB.T6G(SCH_1):GND    I44 @T6G_MB_LIB.T6G(SCH_1):PAGE411

C608 Q_CAP_C0201-0.1UF,10V,10%,X7S,CH4102K6E00
     1 P0V9_CPU0_RT_2D @T6G_MB_LIB.T6G(SCH_1):P0V9_CPU0_RT_2D    I81 @T6G_MB_LIB.T6G(SCH_1):PAGE411
     2    GND @T6G_MB_LIB.T6G(SCH_1):GND    I81 @T6G_MB_LIB.T6G(SCH_1):PAGE411

C609 Q_CAP_0201-1UF,4V,20%,X6S,CH-10KMEE00
     1 P0V9_CPU0_RT1_2A @T6G_MB_LIB.T6G(SCH_1):P0V9_CPU0_RT1_2A    I38 @T6G_MB_LIB.T6G(SCH_1):PAGE411
     2    GND @T6G_MB_LIB.T6G(SCH_1):GND    I38 @T6G_MB_LIB.T6G(SCH_1):PAGE411

C610 Q_CAP_C0201-0.1UF,10V,10%,X7S,CH4102K6E00
     1 P0V9_CPU0_RT_2D @T6G_MB_LIB.T6G(SCH_1):P0V9_CPU0_RT_2D    I82 @T6G_MB_LIB.T6G(SCH_1):PAGE411
     2    GND @T6G_MB_LIB.T6G(SCH_1):GND    I82 @T6G_MB_LIB.T6G(SCH_1):PAGE411

C611 Q_CAP_0402-0.1UF,25V,10%,X7R,CH4104K1B00
     1 P3V3_AUX @T6G_MB_LIB.T6G(SCH_1):P3V3_AUX     I6 @T6G_MB_LIB.T6G(SCH_1):PAGE137
     2    GND @T6G_MB_LIB.T6G(SCH_1):GND     I6 @T6G_MB_LIB.T6G(SCH_1):PAGE137

C612 Q_CAP_0402-0.1UF,25V,10%,X7R,CH4104K1B00
     1 PVDD18_S5_P0 @T6G_MB_LIB.T6G(SCH_1):PVDD18_S5_P0     I8 @T6G_MB_LIB.T6G(SCH_1):PAGE137
     2    GND @T6G_MB_LIB.T6G(SCH_1):GND     I8 @T6G_MB_LIB.T6G(SCH_1):PAGE137

C613 Q_CAP_0201-1UF,4V,20%,X6S,CH-10KMEE00
     1 P0V9_CPU0_RT1_2A @T6G_MB_LIB.T6G(SCH_1):P0V9_CPU0_RT1_2A    I61 @T6G_MB_LIB.T6G(SCH_1):PAGE411
     2    GND @T6G_MB_LIB.T6G(SCH_1):GND    I61 @T6G_MB_LIB.T6G(SCH_1):PAGE411

C614 Q_CAP_C0201-0.1UF,10V,10%,X7S,CH4102K6E00
     1 P0V9_CPU0_RT1_2A @T6G_MB_LIB.T6G(SCH_1):P0V9_CPU0_RT1_2A    I85 @T6G_MB_LIB.T6G(SCH_1):PAGE411
     2    GND @T6G_MB_LIB.T6G(SCH_1):GND    I85 @T6G_MB_LIB.T6G(SCH_1):PAGE411

C615 Q_CAP_C0201-0.1UF,10V,10%,X7S,CH4102K6E00
     1 P0V9_CPU0_RT_2D @T6G_MB_LIB.T6G(SCH_1):P0V9_CPU0_RT_2D    I83 @T6G_MB_LIB.T6G(SCH_1):PAGE411
     2    GND @T6G_MB_LIB.T6G(SCH_1):GND    I83 @T6G_MB_LIB.T6G(SCH_1):PAGE411

C616 Q_CAP_C0201-0.1UF,10V,10%,X7S,CH4102K6E00
     1 P0V9_CPU0_RT1_2A @T6G_MB_LIB.T6G(SCH_1):P0V9_CPU0_RT1_2A    I42 @T6G_MB_LIB.T6G(SCH_1):PAGE411
     2    GND @T6G_MB_LIB.T6G(SCH_1):GND    I42 @T6G_MB_LIB.T6G(SCH_1):PAGE411

C617 Q_CAP_C0201-0.1UF,10V,10%,X7S,CH4102K6E00
     1 P0V9_CPU0_RT1_2A_2D @T6G_MB_LIB.T6G(SCH_1):P0V9_CPU0_RT1_2A_2D    I32 @T6G_MB_LIB.T6G(SCH_1):PAGE411
     2    GND @T6G_MB_LIB.T6G(SCH_1):GND    I32 @T6G_MB_LIB.T6G(SCH_1):PAGE411

C618 Q_CAP_0201-1UF,4V,20%,X6S,CH-10KMEE00
     1 P0V9_CPU0_RT1_2A @T6G_MB_LIB.T6G(SCH_1):P0V9_CPU0_RT1_2A    I39 @T6G_MB_LIB.T6G(SCH_1):PAGE411
     2    GND @T6G_MB_LIB.T6G(SCH_1):GND    I39 @T6G_MB_LIB.T6G(SCH_1):PAGE411

C619 Q_CAP_C0201-0.1UF,10V,10%,X7S,CH4102K6E00
     1 P0V9_CPU0_RT_2D @T6G_MB_LIB.T6G(SCH_1):P0V9_CPU0_RT_2D    I84 @T6G_MB_LIB.T6G(SCH_1):PAGE411
     2    GND @T6G_MB_LIB.T6G(SCH_1):GND    I84 @T6G_MB_LIB.T6G(SCH_1):PAGE411

C620 Q_CAP_0201-1UF,4V,20%,X6S,CH-10KMEE00
     1 P0V9_CPU0_RT1_2A @T6G_MB_LIB.T6G(SCH_1):P0V9_CPU0_RT1_2A    I59 @T6G_MB_LIB.T6G(SCH_1):PAGE411
     2    GND @T6G_MB_LIB.T6G(SCH_1):GND    I59 @T6G_MB_LIB.T6G(SCH_1):PAGE411

C621 Q_CAP_0201-1UF,4V,20%,X6S,CH-10KMEE00
     1 P0V9_CPU0_RT1_2A_2D @T6G_MB_LIB.T6G(SCH_1):P0V9_CPU0_RT1_2A_2D    I90 @T6G_MB_LIB.T6G(SCH_1):PAGE411
     2    GND @T6G_MB_LIB.T6G(SCH_1):GND    I90 @T6G_MB_LIB.T6G(SCH_1):PAGE411

C622 Q_CAP_0201-1UF,4V,20%,X6S,CH-10KMEE00
     1 P0V9_CPU0_RT1_2A @T6G_MB_LIB.T6G(SCH_1):P0V9_CPU0_RT1_2A    I86 @T6G_MB_LIB.T6G(SCH_1):PAGE411
     2    GND @T6G_MB_LIB.T6G(SCH_1):GND    I86 @T6G_MB_LIB.T6G(SCH_1):PAGE411

C623 Q_CAP_C0201-0.1UF,10V,10%,X7S,CH4102K6E00
     1 P0V9_CPU0_RT1_2A_2D @T6G_MB_LIB.T6G(SCH_1):P0V9_CPU0_RT1_2A_2D    I34 @T6G_MB_LIB.T6G(SCH_1):PAGE411
     2    GND @T6G_MB_LIB.T6G(SCH_1):GND    I34 @T6G_MB_LIB.T6G(SCH_1):PAGE411

C624 Q_CAP_0201-1UF,4V,20%,X6S,CH-10KMEE00
     1 P0V9_CPU0_RT1_2A_2D @T6G_MB_LIB.T6G(SCH_1):P0V9_CPU0_RT1_2A_2D    I91 @T6G_MB_LIB.T6G(SCH_1):PAGE411
     2    GND @T6G_MB_LIB.T6G(SCH_1):GND    I91 @T6G_MB_LIB.T6G(SCH_1):PAGE411

C625 Q_CAP_C0805-100UF,4V,20%,X6S,CH710KMEA01
     1 P0V9_CPU0_RT1_2A @T6G_MB_LIB.T6G(SCH_1):P0V9_CPU0_RT1_2A    I64 @T6G_MB_LIB.T6G(SCH_1):PAGE411
     2    GND @T6G_MB_LIB.T6G(SCH_1):GND    I64 @T6G_MB_LIB.T6G(SCH_1):PAGE411

C626 Q_CAP_C0402-10UF,6.3V,20%,X6S,CH6101MEB01
     1 P0V9_CPU0_RT1_2A @T6G_MB_LIB.T6G(SCH_1):P0V9_CPU0_RT1_2A    I40 @T6G_MB_LIB.T6G(SCH_1):PAGE411
     2    GND @T6G_MB_LIB.T6G(SCH_1):GND    I40 @T6G_MB_LIB.T6G(SCH_1):PAGE411

C627 Q_CAP_C0201-0.1UF,10V,10%,X7S,CH4102K6E00
     1 P0V9_CPU0_RT1_2A @T6G_MB_LIB.T6G(SCH_1):P0V9_CPU0_RT1_2A    I47 @T6G_MB_LIB.T6G(SCH_1):PAGE411
     2    GND @T6G_MB_LIB.T6G(SCH_1):GND    I47 @T6G_MB_LIB.T6G(SCH_1):PAGE411

C628 Q_CAP_C0805-100UF,4V,20%,X6S,CH710KMEA01
     1 P0V9_CPU0_RT1_2A @T6G_MB_LIB.T6G(SCH_1):P0V9_CPU0_RT1_2A    I65 @T6G_MB_LIB.T6G(SCH_1):PAGE411
     2    GND @T6G_MB_LIB.T6G(SCH_1):GND    I65 @T6G_MB_LIB.T6G(SCH_1):PAGE411

C629 Q_CAP_0402-0.1UF,25V,10%,X7R,CH4104K1B00
     1 P3V3_AUX @T6G_MB_LIB.T6G(SCH_1):P3V3_AUX    I55 @T6G_MB_LIB.T6G(SCH_1):PAGE361
     2    GND @T6G_MB_LIB.T6G(SCH_1):GND    I55 @T6G_MB_LIB.T6G(SCH_1):PAGE361

C630 Q_CAP_C0402-22UF,4V,20%,X6S,CH622KMEB02
     1 P0V9_CPU0_RT1_2A @T6G_MB_LIB.T6G(SCH_1):P0V9_CPU0_RT1_2A    I73 @T6G_MB_LIB.T6G(SCH_1):PAGE411
     2    GND @T6G_MB_LIB.T6G(SCH_1):GND    I73 @T6G_MB_LIB.T6G(SCH_1):PAGE411

C631 Q_CAP_C0201-0.1UF,10V,10%,X7S,CH4102K6E00
     1 P0V9_CPU0_RT1_2A @T6G_MB_LIB.T6G(SCH_1):P0V9_CPU0_RT1_2A    I55 @T6G_MB_LIB.T6G(SCH_1):PAGE411
     2    GND @T6G_MB_LIB.T6G(SCH_1):GND    I55 @T6G_MB_LIB.T6G(SCH_1):PAGE411

C632 Q_CAP_C0805-100UF,4V,20%,X6S,CH710KMEA01
     1 P0V9_CPU0_RT_2D @T6G_MB_LIB.T6G(SCH_1):P0V9_CPU0_RT_2D    I67 @T6G_MB_LIB.T6G(SCH_1):PAGE411
     2    GND @T6G_MB_LIB.T6G(SCH_1):GND    I67 @T6G_MB_LIB.T6G(SCH_1):PAGE411

C633 Q_CAP_C0805-100UF,4V,20%,X6S,CH710KMEA01
     1 P0V9_CPU0_RT1_2A @T6G_MB_LIB.T6G(SCH_1):P0V9_CPU0_RT1_2A    I69 @T6G_MB_LIB.T6G(SCH_1):PAGE411
     2    GND @T6G_MB_LIB.T6G(SCH_1):GND    I69 @T6G_MB_LIB.T6G(SCH_1):PAGE411

C634 Q_CAP_C0402-22UF,4V,20%,X6S,CH622KMEB02
     1 P0V9_CPU0_RT1_2A @T6G_MB_LIB.T6G(SCH_1):P0V9_CPU0_RT1_2A    I71 @T6G_MB_LIB.T6G(SCH_1):PAGE411
     2    GND @T6G_MB_LIB.T6G(SCH_1):GND    I71 @T6G_MB_LIB.T6G(SCH_1):PAGE411

C635 Q_CAP_C0201-0.1UF,10V,10%,X7S,CH4102K6E00
     1 P0V9_CPU0_RT1_2A @T6G_MB_LIB.T6G(SCH_1):P0V9_CPU0_RT1_2A    I46 @T6G_MB_LIB.T6G(SCH_1):PAGE411
     2    GND @T6G_MB_LIB.T6G(SCH_1):GND    I46 @T6G_MB_LIB.T6G(SCH_1):PAGE411

C636 Q_CAP_C0402-22UF,4V,20%,X6S,CH622KMEB02
     1 P0V9_CPU0_RT_2D @T6G_MB_LIB.T6G(SCH_1):P0V9_CPU0_RT_2D    I68 @T6G_MB_LIB.T6G(SCH_1):PAGE411
     2    GND @T6G_MB_LIB.T6G(SCH_1):GND    I68 @T6G_MB_LIB.T6G(SCH_1):PAGE411

C637 Q_CAP_C0805-100UF,4V,20%,X6S,CH710KMEA01
     1 P0V9_CPU0_RT1_2A @T6G_MB_LIB.T6G(SCH_1):P0V9_CPU0_RT1_2A    I70 @T6G_MB_LIB.T6G(SCH_1):PAGE411
     2    GND @T6G_MB_LIB.T6G(SCH_1):GND    I70 @T6G_MB_LIB.T6G(SCH_1):PAGE411

C638 Q_CAP_0402-4.7UF,6.3V,20%,X6S,CH5471MEB01
     1 P0V9_CPU0_RT1_2A @T6G_MB_LIB.T6G(SCH_1):P0V9_CPU0_RT1_2A    I51 @T6G_MB_LIB.T6G(SCH_1):PAGE411
     2    GND @T6G_MB_LIB.T6G(SCH_1):GND    I51 @T6G_MB_LIB.T6G(SCH_1):PAGE411

C639 Q_CAP_0402-0.1UF,25V,10%,X7R,CH4104K1B00
     1 P3V3_AUX @T6G_MB_LIB.T6G(SCH_1):P3V3_AUX    I59 @T6G_MB_LIB.T6G(SCH_1):PAGE336
     2    GND @T6G_MB_LIB.T6G(SCH_1):GND    I59 @T6G_MB_LIB.T6G(SCH_1):PAGE336

C640 Q_CAP_0402-0.1UF,25V,10%,X7R,CH4104K1B00
     1 P3V3_AUX @T6G_MB_LIB.T6G(SCH_1):P3V3_AUX    I47 @T6G_MB_LIB.T6G(SCH_1):PAGE336
     2    GND @T6G_MB_LIB.T6G(SCH_1):GND    I47 @T6G_MB_LIB.T6G(SCH_1):PAGE336

C641 Q_CAP_0402-0.1UF,25V,10%,X7R,CH4104K1B00
     1 P3V3_AUX @T6G_MB_LIB.T6G(SCH_1):P3V3_AUX    I16 @T6G_MB_LIB.T6G(SCH_1):PAGE336
     2    GND @T6G_MB_LIB.T6G(SCH_1):GND    I16 @T6G_MB_LIB.T6G(SCH_1):PAGE336

C642 Q_CAP_0402-1000PF,50V,5%,X7R,TMP_QCH21006JB10
     1 PVDD11_S3_P1_EN_R @T6G_MB_LIB.T6G(SCH_1):PVDD11_S3_P1_EN_R    I44 @T6G_MB_LIB.T6G(SCH_1):PAGE199
     2    GND @T6G_MB_LIB.T6G(SCH_1):GND    I44 @T6G_MB_LIB.T6G(SCH_1):PAGE199

C643 Q_CAP_0201-1UF,4V,20%,X6S,CH-10KMEE00
     1 P0V9_CPU0_RT1_2A @T6G_MB_LIB.T6G(SCH_1):P0V9_CPU0_RT1_2A    I45 @T6G_MB_LIB.T6G(SCH_1):PAGE411
     2    GND @T6G_MB_LIB.T6G(SCH_1):GND    I45 @T6G_MB_LIB.T6G(SCH_1):PAGE411

C644 Q_CAP_0402-4.7UF,6.3V,20%,X6S,CH5471MEB01
     1 P0V9_CPU0_RT1_2A @T6G_MB_LIB.T6G(SCH_1):P0V9_CPU0_RT1_2A    I50 @T6G_MB_LIB.T6G(SCH_1):PAGE411
     2    GND @T6G_MB_LIB.T6G(SCH_1):GND    I50 @T6G_MB_LIB.T6G(SCH_1):PAGE411

C645 Q_CAP_C0402-10UF,6.3V,20%,X6S,CH6101MEB01
     1 P0V9_CPU0_RT1_2A @T6G_MB_LIB.T6G(SCH_1):P0V9_CPU0_RT1_2A    I41 @T6G_MB_LIB.T6G(SCH_1):PAGE411
     2    GND @T6G_MB_LIB.T6G(SCH_1):GND    I41 @T6G_MB_LIB.T6G(SCH_1):PAGE411

C646 Q_CAP_C0402-10UF,6.3V,20%,X6S,CH6101MEB01
     1 P0V9_CPU0_RT_2D @T6G_MB_LIB.T6G(SCH_1):P0V9_CPU0_RT_2D    I74 @T6G_MB_LIB.T6G(SCH_1):PAGE411
     2    GND @T6G_MB_LIB.T6G(SCH_1):GND    I74 @T6G_MB_LIB.T6G(SCH_1):PAGE411

C647 Q_CAP_0201-1UF,4V,20%,X6S,CH-10KMEE00
     1 P0V9_CPU0_RT1_2A @T6G_MB_LIB.T6G(SCH_1):P0V9_CPU0_RT1_2A    I48 @T6G_MB_LIB.T6G(SCH_1):PAGE411
     2    GND @T6G_MB_LIB.T6G(SCH_1):GND    I48 @T6G_MB_LIB.T6G(SCH_1):PAGE411

C648 Q_CAP_C0402-10UF,6.3V,20%,X6S,CH6101MEB01
     1 P0V9_CPU0_RT1_2A @T6G_MB_LIB.T6G(SCH_1):P0V9_CPU0_RT1_2A    I79 @T6G_MB_LIB.T6G(SCH_1):PAGE411
     2    GND @T6G_MB_LIB.T6G(SCH_1):GND    I79 @T6G_MB_LIB.T6G(SCH_1):PAGE411

C649 Q_CAP_0402-4.7UF,6.3V,20%,X6S,CH5471MEB01
     1 P0V9_CPU0_RT1_2A @T6G_MB_LIB.T6G(SCH_1):P0V9_CPU0_RT1_2A    I52 @T6G_MB_LIB.T6G(SCH_1):PAGE411
     2    GND @T6G_MB_LIB.T6G(SCH_1):GND    I52 @T6G_MB_LIB.T6G(SCH_1):PAGE411

C650 Q_CAP_C0201-0.1UF,10V,10%,X7S,CH4102K6E00
     1 P0V9_CPU0_RT1_2A @T6G_MB_LIB.T6G(SCH_1):P0V9_CPU0_RT1_2A    I58 @T6G_MB_LIB.T6G(SCH_1):PAGE411
     2    GND @T6G_MB_LIB.T6G(SCH_1):GND    I58 @T6G_MB_LIB.T6G(SCH_1):PAGE411

C651 Q_CAP_0402-4.7UF,6.3V,20%,X6S,CH5471MEB01
     1 P0V9_CPU0_RT_2D @T6G_MB_LIB.T6G(SCH_1):P0V9_CPU0_RT_2D    I75 @T6G_MB_LIB.T6G(SCH_1):PAGE411
     2    GND @T6G_MB_LIB.T6G(SCH_1):GND    I75 @T6G_MB_LIB.T6G(SCH_1):PAGE411

C652 Q_CAP_0402-4.7UF,6.3V,20%,X6S,CH5471MEB01
     1 P0V9_CPU0_RT1_2A @T6G_MB_LIB.T6G(SCH_1):P0V9_CPU0_RT1_2A    I87 @T6G_MB_LIB.T6G(SCH_1):PAGE411
     2    GND @T6G_MB_LIB.T6G(SCH_1):GND    I87 @T6G_MB_LIB.T6G(SCH_1):PAGE411

C653 Q_CAP_0201-1UF,4V,20%,X6S,CH-10KMEE00
     1 P0V9_CPU0_RT1_2A @T6G_MB_LIB.T6G(SCH_1):P0V9_CPU0_RT1_2A    I53 @T6G_MB_LIB.T6G(SCH_1):PAGE411
     2    GND @T6G_MB_LIB.T6G(SCH_1):GND    I53 @T6G_MB_LIB.T6G(SCH_1):PAGE411

C654 Q_CAP_0201-1UF,4V,20%,X6S,CH-10KMEE00
     1 P0V9_CPU0_RT1_2A @T6G_MB_LIB.T6G(SCH_1):P0V9_CPU0_RT1_2A    I49 @T6G_MB_LIB.T6G(SCH_1):PAGE411
     2    GND @T6G_MB_LIB.T6G(SCH_1):GND    I49 @T6G_MB_LIB.T6G(SCH_1):PAGE411

C655 Q_CAP_0201-1UF,4V,20%,X6S,CH-10KMEE00
     1 P0V9_CPU0_RT_2D @T6G_MB_LIB.T6G(SCH_1):P0V9_CPU0_RT_2D    I76 @T6G_MB_LIB.T6G(SCH_1):PAGE411
     2    GND @T6G_MB_LIB.T6G(SCH_1):GND    I76 @T6G_MB_LIB.T6G(SCH_1):PAGE411

C656 Q_CAP_C0402-22UF,4V,20%,X6S,CH622KMEB02
     1 P0V9_CPU0_RT1_2A @T6G_MB_LIB.T6G(SCH_1):P0V9_CPU0_RT1_2A    I77 @T6G_MB_LIB.T6G(SCH_1):PAGE411
     2    GND @T6G_MB_LIB.T6G(SCH_1):GND    I77 @T6G_MB_LIB.T6G(SCH_1):PAGE411

C657 Q_CAP_C0201-0.1UF,10V,10%,X7S,CH4102K6E00
     1 P0V9_CPU0_RT1_2A @T6G_MB_LIB.T6G(SCH_1):P0V9_CPU0_RT1_2A    I43 @T6G_MB_LIB.T6G(SCH_1):PAGE411
     2    GND @T6G_MB_LIB.T6G(SCH_1):GND    I43 @T6G_MB_LIB.T6G(SCH_1):PAGE411

C658 Q_CAP_C0201-0.1UF,10V,10%,X7S,CH4102K6E00
     1 P0V9_CPU0_RT1_2A @T6G_MB_LIB.T6G(SCH_1):P0V9_CPU0_RT1_2A    I92 @T6G_MB_LIB.T6G(SCH_1):PAGE411
     2    GND @T6G_MB_LIB.T6G(SCH_1):GND    I92 @T6G_MB_LIB.T6G(SCH_1):PAGE411

C659 Q_CAP_C0201-0.1UF,10V,10%,X7S,CH4102K6E00
     1 P0V9_CPU0_RT1_2A @T6G_MB_LIB.T6G(SCH_1):P0V9_CPU0_RT1_2A    I93 @T6G_MB_LIB.T6G(SCH_1):PAGE411
     2    GND @T6G_MB_LIB.T6G(SCH_1):GND    I93 @T6G_MB_LIB.T6G(SCH_1):PAGE411

C660 Q_CAP_0201-1UF,4V,20%,X6S,CH-10KMEE00
     1 P0V9_CPU0_RT1_2A @T6G_MB_LIB.T6G(SCH_1):P0V9_CPU0_RT1_2A    I94 @T6G_MB_LIB.T6G(SCH_1):PAGE411
     2    GND @T6G_MB_LIB.T6G(SCH_1):GND    I94 @T6G_MB_LIB.T6G(SCH_1):PAGE411

C661 Q_CAP_C0402-10UF,6.3V,20%,X6S,CH6101MEB01
     1 P0V9_CPU0_RT1_2A @T6G_MB_LIB.T6G(SCH_1):P0V9_CPU0_RT1_2A    I78 @T6G_MB_LIB.T6G(SCH_1):PAGE411
     2    GND @T6G_MB_LIB.T6G(SCH_1):GND    I78 @T6G_MB_LIB.T6G(SCH_1):PAGE411

C662 Q_CAP_C0201-0.1UF,10V,10%,X7S,CH4102K6E00
     1 P0V9_CPU0_RT1_2A @T6G_MB_LIB.T6G(SCH_1):P0V9_CPU0_RT1_2A    I37 @T6G_MB_LIB.T6G(SCH_1):PAGE411
     2    GND @T6G_MB_LIB.T6G(SCH_1):GND    I37 @T6G_MB_LIB.T6G(SCH_1):PAGE411

C663 Q_CAP_C0402-22UF,4V,20%,X6S,CH622KMEB02
     1 P0V9_CPU0_RT1_2A @T6G_MB_LIB.T6G(SCH_1):P0V9_CPU0_RT1_2A    I72 @T6G_MB_LIB.T6G(SCH_1):PAGE411
     2    GND @T6G_MB_LIB.T6G(SCH_1):GND    I72 @T6G_MB_LIB.T6G(SCH_1):PAGE411

C664 Q_CAP_C0201-0.1UF,10V,10%,X7S,CH4102K6E00
     1 P1V8_CPU0_RT_1D @T6G_MB_LIB.T6G(SCH_1):P1V8_CPU0_RT_1D    I24 @T6G_MB_LIB.T6G(SCH_1):PAGE410
     2    GND @T6G_MB_LIB.T6G(SCH_1):GND    I24 @T6G_MB_LIB.T6G(SCH_1):PAGE410

C665 Q_CAP_C0805-100UF,4V,20%,X6S,CH710KMEA01
     1 P1V8_CPU0_RT_1D @T6G_MB_LIB.T6G(SCH_1):P1V8_CPU0_RT_1D    I25 @T6G_MB_LIB.T6G(SCH_1):PAGE422
     2    GND @T6G_MB_LIB.T6G(SCH_1):GND    I25 @T6G_MB_LIB.T6G(SCH_1):PAGE422

C666 Q_CAP_C0805-100UF,4V,20%,X6S,CH710KMEA01
     1 P1V8_CPU0_RT2_1A @T6G_MB_LIB.T6G(SCH_1):P1V8_CPU0_RT2_1A     I6 @T6G_MB_LIB.T6G(SCH_1):PAGE422
     2    GND @T6G_MB_LIB.T6G(SCH_1):GND     I6 @T6G_MB_LIB.T6G(SCH_1):PAGE422

C667 Q_CAP_C0402-22UF,4V,20%,X6S,CH622KMEB02
     1 P1V8_CPU0_RT_1D @T6G_MB_LIB.T6G(SCH_1):P1V8_CPU0_RT_1D    I27 @T6G_MB_LIB.T6G(SCH_1):PAGE422
     2    GND @T6G_MB_LIB.T6G(SCH_1):GND    I27 @T6G_MB_LIB.T6G(SCH_1):PAGE422

C668 Q_CAP_C0402-22UF,4V,20%,X6S,CH622KMEB02
     1 P1V8_CPU0_RT2_1A @T6G_MB_LIB.T6G(SCH_1):P1V8_CPU0_RT2_1A     I7 @T6G_MB_LIB.T6G(SCH_1):PAGE422
     2    GND @T6G_MB_LIB.T6G(SCH_1):GND     I7 @T6G_MB_LIB.T6G(SCH_1):PAGE422

C669 Q_CAP_C0402-10UF,6.3V,20%,X6S,CH6101MEB01
     1 P1V8_CPU0_RT_1D @T6G_MB_LIB.T6G(SCH_1):P1V8_CPU0_RT_1D    I26 @T6G_MB_LIB.T6G(SCH_1):PAGE422
     2    GND @T6G_MB_LIB.T6G(SCH_1):GND    I26 @T6G_MB_LIB.T6G(SCH_1):PAGE422

C670 Q_CAP_0402-4.7UF,6.3V,20%,X6S,CH5471MEB01
     1 P1V8_CPU0_RT2_1A @T6G_MB_LIB.T6G(SCH_1):P1V8_CPU0_RT2_1A    I13 @T6G_MB_LIB.T6G(SCH_1):PAGE422
     2    GND @T6G_MB_LIB.T6G(SCH_1):GND    I13 @T6G_MB_LIB.T6G(SCH_1):PAGE422

C671 Q_CAP_C0402-10UF,6.3V,20%,X6S,CH6101MEB01
     1 P1V8_CPU0_RT2_1A @T6G_MB_LIB.T6G(SCH_1):P1V8_CPU0_RT2_1A    I12 @T6G_MB_LIB.T6G(SCH_1):PAGE422
     2    GND @T6G_MB_LIB.T6G(SCH_1):GND    I12 @T6G_MB_LIB.T6G(SCH_1):PAGE422

C672 Q_CAP_0402-4.7UF,6.3V,20%,X6S,CH5471MEB01
     1 P1V8_CPU0_RT_1D @T6G_MB_LIB.T6G(SCH_1):P1V8_CPU0_RT_1D    I29 @T6G_MB_LIB.T6G(SCH_1):PAGE422
     2    GND @T6G_MB_LIB.T6G(SCH_1):GND    I29 @T6G_MB_LIB.T6G(SCH_1):PAGE422

C673 Q_CAP_0201-1UF,4V,20%,X6S,CH-10KMEE00
     1 P1V8_CPU0_RT2_1A @T6G_MB_LIB.T6G(SCH_1):P1V8_CPU0_RT2_1A    I15 @T6G_MB_LIB.T6G(SCH_1):PAGE422
     2    GND @T6G_MB_LIB.T6G(SCH_1):GND    I15 @T6G_MB_LIB.T6G(SCH_1):PAGE422

C674 Q_CAP_0402-0.1UF,25V,10%,EMPTY,CH4104K1B00
     1 PVDD18_S5_P0_EN @T6G_MB_LIB.T6G(SCH_1):PVDD18_S5_P0_EN     I4 @T6G_MB_LIB.T6G(SCH_1):PAGE184
     2    GND @T6G_MB_LIB.T6G(SCH_1):GND     I4 @T6G_MB_LIB.T6G(SCH_1):PAGE184

C675 Q_CAP_0402-0.1UF,25V,10%,EMPTY,CH4104K1B00
     1 PVDD18_S5_P1_EN @T6G_MB_LIB.T6G(SCH_1):PVDD18_S5_P1_EN     I6 @T6G_MB_LIB.T6G(SCH_1):PAGE201
     2    GND @T6G_MB_LIB.T6G(SCH_1):GND     I6 @T6G_MB_LIB.T6G(SCH_1):PAGE201

C676 Q_CAP_0201-1UF,4V,20%,X6S,CH-10KMEE00
     1 P1V8_CPU0_RT2_1A_1D @T6G_MB_LIB.T6G(SCH_1):P1V8_CPU0_RT2_1A_1D     I9 @T6G_MB_LIB.T6G(SCH_1):PAGE422
     2    GND @T6G_MB_LIB.T6G(SCH_1):GND     I9 @T6G_MB_LIB.T6G(SCH_1):PAGE422

C677 Q_CAP_0201-1UF,4V,20%,X6S,CH-10KMEE00
     1 P1V8_CPU0_RT2_1A @T6G_MB_LIB.T6G(SCH_1):P1V8_CPU0_RT2_1A    I16 @T6G_MB_LIB.T6G(SCH_1):PAGE422
     2    GND @T6G_MB_LIB.T6G(SCH_1):GND    I16 @T6G_MB_LIB.T6G(SCH_1):PAGE422

C678 Q_CAP_DIFFBUS_C0201-DIFF BUS_0.22UF,6.3V,20%,X6S,SA
     1 P5E_CPU1_G1_TX_C_DN<15> @T6G_MB_LIB.T6G(SCH_1):P5E_CPU1_G1_TX_C_DN(15)   I251 @T6G_MB_LIB.T6G(SCH_1):PAGE355
     2 P5E_CPU1_G1_TX_DN<15> @T6G_MB_LIB.T6G(SCH_1):P5E_CPU1_G1_TX_DN(15)   I251 @T6G_MB_LIB.T6G(SCH_1):PAGE355

C679 Q_CAP_DIFFBUS_C0201-DIFF BUS_0.22UF,6.3V,20%,X6S,SA
     1 P5E_CPU1_G1_TX_C_DP<15> @T6G_MB_LIB.T6G(SCH_1):P5E_CPU1_G1_TX_C_DP(15)   I250 @T6G_MB_LIB.T6G(SCH_1):PAGE355
     2 P5E_CPU1_G1_TX_DP<15> @T6G_MB_LIB.T6G(SCH_1):P5E_CPU1_G1_TX_DP(15)   I250 @T6G_MB_LIB.T6G(SCH_1):PAGE355

C680 Q_CAP_DIFFBUS_C0201-DIFF BUS_0.22UF,6.3V,20%,X6S,SA
     1 P5E_CPU1_G1_TX_C_DN<14> @T6G_MB_LIB.T6G(SCH_1):P5E_CPU1_G1_TX_C_DN(14)   I249 @T6G_MB_LIB.T6G(SCH_1):PAGE355
     2 P5E_CPU1_G1_TX_DN<14> @T6G_MB_LIB.T6G(SCH_1):P5E_CPU1_G1_TX_DN(14)   I249 @T6G_MB_LIB.T6G(SCH_1):PAGE355

C681 Q_CAP_DIFFBUS_C0201-DIFF BUS_0.22UF,6.3V,20%,X6S,SA
     1 P5E_CPU1_G1_TX_C_DP<14> @T6G_MB_LIB.T6G(SCH_1):P5E_CPU1_G1_TX_C_DP(14)   I248 @T6G_MB_LIB.T6G(SCH_1):PAGE355
     2 P5E_CPU1_G1_TX_DP<14> @T6G_MB_LIB.T6G(SCH_1):P5E_CPU1_G1_TX_DP(14)   I248 @T6G_MB_LIB.T6G(SCH_1):PAGE355

C682 Q_CAP_DIFFBUS_C0201-DIFF BUS_0.22UF,6.3V,20%,X6S,SA
     1 P5E_CPU1_G1_TX_C_DN<13> @T6G_MB_LIB.T6G(SCH_1):P5E_CPU1_G1_TX_C_DN(13)   I247 @T6G_MB_LIB.T6G(SCH_1):PAGE355
     2 P5E_CPU1_G1_TX_DN<13> @T6G_MB_LIB.T6G(SCH_1):P5E_CPU1_G1_TX_DN(13)   I247 @T6G_MB_LIB.T6G(SCH_1):PAGE355

C683 Q_CAP_DIFFBUS_C0201-DIFF BUS_0.22UF,6.3V,20%,X6S,SA
     1 P5E_CPU1_G1_TX_C_DP<13> @T6G_MB_LIB.T6G(SCH_1):P5E_CPU1_G1_TX_C_DP(13)   I236 @T6G_MB_LIB.T6G(SCH_1):PAGE355
     2 P5E_CPU1_G1_TX_DP<13> @T6G_MB_LIB.T6G(SCH_1):P5E_CPU1_G1_TX_DP(13)   I236 @T6G_MB_LIB.T6G(SCH_1):PAGE355

C684 Q_CAP_DIFFBUS_C0201-DIFF BUS_0.22UF,6.3V,20%,X6S,SA
     1 P5E_CPU1_G1_TX_C_DN<12> @T6G_MB_LIB.T6G(SCH_1):P5E_CPU1_G1_TX_C_DN(12)   I225 @T6G_MB_LIB.T6G(SCH_1):PAGE355
     2 P5E_CPU1_G1_TX_DN<12> @T6G_MB_LIB.T6G(SCH_1):P5E_CPU1_G1_TX_DN(12)   I225 @T6G_MB_LIB.T6G(SCH_1):PAGE355

C685 Q_CAP_DIFFBUS_C0201-DIFF BUS_0.22UF,6.3V,20%,X6S,SA
     1 P5E_CPU1_G1_TX_C_DP<12> @T6G_MB_LIB.T6G(SCH_1):P5E_CPU1_G1_TX_C_DP(12)   I224 @T6G_MB_LIB.T6G(SCH_1):PAGE355
     2 P5E_CPU1_G1_TX_DP<12> @T6G_MB_LIB.T6G(SCH_1):P5E_CPU1_G1_TX_DP(12)   I224 @T6G_MB_LIB.T6G(SCH_1):PAGE355

C686 Q_CAP_DIFFBUS_C0201-DIFF BUS_0.22UF,6.3V,20%,X6S,SA
     1 P5E_CPU1_G1_TX_C_DN<11> @T6G_MB_LIB.T6G(SCH_1):P5E_CPU1_G1_TX_C_DN(11)   I223 @T6G_MB_LIB.T6G(SCH_1):PAGE355
     2 P5E_CPU1_G1_TX_DN<11> @T6G_MB_LIB.T6G(SCH_1):P5E_CPU1_G1_TX_DN(11)   I223 @T6G_MB_LIB.T6G(SCH_1):PAGE355

C687 Q_CAP_DIFFBUS_C0201-DIFF BUS_0.22UF,6.3V,20%,X6S,SA
     1 P5E_CPU1_G1_TX_C_DP<11> @T6G_MB_LIB.T6G(SCH_1):P5E_CPU1_G1_TX_C_DP(11)   I222 @T6G_MB_LIB.T6G(SCH_1):PAGE355
     2 P5E_CPU1_G1_TX_DP<11> @T6G_MB_LIB.T6G(SCH_1):P5E_CPU1_G1_TX_DP(11)   I222 @T6G_MB_LIB.T6G(SCH_1):PAGE355

C688 Q_CAP_DIFFBUS_C0201-DIFF BUS_0.22UF,6.3V,20%,X6S,SA
     1 P5E_CPU1_G1_TX_C_DN<10> @T6G_MB_LIB.T6G(SCH_1):P5E_CPU1_G1_TX_C_DN(10)   I220 @T6G_MB_LIB.T6G(SCH_1):PAGE355
     2 P5E_CPU1_G1_TX_DN<10> @T6G_MB_LIB.T6G(SCH_1):P5E_CPU1_G1_TX_DN(10)   I220 @T6G_MB_LIB.T6G(SCH_1):PAGE355

C689 Q_CAP_DIFFBUS_C0201-DIFF BUS_0.22UF,6.3V,20%,X6S,SA
     1 P5E_CPU1_G1_TX_C_DP<10> @T6G_MB_LIB.T6G(SCH_1):P5E_CPU1_G1_TX_C_DP(10)   I221 @T6G_MB_LIB.T6G(SCH_1):PAGE355
     2 P5E_CPU1_G1_TX_DP<10> @T6G_MB_LIB.T6G(SCH_1):P5E_CPU1_G1_TX_DP(10)   I221 @T6G_MB_LIB.T6G(SCH_1):PAGE355

C690 Q_CAP_DIFFBUS_C0201-DIFF BUS_0.22UF,6.3V,20%,X6S,SA
     1 P5E_CPU1_G1_TX_C_DN<9> @T6G_MB_LIB.T6G(SCH_1):P5E_CPU1_G1_TX_C_DN(9)   I219 @T6G_MB_LIB.T6G(SCH_1):PAGE355
     2 P5E_CPU1_G1_TX_DN<9> @T6G_MB_LIB.T6G(SCH_1):P5E_CPU1_G1_TX_DN(9)   I219 @T6G_MB_LIB.T6G(SCH_1):PAGE355

C691 Q_CAP_DIFFBUS_C0201-DIFF BUS_0.22UF,6.3V,20%,X6S,SA
     1 P5E_CPU1_G1_TX_C_DP<9> @T6G_MB_LIB.T6G(SCH_1):P5E_CPU1_G1_TX_C_DP(9)   I218 @T6G_MB_LIB.T6G(SCH_1):PAGE355
     2 P5E_CPU1_G1_TX_DP<9> @T6G_MB_LIB.T6G(SCH_1):P5E_CPU1_G1_TX_DP(9)   I218 @T6G_MB_LIB.T6G(SCH_1):PAGE355

C692 Q_CAP_DIFFBUS_C0201-DIFF BUS_0.22UF,6.3V,20%,X6S,SA
     1 P5E_CPU1_G1_TX_C_DN<8> @T6G_MB_LIB.T6G(SCH_1):P5E_CPU1_G1_TX_C_DN(8)   I217 @T6G_MB_LIB.T6G(SCH_1):PAGE355
     2 P5E_CPU1_G1_TX_DN<8> @T6G_MB_LIB.T6G(SCH_1):P5E_CPU1_G1_TX_DN(8)   I217 @T6G_MB_LIB.T6G(SCH_1):PAGE355

C693 Q_CAP_0402-0.1UF,25V,10%,X7R,CH4104K1B00
     1 U124_VCC @T6G_MB_LIB.T6G(SCH_1):U124_VCC    I39 @T6G_MB_LIB.T6G(SCH_1):PAGE144
     2    GND @T6G_MB_LIB.T6G(SCH_1):GND    I39 @T6G_MB_LIB.T6G(SCH_1):PAGE144

C694 Q_CAP_DIFFBUS_C0201-DIFF BUS_0.22UF,6.3V,20%,X6S,SA
     1 P5E_CPU1_G1_TX_C_DN<7> @T6G_MB_LIB.T6G(SCH_1):P5E_CPU1_G1_TX_C_DN(7)   I206 @T6G_MB_LIB.T6G(SCH_1):PAGE355
     2 P5E_CPU1_G1_TX_DN<7> @T6G_MB_LIB.T6G(SCH_1):P5E_CPU1_G1_TX_DN(7)   I206 @T6G_MB_LIB.T6G(SCH_1):PAGE355

C695 Q_CAP_DIFFBUS_C0201-DIFF BUS_0.22UF,6.3V,20%,X6S,SA
     1 P5E_CPU1_G1_TX_C_DP<7> @T6G_MB_LIB.T6G(SCH_1):P5E_CPU1_G1_TX_C_DP(7)   I205 @T6G_MB_LIB.T6G(SCH_1):PAGE355
     2 P5E_CPU1_G1_TX_DP<7> @T6G_MB_LIB.T6G(SCH_1):P5E_CPU1_G1_TX_DP(7)   I205 @T6G_MB_LIB.T6G(SCH_1):PAGE355

C696 Q_CAP_DIFFBUS_C0201-DIFF BUS_0.22UF,6.3V,20%,X6S,SA
     1 P5E_CPU1_G1_TX_C_DN<6> @T6G_MB_LIB.T6G(SCH_1):P5E_CPU1_G1_TX_C_DN(6)   I204 @T6G_MB_LIB.T6G(SCH_1):PAGE355
     2 P5E_CPU1_G1_TX_DN<6> @T6G_MB_LIB.T6G(SCH_1):P5E_CPU1_G1_TX_DN(6)   I204 @T6G_MB_LIB.T6G(SCH_1):PAGE355

C697 Q_CAP_DIFFBUS_C0201-DIFF BUS_0.22UF,6.3V,20%,X6S,SA
     1 P5E_CPU1_G1_TX_C_DP<6> @T6G_MB_LIB.T6G(SCH_1):P5E_CPU1_G1_TX_C_DP(6)   I203 @T6G_MB_LIB.T6G(SCH_1):PAGE355
     2 P5E_CPU1_G1_TX_DP<6> @T6G_MB_LIB.T6G(SCH_1):P5E_CPU1_G1_TX_DP(6)   I203 @T6G_MB_LIB.T6G(SCH_1):PAGE355

C698 Q_CAP_DIFFBUS_C0201-DIFF BUS_0.22UF,6.3V,20%,X6S,SA
     1 P5E_CPU1_G1_TX_C_DN<5> @T6G_MB_LIB.T6G(SCH_1):P5E_CPU1_G1_TX_C_DN(5)   I201 @T6G_MB_LIB.T6G(SCH_1):PAGE355
     2 P5E_CPU1_G1_TX_DN<5> @T6G_MB_LIB.T6G(SCH_1):P5E_CPU1_G1_TX_DN(5)   I201 @T6G_MB_LIB.T6G(SCH_1):PAGE355

C699 Q_CAP_DIFFBUS_C0201-DIFF BUS_0.22UF,6.3V,20%,X6S,SA
     1 P5E_CPU1_G1_TX_C_DP<5> @T6G_MB_LIB.T6G(SCH_1):P5E_CPU1_G1_TX_C_DP(5)   I202 @T6G_MB_LIB.T6G(SCH_1):PAGE355
     2 P5E_CPU1_G1_TX_DP<5> @T6G_MB_LIB.T6G(SCH_1):P5E_CPU1_G1_TX_DP(5)   I202 @T6G_MB_LIB.T6G(SCH_1):PAGE355

C700 Q_CAP_DIFFBUS_C0201-DIFF BUS_0.22UF,6.3V,20%,X6S,SA
     1 P5E_CPU1_G1_TX_C_DN<4> @T6G_MB_LIB.T6G(SCH_1):P5E_CPU1_G1_TX_C_DN(4)   I200 @T6G_MB_LIB.T6G(SCH_1):PAGE355
     2 P5E_CPU1_G1_TX_DN<4> @T6G_MB_LIB.T6G(SCH_1):P5E_CPU1_G1_TX_DN(4)   I200 @T6G_MB_LIB.T6G(SCH_1):PAGE355

C701 Q_CAP_DIFFBUS_C0201-DIFF BUS_0.22UF,6.3V,20%,X6S,SA
     1 P5E_CPU1_G1_TX_C_DP<4> @T6G_MB_LIB.T6G(SCH_1):P5E_CPU1_G1_TX_C_DP(4)   I199 @T6G_MB_LIB.T6G(SCH_1):PAGE355
     2 P5E_CPU1_G1_TX_DP<4> @T6G_MB_LIB.T6G(SCH_1):P5E_CPU1_G1_TX_DP(4)   I199 @T6G_MB_LIB.T6G(SCH_1):PAGE355

C702 Q_CAP_DIFFBUS_C0201-DIFF BUS_0.22UF,6.3V,20%,X6S,SA
     1 P5E_CPU1_G1_TX_C_DN<3> @T6G_MB_LIB.T6G(SCH_1):P5E_CPU1_G1_TX_C_DN(3)   I197 @T6G_MB_LIB.T6G(SCH_1):PAGE355
     2 P5E_CPU1_G1_TX_DN<3> @T6G_MB_LIB.T6G(SCH_1):P5E_CPU1_G1_TX_DN(3)   I197 @T6G_MB_LIB.T6G(SCH_1):PAGE355

C703 Q_CAP_DIFFBUS_C0201-DIFF BUS_0.22UF,6.3V,20%,X6S,SA
     1 P5E_CPU1_G1_TX_C_DP<3> @T6G_MB_LIB.T6G(SCH_1):P5E_CPU1_G1_TX_C_DP(3)   I198 @T6G_MB_LIB.T6G(SCH_1):PAGE355
     2 P5E_CPU1_G1_TX_DP<3> @T6G_MB_LIB.T6G(SCH_1):P5E_CPU1_G1_TX_DP(3)   I198 @T6G_MB_LIB.T6G(SCH_1):PAGE355

C704 Q_CAP_DIFFBUS_C0201-DIFF BUS_0.22UF,6.3V,20%,X6S,SA
     1 P5E_CPU1_G1_TX_C_DN<2> @T6G_MB_LIB.T6G(SCH_1):P5E_CPU1_G1_TX_C_DN(2)   I170 @T6G_MB_LIB.T6G(SCH_1):PAGE355
     2 P5E_CPU1_G1_TX_DN<2> @T6G_MB_LIB.T6G(SCH_1):P5E_CPU1_G1_TX_DN(2)   I170 @T6G_MB_LIB.T6G(SCH_1):PAGE355

C705 Q_CAP_DIFFBUS_C0201-DIFF BUS_0.22UF,6.3V,20%,X6S,SA
     1 P5E_CPU1_G1_TX_C_DP<2> @T6G_MB_LIB.T6G(SCH_1):P5E_CPU1_G1_TX_C_DP(2)   I169 @T6G_MB_LIB.T6G(SCH_1):PAGE355
     2 P5E_CPU1_G1_TX_DP<2> @T6G_MB_LIB.T6G(SCH_1):P5E_CPU1_G1_TX_DP(2)   I169 @T6G_MB_LIB.T6G(SCH_1):PAGE355

C706 Q_CAP_DIFFBUS_C0201-DIFF BUS_0.22UF,6.3V,20%,X6S,SA
     1 P5E_CPU1_G1_TX_C_DN<1> @T6G_MB_LIB.T6G(SCH_1):P5E_CPU1_G1_TX_C_DN(1)   I167 @T6G_MB_LIB.T6G(SCH_1):PAGE355
     2 P5E_CPU1_G1_TX_DN<1> @T6G_MB_LIB.T6G(SCH_1):P5E_CPU1_G1_TX_DN(1)   I167 @T6G_MB_LIB.T6G(SCH_1):PAGE355

C707 Q_CAP_DIFFBUS_C0201-DIFF BUS_0.22UF,6.3V,20%,X6S,SA
     1 P5E_CPU1_G1_TX_C_DP<1> @T6G_MB_LIB.T6G(SCH_1):P5E_CPU1_G1_TX_C_DP(1)   I168 @T6G_MB_LIB.T6G(SCH_1):PAGE355
     2 P5E_CPU1_G1_TX_DP<1> @T6G_MB_LIB.T6G(SCH_1):P5E_CPU1_G1_TX_DP(1)   I168 @T6G_MB_LIB.T6G(SCH_1):PAGE355

C708 Q_CAP_DIFFBUS_C0201-DIFF BUS_0.22UF,6.3V,20%,X6S,SA
     1 P5E_CPU1_G1_TX_C_DN<0> @T6G_MB_LIB.T6G(SCH_1):P5E_CPU1_G1_TX_C_DN(0)   I166 @T6G_MB_LIB.T6G(SCH_1):PAGE355
     2 P5E_CPU1_G1_TX_DN<0> @T6G_MB_LIB.T6G(SCH_1):P5E_CPU1_G1_TX_DN(0)   I166 @T6G_MB_LIB.T6G(SCH_1):PAGE355

C709 Q_CAP_DIFFBUS_C0201-DIFF BUS_0.22UF,6.3V,20%,X6S,SA
     1 P5E_CPU1_G1_TX_C_DP<0> @T6G_MB_LIB.T6G(SCH_1):P5E_CPU1_G1_TX_C_DP(0)   I165 @T6G_MB_LIB.T6G(SCH_1):PAGE355
     2 P5E_CPU1_G1_TX_DP<0> @T6G_MB_LIB.T6G(SCH_1):P5E_CPU1_G1_TX_DP(0)   I165 @T6G_MB_LIB.T6G(SCH_1):PAGE355

C710 Q_CAP_DIFFBUS_C0201-DIFF BUS_0.22UF,6.3V,20%,X6S,SA
     1 P5E_CPU1_P1_TX_C_DN<15> @T6G_MB_LIB.T6G(SCH_1):P5E_CPU1_P1_TX_C_DN(15)   I299 @T6G_MB_LIB.T6G(SCH_1):PAGE354
     2 P5E_CPU1_P1_TX_DN<15> @T6G_MB_LIB.T6G(SCH_1):P5E_CPU1_P1_TX_DN(15)   I299 @T6G_MB_LIB.T6G(SCH_1):PAGE354

C711 Q_CAP_DIFFBUS_C0201-DIFF BUS_0.22UF,6.3V,20%,X6S,SA
     1 P5E_CPU1_P1_TX_C_DP<15> @T6G_MB_LIB.T6G(SCH_1):P5E_CPU1_P1_TX_C_DP(15)   I298 @T6G_MB_LIB.T6G(SCH_1):PAGE354
     2 P5E_CPU1_P1_TX_DP<15> @T6G_MB_LIB.T6G(SCH_1):P5E_CPU1_P1_TX_DP(15)   I298 @T6G_MB_LIB.T6G(SCH_1):PAGE354

C712 Q_CAP_DIFFBUS_C0201-DIFF BUS_0.22UF,6.3V,20%,X6S,SA
     1 P5E_CPU1_P1_TX_C_DN<14> @T6G_MB_LIB.T6G(SCH_1):P5E_CPU1_P1_TX_C_DN(14)   I296 @T6G_MB_LIB.T6G(SCH_1):PAGE354
     2 P5E_CPU1_P1_TX_DN<14> @T6G_MB_LIB.T6G(SCH_1):P5E_CPU1_P1_TX_DN(14)   I296 @T6G_MB_LIB.T6G(SCH_1):PAGE354

C713 Q_CAP_DIFFBUS_C0201-DIFF BUS_0.22UF,6.3V,20%,X6S,SA
     1 P5E_CPU1_P1_TX_C_DP<14> @T6G_MB_LIB.T6G(SCH_1):P5E_CPU1_P1_TX_C_DP(14)   I297 @T6G_MB_LIB.T6G(SCH_1):PAGE354
     2 P5E_CPU1_P1_TX_DP<14> @T6G_MB_LIB.T6G(SCH_1):P5E_CPU1_P1_TX_DP(14)   I297 @T6G_MB_LIB.T6G(SCH_1):PAGE354

C714 Q_CAP_DIFFBUS_C0201-DIFF BUS_0.22UF,6.3V,20%,X6S,SA
     1 P5E_CPU1_P1_TX_C_DN<13> @T6G_MB_LIB.T6G(SCH_1):P5E_CPU1_P1_TX_C_DN(13)   I295 @T6G_MB_LIB.T6G(SCH_1):PAGE354
     2 P5E_CPU1_P1_TX_DN<13> @T6G_MB_LIB.T6G(SCH_1):P5E_CPU1_P1_TX_DN(13)   I295 @T6G_MB_LIB.T6G(SCH_1):PAGE354

C715 Q_CAP_DIFFBUS_C0201-DIFF BUS_0.22UF,6.3V,20%,X6S,SA
     1 P5E_CPU1_P1_TX_C_DP<13> @T6G_MB_LIB.T6G(SCH_1):P5E_CPU1_P1_TX_C_DP(13)   I294 @T6G_MB_LIB.T6G(SCH_1):PAGE354
     2 P5E_CPU1_P1_TX_DP<13> @T6G_MB_LIB.T6G(SCH_1):P5E_CPU1_P1_TX_DP(13)   I294 @T6G_MB_LIB.T6G(SCH_1):PAGE354

C716 Q_CAP_DIFFBUS_C0201-DIFF BUS_0.22UF,6.3V,20%,X6S,SA
     1 P5E_CPU1_P1_TX_C_DN<12> @T6G_MB_LIB.T6G(SCH_1):P5E_CPU1_P1_TX_C_DN(12)   I283 @T6G_MB_LIB.T6G(SCH_1):PAGE354
     2 P5E_CPU1_P1_TX_DN<12> @T6G_MB_LIB.T6G(SCH_1):P5E_CPU1_P1_TX_DN(12)   I283 @T6G_MB_LIB.T6G(SCH_1):PAGE354

C717 Q_CAP_DIFFBUS_C0201-DIFF BUS_0.22UF,6.3V,20%,X6S,SA
     1 P5E_CPU1_P1_TX_C_DP<12> @T6G_MB_LIB.T6G(SCH_1):P5E_CPU1_P1_TX_C_DP(12)   I282 @T6G_MB_LIB.T6G(SCH_1):PAGE354
     2 P5E_CPU1_P1_TX_DP<12> @T6G_MB_LIB.T6G(SCH_1):P5E_CPU1_P1_TX_DP(12)   I282 @T6G_MB_LIB.T6G(SCH_1):PAGE354

C718 Q_CAP_DIFFBUS_C0201-DIFF BUS_0.22UF,6.3V,20%,X6S,SA
     1 P5E_CPU1_P1_TX_C_DN<11> @T6G_MB_LIB.T6G(SCH_1):P5E_CPU1_P1_TX_C_DN(11)   I281 @T6G_MB_LIB.T6G(SCH_1):PAGE354
     2 P5E_CPU1_P1_TX_DN<11> @T6G_MB_LIB.T6G(SCH_1):P5E_CPU1_P1_TX_DN(11)   I281 @T6G_MB_LIB.T6G(SCH_1):PAGE354

C719 Q_CAP_DIFFBUS_C0201-DIFF BUS_0.22UF,6.3V,20%,X6S,SA
     1 P5E_CPU1_P1_TX_C_DP<11> @T6G_MB_LIB.T6G(SCH_1):P5E_CPU1_P1_TX_C_DP(11)   I280 @T6G_MB_LIB.T6G(SCH_1):PAGE354
     2 P5E_CPU1_P1_TX_DP<11> @T6G_MB_LIB.T6G(SCH_1):P5E_CPU1_P1_TX_DP(11)   I280 @T6G_MB_LIB.T6G(SCH_1):PAGE354

C720 Q_CAP_DIFFBUS_C0201-DIFF BUS_0.22UF,6.3V,20%,X6S,SA
     1 P5E_CPU1_P1_TX_C_DN<10> @T6G_MB_LIB.T6G(SCH_1):P5E_CPU1_P1_TX_C_DN(10)   I279 @T6G_MB_LIB.T6G(SCH_1):PAGE354
     2 P5E_CPU1_P1_TX_DN<10> @T6G_MB_LIB.T6G(SCH_1):P5E_CPU1_P1_TX_DN(10)   I279 @T6G_MB_LIB.T6G(SCH_1):PAGE354

C721 Q_CAP_DIFFBUS_C0201-DIFF BUS_0.22UF,6.3V,20%,X6S,SA
     1 P5E_CPU1_P1_TX_C_DP<10> @T6G_MB_LIB.T6G(SCH_1):P5E_CPU1_P1_TX_C_DP(10)   I278 @T6G_MB_LIB.T6G(SCH_1):PAGE354
     2 P5E_CPU1_P1_TX_DP<10> @T6G_MB_LIB.T6G(SCH_1):P5E_CPU1_P1_TX_DP(10)   I278 @T6G_MB_LIB.T6G(SCH_1):PAGE354

C722 Q_CAP_DIFFBUS_C0201-DIFF BUS_0.22UF,6.3V,20%,X6S,SA
     1 P5E_CPU1_P1_TX_C_DN<9> @T6G_MB_LIB.T6G(SCH_1):P5E_CPU1_P1_TX_C_DN(9)   I276 @T6G_MB_LIB.T6G(SCH_1):PAGE354
     2 P5E_CPU1_P1_TX_DN<9> @T6G_MB_LIB.T6G(SCH_1):P5E_CPU1_P1_TX_DN(9)   I276 @T6G_MB_LIB.T6G(SCH_1):PAGE354

C723 Q_CAP_DIFFBUS_C0201-DIFF BUS_0.22UF,6.3V,20%,X6S,SA
     1 P5E_CPU1_P1_TX_C_DP<9> @T6G_MB_LIB.T6G(SCH_1):P5E_CPU1_P1_TX_C_DP(9)   I277 @T6G_MB_LIB.T6G(SCH_1):PAGE354
     2 P5E_CPU1_P1_TX_DP<9> @T6G_MB_LIB.T6G(SCH_1):P5E_CPU1_P1_TX_DP(9)   I277 @T6G_MB_LIB.T6G(SCH_1):PAGE354

C724 Q_CAP_DIFFBUS_C0201-DIFF BUS_0.22UF,6.3V,20%,X6S,SA
     1 P5E_CPU1_P1_TX_C_DN<8> @T6G_MB_LIB.T6G(SCH_1):P5E_CPU1_P1_TX_C_DN(8)   I275 @T6G_MB_LIB.T6G(SCH_1):PAGE354
     2 P5E_CPU1_P1_TX_DN<8> @T6G_MB_LIB.T6G(SCH_1):P5E_CPU1_P1_TX_DN(8)   I275 @T6G_MB_LIB.T6G(SCH_1):PAGE354

C725 Q_CAP_DIFFBUS_C0201-DIFF BUS_0.22UF,6.3V,20%,X6S,SA
     1 P5E_CPU1_P1_TX_C_DP<8> @T6G_MB_LIB.T6G(SCH_1):P5E_CPU1_P1_TX_C_DP(8)   I274 @T6G_MB_LIB.T6G(SCH_1):PAGE354
     2 P5E_CPU1_P1_TX_DP<8> @T6G_MB_LIB.T6G(SCH_1):P5E_CPU1_P1_TX_DP(8)   I274 @T6G_MB_LIB.T6G(SCH_1):PAGE354

C726 Q_CAP_DIFFBUS_C0201-DIFF BUS_0.22UF,6.3V,20%,X6S,SA
     1 P5E_CPU1_P1_TX_C_DN<7> @T6G_MB_LIB.T6G(SCH_1):P5E_CPU1_P1_TX_C_DN(7)   I312 @T6G_MB_LIB.T6G(SCH_1):PAGE354
     2 P5E_CPU1_P1_TX_DN<7> @T6G_MB_LIB.T6G(SCH_1):P5E_CPU1_P1_TX_DN(7)   I312 @T6G_MB_LIB.T6G(SCH_1):PAGE354

C727 Q_CAP_DIFFBUS_C0201-DIFF BUS_0.22UF,6.3V,20%,X6S,SA
     1 P5E_CPU1_P1_TX_C_DP<7> @T6G_MB_LIB.T6G(SCH_1):P5E_CPU1_P1_TX_C_DP(7)   I251 @T6G_MB_LIB.T6G(SCH_1):PAGE354
     2 P5E_CPU1_P1_TX_DP<7> @T6G_MB_LIB.T6G(SCH_1):P5E_CPU1_P1_TX_DP(7)   I251 @T6G_MB_LIB.T6G(SCH_1):PAGE354

C728 Q_CAP_DIFFBUS_C0201-DIFF BUS_0.22UF,6.3V,20%,X6S,SA
     1 P5E_CPU1_P1_TX_C_DN<6> @T6G_MB_LIB.T6G(SCH_1):P5E_CPU1_P1_TX_C_DN(6)   I250 @T6G_MB_LIB.T6G(SCH_1):PAGE354
     2 P5E_CPU1_P1_TX_DN<6> @T6G_MB_LIB.T6G(SCH_1):P5E_CPU1_P1_TX_DN(6)   I250 @T6G_MB_LIB.T6G(SCH_1):PAGE354

C729 Q_CAP_DIFFBUS_C0201-DIFF BUS_0.22UF,6.3V,20%,X6S,SA
     1 P5E_CPU1_P1_TX_C_DP<6> @T6G_MB_LIB.T6G(SCH_1):P5E_CPU1_P1_TX_C_DP(6)   I249 @T6G_MB_LIB.T6G(SCH_1):PAGE354
     2 P5E_CPU1_P1_TX_DP<6> @T6G_MB_LIB.T6G(SCH_1):P5E_CPU1_P1_TX_DP(6)   I249 @T6G_MB_LIB.T6G(SCH_1):PAGE354

C730 Q_CAP_DIFFBUS_C0201-DIFF BUS_0.22UF,6.3V,20%,X6S,SA
     1 P5E_CPU1_P1_TX_C_DN<5> @T6G_MB_LIB.T6G(SCH_1):P5E_CPU1_P1_TX_C_DN(5)   I248 @T6G_MB_LIB.T6G(SCH_1):PAGE354
     2 P5E_CPU1_P1_TX_DN<5> @T6G_MB_LIB.T6G(SCH_1):P5E_CPU1_P1_TX_DN(5)   I248 @T6G_MB_LIB.T6G(SCH_1):PAGE354

C731 Q_CAP_DIFFBUS_C0201-DIFF BUS_0.22UF,6.3V,20%,X6S,SA
     1 P5E_CPU1_P1_TX_C_DP<5> @T6G_MB_LIB.T6G(SCH_1):P5E_CPU1_P1_TX_C_DP(5)   I247 @T6G_MB_LIB.T6G(SCH_1):PAGE354
     2 P5E_CPU1_P1_TX_DP<5> @T6G_MB_LIB.T6G(SCH_1):P5E_CPU1_P1_TX_DP(5)   I247 @T6G_MB_LIB.T6G(SCH_1):PAGE354

C732 Q_CAP_DIFFBUS_C0201-DIFF BUS_0.22UF,6.3V,20%,X6S,SA
     1 P5E_CPU1_P1_TX_C_DN<4> @T6G_MB_LIB.T6G(SCH_1):P5E_CPU1_P1_TX_C_DN(4)   I246 @T6G_MB_LIB.T6G(SCH_1):PAGE354
     2 P5E_CPU1_P1_TX_DN<4> @T6G_MB_LIB.T6G(SCH_1):P5E_CPU1_P1_TX_DN(4)   I246 @T6G_MB_LIB.T6G(SCH_1):PAGE354

C733 Q_CAP_DIFFBUS_C0201-DIFF BUS_0.22UF,6.3V,20%,X6S,SA
     1 P5E_CPU1_P1_TX_C_DP<4> @T6G_MB_LIB.T6G(SCH_1):P5E_CPU1_P1_TX_C_DP(4)   I237 @T6G_MB_LIB.T6G(SCH_1):PAGE354
     2 P5E_CPU1_P1_TX_DP<4> @T6G_MB_LIB.T6G(SCH_1):P5E_CPU1_P1_TX_DP(4)   I237 @T6G_MB_LIB.T6G(SCH_1):PAGE354

C734 Q_CAP_DIFFBUS_C0201-DIFF BUS_0.22UF,6.3V,20%,X6S,SA
     1 P5E_CPU1_P1_TX_C_DN<3> @T6G_MB_LIB.T6G(SCH_1):P5E_CPU1_P1_TX_C_DN(3)   I235 @T6G_MB_LIB.T6G(SCH_1):PAGE354
     2 P5E_CPU1_P1_TX_DN<3> @T6G_MB_LIB.T6G(SCH_1):P5E_CPU1_P1_TX_DN(3)   I235 @T6G_MB_LIB.T6G(SCH_1):PAGE354

C735 Q_CAP_DIFFBUS_C0201-DIFF BUS_0.22UF,6.3V,20%,X6S,SA
     1 P5E_CPU1_P1_TX_C_DP<3> @T6G_MB_LIB.T6G(SCH_1):P5E_CPU1_P1_TX_C_DP(3)   I236 @T6G_MB_LIB.T6G(SCH_1):PAGE354
     2 P5E_CPU1_P1_TX_DP<3> @T6G_MB_LIB.T6G(SCH_1):P5E_CPU1_P1_TX_DP(3)   I236 @T6G_MB_LIB.T6G(SCH_1):PAGE354

C736 Q_CAP_DIFFBUS_C0201-DIFF BUS_0.22UF,6.3V,20%,X6S,SA
     1 P5E_CPU1_P1_TX_C_DN<2> @T6G_MB_LIB.T6G(SCH_1):P5E_CPU1_P1_TX_C_DN(2)   I234 @T6G_MB_LIB.T6G(SCH_1):PAGE354
     2 P5E_CPU1_P1_TX_DN<2> @T6G_MB_LIB.T6G(SCH_1):P5E_CPU1_P1_TX_DN(2)   I234 @T6G_MB_LIB.T6G(SCH_1):PAGE354

C737 Q_CAP_DIFFBUS_C0201-DIFF BUS_0.22UF,6.3V,20%,X6S,SA
     1 P5E_CPU1_P1_TX_C_DP<2> @T6G_MB_LIB.T6G(SCH_1):P5E_CPU1_P1_TX_C_DP(2)   I233 @T6G_MB_LIB.T6G(SCH_1):PAGE354
     2 P5E_CPU1_P1_TX_DP<2> @T6G_MB_LIB.T6G(SCH_1):P5E_CPU1_P1_TX_DP(2)   I233 @T6G_MB_LIB.T6G(SCH_1):PAGE354

C738 Q_CAP_DIFFBUS_C0201-DIFF BUS_0.22UF,6.3V,20%,X6S,SA
     1 P5E_CPU1_P1_TX_C_DN<1> @T6G_MB_LIB.T6G(SCH_1):P5E_CPU1_P1_TX_C_DN(1)   I232 @T6G_MB_LIB.T6G(SCH_1):PAGE354
     2 P5E_CPU1_P1_TX_DN<1> @T6G_MB_LIB.T6G(SCH_1):P5E_CPU1_P1_TX_DN(1)   I232 @T6G_MB_LIB.T6G(SCH_1):PAGE354

C739 Q_CAP_DIFFBUS_C0201-DIFF BUS_0.22UF,6.3V,20%,X6S,SA
     1 P5E_CPU1_P1_TX_C_DP<1> @T6G_MB_LIB.T6G(SCH_1):P5E_CPU1_P1_TX_C_DP(1)   I231 @T6G_MB_LIB.T6G(SCH_1):PAGE354
     2 P5E_CPU1_P1_TX_DP<1> @T6G_MB_LIB.T6G(SCH_1):P5E_CPU1_P1_TX_DP(1)   I231 @T6G_MB_LIB.T6G(SCH_1):PAGE354

C740 Q_CAP_DIFFBUS_C0201-DIFF BUS_0.22UF,6.3V,20%,X6S,SA
     1 P5E_CPU1_P1_TX_C_DN<0> @T6G_MB_LIB.T6G(SCH_1):P5E_CPU1_P1_TX_C_DN(0)   I229 @T6G_MB_LIB.T6G(SCH_1):PAGE354
     2 P5E_CPU1_P1_TX_DN<0> @T6G_MB_LIB.T6G(SCH_1):P5E_CPU1_P1_TX_DN(0)   I229 @T6G_MB_LIB.T6G(SCH_1):PAGE354

C741 Q_CAP_DIFFBUS_C0201-DIFF BUS_0.22UF,6.3V,20%,X6S,SA
     1 P5E_CPU1_P1_TX_C_DP<0> @T6G_MB_LIB.T6G(SCH_1):P5E_CPU1_P1_TX_C_DP(0)   I230 @T6G_MB_LIB.T6G(SCH_1):PAGE354
     2 P5E_CPU1_P1_TX_DP<0> @T6G_MB_LIB.T6G(SCH_1):P5E_CPU1_P1_TX_DP(0)   I230 @T6G_MB_LIB.T6G(SCH_1):PAGE354

C742 Q_CAP_DIFFBUS_C0201-DIFF BUS_0.22UF,6.3V,20%,X6S,SA
     1 P5E_CPU1_P2_TX_C_DN<15> @T6G_MB_LIB.T6G(SCH_1):P5E_CPU1_P2_TX_C_DN(15)   I172 @T6G_MB_LIB.T6G(SCH_1):PAGE354
     2 P5E_CPU1_P2_TX_DN<15> @T6G_MB_LIB.T6G(SCH_1):P5E_CPU1_P2_TX_DN(15)   I172 @T6G_MB_LIB.T6G(SCH_1):PAGE354

C743 Q_CAP_DIFFBUS_C0201-DIFF BUS_0.22UF,6.3V,20%,X6S,SA
     1 P5E_CPU1_P2_TX_C_DP<15> @T6G_MB_LIB.T6G(SCH_1):P5E_CPU1_P2_TX_C_DP(15)   I171 @T6G_MB_LIB.T6G(SCH_1):PAGE354
     2 P5E_CPU1_P2_TX_DP<15> @T6G_MB_LIB.T6G(SCH_1):P5E_CPU1_P2_TX_DP(15)   I171 @T6G_MB_LIB.T6G(SCH_1):PAGE354

C744 Q_CAP_DIFFBUS_C0201-DIFF BUS_0.22UF,6.3V,20%,X6S,SA
     1 P5E_CPU1_P2_TX_C_DN<14> @T6G_MB_LIB.T6G(SCH_1):P5E_CPU1_P2_TX_C_DN(14)   I170 @T6G_MB_LIB.T6G(SCH_1):PAGE354
     2 P5E_CPU1_P2_TX_DN<14> @T6G_MB_LIB.T6G(SCH_1):P5E_CPU1_P2_TX_DN(14)   I170 @T6G_MB_LIB.T6G(SCH_1):PAGE354

C745 Q_CAP_DIFFBUS_C0201-DIFF BUS_0.22UF,6.3V,20%,X6S,SA
     1 P5E_CPU1_P2_TX_C_DP<14> @T6G_MB_LIB.T6G(SCH_1):P5E_CPU1_P2_TX_C_DP(14)   I169 @T6G_MB_LIB.T6G(SCH_1):PAGE354
     2 P5E_CPU1_P2_TX_DP<14> @T6G_MB_LIB.T6G(SCH_1):P5E_CPU1_P2_TX_DP(14)   I169 @T6G_MB_LIB.T6G(SCH_1):PAGE354

C746 Q_CAP_DIFFBUS_C0201-DIFF BUS_0.22UF,6.3V,20%,X6S,SA
     1 P5E_CPU1_P2_TX_C_DN<13> @T6G_MB_LIB.T6G(SCH_1):P5E_CPU1_P2_TX_C_DN(13)   I168 @T6G_MB_LIB.T6G(SCH_1):PAGE354
     2 P5E_CPU1_P2_TX_DN<13> @T6G_MB_LIB.T6G(SCH_1):P5E_CPU1_P2_TX_DN(13)   I168 @T6G_MB_LIB.T6G(SCH_1):PAGE354

C747 Q_CAP_DIFFBUS_C0201-DIFF BUS_0.22UF,6.3V,20%,X6S,SA
     1 P5E_CPU1_P2_TX_C_DP<13> @T6G_MB_LIB.T6G(SCH_1):P5E_CPU1_P2_TX_C_DP(13)   I167 @T6G_MB_LIB.T6G(SCH_1):PAGE354
     2 P5E_CPU1_P2_TX_DP<13> @T6G_MB_LIB.T6G(SCH_1):P5E_CPU1_P2_TX_DP(13)   I167 @T6G_MB_LIB.T6G(SCH_1):PAGE354

C748 Q_CAP_DIFFBUS_C0201-DIFF BUS_0.22UF,6.3V,20%,X6S,SA
     1 P5E_CPU1_P2_TX_C_DN<12> @T6G_MB_LIB.T6G(SCH_1):P5E_CPU1_P2_TX_C_DN(12)   I163 @T6G_MB_LIB.T6G(SCH_1):PAGE354
     2 P5E_CPU1_P2_TX_DN<12> @T6G_MB_LIB.T6G(SCH_1):P5E_CPU1_P2_TX_DN(12)   I163 @T6G_MB_LIB.T6G(SCH_1):PAGE354

C749 Q_CAP_DIFFBUS_C0201-DIFF BUS_0.22UF,6.3V,20%,X6S,SA
     1 P5E_CPU1_P2_TX_C_DP<12> @T6G_MB_LIB.T6G(SCH_1):P5E_CPU1_P2_TX_C_DP(12)   I162 @T6G_MB_LIB.T6G(SCH_1):PAGE354
     2 P5E_CPU1_P2_TX_DP<12> @T6G_MB_LIB.T6G(SCH_1):P5E_CPU1_P2_TX_DP(12)   I162 @T6G_MB_LIB.T6G(SCH_1):PAGE354

C750 Q_CAP_DIFFBUS_C0201-DIFF BUS_0.22UF,6.3V,20%,X6S,SA
     1 P5E_CPU1_P2_TX_C_DN<11> @T6G_MB_LIB.T6G(SCH_1):P5E_CPU1_P2_TX_C_DN(11)   I160 @T6G_MB_LIB.T6G(SCH_1):PAGE354
     2 P5E_CPU1_P2_TX_DN<11> @T6G_MB_LIB.T6G(SCH_1):P5E_CPU1_P2_TX_DN(11)   I160 @T6G_MB_LIB.T6G(SCH_1):PAGE354

C751 Q_CAP_DIFFBUS_C0201-DIFF BUS_0.22UF,6.3V,20%,X6S,SA
     1 P5E_CPU1_P2_TX_C_DP<11> @T6G_MB_LIB.T6G(SCH_1):P5E_CPU1_P2_TX_C_DP(11)   I161 @T6G_MB_LIB.T6G(SCH_1):PAGE354
     2 P5E_CPU1_P2_TX_DP<11> @T6G_MB_LIB.T6G(SCH_1):P5E_CPU1_P2_TX_DP(11)   I161 @T6G_MB_LIB.T6G(SCH_1):PAGE354

C752 Q_CAP_DIFFBUS_C0201-DIFF BUS_0.22UF,6.3V,20%,X6S,SA
     1 P5E_CPU1_P2_TX_C_DN<10> @T6G_MB_LIB.T6G(SCH_1):P5E_CPU1_P2_TX_C_DN(10)   I159 @T6G_MB_LIB.T6G(SCH_1):PAGE354
     2 P5E_CPU1_P2_TX_DN<10> @T6G_MB_LIB.T6G(SCH_1):P5E_CPU1_P2_TX_DN(10)   I159 @T6G_MB_LIB.T6G(SCH_1):PAGE354

C753 Q_CAP_DIFFBUS_C0201-DIFF BUS_0.22UF,6.3V,20%,X6S,SA
     1 P5E_CPU1_P2_TX_C_DP<10> @T6G_MB_LIB.T6G(SCH_1):P5E_CPU1_P2_TX_C_DP(10)   I158 @T6G_MB_LIB.T6G(SCH_1):PAGE354
     2 P5E_CPU1_P2_TX_DP<10> @T6G_MB_LIB.T6G(SCH_1):P5E_CPU1_P2_TX_DP(10)   I158 @T6G_MB_LIB.T6G(SCH_1):PAGE354

C754 Q_CAP_DIFFBUS_C0201-DIFF BUS_0.22UF,6.3V,20%,X6S,SA
     1 P5E_CPU1_P2_TX_C_DN<9> @T6G_MB_LIB.T6G(SCH_1):P5E_CPU1_P2_TX_C_DN(9)   I157 @T6G_MB_LIB.T6G(SCH_1):PAGE354
     2 P5E_CPU1_P2_TX_DN<9> @T6G_MB_LIB.T6G(SCH_1):P5E_CPU1_P2_TX_DN(9)   I157 @T6G_MB_LIB.T6G(SCH_1):PAGE354

C755 Q_CAP_DIFFBUS_C0201-DIFF BUS_0.22UF,6.3V,20%,X6S,SA
     1 P5E_CPU1_P2_TX_C_DP<9> @T6G_MB_LIB.T6G(SCH_1):P5E_CPU1_P2_TX_C_DP(9)   I156 @T6G_MB_LIB.T6G(SCH_1):PAGE354
     2 P5E_CPU1_P2_TX_DP<9> @T6G_MB_LIB.T6G(SCH_1):P5E_CPU1_P2_TX_DP(9)   I156 @T6G_MB_LIB.T6G(SCH_1):PAGE354

C756 Q_CAP_DIFFBUS_C0201-DIFF BUS_0.22UF,6.3V,20%,X6S,SA
     1 P5E_CPU1_P2_TX_C_DN<8> @T6G_MB_LIB.T6G(SCH_1):P5E_CPU1_P2_TX_C_DN(8)   I154 @T6G_MB_LIB.T6G(SCH_1):PAGE354
     2 P5E_CPU1_P2_TX_DN<8> @T6G_MB_LIB.T6G(SCH_1):P5E_CPU1_P2_TX_DN(8)   I154 @T6G_MB_LIB.T6G(SCH_1):PAGE354

C757 Q_CAP_DIFFBUS_C0201-DIFF BUS_0.22UF,6.3V,20%,X6S,SA
     1 P5E_CPU1_P2_TX_C_DP<8> @T6G_MB_LIB.T6G(SCH_1):P5E_CPU1_P2_TX_C_DP(8)   I155 @T6G_MB_LIB.T6G(SCH_1):PAGE354
     2 P5E_CPU1_P2_TX_DP<8> @T6G_MB_LIB.T6G(SCH_1):P5E_CPU1_P2_TX_DP(8)   I155 @T6G_MB_LIB.T6G(SCH_1):PAGE354

C758 Q_CAP_DIFFBUS_C0201-DIFF BUS_0.22UF,6.3V,20%,X6S,SA
     1 P5E_CPU1_P2_TX_C_DN<7> @T6G_MB_LIB.T6G(SCH_1):P5E_CPU1_P2_TX_C_DN(7)   I140 @T6G_MB_LIB.T6G(SCH_1):PAGE354
     2 P5E_CPU1_P2_TX_DN<7> @T6G_MB_LIB.T6G(SCH_1):P5E_CPU1_P2_TX_DN(7)   I140 @T6G_MB_LIB.T6G(SCH_1):PAGE354

C759 Q_CAP_DIFFBUS_C0201-DIFF BUS_0.22UF,6.3V,20%,X6S,SA
     1 P5E_CPU1_P2_TX_C_DP<7> @T6G_MB_LIB.T6G(SCH_1):P5E_CPU1_P2_TX_C_DP(7)   I139 @T6G_MB_LIB.T6G(SCH_1):PAGE354
     2 P5E_CPU1_P2_TX_DP<7> @T6G_MB_LIB.T6G(SCH_1):P5E_CPU1_P2_TX_DP(7)   I139 @T6G_MB_LIB.T6G(SCH_1):PAGE354

C760 Q_CAP_DIFFBUS_C0201-DIFF BUS_0.22UF,6.3V,20%,X6S,SA
     1 P5E_CPU1_P2_TX_C_DN<6> @T6G_MB_LIB.T6G(SCH_1):P5E_CPU1_P2_TX_C_DN(6)   I138 @T6G_MB_LIB.T6G(SCH_1):PAGE354
     2 P5E_CPU1_P2_TX_DN<6> @T6G_MB_LIB.T6G(SCH_1):P5E_CPU1_P2_TX_DN(6)   I138 @T6G_MB_LIB.T6G(SCH_1):PAGE354

C761 Q_CAP_DIFFBUS_C0201-DIFF BUS_0.22UF,6.3V,20%,X6S,SA
     1 P5E_CPU1_P2_TX_C_DP<6> @T6G_MB_LIB.T6G(SCH_1):P5E_CPU1_P2_TX_C_DP(6)   I137 @T6G_MB_LIB.T6G(SCH_1):PAGE354
     2 P5E_CPU1_P2_TX_DP<6> @T6G_MB_LIB.T6G(SCH_1):P5E_CPU1_P2_TX_DP(6)   I137 @T6G_MB_LIB.T6G(SCH_1):PAGE354

C762 Q_CAP_DIFFBUS_C0201-DIFF BUS_0.22UF,6.3V,20%,X6S,SA
     1 P5E_CPU1_P2_TX_C_DN<5> @T6G_MB_LIB.T6G(SCH_1):P5E_CPU1_P2_TX_C_DN(5)   I136 @T6G_MB_LIB.T6G(SCH_1):PAGE354
     2 P5E_CPU1_P2_TX_DN<5> @T6G_MB_LIB.T6G(SCH_1):P5E_CPU1_P2_TX_DN(5)   I136 @T6G_MB_LIB.T6G(SCH_1):PAGE354

C763 Q_CAP_DIFFBUS_C0201-DIFF BUS_0.22UF,6.3V,20%,X6S,SA
     1 P5E_CPU1_P2_TX_C_DP<5> @T6G_MB_LIB.T6G(SCH_1):P5E_CPU1_P2_TX_C_DP(5)   I135 @T6G_MB_LIB.T6G(SCH_1):PAGE354
     2 P5E_CPU1_P2_TX_DP<5> @T6G_MB_LIB.T6G(SCH_1):P5E_CPU1_P2_TX_DP(5)   I135 @T6G_MB_LIB.T6G(SCH_1):PAGE354

C764 Q_CAP_DIFFBUS_C0201-DIFF BUS_0.22UF,6.3V,20%,X6S,SA
     1 P5E_CPU1_P2_TX_C_DN<4> @T6G_MB_LIB.T6G(SCH_1):P5E_CPU1_P2_TX_C_DN(4)   I130 @T6G_MB_LIB.T6G(SCH_1):PAGE354
     2 P5E_CPU1_P2_TX_DN<4> @T6G_MB_LIB.T6G(SCH_1):P5E_CPU1_P2_TX_DN(4)   I130 @T6G_MB_LIB.T6G(SCH_1):PAGE354

C765 Q_CAP_DIFFBUS_C0201-DIFF BUS_0.22UF,6.3V,20%,X6S,SA
     1 P5E_CPU1_P2_TX_C_DP<4> @T6G_MB_LIB.T6G(SCH_1):P5E_CPU1_P2_TX_C_DP(4)   I131 @T6G_MB_LIB.T6G(SCH_1):PAGE354
     2 P5E_CPU1_P2_TX_DP<4> @T6G_MB_LIB.T6G(SCH_1):P5E_CPU1_P2_TX_DP(4)   I131 @T6G_MB_LIB.T6G(SCH_1):PAGE354

C766 Q_CAP_DIFFBUS_C0201-DIFF BUS_0.22UF,6.3V,20%,X6S,SA
     1 P5E_CPU1_P2_TX_C_DN<3> @T6G_MB_LIB.T6G(SCH_1):P5E_CPU1_P2_TX_C_DN(3)   I129 @T6G_MB_LIB.T6G(SCH_1):PAGE354
     2 P5E_CPU1_P2_TX_DN<3> @T6G_MB_LIB.T6G(SCH_1):P5E_CPU1_P2_TX_DN(3)   I129 @T6G_MB_LIB.T6G(SCH_1):PAGE354

C767 Q_CAP_DIFFBUS_C0201-DIFF BUS_0.22UF,6.3V,20%,X6S,SA
     1 P5E_CPU1_P2_TX_C_DP<3> @T6G_MB_LIB.T6G(SCH_1):P5E_CPU1_P2_TX_C_DP(3)   I128 @T6G_MB_LIB.T6G(SCH_1):PAGE354
     2 P5E_CPU1_P2_TX_DP<3> @T6G_MB_LIB.T6G(SCH_1):P5E_CPU1_P2_TX_DP(3)   I128 @T6G_MB_LIB.T6G(SCH_1):PAGE354

C768 Q_CAP_DIFFBUS_C0201-DIFF BUS_0.22UF,6.3V,20%,X6S,SA
     1 P5E_CPU1_P2_TX_C_DN<2> @T6G_MB_LIB.T6G(SCH_1):P5E_CPU1_P2_TX_C_DN(2)   I127 @T6G_MB_LIB.T6G(SCH_1):PAGE354
     2 P5E_CPU1_P2_TX_DN<2> @T6G_MB_LIB.T6G(SCH_1):P5E_CPU1_P2_TX_DN(2)   I127 @T6G_MB_LIB.T6G(SCH_1):PAGE354

C769 Q_CAP_DIFFBUS_C0201-DIFF BUS_0.22UF,6.3V,20%,X6S,SA
     1 P5E_CPU1_P2_TX_C_DP<2> @T6G_MB_LIB.T6G(SCH_1):P5E_CPU1_P2_TX_C_DP(2)   I126 @T6G_MB_LIB.T6G(SCH_1):PAGE354
     2 P5E_CPU1_P2_TX_DP<2> @T6G_MB_LIB.T6G(SCH_1):P5E_CPU1_P2_TX_DP(2)   I126 @T6G_MB_LIB.T6G(SCH_1):PAGE354

C770 Q_CAP_DIFFBUS_C0201-DIFF BUS_0.22UF,6.3V,20%,X6S,SA
     1 P5E_CPU1_P2_TX_C_DN<1> @T6G_MB_LIB.T6G(SCH_1):P5E_CPU1_P2_TX_C_DN(1)   I125 @T6G_MB_LIB.T6G(SCH_1):PAGE354
     2 P5E_CPU1_P2_TX_DN<1> @T6G_MB_LIB.T6G(SCH_1):P5E_CPU1_P2_TX_DN(1)   I125 @T6G_MB_LIB.T6G(SCH_1):PAGE354

C771 Q_CAP_DIFFBUS_C0201-DIFF BUS_0.22UF,6.3V,20%,X6S,SA
     1 P5E_CPU1_P2_TX_C_DP<1> @T6G_MB_LIB.T6G(SCH_1):P5E_CPU1_P2_TX_C_DP(1)   I124 @T6G_MB_LIB.T6G(SCH_1):PAGE354
     2 P5E_CPU1_P2_TX_DP<1> @T6G_MB_LIB.T6G(SCH_1):P5E_CPU1_P2_TX_DP(1)   I124 @T6G_MB_LIB.T6G(SCH_1):PAGE354

C772 Q_CAP_DIFFBUS_C0201-DIFF BUS_0.22UF,6.3V,20%,X6S,SA
     1 P5E_CPU1_P2_TX_C_DN<0> @T6G_MB_LIB.T6G(SCH_1):P5E_CPU1_P2_TX_C_DN(0)   I123 @T6G_MB_LIB.T6G(SCH_1):PAGE354
     2 P5E_CPU1_P2_TX_DN<0> @T6G_MB_LIB.T6G(SCH_1):P5E_CPU1_P2_TX_DN(0)   I123 @T6G_MB_LIB.T6G(SCH_1):PAGE354

C773 Q_CAP_DIFFBUS_C0201-DIFF BUS_0.22UF,6.3V,20%,X6S,SA
     1 P5E_CPU1_P2_TX_C_DP<0> @T6G_MB_LIB.T6G(SCH_1):P5E_CPU1_P2_TX_C_DP(0)   I122 @T6G_MB_LIB.T6G(SCH_1):PAGE354
     2 P5E_CPU1_P2_TX_DP<0> @T6G_MB_LIB.T6G(SCH_1):P5E_CPU1_P2_TX_DP(0)   I122 @T6G_MB_LIB.T6G(SCH_1):PAGE354

C774 Q_CAP_C0201-0.1UF,10V,10%,X7S,CH4102K6E00
     1 P1V8_CPU0_RT2_1A @T6G_MB_LIB.T6G(SCH_1):P1V8_CPU0_RT2_1A    I17 @T6G_MB_LIB.T6G(SCH_1):PAGE422
     2    GND @T6G_MB_LIB.T6G(SCH_1):GND    I17 @T6G_MB_LIB.T6G(SCH_1):PAGE422

C775 Q_CAP_C0201-0.1UF,10V,10%,X7S,CH4102K6E00
     1 P1V8_CPU0_RT2_1A_1D @T6G_MB_LIB.T6G(SCH_1):P1V8_CPU0_RT2_1A_1D    I10 @T6G_MB_LIB.T6G(SCH_1):PAGE422
     2    GND @T6G_MB_LIB.T6G(SCH_1):GND    I10 @T6G_MB_LIB.T6G(SCH_1):PAGE422

C776 Q_CAP_C0201-0.1UF,10V,10%,X7S,CH4102K6E00
     1 P1V8_CPU0_RT2_1A @T6G_MB_LIB.T6G(SCH_1):P1V8_CPU0_RT2_1A    I18 @T6G_MB_LIB.T6G(SCH_1):PAGE422
     2    GND @T6G_MB_LIB.T6G(SCH_1):GND    I18 @T6G_MB_LIB.T6G(SCH_1):PAGE422

C777 Q_CAP_C0201-0.1UF,10V,10%,X7S,CH4102K6E00
     1 P1V8_CPU0_RT2_1A @T6G_MB_LIB.T6G(SCH_1):P1V8_CPU0_RT2_1A    I19 @T6G_MB_LIB.T6G(SCH_1):PAGE422
     2    GND @T6G_MB_LIB.T6G(SCH_1):GND    I19 @T6G_MB_LIB.T6G(SCH_1):PAGE422

C778 Q_CAP_C0201-0.1UF,10V,10%,X7S,CH4102K6E00
     1 P1V8_CPU0_RT2_1A @T6G_MB_LIB.T6G(SCH_1):P1V8_CPU0_RT2_1A    I20 @T6G_MB_LIB.T6G(SCH_1):PAGE422
     2    GND @T6G_MB_LIB.T6G(SCH_1):GND    I20 @T6G_MB_LIB.T6G(SCH_1):PAGE422

C779 Q_CAP_0201-1UF,4V,20%,X6S,CH-10KMEE00
     1 P0V9_CPU0_RT2_2A @T6G_MB_LIB.T6G(SCH_1):P0V9_CPU0_RT2_2A    I73 @T6G_MB_LIB.T6G(SCH_1):PAGE422
     2    GND @T6G_MB_LIB.T6G(SCH_1):GND    I73 @T6G_MB_LIB.T6G(SCH_1):PAGE422

C780 Q_CAP_C0201-0.1UF,10V,10%,X7S,CH4102K6E00
     1 P0V9_CPU0_RT_2D @T6G_MB_LIB.T6G(SCH_1):P0V9_CPU0_RT_2D    I82 @T6G_MB_LIB.T6G(SCH_1):PAGE422
     2    GND @T6G_MB_LIB.T6G(SCH_1):GND    I82 @T6G_MB_LIB.T6G(SCH_1):PAGE422

C781 Q_CAP_0201-1UF,4V,20%,X6S,CH-10KMEE00
     1 P0V9_CPU0_RT2_2A @T6G_MB_LIB.T6G(SCH_1):P0V9_CPU0_RT2_2A    I45 @T6G_MB_LIB.T6G(SCH_1):PAGE422
     2    GND @T6G_MB_LIB.T6G(SCH_1):GND    I45 @T6G_MB_LIB.T6G(SCH_1):PAGE422

C782 Q_CAP_C0201-0.1UF,10V,10%,X7S,CH4102K6E00
     1 P0V9_CPU0_RT_2D @T6G_MB_LIB.T6G(SCH_1):P0V9_CPU0_RT_2D    I83 @T6G_MB_LIB.T6G(SCH_1):PAGE422
     2    GND @T6G_MB_LIB.T6G(SCH_1):GND    I83 @T6G_MB_LIB.T6G(SCH_1):PAGE422

C783 Q_CAP_0201-1UF,4V,20%,X6S,CH-10KMEE00
     1 P0V9_CPU0_RT2_2A @T6G_MB_LIB.T6G(SCH_1):P0V9_CPU0_RT2_2A    I62 @T6G_MB_LIB.T6G(SCH_1):PAGE422
     2    GND @T6G_MB_LIB.T6G(SCH_1):GND    I62 @T6G_MB_LIB.T6G(SCH_1):PAGE422

C784 Q_CAP_C0201-0.1UF,10V,10%,X7S,CH4102K6E00
     1 P0V9_CPU0_RT2_2A @T6G_MB_LIB.T6G(SCH_1):P0V9_CPU0_RT2_2A    I43 @T6G_MB_LIB.T6G(SCH_1):PAGE422
     2    GND @T6G_MB_LIB.T6G(SCH_1):GND    I43 @T6G_MB_LIB.T6G(SCH_1):PAGE422

C785 Q_CAP_C0201-0.1UF,10V,10%,X7S,CH4102K6E00
     1 P0V9_CPU0_RT_2D @T6G_MB_LIB.T6G(SCH_1):P0V9_CPU0_RT_2D    I84 @T6G_MB_LIB.T6G(SCH_1):PAGE422
     2    GND @T6G_MB_LIB.T6G(SCH_1):GND    I84 @T6G_MB_LIB.T6G(SCH_1):PAGE422

C786 Q_CAP_0201-1UF,4V,20%,X6S,CH-10KMEE00
     1 P0V9_CPU0_RT2_2A @T6G_MB_LIB.T6G(SCH_1):P0V9_CPU0_RT2_2A    I72 @T6G_MB_LIB.T6G(SCH_1):PAGE422
     2    GND @T6G_MB_LIB.T6G(SCH_1):GND    I72 @T6G_MB_LIB.T6G(SCH_1):PAGE422

C787 Q_CAP_0201-1UF,4V,20%,X6S,CH-10KMEE00
     1 P0V9_CPU0_RT2_2A_2D @T6G_MB_LIB.T6G(SCH_1):P0V9_CPU0_RT2_2A_2D    I90 @T6G_MB_LIB.T6G(SCH_1):PAGE422
     2    GND @T6G_MB_LIB.T6G(SCH_1):GND    I90 @T6G_MB_LIB.T6G(SCH_1):PAGE422

C788 Q_CAP_0201-1UF,4V,20%,X6S,CH-10KMEE00
     1 P0V9_CPU0_RT2_2A @T6G_MB_LIB.T6G(SCH_1):P0V9_CPU0_RT2_2A    I46 @T6G_MB_LIB.T6G(SCH_1):PAGE422
     2    GND @T6G_MB_LIB.T6G(SCH_1):GND    I46 @T6G_MB_LIB.T6G(SCH_1):PAGE422

C789 Q_CAP_C0201-0.1UF,10V,10%,X7S,CH4102K6E00
     1 P0V9_CPU0_RT_2D @T6G_MB_LIB.T6G(SCH_1):P0V9_CPU0_RT_2D    I86 @T6G_MB_LIB.T6G(SCH_1):PAGE422
     2    GND @T6G_MB_LIB.T6G(SCH_1):GND    I86 @T6G_MB_LIB.T6G(SCH_1):PAGE422

C790 Q_CAP_C0201-0.1UF,10V,10%,X7S,CH4102K6E00
     1 P0V9_CPU0_RT2_2A @T6G_MB_LIB.T6G(SCH_1):P0V9_CPU0_RT2_2A    I40 @T6G_MB_LIB.T6G(SCH_1):PAGE422
     2    GND @T6G_MB_LIB.T6G(SCH_1):GND    I40 @T6G_MB_LIB.T6G(SCH_1):PAGE422

C791 Q_CAP_C0201-0.1UF,10V,10%,X7S,CH4102K6E00
     1 P0V9_CPU0_RT2_2A_2D @T6G_MB_LIB.T6G(SCH_1):P0V9_CPU0_RT2_2A_2D    I36 @T6G_MB_LIB.T6G(SCH_1):PAGE422
     2    GND @T6G_MB_LIB.T6G(SCH_1):GND    I36 @T6G_MB_LIB.T6G(SCH_1):PAGE422

C792 Q_CAP_0201-1UF,4V,20%,X6S,CH-10KMEE00
     1 P0V9_CPU0_RT2_2A @T6G_MB_LIB.T6G(SCH_1):P0V9_CPU0_RT2_2A    I52 @T6G_MB_LIB.T6G(SCH_1):PAGE422
     2    GND @T6G_MB_LIB.T6G(SCH_1):GND    I52 @T6G_MB_LIB.T6G(SCH_1):PAGE422

C793 Q_CAP_0201-1UF,4V,20%,X6S,CH-10KMEE00
     1 P0V9_CPU0_RT2_2A_2D @T6G_MB_LIB.T6G(SCH_1):P0V9_CPU0_RT2_2A_2D    I91 @T6G_MB_LIB.T6G(SCH_1):PAGE422
     2    GND @T6G_MB_LIB.T6G(SCH_1):GND    I91 @T6G_MB_LIB.T6G(SCH_1):PAGE422

C794 Q_CAP_C0201-0.1UF,10V,10%,X7S,CH4102K6E00
     1 P0V9_CPU0_RT2_2A_2D @T6G_MB_LIB.T6G(SCH_1):P0V9_CPU0_RT2_2A_2D    I39 @T6G_MB_LIB.T6G(SCH_1):PAGE422
     2    GND @T6G_MB_LIB.T6G(SCH_1):GND    I39 @T6G_MB_LIB.T6G(SCH_1):PAGE422

C795 Q_CAP_C0805-100UF,4V,20%,X6S,CH710KMEA01
     1 P0V9_CPU0_RT2_2A @T6G_MB_LIB.T6G(SCH_1):P0V9_CPU0_RT2_2A    I48 @T6G_MB_LIB.T6G(SCH_1):PAGE422
     2    GND @T6G_MB_LIB.T6G(SCH_1):GND    I48 @T6G_MB_LIB.T6G(SCH_1):PAGE422

C796 Q_CAP_C0402-10UF,6.3V,20%,X6S,CH6101MEB01
     1 P0V9_CPU0_RT2_2A @T6G_MB_LIB.T6G(SCH_1):P0V9_CPU0_RT2_2A    I47 @T6G_MB_LIB.T6G(SCH_1):PAGE422
     2    GND @T6G_MB_LIB.T6G(SCH_1):GND    I47 @T6G_MB_LIB.T6G(SCH_1):PAGE422

C797 Q_CAP_0201-1UF,4V,20%,X6S,CH-10KMEE00
     1 P0V9_CPU0_RT2_2A @T6G_MB_LIB.T6G(SCH_1):P0V9_CPU0_RT2_2A    I44 @T6G_MB_LIB.T6G(SCH_1):PAGE422
     2    GND @T6G_MB_LIB.T6G(SCH_1):GND    I44 @T6G_MB_LIB.T6G(SCH_1):PAGE422

C798 Q_CAP_C0805-100UF,4V,20%,X6S,CH710KMEA01
     1 P0V9_CPU0_RT2_2A @T6G_MB_LIB.T6G(SCH_1):P0V9_CPU0_RT2_2A    I50 @T6G_MB_LIB.T6G(SCH_1):PAGE422
     2    GND @T6G_MB_LIB.T6G(SCH_1):GND    I50 @T6G_MB_LIB.T6G(SCH_1):PAGE422

C799 Q_CAP_C0402-22UF,4V,20%,X6S,CH622KMEB02
     1 P0V9_CPU0_RT2_2A @T6G_MB_LIB.T6G(SCH_1):P0V9_CPU0_RT2_2A    I65 @T6G_MB_LIB.T6G(SCH_1):PAGE422
     2    GND @T6G_MB_LIB.T6G(SCH_1):GND    I65 @T6G_MB_LIB.T6G(SCH_1):PAGE422

C800 Q_CAP_C0201-0.1UF,10V,10%,X7S,CH4102K6E00
     1 P0V9_CPU0_RT2_2A @T6G_MB_LIB.T6G(SCH_1):P0V9_CPU0_RT2_2A    I42 @T6G_MB_LIB.T6G(SCH_1):PAGE422
     2    GND @T6G_MB_LIB.T6G(SCH_1):GND    I42 @T6G_MB_LIB.T6G(SCH_1):PAGE422

C801 Q_CAP_C0805-100UF,4V,20%,X6S,CH710KMEA01
     1 P0V9_CPU0_RT_2D @T6G_MB_LIB.T6G(SCH_1):P0V9_CPU0_RT_2D    I77 @T6G_MB_LIB.T6G(SCH_1):PAGE422
     2    GND @T6G_MB_LIB.T6G(SCH_1):GND    I77 @T6G_MB_LIB.T6G(SCH_1):PAGE422

C802 Q_CAP_C0805-100UF,4V,20%,X6S,CH710KMEA01
     1 P0V9_CPU0_RT2_2A @T6G_MB_LIB.T6G(SCH_1):P0V9_CPU0_RT2_2A    I51 @T6G_MB_LIB.T6G(SCH_1):PAGE422
     2    GND @T6G_MB_LIB.T6G(SCH_1):GND    I51 @T6G_MB_LIB.T6G(SCH_1):PAGE422

C803 Q_CAP_C0402-10UF,6.3V,20%,X6S,CH6101MEB01
     1 P0V9_CPU0_RT2_2A @T6G_MB_LIB.T6G(SCH_1):P0V9_CPU0_RT2_2A    I87 @T6G_MB_LIB.T6G(SCH_1):PAGE422
     2    GND @T6G_MB_LIB.T6G(SCH_1):GND    I87 @T6G_MB_LIB.T6G(SCH_1):PAGE422

C804 Q_CAP_C0201-0.1UF,10V,10%,X7S,CH4102K6E00
     1 P0V9_CPU0_RT2_2A @T6G_MB_LIB.T6G(SCH_1):P0V9_CPU0_RT2_2A    I68 @T6G_MB_LIB.T6G(SCH_1):PAGE422
     2    GND @T6G_MB_LIB.T6G(SCH_1):GND    I68 @T6G_MB_LIB.T6G(SCH_1):PAGE422

C805 Q_CAP_C0402-22UF,4V,20%,X6S,CH622KMEB02
     1 P0V9_CPU0_RT_2D @T6G_MB_LIB.T6G(SCH_1):P0V9_CPU0_RT_2D    I78 @T6G_MB_LIB.T6G(SCH_1):PAGE422
     2    GND @T6G_MB_LIB.T6G(SCH_1):GND    I78 @T6G_MB_LIB.T6G(SCH_1):PAGE422

C806 Q_CAP_DIFFBUS_C0201-DIFF BUS_0.22UF,6.3V,20%,X6S,SA
     1 P5E_CPU1_P0_TX_C_DN<15> @T6G_MB_LIB.T6G(SCH_1):P5E_CPU1_P0_TX_C_DN(15)   I377 @T6G_MB_LIB.T6G(SCH_1):PAGE353
     2 P5E_CPU1_P0_TX_DN<15> @T6G_MB_LIB.T6G(SCH_1):P5E_CPU1_P0_TX_DN(15)   I377 @T6G_MB_LIB.T6G(SCH_1):PAGE353

C807 Q_CAP_DIFFBUS_C0201-DIFF BUS_0.22UF,6.3V,20%,X6S,SA
     1 P5E_CPU1_P0_TX_C_DP<15> @T6G_MB_LIB.T6G(SCH_1):P5E_CPU1_P0_TX_C_DP(15)   I378 @T6G_MB_LIB.T6G(SCH_1):PAGE353
     2 P5E_CPU1_P0_TX_DP<15> @T6G_MB_LIB.T6G(SCH_1):P5E_CPU1_P0_TX_DP(15)   I378 @T6G_MB_LIB.T6G(SCH_1):PAGE353

C808 Q_CAP_DIFFBUS_C0201-DIFF BUS_0.22UF,6.3V,20%,X6S,SA
     1 P5E_CPU1_P0_TX_C_DN<14> @T6G_MB_LIB.T6G(SCH_1):P5E_CPU1_P0_TX_C_DN(14)   I376 @T6G_MB_LIB.T6G(SCH_1):PAGE353
     2 P5E_CPU1_P0_TX_DN<14> @T6G_MB_LIB.T6G(SCH_1):P5E_CPU1_P0_TX_DN(14)   I376 @T6G_MB_LIB.T6G(SCH_1):PAGE353

C809 Q_CAP_DIFFBUS_C0201-DIFF BUS_0.22UF,6.3V,20%,X6S,SA
     1 P5E_CPU1_P0_TX_C_DP<14> @T6G_MB_LIB.T6G(SCH_1):P5E_CPU1_P0_TX_C_DP(14)   I375 @T6G_MB_LIB.T6G(SCH_1):PAGE353
     2 P5E_CPU1_P0_TX_DP<14> @T6G_MB_LIB.T6G(SCH_1):P5E_CPU1_P0_TX_DP(14)   I375 @T6G_MB_LIB.T6G(SCH_1):PAGE353

C810 Q_CAP_DIFFBUS_C0201-DIFF BUS_0.22UF,6.3V,20%,X6S,SA
     1 P5E_CPU1_P0_TX_C_DN<13> @T6G_MB_LIB.T6G(SCH_1):P5E_CPU1_P0_TX_C_DN(13)   I374 @T6G_MB_LIB.T6G(SCH_1):PAGE353
     2 P5E_CPU1_P0_TX_DN<13> @T6G_MB_LIB.T6G(SCH_1):P5E_CPU1_P0_TX_DN(13)   I374 @T6G_MB_LIB.T6G(SCH_1):PAGE353

C811 Q_CAP_DIFFBUS_C0201-DIFF BUS_0.22UF,6.3V,20%,X6S,SA
     1 P5E_CPU1_P0_TX_C_DP<13> @T6G_MB_LIB.T6G(SCH_1):P5E_CPU1_P0_TX_C_DP(13)   I373 @T6G_MB_LIB.T6G(SCH_1):PAGE353
     2 P5E_CPU1_P0_TX_DP<13> @T6G_MB_LIB.T6G(SCH_1):P5E_CPU1_P0_TX_DP(13)   I373 @T6G_MB_LIB.T6G(SCH_1):PAGE353

C812 Q_CAP_DIFFBUS_C0201-DIFF BUS_0.22UF,6.3V,20%,X6S,SA
     1 P5E_CPU1_P0_TX_C_DN<12> @T6G_MB_LIB.T6G(SCH_1):P5E_CPU1_P0_TX_C_DN(12)   I371 @T6G_MB_LIB.T6G(SCH_1):PAGE353
     2 P5E_CPU1_P0_TX_DN<12> @T6G_MB_LIB.T6G(SCH_1):P5E_CPU1_P0_TX_DN(12)   I371 @T6G_MB_LIB.T6G(SCH_1):PAGE353

C813 Q_CAP_DIFFBUS_C0201-DIFF BUS_0.22UF,6.3V,20%,X6S,SA
     1 P5E_CPU1_P0_TX_C_DP<12> @T6G_MB_LIB.T6G(SCH_1):P5E_CPU1_P0_TX_C_DP(12)   I372 @T6G_MB_LIB.T6G(SCH_1):PAGE353
     2 P5E_CPU1_P0_TX_DP<12> @T6G_MB_LIB.T6G(SCH_1):P5E_CPU1_P0_TX_DP(12)   I372 @T6G_MB_LIB.T6G(SCH_1):PAGE353

C814 Q_CAP_DIFFBUS_C0201-DIFF BUS_0.22UF,6.3V,20%,X6S,SA
     1 P5E_CPU1_P0_TX_C_DN<11> @T6G_MB_LIB.T6G(SCH_1):P5E_CPU1_P0_TX_C_DN(11)   I370 @T6G_MB_LIB.T6G(SCH_1):PAGE353
     2 P5E_CPU1_P0_TX_DN<11> @T6G_MB_LIB.T6G(SCH_1):P5E_CPU1_P0_TX_DN(11)   I370 @T6G_MB_LIB.T6G(SCH_1):PAGE353

C815 Q_CAP_DIFFBUS_C0201-DIFF BUS_0.22UF,6.3V,20%,X6S,SA
     1 P5E_CPU1_P0_TX_C_DP<11> @T6G_MB_LIB.T6G(SCH_1):P5E_CPU1_P0_TX_C_DP(11)   I369 @T6G_MB_LIB.T6G(SCH_1):PAGE353
     2 P5E_CPU1_P0_TX_DP<11> @T6G_MB_LIB.T6G(SCH_1):P5E_CPU1_P0_TX_DP(11)   I369 @T6G_MB_LIB.T6G(SCH_1):PAGE353

C816 Q_CAP_DIFFBUS_C0201-DIFF BUS_0.22UF,6.3V,20%,X6S,SA
     1 P5E_CPU1_P0_TX_C_DN<10> @T6G_MB_LIB.T6G(SCH_1):P5E_CPU1_P0_TX_C_DN(10)   I368 @T6G_MB_LIB.T6G(SCH_1):PAGE353
     2 P5E_CPU1_P0_TX_DN<10> @T6G_MB_LIB.T6G(SCH_1):P5E_CPU1_P0_TX_DN(10)   I368 @T6G_MB_LIB.T6G(SCH_1):PAGE353

C817 Q_CAP_DIFFBUS_C0201-DIFF BUS_0.22UF,6.3V,20%,X6S,SA
     1 P5E_CPU1_P0_TX_C_DP<10> @T6G_MB_LIB.T6G(SCH_1):P5E_CPU1_P0_TX_C_DP(10)   I367 @T6G_MB_LIB.T6G(SCH_1):PAGE353
     2 P5E_CPU1_P0_TX_DP<10> @T6G_MB_LIB.T6G(SCH_1):P5E_CPU1_P0_TX_DP(10)   I367 @T6G_MB_LIB.T6G(SCH_1):PAGE353

C818 Q_CAP_DIFFBUS_C0201-DIFF BUS_0.22UF,6.3V,20%,X6S,SA
     1 P5E_CPU1_P0_TX_C_DN<9> @T6G_MB_LIB.T6G(SCH_1):P5E_CPU1_P0_TX_C_DN(9)   I365 @T6G_MB_LIB.T6G(SCH_1):PAGE353
     2 P5E_CPU1_P0_TX_DN<9> @T6G_MB_LIB.T6G(SCH_1):P5E_CPU1_P0_TX_DN(9)   I365 @T6G_MB_LIB.T6G(SCH_1):PAGE353

C819 Q_CAP_DIFFBUS_C0201-DIFF BUS_0.22UF,6.3V,20%,X6S,SA
     1 P5E_CPU1_P0_TX_C_DP<9> @T6G_MB_LIB.T6G(SCH_1):P5E_CPU1_P0_TX_C_DP(9)   I366 @T6G_MB_LIB.T6G(SCH_1):PAGE353
     2 P5E_CPU1_P0_TX_DP<9> @T6G_MB_LIB.T6G(SCH_1):P5E_CPU1_P0_TX_DP(9)   I366 @T6G_MB_LIB.T6G(SCH_1):PAGE353

C820 Q_CAP_DIFFBUS_C0201-DIFF BUS_0.22UF,6.3V,20%,X6S,SA
     1 P5E_CPU1_P0_TX_C_DN<8> @T6G_MB_LIB.T6G(SCH_1):P5E_CPU1_P0_TX_C_DN(8)   I363 @T6G_MB_LIB.T6G(SCH_1):PAGE353
     2 P5E_CPU1_P0_TX_DN<8> @T6G_MB_LIB.T6G(SCH_1):P5E_CPU1_P0_TX_DN(8)   I363 @T6G_MB_LIB.T6G(SCH_1):PAGE353

C821 Q_CAP_DIFFBUS_C0201-DIFF BUS_0.22UF,6.3V,20%,X6S,SA
     1 P5E_CPU1_P0_TX_C_DP<8> @T6G_MB_LIB.T6G(SCH_1):P5E_CPU1_P0_TX_C_DP(8)   I364 @T6G_MB_LIB.T6G(SCH_1):PAGE353
     2 P5E_CPU1_P0_TX_DP<8> @T6G_MB_LIB.T6G(SCH_1):P5E_CPU1_P0_TX_DP(8)   I364 @T6G_MB_LIB.T6G(SCH_1):PAGE353

C822 Q_CAP_DIFFBUS_C0201-DIFF BUS_0.22UF,6.3V,20%,X6S,SA
     1 P5E_CPU1_P0_TX_C_DN<7> @T6G_MB_LIB.T6G(SCH_1):P5E_CPU1_P0_TX_C_DN(7)   I345 @T6G_MB_LIB.T6G(SCH_1):PAGE353
     2 P5E_CPU1_P0_TX_DN<7> @T6G_MB_LIB.T6G(SCH_1):P5E_CPU1_P0_TX_DN(7)   I345 @T6G_MB_LIB.T6G(SCH_1):PAGE353

C823 Q_CAP_DIFFBUS_C0201-DIFF BUS_0.22UF,6.3V,20%,X6S,SA
     1 P5E_CPU1_P0_TX_C_DP<7> @T6G_MB_LIB.T6G(SCH_1):P5E_CPU1_P0_TX_C_DP(7)   I346 @T6G_MB_LIB.T6G(SCH_1):PAGE353
     2 P5E_CPU1_P0_TX_DP<7> @T6G_MB_LIB.T6G(SCH_1):P5E_CPU1_P0_TX_DP(7)   I346 @T6G_MB_LIB.T6G(SCH_1):PAGE353

C824 Q_CAP_DIFFBUS_C0201-DIFF BUS_0.22UF,6.3V,20%,X6S,SA
     1 P5E_CPU1_P0_TX_C_DN<6> @T6G_MB_LIB.T6G(SCH_1):P5E_CPU1_P0_TX_C_DN(6)   I416 @T6G_MB_LIB.T6G(SCH_1):PAGE353
     2 P5E_CPU1_P0_TX_DN<6> @T6G_MB_LIB.T6G(SCH_1):P5E_CPU1_P0_TX_DN(6)   I416 @T6G_MB_LIB.T6G(SCH_1):PAGE353

C825 Q_CAP_DIFFBUS_C0201-DIFF BUS_0.22UF,6.3V,20%,X6S,SA
     1 P5E_CPU1_P0_TX_C_DP<6> @T6G_MB_LIB.T6G(SCH_1):P5E_CPU1_P0_TX_C_DP(6)   I415 @T6G_MB_LIB.T6G(SCH_1):PAGE353
     2 P5E_CPU1_P0_TX_DP<6> @T6G_MB_LIB.T6G(SCH_1):P5E_CPU1_P0_TX_DP(6)   I415 @T6G_MB_LIB.T6G(SCH_1):PAGE353

C826 Q_CAP_DIFFBUS_C0201-DIFF BUS_0.22UF,6.3V,20%,X6S,SA
     1 P5E_CPU1_P0_TX_C_DN<5> @T6G_MB_LIB.T6G(SCH_1):P5E_CPU1_P0_TX_C_DN(5)   I344 @T6G_MB_LIB.T6G(SCH_1):PAGE353
     2 P5E_CPU1_P0_TX_DN<5> @T6G_MB_LIB.T6G(SCH_1):P5E_CPU1_P0_TX_DN(5)   I344 @T6G_MB_LIB.T6G(SCH_1):PAGE353

C827 Q_CAP_DIFFBUS_C0201-DIFF BUS_0.22UF,6.3V,20%,X6S,SA
     1 P5E_CPU1_P0_TX_C_DP<5> @T6G_MB_LIB.T6G(SCH_1):P5E_CPU1_P0_TX_C_DP(5)   I343 @T6G_MB_LIB.T6G(SCH_1):PAGE353
     2 P5E_CPU1_P0_TX_DP<5> @T6G_MB_LIB.T6G(SCH_1):P5E_CPU1_P0_TX_DP(5)   I343 @T6G_MB_LIB.T6G(SCH_1):PAGE353

C828 Q_CAP_DIFFBUS_C0201-DIFF BUS_0.22UF,6.3V,20%,X6S,SA
     1 P5E_CPU1_P0_TX_C_DN<4> @T6G_MB_LIB.T6G(SCH_1):P5E_CPU1_P0_TX_C_DN(4)   I340 @T6G_MB_LIB.T6G(SCH_1):PAGE353
     2 P5E_CPU1_P0_TX_DN<4> @T6G_MB_LIB.T6G(SCH_1):P5E_CPU1_P0_TX_DN(4)   I340 @T6G_MB_LIB.T6G(SCH_1):PAGE353

C829 Q_CAP_DIFFBUS_C0201-DIFF BUS_0.22UF,6.3V,20%,X6S,SA
     1 P5E_CPU1_P0_TX_C_DP<4> @T6G_MB_LIB.T6G(SCH_1):P5E_CPU1_P0_TX_C_DP(4)   I342 @T6G_MB_LIB.T6G(SCH_1):PAGE353
     2 P5E_CPU1_P0_TX_DP<4> @T6G_MB_LIB.T6G(SCH_1):P5E_CPU1_P0_TX_DP(4)   I342 @T6G_MB_LIB.T6G(SCH_1):PAGE353

C830 Q_CAP_DIFFBUS_C0201-DIFF BUS_0.22UF,6.3V,20%,X6S,SA
     1 P5E_CPU1_P0_TX_C_DN<3> @T6G_MB_LIB.T6G(SCH_1):P5E_CPU1_P0_TX_C_DN(3)   I341 @T6G_MB_LIB.T6G(SCH_1):PAGE353
     2 P5E_CPU1_P0_TX_DN<3> @T6G_MB_LIB.T6G(SCH_1):P5E_CPU1_P0_TX_DN(3)   I341 @T6G_MB_LIB.T6G(SCH_1):PAGE353

C831 Q_CAP_DIFFBUS_C0201-DIFF BUS_0.22UF,6.3V,20%,X6S,SA
     1 P5E_CPU1_P0_TX_C_DP<3> @T6G_MB_LIB.T6G(SCH_1):P5E_CPU1_P0_TX_C_DP(3)   I337 @T6G_MB_LIB.T6G(SCH_1):PAGE353
     2 P5E_CPU1_P0_TX_DP<3> @T6G_MB_LIB.T6G(SCH_1):P5E_CPU1_P0_TX_DP(3)   I337 @T6G_MB_LIB.T6G(SCH_1):PAGE353

C832 Q_CAP_DIFFBUS_C0201-DIFF BUS_0.22UF,6.3V,20%,X6S,SA
     1 P5E_CPU1_P0_TX_C_DN<2> @T6G_MB_LIB.T6G(SCH_1):P5E_CPU1_P0_TX_C_DN(2)   I338 @T6G_MB_LIB.T6G(SCH_1):PAGE353
     2 P5E_CPU1_P0_TX_DN<2> @T6G_MB_LIB.T6G(SCH_1):P5E_CPU1_P0_TX_DN(2)   I338 @T6G_MB_LIB.T6G(SCH_1):PAGE353

C833 Q_CAP_DIFFBUS_C0201-DIFF BUS_0.22UF,6.3V,20%,X6S,SA
     1 P5E_CPU1_P0_TX_C_DP<2> @T6G_MB_LIB.T6G(SCH_1):P5E_CPU1_P0_TX_C_DP(2)   I339 @T6G_MB_LIB.T6G(SCH_1):PAGE353
     2 P5E_CPU1_P0_TX_DP<2> @T6G_MB_LIB.T6G(SCH_1):P5E_CPU1_P0_TX_DP(2)   I339 @T6G_MB_LIB.T6G(SCH_1):PAGE353

C834 Q_CAP_DIFFBUS_C0201-DIFF BUS_0.22UF,6.3V,20%,X6S,SA
     1 P5E_CPU1_P0_TX_C_DN<1> @T6G_MB_LIB.T6G(SCH_1):P5E_CPU1_P0_TX_C_DN(1)   I335 @T6G_MB_LIB.T6G(SCH_1):PAGE353
     2 P5E_CPU1_P0_TX_DN<1> @T6G_MB_LIB.T6G(SCH_1):P5E_CPU1_P0_TX_DN(1)   I335 @T6G_MB_LIB.T6G(SCH_1):PAGE353

C835 Q_CAP_DIFFBUS_C0201-DIFF BUS_0.22UF,6.3V,20%,X6S,SA
     1 P5E_CPU1_P0_TX_C_DP<1> @T6G_MB_LIB.T6G(SCH_1):P5E_CPU1_P0_TX_C_DP(1)   I336 @T6G_MB_LIB.T6G(SCH_1):PAGE353
     2 P5E_CPU1_P0_TX_DP<1> @T6G_MB_LIB.T6G(SCH_1):P5E_CPU1_P0_TX_DP(1)   I336 @T6G_MB_LIB.T6G(SCH_1):PAGE353

C836 Q_CAP_DIFFBUS_C0201-DIFF BUS_0.22UF,6.3V,20%,X6S,SA
     1 P5E_CPU1_P0_TX_C_DN<0> @T6G_MB_LIB.T6G(SCH_1):P5E_CPU1_P0_TX_C_DN(0)   I333 @T6G_MB_LIB.T6G(SCH_1):PAGE353
     2 P5E_CPU1_P0_TX_DN<0> @T6G_MB_LIB.T6G(SCH_1):P5E_CPU1_P0_TX_DN(0)   I333 @T6G_MB_LIB.T6G(SCH_1):PAGE353

C837 Q_CAP_DIFFBUS_C0201-DIFF BUS_0.22UF,6.3V,20%,X6S,SA
     1 P5E_CPU1_P0_TX_C_DP<0> @T6G_MB_LIB.T6G(SCH_1):P5E_CPU1_P0_TX_C_DP(0)   I334 @T6G_MB_LIB.T6G(SCH_1):PAGE353
     2 P5E_CPU1_P0_TX_DP<0> @T6G_MB_LIB.T6G(SCH_1):P5E_CPU1_P0_TX_DP(0)   I334 @T6G_MB_LIB.T6G(SCH_1):PAGE353

C838 Q_CAP_DIFFBUS_C0201-DIFF BUS_0.22UF,6.3V,20%,X6S,SA
     1 P5E_CPU0_P2_TX_C_DN<15> @T6G_MB_LIB.T6G(SCH_1):P5E_CPU0_P2_TX_C_DN(15)    I80 @T6G_MB_LIB.T6G(SCH_1):PAGE352
     2 P5E_CPU0_P2_TX_DN<15> @T6G_MB_LIB.T6G(SCH_1):P5E_CPU0_P2_TX_DN(15)    I80 @T6G_MB_LIB.T6G(SCH_1):PAGE352

C839 Q_CAP_DIFFBUS_C0201-DIFF BUS_0.22UF,6.3V,20%,X6S,SA
     1 P5E_CPU0_P2_TX_C_DP<15> @T6G_MB_LIB.T6G(SCH_1):P5E_CPU0_P2_TX_C_DP(15)    I81 @T6G_MB_LIB.T6G(SCH_1):PAGE352
     2 P5E_CPU0_P2_TX_DP<15> @T6G_MB_LIB.T6G(SCH_1):P5E_CPU0_P2_TX_DP(15)    I81 @T6G_MB_LIB.T6G(SCH_1):PAGE352

C840 Q_CAP_DIFFBUS_C0201-DIFF BUS_0.22UF,6.3V,20%,X6S,SA
     1 P5E_CPU0_P2_TX_C_DN<14> @T6G_MB_LIB.T6G(SCH_1):P5E_CPU0_P2_TX_C_DN(14)    I79 @T6G_MB_LIB.T6G(SCH_1):PAGE352
     2 P5E_CPU0_P2_TX_DN<14> @T6G_MB_LIB.T6G(SCH_1):P5E_CPU0_P2_TX_DN(14)    I79 @T6G_MB_LIB.T6G(SCH_1):PAGE352

C841 Q_CAP_DIFFBUS_C0201-DIFF BUS_0.22UF,6.3V,20%,X6S,SA
     1 P5E_CPU0_P2_TX_C_DP<14> @T6G_MB_LIB.T6G(SCH_1):P5E_CPU0_P2_TX_C_DP(14)    I78 @T6G_MB_LIB.T6G(SCH_1):PAGE352
     2 P5E_CPU0_P2_TX_DP<14> @T6G_MB_LIB.T6G(SCH_1):P5E_CPU0_P2_TX_DP(14)    I78 @T6G_MB_LIB.T6G(SCH_1):PAGE352

C842 Q_CAP_DIFFBUS_C0201-DIFF BUS_0.22UF,6.3V,20%,X6S,SA
     1 P5E_CPU0_P2_TX_C_DN<13> @T6G_MB_LIB.T6G(SCH_1):P5E_CPU0_P2_TX_C_DN(13)    I76 @T6G_MB_LIB.T6G(SCH_1):PAGE352
     2 P5E_CPU0_P2_TX_DN<13> @T6G_MB_LIB.T6G(SCH_1):P5E_CPU0_P2_TX_DN(13)    I76 @T6G_MB_LIB.T6G(SCH_1):PAGE352

C843 Q_CAP_DIFFBUS_C0201-DIFF BUS_0.22UF,6.3V,20%,X6S,SA
     1 P5E_CPU0_P2_TX_C_DP<13> @T6G_MB_LIB.T6G(SCH_1):P5E_CPU0_P2_TX_C_DP(13)    I77 @T6G_MB_LIB.T6G(SCH_1):PAGE352
     2 P5E_CPU0_P2_TX_DP<13> @T6G_MB_LIB.T6G(SCH_1):P5E_CPU0_P2_TX_DP(13)    I77 @T6G_MB_LIB.T6G(SCH_1):PAGE352

C844 Q_CAP_DIFFBUS_C0201-DIFF BUS_0.22UF,6.3V,20%,X6S,SA
     1 P5E_CPU0_P2_TX_C_DN<12> @T6G_MB_LIB.T6G(SCH_1):P5E_CPU0_P2_TX_C_DN(12)    I70 @T6G_MB_LIB.T6G(SCH_1):PAGE352
     2 P5E_CPU0_P2_TX_DN<12> @T6G_MB_LIB.T6G(SCH_1):P5E_CPU0_P2_TX_DN(12)    I70 @T6G_MB_LIB.T6G(SCH_1):PAGE352

C845 Q_CAP_DIFFBUS_C0201-DIFF BUS_0.22UF,6.3V,20%,X6S,SA
     1 P5E_CPU0_P2_TX_C_DP<12> @T6G_MB_LIB.T6G(SCH_1):P5E_CPU0_P2_TX_C_DP(12)    I69 @T6G_MB_LIB.T6G(SCH_1):PAGE352
     2 P5E_CPU0_P2_TX_DP<12> @T6G_MB_LIB.T6G(SCH_1):P5E_CPU0_P2_TX_DP(12)    I69 @T6G_MB_LIB.T6G(SCH_1):PAGE352

C846 Q_CAP_DIFFBUS_C0201-DIFF BUS_0.22UF,6.3V,20%,X6S,SA
     1 P5E_CPU0_P2_TX_C_DN<11> @T6G_MB_LIB.T6G(SCH_1):P5E_CPU0_P2_TX_C_DN(11)    I68 @T6G_MB_LIB.T6G(SCH_1):PAGE352
     2 P5E_CPU0_P2_TX_DN<11> @T6G_MB_LIB.T6G(SCH_1):P5E_CPU0_P2_TX_DN(11)    I68 @T6G_MB_LIB.T6G(SCH_1):PAGE352

C847 Q_CAP_DIFFBUS_C0201-DIFF BUS_0.22UF,6.3V,20%,X6S,SA
     1 P5E_CPU0_P2_TX_C_DP<11> @T6G_MB_LIB.T6G(SCH_1):P5E_CPU0_P2_TX_C_DP(11)    I67 @T6G_MB_LIB.T6G(SCH_1):PAGE352
     2 P5E_CPU0_P2_TX_DP<11> @T6G_MB_LIB.T6G(SCH_1):P5E_CPU0_P2_TX_DP(11)    I67 @T6G_MB_LIB.T6G(SCH_1):PAGE352

C848 Q_CAP_DIFFBUS_C0201-DIFF BUS_0.22UF,6.3V,20%,X6S,SA
     1 P5E_CPU0_P2_TX_C_DN<10> @T6G_MB_LIB.T6G(SCH_1):P5E_CPU0_P2_TX_C_DN(10)    I66 @T6G_MB_LIB.T6G(SCH_1):PAGE352
     2 P5E_CPU0_P2_TX_DN<10> @T6G_MB_LIB.T6G(SCH_1):P5E_CPU0_P2_TX_DN(10)    I66 @T6G_MB_LIB.T6G(SCH_1):PAGE352

C849 Q_CAP_DIFFBUS_C0201-DIFF BUS_0.22UF,6.3V,20%,X6S,SA
     1 P5E_CPU0_P2_TX_C_DP<10> @T6G_MB_LIB.T6G(SCH_1):P5E_CPU0_P2_TX_C_DP(10)    I65 @T6G_MB_LIB.T6G(SCH_1):PAGE352
     2 P5E_CPU0_P2_TX_DP<10> @T6G_MB_LIB.T6G(SCH_1):P5E_CPU0_P2_TX_DP(10)    I65 @T6G_MB_LIB.T6G(SCH_1):PAGE352

C850 Q_CAP_DIFFBUS_C0201-DIFF BUS_0.22UF,6.3V,20%,X6S,SA
     1 P5E_CPU0_P2_TX_C_DN<9> @T6G_MB_LIB.T6G(SCH_1):P5E_CPU0_P2_TX_C_DN(9)    I64 @T6G_MB_LIB.T6G(SCH_1):PAGE352
     2 P5E_CPU0_P2_TX_DN<9> @T6G_MB_LIB.T6G(SCH_1):P5E_CPU0_P2_TX_DN(9)    I64 @T6G_MB_LIB.T6G(SCH_1):PAGE352

C851 Q_CAP_DIFFBUS_C0201-DIFF BUS_0.22UF,6.3V,20%,X6S,SA
     1 P5E_CPU0_P2_TX_C_DP<9> @T6G_MB_LIB.T6G(SCH_1):P5E_CPU0_P2_TX_C_DP(9)    I63 @T6G_MB_LIB.T6G(SCH_1):PAGE352
     2 P5E_CPU0_P2_TX_DP<9> @T6G_MB_LIB.T6G(SCH_1):P5E_CPU0_P2_TX_DP(9)    I63 @T6G_MB_LIB.T6G(SCH_1):PAGE352

C852 Q_CAP_DIFFBUS_C0201-DIFF BUS_0.22UF,6.3V,20%,X6S,SA
     1 P5E_CPU0_P2_TX_C_DN<8> @T6G_MB_LIB.T6G(SCH_1):P5E_CPU0_P2_TX_C_DN(8)    I61 @T6G_MB_LIB.T6G(SCH_1):PAGE352
     2 P5E_CPU0_P2_TX_DN<8> @T6G_MB_LIB.T6G(SCH_1):P5E_CPU0_P2_TX_DN(8)    I61 @T6G_MB_LIB.T6G(SCH_1):PAGE352

C853 Q_CAP_DIFFBUS_C0201-DIFF BUS_0.22UF,6.3V,20%,X6S,SA
     1 P5E_CPU0_P2_TX_C_DP<8> @T6G_MB_LIB.T6G(SCH_1):P5E_CPU0_P2_TX_C_DP(8)    I62 @T6G_MB_LIB.T6G(SCH_1):PAGE352
     2 P5E_CPU0_P2_TX_DP<8> @T6G_MB_LIB.T6G(SCH_1):P5E_CPU0_P2_TX_DP(8)    I62 @T6G_MB_LIB.T6G(SCH_1):PAGE352

C854 Q_CAP_DIFFBUS_C0201-DIFF BUS_0.22UF,6.3V,20%,X6S,SA
     1 P5E_CPU0_P2_TX_C_DN<7> @T6G_MB_LIB.T6G(SCH_1):P5E_CPU0_P2_TX_C_DN(7)    I41 @T6G_MB_LIB.T6G(SCH_1):PAGE352
     2 P5E_CPU0_P2_TX_DN<7> @T6G_MB_LIB.T6G(SCH_1):P5E_CPU0_P2_TX_DN(7)    I41 @T6G_MB_LIB.T6G(SCH_1):PAGE352

C855 Q_CAP_DIFFBUS_C0201-DIFF BUS_0.22UF,6.3V,20%,X6S,SA
     1 P5E_CPU0_P2_TX_C_DP<7> @T6G_MB_LIB.T6G(SCH_1):P5E_CPU0_P2_TX_C_DP(7)    I40 @T6G_MB_LIB.T6G(SCH_1):PAGE352
     2 P5E_CPU0_P2_TX_DP<7> @T6G_MB_LIB.T6G(SCH_1):P5E_CPU0_P2_TX_DP(7)    I40 @T6G_MB_LIB.T6G(SCH_1):PAGE352

C856 Q_CAP_DIFFBUS_C0201-DIFF BUS_0.22UF,6.3V,20%,X6S,SA
     1 P5E_CPU0_P2_TX_C_DN<6> @T6G_MB_LIB.T6G(SCH_1):P5E_CPU0_P2_TX_C_DN(6)    I39 @T6G_MB_LIB.T6G(SCH_1):PAGE352
     2 P5E_CPU0_P2_TX_DN<6> @T6G_MB_LIB.T6G(SCH_1):P5E_CPU0_P2_TX_DN(6)    I39 @T6G_MB_LIB.T6G(SCH_1):PAGE352

C857 Q_CAP_DIFFBUS_C0201-DIFF BUS_0.22UF,6.3V,20%,X6S,SA
     1 P5E_CPU0_P2_TX_C_DP<6> @T6G_MB_LIB.T6G(SCH_1):P5E_CPU0_P2_TX_C_DP(6)    I38 @T6G_MB_LIB.T6G(SCH_1):PAGE352
     2 P5E_CPU0_P2_TX_DP<6> @T6G_MB_LIB.T6G(SCH_1):P5E_CPU0_P2_TX_DP(6)    I38 @T6G_MB_LIB.T6G(SCH_1):PAGE352

C858 Q_CAP_DIFFBUS_C0201-DIFF BUS_0.22UF,6.3V,20%,X6S,SA
     1 P5E_CPU0_P2_TX_C_DN<5> @T6G_MB_LIB.T6G(SCH_1):P5E_CPU0_P2_TX_C_DN(5)    I37 @T6G_MB_LIB.T6G(SCH_1):PAGE352
     2 P5E_CPU0_P2_TX_DN<5> @T6G_MB_LIB.T6G(SCH_1):P5E_CPU0_P2_TX_DN(5)    I37 @T6G_MB_LIB.T6G(SCH_1):PAGE352

C859 Q_CAP_DIFFBUS_C0201-DIFF BUS_0.22UF,6.3V,20%,X6S,SA
     1 P5E_CPU0_P2_TX_C_DP<5> @T6G_MB_LIB.T6G(SCH_1):P5E_CPU0_P2_TX_C_DP(5)    I36 @T6G_MB_LIB.T6G(SCH_1):PAGE352
     2 P5E_CPU0_P2_TX_DP<5> @T6G_MB_LIB.T6G(SCH_1):P5E_CPU0_P2_TX_DP(5)    I36 @T6G_MB_LIB.T6G(SCH_1):PAGE352

C860 Q_CAP_DIFFBUS_C0201-DIFF BUS_0.22UF,6.3V,20%,X6S,SA
     1 P5E_CPU0_P2_TX_C_DN<4> @T6G_MB_LIB.T6G(SCH_1):P5E_CPU0_P2_TX_C_DN(4)    I30 @T6G_MB_LIB.T6G(SCH_1):PAGE352
     2 P5E_CPU0_P2_TX_DN<4> @T6G_MB_LIB.T6G(SCH_1):P5E_CPU0_P2_TX_DN(4)    I30 @T6G_MB_LIB.T6G(SCH_1):PAGE352

C861 Q_CAP_DIFFBUS_C0201-DIFF BUS_0.22UF,6.3V,20%,X6S,SA
     1 P5E_CPU0_P2_TX_C_DP<4> @T6G_MB_LIB.T6G(SCH_1):P5E_CPU0_P2_TX_C_DP(4)    I29 @T6G_MB_LIB.T6G(SCH_1):PAGE352
     2 P5E_CPU0_P2_TX_DP<4> @T6G_MB_LIB.T6G(SCH_1):P5E_CPU0_P2_TX_DP(4)    I29 @T6G_MB_LIB.T6G(SCH_1):PAGE352

C862 Q_CAP_DIFFBUS_C0201-DIFF BUS_0.22UF,6.3V,20%,X6S,SA
     1 P5E_CPU0_P2_TX_C_DN<3> @T6G_MB_LIB.T6G(SCH_1):P5E_CPU0_P2_TX_C_DN(3)    I28 @T6G_MB_LIB.T6G(SCH_1):PAGE352
     2 P5E_CPU0_P2_TX_DN<3> @T6G_MB_LIB.T6G(SCH_1):P5E_CPU0_P2_TX_DN(3)    I28 @T6G_MB_LIB.T6G(SCH_1):PAGE352

C863 Q_CAP_DIFFBUS_C0201-DIFF BUS_0.22UF,6.3V,20%,X6S,SA
     1 P5E_CPU0_P2_TX_C_DP<3> @T6G_MB_LIB.T6G(SCH_1):P5E_CPU0_P2_TX_C_DP(3)    I27 @T6G_MB_LIB.T6G(SCH_1):PAGE352
     2 P5E_CPU0_P2_TX_DP<3> @T6G_MB_LIB.T6G(SCH_1):P5E_CPU0_P2_TX_DP(3)    I27 @T6G_MB_LIB.T6G(SCH_1):PAGE352

C864 Q_CAP_DIFFBUS_C0201-DIFF BUS_0.22UF,6.3V,20%,X6S,SA
     1 P5E_CPU0_P2_TX_C_DN<2> @T6G_MB_LIB.T6G(SCH_1):P5E_CPU0_P2_TX_C_DN(2)    I25 @T6G_MB_LIB.T6G(SCH_1):PAGE352
     2 P5E_CPU0_P2_TX_DN<2> @T6G_MB_LIB.T6G(SCH_1):P5E_CPU0_P2_TX_DN(2)    I25 @T6G_MB_LIB.T6G(SCH_1):PAGE352

C865 Q_CAP_DIFFBUS_C0201-DIFF BUS_0.22UF,6.3V,20%,X6S,SA
     1 P5E_CPU0_P2_TX_C_DP<2> @T6G_MB_LIB.T6G(SCH_1):P5E_CPU0_P2_TX_C_DP(2)    I26 @T6G_MB_LIB.T6G(SCH_1):PAGE352
     2 P5E_CPU0_P2_TX_DP<2> @T6G_MB_LIB.T6G(SCH_1):P5E_CPU0_P2_TX_DP(2)    I26 @T6G_MB_LIB.T6G(SCH_1):PAGE352

C866 Q_CAP_DIFFBUS_C0201-DIFF BUS_0.22UF,6.3V,20%,X6S,SA
     1 P5E_CPU0_P2_TX_C_DN<1> @T6G_MB_LIB.T6G(SCH_1):P5E_CPU0_P2_TX_C_DN(1)    I24 @T6G_MB_LIB.T6G(SCH_1):PAGE352
     2 P5E_CPU0_P2_TX_DN<1> @T6G_MB_LIB.T6G(SCH_1):P5E_CPU0_P2_TX_DN(1)    I24 @T6G_MB_LIB.T6G(SCH_1):PAGE352

C867 Q_CAP_DIFFBUS_C0201-DIFF BUS_0.22UF,6.3V,20%,X6S,SA
     1 P5E_CPU0_P2_TX_C_DP<1> @T6G_MB_LIB.T6G(SCH_1):P5E_CPU0_P2_TX_C_DP(1)    I23 @T6G_MB_LIB.T6G(SCH_1):PAGE352
     2 P5E_CPU0_P2_TX_DP<1> @T6G_MB_LIB.T6G(SCH_1):P5E_CPU0_P2_TX_DP(1)    I23 @T6G_MB_LIB.T6G(SCH_1):PAGE352

C868 Q_CAP_DIFFBUS_C0201-DIFF BUS_0.22UF,6.3V,20%,X6S,SA
     1 P5E_CPU0_P2_TX_C_DN<0> @T6G_MB_LIB.T6G(SCH_1):P5E_CPU0_P2_TX_C_DN(0)    I22 @T6G_MB_LIB.T6G(SCH_1):PAGE352
     2 P5E_CPU0_P2_TX_DN<0> @T6G_MB_LIB.T6G(SCH_1):P5E_CPU0_P2_TX_DN(0)    I22 @T6G_MB_LIB.T6G(SCH_1):PAGE352

C869 Q_CAP_DIFFBUS_C0201-DIFF BUS_0.22UF,6.3V,20%,X6S,SA
     1 P5E_CPU0_P2_TX_C_DP<0> @T6G_MB_LIB.T6G(SCH_1):P5E_CPU0_P2_TX_C_DP(0)    I21 @T6G_MB_LIB.T6G(SCH_1):PAGE352
     2 P5E_CPU0_P2_TX_DP<0> @T6G_MB_LIB.T6G(SCH_1):P5E_CPU0_P2_TX_DP(0)    I21 @T6G_MB_LIB.T6G(SCH_1):PAGE352

C870 Q_CAP_DIFFBUS_C0201-DIFF BUS_0.22UF,6.3V,20%,X6S,SA
     1 P5E_CPU0_P3_TX_C_DN<15> @T6G_MB_LIB.T6G(SCH_1):P5E_CPU0_P3_TX_C_DN(15)   I169 @T6G_MB_LIB.T6G(SCH_1):PAGE352
     2 P5E_CPU0_P3_TX_DN<15> @T6G_MB_LIB.T6G(SCH_1):P5E_CPU0_P3_TX_DN(15)   I169 @T6G_MB_LIB.T6G(SCH_1):PAGE352

C871 Q_CAP_DIFFBUS_C0201-DIFF BUS_0.22UF,6.3V,20%,X6S,SA
     1 P5E_CPU0_P3_TX_C_DP<15> @T6G_MB_LIB.T6G(SCH_1):P5E_CPU0_P3_TX_C_DP(15)   I168 @T6G_MB_LIB.T6G(SCH_1):PAGE352
     2 P5E_CPU0_P3_TX_DP<15> @T6G_MB_LIB.T6G(SCH_1):P5E_CPU0_P3_TX_DP(15)   I168 @T6G_MB_LIB.T6G(SCH_1):PAGE352

C872 Q_CAP_DIFFBUS_C0201-DIFF BUS_0.22UF,6.3V,20%,X6S,SA
     1 P5E_CPU0_P3_TX_C_DN<14> @T6G_MB_LIB.T6G(SCH_1):P5E_CPU0_P3_TX_C_DN(14)   I167 @T6G_MB_LIB.T6G(SCH_1):PAGE352
     2 P5E_CPU0_P3_TX_DN<14> @T6G_MB_LIB.T6G(SCH_1):P5E_CPU0_P3_TX_DN(14)   I167 @T6G_MB_LIB.T6G(SCH_1):PAGE352

C873 Q_CAP_DIFFBUS_C0201-DIFF BUS_0.22UF,6.3V,20%,X6S,SA
     1 P5E_CPU0_P3_TX_C_DP<14> @T6G_MB_LIB.T6G(SCH_1):P5E_CPU0_P3_TX_C_DP(14)   I166 @T6G_MB_LIB.T6G(SCH_1):PAGE352
     2 P5E_CPU0_P3_TX_DP<14> @T6G_MB_LIB.T6G(SCH_1):P5E_CPU0_P3_TX_DP(14)   I166 @T6G_MB_LIB.T6G(SCH_1):PAGE352

C874 Q_CAP_DIFFBUS_C0201-DIFF BUS_0.22UF,6.3V,20%,X6S,SA
     1 P5E_CPU0_P3_TX_C_DN<13> @T6G_MB_LIB.T6G(SCH_1):P5E_CPU0_P3_TX_C_DN(13)   I165 @T6G_MB_LIB.T6G(SCH_1):PAGE352
     2 P5E_CPU0_P3_TX_DN<13> @T6G_MB_LIB.T6G(SCH_1):P5E_CPU0_P3_TX_DN(13)   I165 @T6G_MB_LIB.T6G(SCH_1):PAGE352

C875 Q_CAP_DIFFBUS_C0201-DIFF BUS_0.22UF,6.3V,20%,X6S,SA
     1 P5E_CPU0_P3_TX_C_DP<13> @T6G_MB_LIB.T6G(SCH_1):P5E_CPU0_P3_TX_C_DP(13)   I164 @T6G_MB_LIB.T6G(SCH_1):PAGE352
     2 P5E_CPU0_P3_TX_DP<13> @T6G_MB_LIB.T6G(SCH_1):P5E_CPU0_P3_TX_DP(13)   I164 @T6G_MB_LIB.T6G(SCH_1):PAGE352

C876 Q_CAP_DIFFBUS_C0201-DIFF BUS_0.22UF,6.3V,20%,X6S,SA
     1 P5E_CPU0_P3_TX_C_DN<12> @T6G_MB_LIB.T6G(SCH_1):P5E_CPU0_P3_TX_C_DN(12)   I160 @T6G_MB_LIB.T6G(SCH_1):PAGE352
     2 P5E_CPU0_P3_TX_DN<12> @T6G_MB_LIB.T6G(SCH_1):P5E_CPU0_P3_TX_DN(12)   I160 @T6G_MB_LIB.T6G(SCH_1):PAGE352

C877 Q_CAP_DIFFBUS_C0201-DIFF BUS_0.22UF,6.3V,20%,X6S,SA
     1 P5E_CPU0_P3_TX_C_DP<12> @T6G_MB_LIB.T6G(SCH_1):P5E_CPU0_P3_TX_C_DP(12)   I159 @T6G_MB_LIB.T6G(SCH_1):PAGE352
     2 P5E_CPU0_P3_TX_DP<12> @T6G_MB_LIB.T6G(SCH_1):P5E_CPU0_P3_TX_DP(12)   I159 @T6G_MB_LIB.T6G(SCH_1):PAGE352

C878 Q_CAP_DIFFBUS_C0201-DIFF BUS_0.22UF,6.3V,20%,X6S,SA
     1 P5E_CPU0_P3_TX_C_DN<11> @T6G_MB_LIB.T6G(SCH_1):P5E_CPU0_P3_TX_C_DN(11)   I157 @T6G_MB_LIB.T6G(SCH_1):PAGE352
     2 P5E_CPU0_P3_TX_DN<11> @T6G_MB_LIB.T6G(SCH_1):P5E_CPU0_P3_TX_DN(11)   I157 @T6G_MB_LIB.T6G(SCH_1):PAGE352

C879 Q_CAP_DIFFBUS_C0201-DIFF BUS_0.22UF,6.3V,20%,X6S,SA
     1 P5E_CPU0_P3_TX_C_DP<11> @T6G_MB_LIB.T6G(SCH_1):P5E_CPU0_P3_TX_C_DP(11)   I158 @T6G_MB_LIB.T6G(SCH_1):PAGE352
     2 P5E_CPU0_P3_TX_DP<11> @T6G_MB_LIB.T6G(SCH_1):P5E_CPU0_P3_TX_DP(11)   I158 @T6G_MB_LIB.T6G(SCH_1):PAGE352

C880 Q_CAP_DIFFBUS_C0201-DIFF BUS_0.22UF,6.3V,20%,X6S,SA
     1 P5E_CPU0_P3_TX_C_DN<10> @T6G_MB_LIB.T6G(SCH_1):P5E_CPU0_P3_TX_C_DN(10)   I156 @T6G_MB_LIB.T6G(SCH_1):PAGE352
     2 P5E_CPU0_P3_TX_DN<10> @T6G_MB_LIB.T6G(SCH_1):P5E_CPU0_P3_TX_DN(10)   I156 @T6G_MB_LIB.T6G(SCH_1):PAGE352

C881 Q_CAP_DIFFBUS_C0201-DIFF BUS_0.22UF,6.3V,20%,X6S,SA
     1 P5E_CPU0_P3_TX_C_DP<10> @T6G_MB_LIB.T6G(SCH_1):P5E_CPU0_P3_TX_C_DP(10)   I155 @T6G_MB_LIB.T6G(SCH_1):PAGE352
     2 P5E_CPU0_P3_TX_DP<10> @T6G_MB_LIB.T6G(SCH_1):P5E_CPU0_P3_TX_DP(10)   I155 @T6G_MB_LIB.T6G(SCH_1):PAGE352

C882 Q_CAP_DIFFBUS_C0201-DIFF BUS_0.22UF,6.3V,20%,X6S,SA
     1 P5E_CPU0_P3_TX_C_DN<9> @T6G_MB_LIB.T6G(SCH_1):P5E_CPU0_P3_TX_C_DN(9)   I154 @T6G_MB_LIB.T6G(SCH_1):PAGE352
     2 P5E_CPU0_P3_TX_DN<9> @T6G_MB_LIB.T6G(SCH_1):P5E_CPU0_P3_TX_DN(9)   I154 @T6G_MB_LIB.T6G(SCH_1):PAGE352

C883 Q_CAP_DIFFBUS_C0201-DIFF BUS_0.22UF,6.3V,20%,X6S,SA
     1 P5E_CPU0_P3_TX_C_DP<9> @T6G_MB_LIB.T6G(SCH_1):P5E_CPU0_P3_TX_C_DP(9)   I153 @T6G_MB_LIB.T6G(SCH_1):PAGE352
     2 P5E_CPU0_P3_TX_DP<9> @T6G_MB_LIB.T6G(SCH_1):P5E_CPU0_P3_TX_DP(9)   I153 @T6G_MB_LIB.T6G(SCH_1):PAGE352

C884 Q_CAP_DIFFBUS_C0201-DIFF BUS_0.22UF,6.3V,20%,X6S,SA
     1 P5E_CPU0_P3_TX_C_DN<8> @T6G_MB_LIB.T6G(SCH_1):P5E_CPU0_P3_TX_C_DN(8)   I151 @T6G_MB_LIB.T6G(SCH_1):PAGE352
     2 P5E_CPU0_P3_TX_DN<8> @T6G_MB_LIB.T6G(SCH_1):P5E_CPU0_P3_TX_DN(8)   I151 @T6G_MB_LIB.T6G(SCH_1):PAGE352

C885 Q_CAP_DIFFBUS_C0201-DIFF BUS_0.22UF,6.3V,20%,X6S,SA
     1 P5E_CPU0_P3_TX_C_DP<8> @T6G_MB_LIB.T6G(SCH_1):P5E_CPU0_P3_TX_C_DP(8)   I152 @T6G_MB_LIB.T6G(SCH_1):PAGE352
     2 P5E_CPU0_P3_TX_DP<8> @T6G_MB_LIB.T6G(SCH_1):P5E_CPU0_P3_TX_DP(8)   I152 @T6G_MB_LIB.T6G(SCH_1):PAGE352

C886 Q_CAP_DIFFBUS_C0201-DIFF BUS_0.22UF,6.3V,20%,X6S,SA
     1 P5E_CPU0_P3_TX_C_DN<7> @T6G_MB_LIB.T6G(SCH_1):P5E_CPU0_P3_TX_C_DN(7)   I137 @T6G_MB_LIB.T6G(SCH_1):PAGE352
     2 P5E_CPU0_P3_TX_DN<7> @T6G_MB_LIB.T6G(SCH_1):P5E_CPU0_P3_TX_DN(7)   I137 @T6G_MB_LIB.T6G(SCH_1):PAGE352

C887 Q_CAP_DIFFBUS_C0201-DIFF BUS_0.22UF,6.3V,20%,X6S,SA
     1 P5E_CPU0_P3_TX_C_DP<7> @T6G_MB_LIB.T6G(SCH_1):P5E_CPU0_P3_TX_C_DP(7)   I136 @T6G_MB_LIB.T6G(SCH_1):PAGE352
     2 P5E_CPU0_P3_TX_DP<7> @T6G_MB_LIB.T6G(SCH_1):P5E_CPU0_P3_TX_DP(7)   I136 @T6G_MB_LIB.T6G(SCH_1):PAGE352

C888 Q_CAP_DIFFBUS_C0201-DIFF BUS_0.22UF,6.3V,20%,X6S,SA
     1 P5E_CPU0_P3_TX_C_DN<6> @T6G_MB_LIB.T6G(SCH_1):P5E_CPU0_P3_TX_C_DN(6)   I135 @T6G_MB_LIB.T6G(SCH_1):PAGE352
     2 P5E_CPU0_P3_TX_DN<6> @T6G_MB_LIB.T6G(SCH_1):P5E_CPU0_P3_TX_DN(6)   I135 @T6G_MB_LIB.T6G(SCH_1):PAGE352

C889 Q_CAP_DIFFBUS_C0201-DIFF BUS_0.22UF,6.3V,20%,X6S,SA
     1 P5E_CPU0_P3_TX_C_DP<6> @T6G_MB_LIB.T6G(SCH_1):P5E_CPU0_P3_TX_C_DP(6)   I134 @T6G_MB_LIB.T6G(SCH_1):PAGE352
     2 P5E_CPU0_P3_TX_DP<6> @T6G_MB_LIB.T6G(SCH_1):P5E_CPU0_P3_TX_DP(6)   I134 @T6G_MB_LIB.T6G(SCH_1):PAGE352

C890 Q_CAP_DIFFBUS_C0201-DIFF BUS_0.22UF,6.3V,20%,X6S,SA
     1 P5E_CPU0_P3_TX_C_DN<5> @T6G_MB_LIB.T6G(SCH_1):P5E_CPU0_P3_TX_C_DN(5)   I133 @T6G_MB_LIB.T6G(SCH_1):PAGE352
     2 P5E_CPU0_P3_TX_DN<5> @T6G_MB_LIB.T6G(SCH_1):P5E_CPU0_P3_TX_DN(5)   I133 @T6G_MB_LIB.T6G(SCH_1):PAGE352

C891 Q_CAP_DIFFBUS_C0201-DIFF BUS_0.22UF,6.3V,20%,X6S,SA
     1 P5E_CPU0_P3_TX_C_DP<5> @T6G_MB_LIB.T6G(SCH_1):P5E_CPU0_P3_TX_C_DP(5)   I132 @T6G_MB_LIB.T6G(SCH_1):PAGE352
     2 P5E_CPU0_P3_TX_DP<5> @T6G_MB_LIB.T6G(SCH_1):P5E_CPU0_P3_TX_DP(5)   I132 @T6G_MB_LIB.T6G(SCH_1):PAGE352

C892 Q_CAP_DIFFBUS_C0201-DIFF BUS_0.22UF,6.3V,20%,X6S,SA
     1 P5E_CPU0_P3_TX_C_DN<4> @T6G_MB_LIB.T6G(SCH_1):P5E_CPU0_P3_TX_C_DN(4)   I127 @T6G_MB_LIB.T6G(SCH_1):PAGE352
     2 P5E_CPU0_P3_TX_DN<4> @T6G_MB_LIB.T6G(SCH_1):P5E_CPU0_P3_TX_DN(4)   I127 @T6G_MB_LIB.T6G(SCH_1):PAGE352

C893 Q_CAP_DIFFBUS_C0201-DIFF BUS_0.22UF,6.3V,20%,X6S,SA
     1 P5E_CPU0_P3_TX_C_DP<4> @T6G_MB_LIB.T6G(SCH_1):P5E_CPU0_P3_TX_C_DP(4)   I128 @T6G_MB_LIB.T6G(SCH_1):PAGE352
     2 P5E_CPU0_P3_TX_DP<4> @T6G_MB_LIB.T6G(SCH_1):P5E_CPU0_P3_TX_DP(4)   I128 @T6G_MB_LIB.T6G(SCH_1):PAGE352

C894 Q_CAP_DIFFBUS_C0201-DIFF BUS_0.22UF,6.3V,20%,X6S,SA
     1 P5E_CPU0_P3_TX_C_DN<3> @T6G_MB_LIB.T6G(SCH_1):P5E_CPU0_P3_TX_C_DN(3)   I126 @T6G_MB_LIB.T6G(SCH_1):PAGE352
     2 P5E_CPU0_P3_TX_DN<3> @T6G_MB_LIB.T6G(SCH_1):P5E_CPU0_P3_TX_DN(3)   I126 @T6G_MB_LIB.T6G(SCH_1):PAGE352

C895 Q_CAP_DIFFBUS_C0201-DIFF BUS_0.22UF,6.3V,20%,X6S,SA
     1 P5E_CPU0_P3_TX_C_DP<3> @T6G_MB_LIB.T6G(SCH_1):P5E_CPU0_P3_TX_C_DP(3)   I125 @T6G_MB_LIB.T6G(SCH_1):PAGE352
     2 P5E_CPU0_P3_TX_DP<3> @T6G_MB_LIB.T6G(SCH_1):P5E_CPU0_P3_TX_DP(3)   I125 @T6G_MB_LIB.T6G(SCH_1):PAGE352

C896 Q_CAP_DIFFBUS_C0201-DIFF BUS_0.22UF,6.3V,20%,X6S,SA
     1 P5E_CPU0_P3_TX_C_DN<2> @T6G_MB_LIB.T6G(SCH_1):P5E_CPU0_P3_TX_C_DN(2)   I124 @T6G_MB_LIB.T6G(SCH_1):PAGE352
     2 P5E_CPU0_P3_TX_DN<2> @T6G_MB_LIB.T6G(SCH_1):P5E_CPU0_P3_TX_DN(2)   I124 @T6G_MB_LIB.T6G(SCH_1):PAGE352

C897 Q_CAP_DIFFBUS_C0201-DIFF BUS_0.22UF,6.3V,20%,X6S,SA
     1 P5E_CPU0_P3_TX_C_DP<2> @T6G_MB_LIB.T6G(SCH_1):P5E_CPU0_P3_TX_C_DP(2)   I123 @T6G_MB_LIB.T6G(SCH_1):PAGE352
     2 P5E_CPU0_P3_TX_DP<2> @T6G_MB_LIB.T6G(SCH_1):P5E_CPU0_P3_TX_DP(2)   I123 @T6G_MB_LIB.T6G(SCH_1):PAGE352

C898 Q_CAP_DIFFBUS_C0201-DIFF BUS_0.22UF,6.3V,20%,X6S,SA
     1 P5E_CPU0_P3_TX_C_DN<1> @T6G_MB_LIB.T6G(SCH_1):P5E_CPU0_P3_TX_C_DN(1)   I206 @T6G_MB_LIB.T6G(SCH_1):PAGE352
     2 P5E_CPU0_P3_TX_DN<1> @T6G_MB_LIB.T6G(SCH_1):P5E_CPU0_P3_TX_DN(1)   I206 @T6G_MB_LIB.T6G(SCH_1):PAGE352

C899 Q_CAP_DIFFBUS_C0201-DIFF BUS_0.22UF,6.3V,20%,X6S,SA
     1 P5E_CPU0_P3_TX_C_DP<1> @T6G_MB_LIB.T6G(SCH_1):P5E_CPU0_P3_TX_C_DP(1)   I122 @T6G_MB_LIB.T6G(SCH_1):PAGE352
     2 P5E_CPU0_P3_TX_DP<1> @T6G_MB_LIB.T6G(SCH_1):P5E_CPU0_P3_TX_DP(1)   I122 @T6G_MB_LIB.T6G(SCH_1):PAGE352

C900 Q_CAP_DIFFBUS_C0201-DIFF BUS_0.22UF,6.3V,20%,X6S,SA
     1 P5E_CPU0_P3_TX_C_DN<0> @T6G_MB_LIB.T6G(SCH_1):P5E_CPU0_P3_TX_C_DN(0)   I121 @T6G_MB_LIB.T6G(SCH_1):PAGE352
     2 P5E_CPU0_P3_TX_DN<0> @T6G_MB_LIB.T6G(SCH_1):P5E_CPU0_P3_TX_DN(0)   I121 @T6G_MB_LIB.T6G(SCH_1):PAGE352

C901 Q_CAP_DIFFBUS_C0201-DIFF BUS_0.22UF,6.3V,20%,X6S,SA
     1 P5E_CPU0_P3_TX_C_DP<0> @T6G_MB_LIB.T6G(SCH_1):P5E_CPU0_P3_TX_C_DP(0)   I120 @T6G_MB_LIB.T6G(SCH_1):PAGE352
     2 P5E_CPU0_P3_TX_DP<0> @T6G_MB_LIB.T6G(SCH_1):P5E_CPU0_P3_TX_DP(0)   I120 @T6G_MB_LIB.T6G(SCH_1):PAGE352

C902 Q_CAP_DIFFBUS_C0201-DIFF BUS_0.22UF,6.3V,20%,X6S,SA
     1 P5E_CPU0_P0_TX_C_DN<15> @T6G_MB_LIB.T6G(SCH_1):P5E_CPU0_P0_TX_C_DN(15)    I68 @T6G_MB_LIB.T6G(SCH_1):PAGE351
     2 P5E_CPU0_P0_TX_DN<15> @T6G_MB_LIB.T6G(SCH_1):P5E_CPU0_P0_TX_DN(15)    I68 @T6G_MB_LIB.T6G(SCH_1):PAGE351

C903 Q_CAP_DIFFBUS_C0201-DIFF BUS_0.22UF,6.3V,20%,X6S,SA
     1 P5E_CPU0_P0_TX_C_DP<15> @T6G_MB_LIB.T6G(SCH_1):P5E_CPU0_P0_TX_C_DP(15)    I67 @T6G_MB_LIB.T6G(SCH_1):PAGE351
     2 P5E_CPU0_P0_TX_DP<15> @T6G_MB_LIB.T6G(SCH_1):P5E_CPU0_P0_TX_DP(15)    I67 @T6G_MB_LIB.T6G(SCH_1):PAGE351

C904 Q_CAP_DIFFBUS_C0201-DIFF BUS_0.22UF,6.3V,20%,X6S,SA
     1 P5E_CPU0_P0_TX_C_DN<14> @T6G_MB_LIB.T6G(SCH_1):P5E_CPU0_P0_TX_C_DN(14)    I66 @T6G_MB_LIB.T6G(SCH_1):PAGE351
     2 P5E_CPU0_P0_TX_DN<14> @T6G_MB_LIB.T6G(SCH_1):P5E_CPU0_P0_TX_DN(14)    I66 @T6G_MB_LIB.T6G(SCH_1):PAGE351

C905 Q_CAP_DIFFBUS_C0201-DIFF BUS_0.22UF,6.3V,20%,X6S,SA
     1 P5E_CPU0_P0_TX_C_DP<14> @T6G_MB_LIB.T6G(SCH_1):P5E_CPU0_P0_TX_C_DP(14)    I65 @T6G_MB_LIB.T6G(SCH_1):PAGE351
     2 P5E_CPU0_P0_TX_DP<14> @T6G_MB_LIB.T6G(SCH_1):P5E_CPU0_P0_TX_DP(14)    I65 @T6G_MB_LIB.T6G(SCH_1):PAGE351

C906 Q_CAP_DIFFBUS_C0201-DIFF BUS_0.22UF,6.3V,20%,X6S,SA
     1 P5E_CPU0_P0_TX_C_DN<13> @T6G_MB_LIB.T6G(SCH_1):P5E_CPU0_P0_TX_C_DN(13)    I63 @T6G_MB_LIB.T6G(SCH_1):PAGE351
     2 P5E_CPU0_P0_TX_DN<13> @T6G_MB_LIB.T6G(SCH_1):P5E_CPU0_P0_TX_DN(13)    I63 @T6G_MB_LIB.T6G(SCH_1):PAGE351

C907 Q_CAP_DIFFBUS_C0201-DIFF BUS_0.22UF,6.3V,20%,X6S,SA
     1 P5E_CPU0_P0_TX_C_DP<13> @T6G_MB_LIB.T6G(SCH_1):P5E_CPU0_P0_TX_C_DP(13)    I64 @T6G_MB_LIB.T6G(SCH_1):PAGE351
     2 P5E_CPU0_P0_TX_DP<13> @T6G_MB_LIB.T6G(SCH_1):P5E_CPU0_P0_TX_DP(13)    I64 @T6G_MB_LIB.T6G(SCH_1):PAGE351

C908 Q_CAP_DIFFBUS_C0201-DIFF BUS_0.22UF,6.3V,20%,X6S,SA
     1 P5E_CPU0_P0_TX_C_DN<12> @T6G_MB_LIB.T6G(SCH_1):P5E_CPU0_P0_TX_C_DN(12)    I62 @T6G_MB_LIB.T6G(SCH_1):PAGE351
     2 P5E_CPU0_P0_TX_DN<12> @T6G_MB_LIB.T6G(SCH_1):P5E_CPU0_P0_TX_DN(12)    I62 @T6G_MB_LIB.T6G(SCH_1):PAGE351

C909 Q_CAP_DIFFBUS_C0201-DIFF BUS_0.22UF,6.3V,20%,X6S,SA
     1 P5E_CPU0_P0_TX_C_DP<12> @T6G_MB_LIB.T6G(SCH_1):P5E_CPU0_P0_TX_C_DP(12)    I61 @T6G_MB_LIB.T6G(SCH_1):PAGE351
     2 P5E_CPU0_P0_TX_DP<12> @T6G_MB_LIB.T6G(SCH_1):P5E_CPU0_P0_TX_DP(12)    I61 @T6G_MB_LIB.T6G(SCH_1):PAGE351

C910 Q_CAP_DIFFBUS_C0201-DIFF BUS_0.22UF,6.3V,20%,X6S,SA
     1 P5E_CPU0_P0_TX_C_DN<11> @T6G_MB_LIB.T6G(SCH_1):P5E_CPU0_P0_TX_C_DN(11)    I60 @T6G_MB_LIB.T6G(SCH_1):PAGE351
     2 P5E_CPU0_P0_TX_DN<11> @T6G_MB_LIB.T6G(SCH_1):P5E_CPU0_P0_TX_DN(11)    I60 @T6G_MB_LIB.T6G(SCH_1):PAGE351

C911 Q_CAP_DIFFBUS_C0201-DIFF BUS_0.22UF,6.3V,20%,X6S,SA
     1 P5E_CPU0_P0_TX_C_DP<11> @T6G_MB_LIB.T6G(SCH_1):P5E_CPU0_P0_TX_C_DP(11)    I59 @T6G_MB_LIB.T6G(SCH_1):PAGE351
     2 P5E_CPU0_P0_TX_DP<11> @T6G_MB_LIB.T6G(SCH_1):P5E_CPU0_P0_TX_DP(11)    I59 @T6G_MB_LIB.T6G(SCH_1):PAGE351

C912 Q_CAP_DIFFBUS_C0201-DIFF BUS_0.22UF,6.3V,20%,X6S,SA
     1 P5E_CPU0_P0_TX_C_DN<10> @T6G_MB_LIB.T6G(SCH_1):P5E_CPU0_P0_TX_C_DN(10)    I58 @T6G_MB_LIB.T6G(SCH_1):PAGE351
     2 P5E_CPU0_P0_TX_DN<10> @T6G_MB_LIB.T6G(SCH_1):P5E_CPU0_P0_TX_DN(10)    I58 @T6G_MB_LIB.T6G(SCH_1):PAGE351

C913 Q_CAP_DIFFBUS_C0201-DIFF BUS_0.22UF,6.3V,20%,X6S,SA
     1 P5E_CPU0_P0_TX_C_DP<10> @T6G_MB_LIB.T6G(SCH_1):P5E_CPU0_P0_TX_C_DP(10)    I57 @T6G_MB_LIB.T6G(SCH_1):PAGE351
     2 P5E_CPU0_P0_TX_DP<10> @T6G_MB_LIB.T6G(SCH_1):P5E_CPU0_P0_TX_DP(10)    I57 @T6G_MB_LIB.T6G(SCH_1):PAGE351

C914 Q_CAP_DIFFBUS_C0201-DIFF BUS_0.22UF,6.3V,20%,X6S,SA
     1 P5E_CPU0_P0_TX_C_DN<9> @T6G_MB_LIB.T6G(SCH_1):P5E_CPU0_P0_TX_C_DN(9)    I56 @T6G_MB_LIB.T6G(SCH_1):PAGE351
     2 P5E_CPU0_P0_TX_DN<9> @T6G_MB_LIB.T6G(SCH_1):P5E_CPU0_P0_TX_DN(9)    I56 @T6G_MB_LIB.T6G(SCH_1):PAGE351

C915 Q_CAP_DIFFBUS_C0201-DIFF BUS_0.22UF,6.3V,20%,X6S,SA
     1 P5E_CPU0_P0_TX_C_DP<9> @T6G_MB_LIB.T6G(SCH_1):P5E_CPU0_P0_TX_C_DP(9)    I55 @T6G_MB_LIB.T6G(SCH_1):PAGE351
     2 P5E_CPU0_P0_TX_DP<9> @T6G_MB_LIB.T6G(SCH_1):P5E_CPU0_P0_TX_DP(9)    I55 @T6G_MB_LIB.T6G(SCH_1):PAGE351

C916 Q_CAP_DIFFBUS_C0201-DIFF BUS_0.22UF,6.3V,20%,X6S,SA
     1 P5E_CPU0_P0_TX_C_DN<8> @T6G_MB_LIB.T6G(SCH_1):P5E_CPU0_P0_TX_C_DN(8)    I53 @T6G_MB_LIB.T6G(SCH_1):PAGE351
     2 P5E_CPU0_P0_TX_DN<8> @T6G_MB_LIB.T6G(SCH_1):P5E_CPU0_P0_TX_DN(8)    I53 @T6G_MB_LIB.T6G(SCH_1):PAGE351

C917 Q_CAP_DIFFBUS_C0201-DIFF BUS_0.22UF,6.3V,20%,X6S,SA
     1 P5E_CPU0_P0_TX_C_DP<8> @T6G_MB_LIB.T6G(SCH_1):P5E_CPU0_P0_TX_C_DP(8)    I54 @T6G_MB_LIB.T6G(SCH_1):PAGE351
     2 P5E_CPU0_P0_TX_DP<8> @T6G_MB_LIB.T6G(SCH_1):P5E_CPU0_P0_TX_DP(8)    I54 @T6G_MB_LIB.T6G(SCH_1):PAGE351

C918 Q_CAP_DIFFBUS_C0201-DIFF BUS_0.22UF,6.3V,20%,X6S,SA
     1 P5E_CPU0_P0_TX_C_DN<7> @T6G_MB_LIB.T6G(SCH_1):P5E_CPU0_P0_TX_C_DN(7)    I35 @T6G_MB_LIB.T6G(SCH_1):PAGE351
     2 P5E_CPU0_P0_TX_DN<7> @T6G_MB_LIB.T6G(SCH_1):P5E_CPU0_P0_TX_DN(7)    I35 @T6G_MB_LIB.T6G(SCH_1):PAGE351

C919 Q_CAP_DIFFBUS_C0201-DIFF BUS_0.22UF,6.3V,20%,X6S,SA
     1 P5E_CPU0_P0_TX_C_DP<7> @T6G_MB_LIB.T6G(SCH_1):P5E_CPU0_P0_TX_C_DP(7)    I36 @T6G_MB_LIB.T6G(SCH_1):PAGE351
     2 P5E_CPU0_P0_TX_DP<7> @T6G_MB_LIB.T6G(SCH_1):P5E_CPU0_P0_TX_DP(7)    I36 @T6G_MB_LIB.T6G(SCH_1):PAGE351

C920 Q_CAP_DIFFBUS_C0201-DIFF BUS_0.22UF,6.3V,20%,X6S,SA
     1 P5E_CPU0_P0_TX_C_DN<6> @T6G_MB_LIB.T6G(SCH_1):P5E_CPU0_P0_TX_C_DN(6)    I34 @T6G_MB_LIB.T6G(SCH_1):PAGE351
     2 P5E_CPU0_P0_TX_DN<6> @T6G_MB_LIB.T6G(SCH_1):P5E_CPU0_P0_TX_DN(6)    I34 @T6G_MB_LIB.T6G(SCH_1):PAGE351

C921 Q_CAP_DIFFBUS_C0201-DIFF BUS_0.22UF,6.3V,20%,X6S,SA
     1 P5E_CPU0_P0_TX_C_DP<6> @T6G_MB_LIB.T6G(SCH_1):P5E_CPU0_P0_TX_C_DP(6)    I33 @T6G_MB_LIB.T6G(SCH_1):PAGE351
     2 P5E_CPU0_P0_TX_DP<6> @T6G_MB_LIB.T6G(SCH_1):P5E_CPU0_P0_TX_DP(6)    I33 @T6G_MB_LIB.T6G(SCH_1):PAGE351

C922 Q_CAP_DIFFBUS_C0201-DIFF BUS_0.22UF,6.3V,20%,X6S,SA
     1 P5E_CPU0_P0_TX_C_DN<5> @T6G_MB_LIB.T6G(SCH_1):P5E_CPU0_P0_TX_C_DN(5)    I32 @T6G_MB_LIB.T6G(SCH_1):PAGE351
     2 P5E_CPU0_P0_TX_DN<5> @T6G_MB_LIB.T6G(SCH_1):P5E_CPU0_P0_TX_DN(5)    I32 @T6G_MB_LIB.T6G(SCH_1):PAGE351

C923 Q_CAP_DIFFBUS_C0201-DIFF BUS_0.22UF,6.3V,20%,X6S,SA
     1 P5E_CPU0_P0_TX_C_DP<5> @T6G_MB_LIB.T6G(SCH_1):P5E_CPU0_P0_TX_C_DP(5)    I31 @T6G_MB_LIB.T6G(SCH_1):PAGE351
     2 P5E_CPU0_P0_TX_DP<5> @T6G_MB_LIB.T6G(SCH_1):P5E_CPU0_P0_TX_DP(5)    I31 @T6G_MB_LIB.T6G(SCH_1):PAGE351

C924 Q_CAP_DIFFBUS_C0201-DIFF BUS_0.22UF,6.3V,20%,X6S,SA
     1 P5E_CPU0_P0_TX_C_DN<4> @T6G_MB_LIB.T6G(SCH_1):P5E_CPU0_P0_TX_C_DN(4)    I30 @T6G_MB_LIB.T6G(SCH_1):PAGE351
     2 P5E_CPU0_P0_TX_DN<4> @T6G_MB_LIB.T6G(SCH_1):P5E_CPU0_P0_TX_DN(4)    I30 @T6G_MB_LIB.T6G(SCH_1):PAGE351

C925 Q_CAP_DIFFBUS_C0201-DIFF BUS_0.22UF,6.3V,20%,X6S,SA
     1 P5E_CPU0_P0_TX_C_DP<4> @T6G_MB_LIB.T6G(SCH_1):P5E_CPU0_P0_TX_C_DP(4)    I29 @T6G_MB_LIB.T6G(SCH_1):PAGE351
     2 P5E_CPU0_P0_TX_DP<4> @T6G_MB_LIB.T6G(SCH_1):P5E_CPU0_P0_TX_DP(4)    I29 @T6G_MB_LIB.T6G(SCH_1):PAGE351

C926 Q_CAP_DIFFBUS_C0201-DIFF BUS_0.22UF,6.3V,20%,X6S,SA
     1 P5E_CPU0_P0_TX_C_DN<3> @T6G_MB_LIB.T6G(SCH_1):P5E_CPU0_P0_TX_C_DN(3)    I28 @T6G_MB_LIB.T6G(SCH_1):PAGE351
     2 P5E_CPU0_P0_TX_DN<3> @T6G_MB_LIB.T6G(SCH_1):P5E_CPU0_P0_TX_DN(3)    I28 @T6G_MB_LIB.T6G(SCH_1):PAGE351

C927 Q_CAP_DIFFBUS_C0201-DIFF BUS_0.22UF,6.3V,20%,X6S,SA
     1 P5E_CPU0_P0_TX_C_DP<3> @T6G_MB_LIB.T6G(SCH_1):P5E_CPU0_P0_TX_C_DP(3)    I27 @T6G_MB_LIB.T6G(SCH_1):PAGE351
     2 P5E_CPU0_P0_TX_DP<3> @T6G_MB_LIB.T6G(SCH_1):P5E_CPU0_P0_TX_DP(3)    I27 @T6G_MB_LIB.T6G(SCH_1):PAGE351

C928 Q_CAP_DIFFBUS_C0201-DIFF BUS_0.22UF,6.3V,20%,X6S,SA
     1 P5E_CPU0_P0_TX_C_DN<2> @T6G_MB_LIB.T6G(SCH_1):P5E_CPU0_P0_TX_C_DN(2)    I25 @T6G_MB_LIB.T6G(SCH_1):PAGE351
     2 P5E_CPU0_P0_TX_DN<2> @T6G_MB_LIB.T6G(SCH_1):P5E_CPU0_P0_TX_DN(2)    I25 @T6G_MB_LIB.T6G(SCH_1):PAGE351

C929 Q_CAP_DIFFBUS_C0201-DIFF BUS_0.22UF,6.3V,20%,X6S,SA
     1 P5E_CPU0_P0_TX_C_DP<2> @T6G_MB_LIB.T6G(SCH_1):P5E_CPU0_P0_TX_C_DP(2)    I26 @T6G_MB_LIB.T6G(SCH_1):PAGE351
     2 P5E_CPU0_P0_TX_DP<2> @T6G_MB_LIB.T6G(SCH_1):P5E_CPU0_P0_TX_DP(2)    I26 @T6G_MB_LIB.T6G(SCH_1):PAGE351

C930 Q_CAP_DIFFBUS_C0201-DIFF BUS_0.22UF,6.3V,20%,X6S,SA
     1 P5E_CPU0_P0_TX_C_DN<1> @T6G_MB_LIB.T6G(SCH_1):P5E_CPU0_P0_TX_C_DN(1)    I24 @T6G_MB_LIB.T6G(SCH_1):PAGE351
     2 P5E_CPU0_P0_TX_DN<1> @T6G_MB_LIB.T6G(SCH_1):P5E_CPU0_P0_TX_DN(1)    I24 @T6G_MB_LIB.T6G(SCH_1):PAGE351

C931 Q_CAP_DIFFBUS_C0201-DIFF BUS_0.22UF,6.3V,20%,X6S,SA
     1 P5E_CPU0_P0_TX_C_DP<1> @T6G_MB_LIB.T6G(SCH_1):P5E_CPU0_P0_TX_C_DP(1)    I23 @T6G_MB_LIB.T6G(SCH_1):PAGE351
     2 P5E_CPU0_P0_TX_DP<1> @T6G_MB_LIB.T6G(SCH_1):P5E_CPU0_P0_TX_DP(1)    I23 @T6G_MB_LIB.T6G(SCH_1):PAGE351

C932 Q_CAP_DIFFBUS_C0201-DIFF BUS_0.22UF,6.3V,20%,X6S,SA
     1 P5E_CPU0_P0_TX_C_DN<0> @T6G_MB_LIB.T6G(SCH_1):P5E_CPU0_P0_TX_C_DN(0)    I21 @T6G_MB_LIB.T6G(SCH_1):PAGE351
     2 P5E_CPU0_P0_TX_DN<0> @T6G_MB_LIB.T6G(SCH_1):P5E_CPU0_P0_TX_DN(0)    I21 @T6G_MB_LIB.T6G(SCH_1):PAGE351

C933 Q_CAP_DIFFBUS_C0201-DIFF BUS_0.22UF,6.3V,20%,X6S,SA
     1 P5E_CPU0_P0_TX_C_DP<0> @T6G_MB_LIB.T6G(SCH_1):P5E_CPU0_P0_TX_C_DP(0)    I22 @T6G_MB_LIB.T6G(SCH_1):PAGE351
     2 P5E_CPU0_P0_TX_DP<0> @T6G_MB_LIB.T6G(SCH_1):P5E_CPU0_P0_TX_DP(0)    I22 @T6G_MB_LIB.T6G(SCH_1):PAGE351

C934 Q_CAP_DIFFBUS_C0201-DIFF BUS_0.22UF,6.3V,20%,X6S,SA
     1 P5E_CPU0_P1_TX_C_DN<15> @T6G_MB_LIB.T6G(SCH_1):P5E_CPU0_P1_TX_C_DN(15)   I169 @T6G_MB_LIB.T6G(SCH_1):PAGE351
     2 P5E_CPU0_P1_TX_DN<15> @T6G_MB_LIB.T6G(SCH_1):P5E_CPU0_P1_TX_DN(15)   I169 @T6G_MB_LIB.T6G(SCH_1):PAGE351

C935 Q_CAP_DIFFBUS_C0201-DIFF BUS_0.22UF,6.3V,20%,X6S,SA
     1 P5E_CPU0_P1_TX_C_DP<15> @T6G_MB_LIB.T6G(SCH_1):P5E_CPU0_P1_TX_C_DP(15)   I168 @T6G_MB_LIB.T6G(SCH_1):PAGE351
     2 P5E_CPU0_P1_TX_DP<15> @T6G_MB_LIB.T6G(SCH_1):P5E_CPU0_P1_TX_DP(15)   I168 @T6G_MB_LIB.T6G(SCH_1):PAGE351

C936 Q_CAP_DIFFBUS_C0201-DIFF BUS_0.22UF,6.3V,20%,X6S,SA
     1 P5E_CPU0_P1_TX_C_DN<14> @T6G_MB_LIB.T6G(SCH_1):P5E_CPU0_P1_TX_C_DN(14)   I167 @T6G_MB_LIB.T6G(SCH_1):PAGE351
     2 P5E_CPU0_P1_TX_DN<14> @T6G_MB_LIB.T6G(SCH_1):P5E_CPU0_P1_TX_DN(14)   I167 @T6G_MB_LIB.T6G(SCH_1):PAGE351

C937 Q_CAP_DIFFBUS_C0201-DIFF BUS_0.22UF,6.3V,20%,X6S,SA
     1 P5E_CPU0_P1_TX_C_DP<14> @T6G_MB_LIB.T6G(SCH_1):P5E_CPU0_P1_TX_C_DP(14)   I166 @T6G_MB_LIB.T6G(SCH_1):PAGE351
     2 P5E_CPU0_P1_TX_DP<14> @T6G_MB_LIB.T6G(SCH_1):P5E_CPU0_P1_TX_DP(14)   I166 @T6G_MB_LIB.T6G(SCH_1):PAGE351

C938 Q_CAP_DIFFBUS_C0201-DIFF BUS_0.22UF,6.3V,20%,X6S,SA
     1 P5E_CPU0_P1_TX_C_DN<13> @T6G_MB_LIB.T6G(SCH_1):P5E_CPU0_P1_TX_C_DN(13)   I165 @T6G_MB_LIB.T6G(SCH_1):PAGE351
     2 P5E_CPU0_P1_TX_DN<13> @T6G_MB_LIB.T6G(SCH_1):P5E_CPU0_P1_TX_DN(13)   I165 @T6G_MB_LIB.T6G(SCH_1):PAGE351

C939 Q_CAP_DIFFBUS_C0201-DIFF BUS_0.22UF,6.3V,20%,X6S,SA
     1 P5E_CPU0_P1_TX_C_DP<13> @T6G_MB_LIB.T6G(SCH_1):P5E_CPU0_P1_TX_C_DP(13)   I164 @T6G_MB_LIB.T6G(SCH_1):PAGE351
     2 P5E_CPU0_P1_TX_DP<13> @T6G_MB_LIB.T6G(SCH_1):P5E_CPU0_P1_TX_DP(13)   I164 @T6G_MB_LIB.T6G(SCH_1):PAGE351

C940 Q_CAP_DIFFBUS_C0201-DIFF BUS_0.22UF,6.3V,20%,X6S,SA
     1 P5E_CPU0_P1_TX_C_DN<12> @T6G_MB_LIB.T6G(SCH_1):P5E_CPU0_P1_TX_C_DN(12)   I160 @T6G_MB_LIB.T6G(SCH_1):PAGE351
     2 P5E_CPU0_P1_TX_DN<12> @T6G_MB_LIB.T6G(SCH_1):P5E_CPU0_P1_TX_DN(12)   I160 @T6G_MB_LIB.T6G(SCH_1):PAGE351

C941 Q_CAP_DIFFBUS_C0201-DIFF BUS_0.22UF,6.3V,20%,X6S,SA
     1 P5E_CPU0_P1_TX_C_DP<12> @T6G_MB_LIB.T6G(SCH_1):P5E_CPU0_P1_TX_C_DP(12)   I159 @T6G_MB_LIB.T6G(SCH_1):PAGE351
     2 P5E_CPU0_P1_TX_DP<12> @T6G_MB_LIB.T6G(SCH_1):P5E_CPU0_P1_TX_DP(12)   I159 @T6G_MB_LIB.T6G(SCH_1):PAGE351

C942 Q_CAP_DIFFBUS_C0201-DIFF BUS_0.22UF,6.3V,20%,X6S,SA
     1 P5E_CPU0_P1_TX_C_DN<11> @T6G_MB_LIB.T6G(SCH_1):P5E_CPU0_P1_TX_C_DN(11)   I158 @T6G_MB_LIB.T6G(SCH_1):PAGE351
     2 P5E_CPU0_P1_TX_DN<11> @T6G_MB_LIB.T6G(SCH_1):P5E_CPU0_P1_TX_DN(11)   I158 @T6G_MB_LIB.T6G(SCH_1):PAGE351

C943 Q_CAP_DIFFBUS_C0201-DIFF BUS_0.22UF,6.3V,20%,X6S,SA
     1 P5E_CPU0_P1_TX_C_DP<11> @T6G_MB_LIB.T6G(SCH_1):P5E_CPU0_P1_TX_C_DP(11)   I157 @T6G_MB_LIB.T6G(SCH_1):PAGE351
     2 P5E_CPU0_P1_TX_DP<11> @T6G_MB_LIB.T6G(SCH_1):P5E_CPU0_P1_TX_DP(11)   I157 @T6G_MB_LIB.T6G(SCH_1):PAGE351

C944 Q_CAP_DIFFBUS_C0201-DIFF BUS_0.22UF,6.3V,20%,X6S,SA
     1 P5E_CPU0_P1_TX_C_DN<10> @T6G_MB_LIB.T6G(SCH_1):P5E_CPU0_P1_TX_C_DN(10)   I156 @T6G_MB_LIB.T6G(SCH_1):PAGE351
     2 P5E_CPU0_P1_TX_DN<10> @T6G_MB_LIB.T6G(SCH_1):P5E_CPU0_P1_TX_DN(10)   I156 @T6G_MB_LIB.T6G(SCH_1):PAGE351

C945 Q_CAP_DIFFBUS_C0201-DIFF BUS_0.22UF,6.3V,20%,X6S,SA
     1 P5E_CPU0_P1_TX_C_DP<10> @T6G_MB_LIB.T6G(SCH_1):P5E_CPU0_P1_TX_C_DP(10)   I155 @T6G_MB_LIB.T6G(SCH_1):PAGE351
     2 P5E_CPU0_P1_TX_DP<10> @T6G_MB_LIB.T6G(SCH_1):P5E_CPU0_P1_TX_DP(10)   I155 @T6G_MB_LIB.T6G(SCH_1):PAGE351

C946 Q_CAP_DIFFBUS_C0201-DIFF BUS_0.22UF,6.3V,20%,X6S,SA
     1 P5E_CPU0_P1_TX_C_DN<9> @T6G_MB_LIB.T6G(SCH_1):P5E_CPU0_P1_TX_C_DN(9)   I154 @T6G_MB_LIB.T6G(SCH_1):PAGE351
     2 P5E_CPU0_P1_TX_DN<9> @T6G_MB_LIB.T6G(SCH_1):P5E_CPU0_P1_TX_DN(9)   I154 @T6G_MB_LIB.T6G(SCH_1):PAGE351

C947 Q_CAP_DIFFBUS_C0201-DIFF BUS_0.22UF,6.3V,20%,X6S,SA
     1 P5E_CPU0_P1_TX_C_DP<9> @T6G_MB_LIB.T6G(SCH_1):P5E_CPU0_P1_TX_C_DP(9)   I153 @T6G_MB_LIB.T6G(SCH_1):PAGE351
     2 P5E_CPU0_P1_TX_DP<9> @T6G_MB_LIB.T6G(SCH_1):P5E_CPU0_P1_TX_DP(9)   I153 @T6G_MB_LIB.T6G(SCH_1):PAGE351

C948 Q_CAP_DIFFBUS_C0201-DIFF BUS_0.22UF,6.3V,20%,X6S,SA
     1 P5E_CPU0_P1_TX_C_DN<8> @T6G_MB_LIB.T6G(SCH_1):P5E_CPU0_P1_TX_C_DN(8)   I152 @T6G_MB_LIB.T6G(SCH_1):PAGE351
     2 P5E_CPU0_P1_TX_DN<8> @T6G_MB_LIB.T6G(SCH_1):P5E_CPU0_P1_TX_DN(8)   I152 @T6G_MB_LIB.T6G(SCH_1):PAGE351

C949 Q_CAP_DIFFBUS_C0201-DIFF BUS_0.22UF,6.3V,20%,X6S,SA
     1 P5E_CPU0_P1_TX_C_DP<8> @T6G_MB_LIB.T6G(SCH_1):P5E_CPU0_P1_TX_C_DP(8)   I151 @T6G_MB_LIB.T6G(SCH_1):PAGE351
     2 P5E_CPU0_P1_TX_DP<8> @T6G_MB_LIB.T6G(SCH_1):P5E_CPU0_P1_TX_DP(8)   I151 @T6G_MB_LIB.T6G(SCH_1):PAGE351

C950 Q_CAP_DIFFBUS_C0201-DIFF BUS_0.22UF,6.3V,20%,X6S,SA
     1 P5E_CPU0_P1_TX_C_DN<7> @T6G_MB_LIB.T6G(SCH_1):P5E_CPU0_P1_TX_C_DN(7)   I137 @T6G_MB_LIB.T6G(SCH_1):PAGE351
     2 P5E_CPU0_P1_TX_DN<7> @T6G_MB_LIB.T6G(SCH_1):P5E_CPU0_P1_TX_DN(7)   I137 @T6G_MB_LIB.T6G(SCH_1):PAGE351

C951 Q_CAP_DIFFBUS_C0201-DIFF BUS_0.22UF,6.3V,20%,X6S,SA
     1 P5E_CPU0_P1_TX_C_DP<7> @T6G_MB_LIB.T6G(SCH_1):P5E_CPU0_P1_TX_C_DP(7)   I136 @T6G_MB_LIB.T6G(SCH_1):PAGE351
     2 P5E_CPU0_P1_TX_DP<7> @T6G_MB_LIB.T6G(SCH_1):P5E_CPU0_P1_TX_DP(7)   I136 @T6G_MB_LIB.T6G(SCH_1):PAGE351

C952 Q_CAP_DIFFBUS_C0201-DIFF BUS_0.22UF,6.3V,20%,X6S,SA
     1 P5E_CPU0_P1_TX_C_DN<6> @T6G_MB_LIB.T6G(SCH_1):P5E_CPU0_P1_TX_C_DN(6)   I135 @T6G_MB_LIB.T6G(SCH_1):PAGE351
     2 P5E_CPU0_P1_TX_DN<6> @T6G_MB_LIB.T6G(SCH_1):P5E_CPU0_P1_TX_DN(6)   I135 @T6G_MB_LIB.T6G(SCH_1):PAGE351

C953 Q_CAP_DIFFBUS_C0201-DIFF BUS_0.22UF,6.3V,20%,X6S,SA
     1 P5E_CPU0_P1_TX_C_DP<6> @T6G_MB_LIB.T6G(SCH_1):P5E_CPU0_P1_TX_C_DP(6)   I134 @T6G_MB_LIB.T6G(SCH_1):PAGE351
     2 P5E_CPU0_P1_TX_DP<6> @T6G_MB_LIB.T6G(SCH_1):P5E_CPU0_P1_TX_DP(6)   I134 @T6G_MB_LIB.T6G(SCH_1):PAGE351

C954 Q_CAP_DIFFBUS_C0201-DIFF BUS_0.22UF,6.3V,20%,X6S,SA
     1 P5E_CPU0_P1_TX_C_DN<5> @T6G_MB_LIB.T6G(SCH_1):P5E_CPU0_P1_TX_C_DN(5)   I133 @T6G_MB_LIB.T6G(SCH_1):PAGE351
     2 P5E_CPU0_P1_TX_DN<5> @T6G_MB_LIB.T6G(SCH_1):P5E_CPU0_P1_TX_DN(5)   I133 @T6G_MB_LIB.T6G(SCH_1):PAGE351

C955 Q_CAP_DIFFBUS_C0201-DIFF BUS_0.22UF,6.3V,20%,X6S,SA
     1 P5E_CPU0_P1_TX_C_DP<5> @T6G_MB_LIB.T6G(SCH_1):P5E_CPU0_P1_TX_C_DP(5)   I208 @T6G_MB_LIB.T6G(SCH_1):PAGE351
     2 P5E_CPU0_P1_TX_DP<5> @T6G_MB_LIB.T6G(SCH_1):P5E_CPU0_P1_TX_DP(5)   I208 @T6G_MB_LIB.T6G(SCH_1):PAGE351

C956 Q_CAP_DIFFBUS_C0201-DIFF BUS_0.22UF,6.3V,20%,X6S,SA
     1 P5E_CPU0_P1_TX_C_DN<4> @T6G_MB_LIB.T6G(SCH_1):P5E_CPU0_P1_TX_C_DN(4)   I207 @T6G_MB_LIB.T6G(SCH_1):PAGE351
     2 P5E_CPU0_P1_TX_DN<4> @T6G_MB_LIB.T6G(SCH_1):P5E_CPU0_P1_TX_DN(4)   I207 @T6G_MB_LIB.T6G(SCH_1):PAGE351

C957 Q_CAP_DIFFBUS_C0201-DIFF BUS_0.22UF,6.3V,20%,X6S,SA
     1 P5E_CPU0_P1_TX_C_DP<4> @T6G_MB_LIB.T6G(SCH_1):P5E_CPU0_P1_TX_C_DP(4)   I206 @T6G_MB_LIB.T6G(SCH_1):PAGE351
     2 P5E_CPU0_P1_TX_DP<4> @T6G_MB_LIB.T6G(SCH_1):P5E_CPU0_P1_TX_DP(4)   I206 @T6G_MB_LIB.T6G(SCH_1):PAGE351

C958 Q_CAP_DIFFBUS_C0201-DIFF BUS_0.22UF,6.3V,20%,X6S,SA
     1 P5E_CPU0_P1_TX_C_DN<3> @T6G_MB_LIB.T6G(SCH_1):P5E_CPU0_P1_TX_C_DN(3)   I128 @T6G_MB_LIB.T6G(SCH_1):PAGE351
     2 P5E_CPU0_P1_TX_DN<3> @T6G_MB_LIB.T6G(SCH_1):P5E_CPU0_P1_TX_DN(3)   I128 @T6G_MB_LIB.T6G(SCH_1):PAGE351

C959 Q_CAP_DIFFBUS_C0201-DIFF BUS_0.22UF,6.3V,20%,X6S,SA
     1 P5E_CPU0_P1_TX_C_DP<3> @T6G_MB_LIB.T6G(SCH_1):P5E_CPU0_P1_TX_C_DP(3)   I127 @T6G_MB_LIB.T6G(SCH_1):PAGE351
     2 P5E_CPU0_P1_TX_DP<3> @T6G_MB_LIB.T6G(SCH_1):P5E_CPU0_P1_TX_DP(3)   I127 @T6G_MB_LIB.T6G(SCH_1):PAGE351

C960 Q_CAP_DIFFBUS_C0201-DIFF BUS_0.22UF,6.3V,20%,X6S,SA
     1 P5E_CPU0_P1_TX_C_DN<2> @T6G_MB_LIB.T6G(SCH_1):P5E_CPU0_P1_TX_C_DN(2)   I126 @T6G_MB_LIB.T6G(SCH_1):PAGE351
     2 P5E_CPU0_P1_TX_DN<2> @T6G_MB_LIB.T6G(SCH_1):P5E_CPU0_P1_TX_DN(2)   I126 @T6G_MB_LIB.T6G(SCH_1):PAGE351

C961 Q_CAP_DIFFBUS_C0201-DIFF BUS_0.22UF,6.3V,20%,X6S,SA
     1 P5E_CPU0_P1_TX_C_DP<2> @T6G_MB_LIB.T6G(SCH_1):P5E_CPU0_P1_TX_C_DP(2)   I125 @T6G_MB_LIB.T6G(SCH_1):PAGE351
     2 P5E_CPU0_P1_TX_DP<2> @T6G_MB_LIB.T6G(SCH_1):P5E_CPU0_P1_TX_DP(2)   I125 @T6G_MB_LIB.T6G(SCH_1):PAGE351

C962 Q_CAP_DIFFBUS_C0201-DIFF BUS_0.22UF,6.3V,20%,X6S,SA
     1 P5E_CPU0_P1_TX_C_DN<1> @T6G_MB_LIB.T6G(SCH_1):P5E_CPU0_P1_TX_C_DN(1)   I124 @T6G_MB_LIB.T6G(SCH_1):PAGE351
     2 P5E_CPU0_P1_TX_DN<1> @T6G_MB_LIB.T6G(SCH_1):P5E_CPU0_P1_TX_DN(1)   I124 @T6G_MB_LIB.T6G(SCH_1):PAGE351

C963 Q_CAP_DIFFBUS_C0201-DIFF BUS_0.22UF,6.3V,20%,X6S,SA
     1 P5E_CPU0_P1_TX_C_DP<1> @T6G_MB_LIB.T6G(SCH_1):P5E_CPU0_P1_TX_C_DP(1)   I123 @T6G_MB_LIB.T6G(SCH_1):PAGE351
     2 P5E_CPU0_P1_TX_DP<1> @T6G_MB_LIB.T6G(SCH_1):P5E_CPU0_P1_TX_DP(1)   I123 @T6G_MB_LIB.T6G(SCH_1):PAGE351

C964 Q_CAP_DIFFBUS_C0201-DIFF BUS_0.22UF,6.3V,20%,X6S,SA
     1 P5E_CPU0_P1_TX_C_DN<0> @T6G_MB_LIB.T6G(SCH_1):P5E_CPU0_P1_TX_C_DN(0)   I122 @T6G_MB_LIB.T6G(SCH_1):PAGE351
     2 P5E_CPU0_P1_TX_DN<0> @T6G_MB_LIB.T6G(SCH_1):P5E_CPU0_P1_TX_DN(0)   I122 @T6G_MB_LIB.T6G(SCH_1):PAGE351

C965 Q_CAP_DIFFBUS_C0201-DIFF BUS_0.22UF,6.3V,20%,X6S,SA
     1 P5E_CPU0_P1_TX_C_DP<0> @T6G_MB_LIB.T6G(SCH_1):P5E_CPU0_P1_TX_C_DP(0)   I121 @T6G_MB_LIB.T6G(SCH_1):PAGE351
     2 P5E_CPU0_P1_TX_DP<0> @T6G_MB_LIB.T6G(SCH_1):P5E_CPU0_P1_TX_DP(0)   I121 @T6G_MB_LIB.T6G(SCH_1):PAGE351

C966 Q_CAP_C0805-100UF,4V,20%,X6S,CH710KMEA01
     1 P0V9_CPU0_RT2_2A @T6G_MB_LIB.T6G(SCH_1):P0V9_CPU0_RT2_2A    I58 @T6G_MB_LIB.T6G(SCH_1):PAGE422
     2    GND @T6G_MB_LIB.T6G(SCH_1):GND    I58 @T6G_MB_LIB.T6G(SCH_1):PAGE422

C967 Q_CAP_0402-4.7UF,6.3V,20%,X6S,CH5471MEB01
     1 P0V9_CPU0_RT2_2A @T6G_MB_LIB.T6G(SCH_1):P0V9_CPU0_RT2_2A    I56 @T6G_MB_LIB.T6G(SCH_1):PAGE422
     2    GND @T6G_MB_LIB.T6G(SCH_1):GND    I56 @T6G_MB_LIB.T6G(SCH_1):PAGE422

C968 Q_CAP_C0201-0.1UF,10V,10%,X7S,CH4102K6E00
     1 P0V9_CPU0_RT2_2A @T6G_MB_LIB.T6G(SCH_1):P0V9_CPU0_RT2_2A    I69 @T6G_MB_LIB.T6G(SCH_1):PAGE422
     2    GND @T6G_MB_LIB.T6G(SCH_1):GND    I69 @T6G_MB_LIB.T6G(SCH_1):PAGE422

C969 Q_CAP_C0402-22UF,4V,20%,X6S,CH622KMEB02
     1 P0V9_CPU0_RT2_2A @T6G_MB_LIB.T6G(SCH_1):P0V9_CPU0_RT2_2A    I59 @T6G_MB_LIB.T6G(SCH_1):PAGE422
     2    GND @T6G_MB_LIB.T6G(SCH_1):GND    I59 @T6G_MB_LIB.T6G(SCH_1):PAGE422

C970 Q_CAP_0402-4.7UF,6.3V,20%,X6S,CH5471MEB01
     1 P0V9_CPU0_RT2_2A @T6G_MB_LIB.T6G(SCH_1):P0V9_CPU0_RT2_2A    I57 @T6G_MB_LIB.T6G(SCH_1):PAGE422
     2    GND @T6G_MB_LIB.T6G(SCH_1):GND    I57 @T6G_MB_LIB.T6G(SCH_1):PAGE422

C971 Q_CAP_C0402-10UF,6.3V,20%,X6S,CH6101MEB01
     1 P0V9_CPU0_RT_2D @T6G_MB_LIB.T6G(SCH_1):P0V9_CPU0_RT_2D    I79 @T6G_MB_LIB.T6G(SCH_1):PAGE422
     2    GND @T6G_MB_LIB.T6G(SCH_1):GND    I79 @T6G_MB_LIB.T6G(SCH_1):PAGE422

C972 Q_CAP_C0201-0.1UF,10V,10%,X7S,CH4102K6E00
     1 P0V9_CPU0_RT2_2A @T6G_MB_LIB.T6G(SCH_1):P0V9_CPU0_RT2_2A    I92 @T6G_MB_LIB.T6G(SCH_1):PAGE422
     2    GND @T6G_MB_LIB.T6G(SCH_1):GND    I92 @T6G_MB_LIB.T6G(SCH_1):PAGE422

C973 Q_CAP_C0402-10UF,6.3V,20%,X6S,CH6101MEB01
     1 P0V9_CPU0_RT2_2A @T6G_MB_LIB.T6G(SCH_1):P0V9_CPU0_RT2_2A    I75 @T6G_MB_LIB.T6G(SCH_1):PAGE422
     2    GND @T6G_MB_LIB.T6G(SCH_1):GND    I75 @T6G_MB_LIB.T6G(SCH_1):PAGE422

C974 Q_CAP_C0402-22UF,4V,20%,X6S,CH622KMEB02
     1 P0V9_CPU0_RT2_2A @T6G_MB_LIB.T6G(SCH_1):P0V9_CPU0_RT2_2A    I64 @T6G_MB_LIB.T6G(SCH_1):PAGE422
     2    GND @T6G_MB_LIB.T6G(SCH_1):GND    I64 @T6G_MB_LIB.T6G(SCH_1):PAGE422

C975 Q_CAP_0201-1UF,4V,20%,X6S,CH-10KMEE00
     1 P0V9_CPU0_RT2_2A @T6G_MB_LIB.T6G(SCH_1):P0V9_CPU0_RT2_2A    I54 @T6G_MB_LIB.T6G(SCH_1):PAGE422
     2    GND @T6G_MB_LIB.T6G(SCH_1):GND    I54 @T6G_MB_LIB.T6G(SCH_1):PAGE422

C976 Q_CAP_0402-4.7UF,6.3V,20%,X6S,CH5471MEB01
     1 P0V9_CPU0_RT_2D @T6G_MB_LIB.T6G(SCH_1):P0V9_CPU0_RT_2D    I80 @T6G_MB_LIB.T6G(SCH_1):PAGE422
     2    GND @T6G_MB_LIB.T6G(SCH_1):GND    I80 @T6G_MB_LIB.T6G(SCH_1):PAGE422

C977 Q_CAP_0402-4.7UF,6.3V,20%,X6S,CH5471MEB01
     1 P0V9_CPU0_RT2_2A @T6G_MB_LIB.T6G(SCH_1):P0V9_CPU0_RT2_2A    I60 @T6G_MB_LIB.T6G(SCH_1):PAGE422
     2    GND @T6G_MB_LIB.T6G(SCH_1):GND    I60 @T6G_MB_LIB.T6G(SCH_1):PAGE422

C978 Q_CAP_0201-1UF,4V,20%,X6S,CH-10KMEE00
     1 P0V9_CPU0_RT2_2A @T6G_MB_LIB.T6G(SCH_1):P0V9_CPU0_RT2_2A    I61 @T6G_MB_LIB.T6G(SCH_1):PAGE422
     2    GND @T6G_MB_LIB.T6G(SCH_1):GND    I61 @T6G_MB_LIB.T6G(SCH_1):PAGE422

C979 Q_CAP_0201-1UF,4V,20%,X6S,CH-10KMEE00
     1 P0V9_CPU0_RT2_2A @T6G_MB_LIB.T6G(SCH_1):P0V9_CPU0_RT2_2A    I55 @T6G_MB_LIB.T6G(SCH_1):PAGE422
     2    GND @T6G_MB_LIB.T6G(SCH_1):GND    I55 @T6G_MB_LIB.T6G(SCH_1):PAGE422

C980 Q_CAP_0201-1UF,4V,20%,X6S,CH-10KMEE00
     1 P0V9_CPU0_RT_2D @T6G_MB_LIB.T6G(SCH_1):P0V9_CPU0_RT_2D    I81 @T6G_MB_LIB.T6G(SCH_1):PAGE422
     2    GND @T6G_MB_LIB.T6G(SCH_1):GND    I81 @T6G_MB_LIB.T6G(SCH_1):PAGE422

C981 Q_CAP_0402-4.7UF,6.3V,20%,X6S,CH5471MEB01
     1 P0V9_CPU0_RT2_2A @T6G_MB_LIB.T6G(SCH_1):P0V9_CPU0_RT2_2A    I49 @T6G_MB_LIB.T6G(SCH_1):PAGE422
     2    GND @T6G_MB_LIB.T6G(SCH_1):GND    I49 @T6G_MB_LIB.T6G(SCH_1):PAGE422

C982 Q_CAP_C0201-0.1UF,10V,10%,X7S,CH4102K6E00
     1 P0V9_CPU0_RT2_2A @T6G_MB_LIB.T6G(SCH_1):P0V9_CPU0_RT2_2A    I34 @T6G_MB_LIB.T6G(SCH_1):PAGE422
     2    GND @T6G_MB_LIB.T6G(SCH_1):GND    I34 @T6G_MB_LIB.T6G(SCH_1):PAGE422

C983 Q_CAP_0201-1UF,4V,20%,X6S,CH-10KMEE00
     1 P0V9_CPU0_RT2_2A @T6G_MB_LIB.T6G(SCH_1):P0V9_CPU0_RT2_2A    I66 @T6G_MB_LIB.T6G(SCH_1):PAGE422
     2    GND @T6G_MB_LIB.T6G(SCH_1):GND    I66 @T6G_MB_LIB.T6G(SCH_1):PAGE422

C984 Q_CAP_C0201-0.1UF,10V,10%,X7S,CH4102K6E00
     1 P0V9_CPU0_RT2_2A @T6G_MB_LIB.T6G(SCH_1):P0V9_CPU0_RT2_2A    I35 @T6G_MB_LIB.T6G(SCH_1):PAGE422
     2    GND @T6G_MB_LIB.T6G(SCH_1):GND    I35 @T6G_MB_LIB.T6G(SCH_1):PAGE422

C985 Q_CAP_C0201-0.1UF,10V,10%,X7S,CH4102K6E00
     1 P0V9_CPU0_RT2_2A @T6G_MB_LIB.T6G(SCH_1):P0V9_CPU0_RT2_2A    I93 @T6G_MB_LIB.T6G(SCH_1):PAGE422
     2    GND @T6G_MB_LIB.T6G(SCH_1):GND    I93 @T6G_MB_LIB.T6G(SCH_1):PAGE422

C986 Q_CAP_C0402-10UF,6.3V,20%,X6S,CH6101MEB01
     1 P0V9_CPU0_RT2_2A @T6G_MB_LIB.T6G(SCH_1):P0V9_CPU0_RT2_2A    I74 @T6G_MB_LIB.T6G(SCH_1):PAGE422
     2    GND @T6G_MB_LIB.T6G(SCH_1):GND    I74 @T6G_MB_LIB.T6G(SCH_1):PAGE422

C987 Q_CAP_C0201-0.1UF,10V,10%,X7S,CH4102K6E00
     1 P0V9_CPU0_RT2_2A @T6G_MB_LIB.T6G(SCH_1):P0V9_CPU0_RT2_2A    I41 @T6G_MB_LIB.T6G(SCH_1):PAGE422
     2    GND @T6G_MB_LIB.T6G(SCH_1):GND    I41 @T6G_MB_LIB.T6G(SCH_1):PAGE422

C988 Q_CAP_C0402-22UF,4V,20%,X6S,CH622KMEB02
     1 P0V9_CPU0_RT2_2A @T6G_MB_LIB.T6G(SCH_1):P0V9_CPU0_RT2_2A    I63 @T6G_MB_LIB.T6G(SCH_1):PAGE422
     2    GND @T6G_MB_LIB.T6G(SCH_1):GND    I63 @T6G_MB_LIB.T6G(SCH_1):PAGE422

C989 Q_CAP_C0201-0.1UF,10V,10%,X7S,CH4102K6E00
     1 P1V8_CPU0_RT_1D @T6G_MB_LIB.T6G(SCH_1):P1V8_CPU0_RT_1D    I23 @T6G_MB_LIB.T6G(SCH_1):PAGE421
     2    GND @T6G_MB_LIB.T6G(SCH_1):GND    I23 @T6G_MB_LIB.T6G(SCH_1):PAGE421

C990 Q_CAP_C0805-100UF,4V,20%,X6S,CH710KMEA01
     1 P1V8_CPU0_RT_1D @T6G_MB_LIB.T6G(SCH_1):P1V8_CPU0_RT_1D    I19 @T6G_MB_LIB.T6G(SCH_1):PAGE433
     2    GND @T6G_MB_LIB.T6G(SCH_1):GND    I19 @T6G_MB_LIB.T6G(SCH_1):PAGE433

C991 Q_CAP_C0805-100UF,4V,20%,X6S,CH710KMEA01
     1 P1V8_CPU0_RT3_1A @T6G_MB_LIB.T6G(SCH_1):P1V8_CPU0_RT3_1A    I12 @T6G_MB_LIB.T6G(SCH_1):PAGE433
     2    GND @T6G_MB_LIB.T6G(SCH_1):GND    I12 @T6G_MB_LIB.T6G(SCH_1):PAGE433

C992 Q_CAP_C0402-22UF,4V,20%,X6S,CH622KMEB02
     1 P1V8_CPU0_RT_1D @T6G_MB_LIB.T6G(SCH_1):P1V8_CPU0_RT_1D    I20 @T6G_MB_LIB.T6G(SCH_1):PAGE433
     2    GND @T6G_MB_LIB.T6G(SCH_1):GND    I20 @T6G_MB_LIB.T6G(SCH_1):PAGE433

C993 Q_CAP_C0402-22UF,4V,20%,X6S,CH622KMEB02
     1 P1V8_CPU0_RT3_1A @T6G_MB_LIB.T6G(SCH_1):P1V8_CPU0_RT3_1A    I13 @T6G_MB_LIB.T6G(SCH_1):PAGE433
     2    GND @T6G_MB_LIB.T6G(SCH_1):GND    I13 @T6G_MB_LIB.T6G(SCH_1):PAGE433

C994 Q_CAP_C0402-10UF,6.3V,20%,X6S,CH6101MEB01
     1 P1V8_CPU0_RT_1D @T6G_MB_LIB.T6G(SCH_1):P1V8_CPU0_RT_1D    I21 @T6G_MB_LIB.T6G(SCH_1):PAGE433
     2    GND @T6G_MB_LIB.T6G(SCH_1):GND    I21 @T6G_MB_LIB.T6G(SCH_1):PAGE433

C995 Q_CAP_C0402-10UF,6.3V,20%,X6S,CH6101MEB01
     1 P1V8_CPU0_RT3_1A @T6G_MB_LIB.T6G(SCH_1):P1V8_CPU0_RT3_1A    I15 @T6G_MB_LIB.T6G(SCH_1):PAGE433
     2    GND @T6G_MB_LIB.T6G(SCH_1):GND    I15 @T6G_MB_LIB.T6G(SCH_1):PAGE433

C996 Q_CAP_0402-4.7UF,6.3V,20%,X6S,CH5471MEB01
     1 P1V8_CPU0_RT3_1A @T6G_MB_LIB.T6G(SCH_1):P1V8_CPU0_RT3_1A    I16 @T6G_MB_LIB.T6G(SCH_1):PAGE433
     2    GND @T6G_MB_LIB.T6G(SCH_1):GND    I16 @T6G_MB_LIB.T6G(SCH_1):PAGE433

C997 Q_CAP_0402-4.7UF,6.3V,20%,X6S,CH5471MEB01
     1 P1V8_CPU0_RT_1D @T6G_MB_LIB.T6G(SCH_1):P1V8_CPU0_RT_1D    I22 @T6G_MB_LIB.T6G(SCH_1):PAGE433
     2    GND @T6G_MB_LIB.T6G(SCH_1):GND    I22 @T6G_MB_LIB.T6G(SCH_1):PAGE433

C998 Q_CAP_0201-1UF,4V,20%,X6S,CH-10KMEE00
     1 P1V8_CPU0_RT3_1A @T6G_MB_LIB.T6G(SCH_1):P1V8_CPU0_RT3_1A    I17 @T6G_MB_LIB.T6G(SCH_1):PAGE433
     2    GND @T6G_MB_LIB.T6G(SCH_1):GND    I17 @T6G_MB_LIB.T6G(SCH_1):PAGE433

C999 Q_CAP_0201-1UF,4V,20%,X6S,CH-10KMEE00
     1 P1V8_CPU0_RT3_1A_1D @T6G_MB_LIB.T6G(SCH_1):P1V8_CPU0_RT3_1A_1D     I5 @T6G_MB_LIB.T6G(SCH_1):PAGE433
     2    GND @T6G_MB_LIB.T6G(SCH_1):GND     I5 @T6G_MB_LIB.T6G(SCH_1):PAGE433

C1000 Q_CAP_0201-1UF,4V,20%,X6S,CH-10KMEE00
     1 P1V8_CPU0_RT3_1A @T6G_MB_LIB.T6G(SCH_1):P1V8_CPU0_RT3_1A    I24 @T6G_MB_LIB.T6G(SCH_1):PAGE433
     2    GND @T6G_MB_LIB.T6G(SCH_1):GND    I24 @T6G_MB_LIB.T6G(SCH_1):PAGE433

C1001 Q_CAP_C0201-0.1UF,10V,10%,X7S,CH4102K6E00
     1 P1V8_CPU0_RT3_1A @T6G_MB_LIB.T6G(SCH_1):P1V8_CPU0_RT3_1A    I25 @T6G_MB_LIB.T6G(SCH_1):PAGE433
     2    GND @T6G_MB_LIB.T6G(SCH_1):GND    I25 @T6G_MB_LIB.T6G(SCH_1):PAGE433

C1002 Q_CAP_C0201-0.1UF,10V,10%,X7S,CH4102K6E00
     1 P1V8_CPU0_RT3_1A_1D @T6G_MB_LIB.T6G(SCH_1):P1V8_CPU0_RT3_1A_1D     I6 @T6G_MB_LIB.T6G(SCH_1):PAGE433
     2    GND @T6G_MB_LIB.T6G(SCH_1):GND     I6 @T6G_MB_LIB.T6G(SCH_1):PAGE433

C1003 Q_CAP_C0201-0.1UF,10V,10%,X7S,CH4102K6E00
     1 P1V8_CPU0_RT3_1A @T6G_MB_LIB.T6G(SCH_1):P1V8_CPU0_RT3_1A    I26 @T6G_MB_LIB.T6G(SCH_1):PAGE433
     2    GND @T6G_MB_LIB.T6G(SCH_1):GND    I26 @T6G_MB_LIB.T6G(SCH_1):PAGE433

C1004 Q_CAP_C0201-0.1UF,10V,10%,X7S,CH4102K6E00
     1 P1V8_CPU0_RT3_1A @T6G_MB_LIB.T6G(SCH_1):P1V8_CPU0_RT3_1A    I27 @T6G_MB_LIB.T6G(SCH_1):PAGE433
     2    GND @T6G_MB_LIB.T6G(SCH_1):GND    I27 @T6G_MB_LIB.T6G(SCH_1):PAGE433

C1005 Q_CAP_C0201-0.1UF,10V,10%,X7S,CH4102K6E00
     1 P1V8_CPU0_RT3_1A @T6G_MB_LIB.T6G(SCH_1):P1V8_CPU0_RT3_1A    I28 @T6G_MB_LIB.T6G(SCH_1):PAGE433
     2    GND @T6G_MB_LIB.T6G(SCH_1):GND    I28 @T6G_MB_LIB.T6G(SCH_1):PAGE433

C1006 Q_CAP_0201-1UF,4V,20%,X6S,CH-10KMEE00
     1 P0V9_CPU0_RT3_2A @T6G_MB_LIB.T6G(SCH_1):P0V9_CPU0_RT3_2A    I46 @T6G_MB_LIB.T6G(SCH_1):PAGE433
     2    GND @T6G_MB_LIB.T6G(SCH_1):GND    I46 @T6G_MB_LIB.T6G(SCH_1):PAGE433

C1007 Q_CAP_C0201-0.1UF,10V,10%,X7S,CH4102K6E00
     1 P0V9_CPU0_RT_2D @T6G_MB_LIB.T6G(SCH_1):P0V9_CPU0_RT_2D    I81 @T6G_MB_LIB.T6G(SCH_1):PAGE433
     2    GND @T6G_MB_LIB.T6G(SCH_1):GND    I81 @T6G_MB_LIB.T6G(SCH_1):PAGE433

C1008 Q_CAP_C0201-0.1UF,10V,10%,X7S,CH4102K6E00
     1 P0V9_CPU0_RT3_2A @T6G_MB_LIB.T6G(SCH_1):P0V9_CPU0_RT3_2A    I52 @T6G_MB_LIB.T6G(SCH_1):PAGE433
     2    GND @T6G_MB_LIB.T6G(SCH_1):GND    I52 @T6G_MB_LIB.T6G(SCH_1):PAGE433

C1009 Q_CAP_C0201-0.1UF,10V,10%,X7S,CH4102K6E00
     1 P0V9_CPU0_RT_2D @T6G_MB_LIB.T6G(SCH_1):P0V9_CPU0_RT_2D    I82 @T6G_MB_LIB.T6G(SCH_1):PAGE433
     2    GND @T6G_MB_LIB.T6G(SCH_1):GND    I82 @T6G_MB_LIB.T6G(SCH_1):PAGE433

C1010 Q_CAP_C0201-0.1UF,10V,10%,X7S,CH4102K6E00
     1 P0V9_CPU0_RT3_2A @T6G_MB_LIB.T6G(SCH_1):P0V9_CPU0_RT3_2A    I41 @T6G_MB_LIB.T6G(SCH_1):PAGE433
     2    GND @T6G_MB_LIB.T6G(SCH_1):GND    I41 @T6G_MB_LIB.T6G(SCH_1):PAGE433

C1011 Q_CAP_C0201-0.1UF,10V,10%,X7S,CH4102K6E00
     1 P0V9_CPU0_RT3_2A @T6G_MB_LIB.T6G(SCH_1):P0V9_CPU0_RT3_2A    I53 @T6G_MB_LIB.T6G(SCH_1):PAGE433
     2    GND @T6G_MB_LIB.T6G(SCH_1):GND    I53 @T6G_MB_LIB.T6G(SCH_1):PAGE433

C1012 Q_CAP_C0201-0.1UF,10V,10%,X7S,CH4102K6E00
     1 P0V9_CPU0_RT_2D @T6G_MB_LIB.T6G(SCH_1):P0V9_CPU0_RT_2D    I84 @T6G_MB_LIB.T6G(SCH_1):PAGE433
     2    GND @T6G_MB_LIB.T6G(SCH_1):GND    I84 @T6G_MB_LIB.T6G(SCH_1):PAGE433

C1013 Q_CAP_0201-1UF,4V,20%,X6S,CH-10KMEE00
     1 P0V9_CPU0_RT3_2A @T6G_MB_LIB.T6G(SCH_1):P0V9_CPU0_RT3_2A    I62 @T6G_MB_LIB.T6G(SCH_1):PAGE433
     2    GND @T6G_MB_LIB.T6G(SCH_1):GND    I62 @T6G_MB_LIB.T6G(SCH_1):PAGE433

C1014 Q_CAP_C0201-0.1UF,10V,10%,X7S,CH4102K6E00
     1 P0V9_CPU0_RT3_2A_2D @T6G_MB_LIB.T6G(SCH_1):P0V9_CPU0_RT3_2A_2D    I30 @T6G_MB_LIB.T6G(SCH_1):PAGE433
     2    GND @T6G_MB_LIB.T6G(SCH_1):GND    I30 @T6G_MB_LIB.T6G(SCH_1):PAGE433

C1015 Q_CAP_0201-1UF,4V,20%,X6S,CH-10KMEE00
     1 P0V9_CPU0_RT3_2A @T6G_MB_LIB.T6G(SCH_1):P0V9_CPU0_RT3_2A    I49 @T6G_MB_LIB.T6G(SCH_1):PAGE433
     2    GND @T6G_MB_LIB.T6G(SCH_1):GND    I49 @T6G_MB_LIB.T6G(SCH_1):PAGE433

C1016 Q_CAP_0201-1UF,4V,20%,X6S,CH-10KMEE00
     1 P0V9_CPU0_RT_2D @T6G_MB_LIB.T6G(SCH_1):P0V9_CPU0_RT_2D    I76 @T6G_MB_LIB.T6G(SCH_1):PAGE433
     2    GND @T6G_MB_LIB.T6G(SCH_1):GND    I76 @T6G_MB_LIB.T6G(SCH_1):PAGE433

C1017 Q_CAP_0201-1UF,4V,20%,X6S,CH-10KMEE00
     1 P0V9_CPU0_RT3_2A @T6G_MB_LIB.T6G(SCH_1):P0V9_CPU0_RT3_2A    I63 @T6G_MB_LIB.T6G(SCH_1):PAGE433
     2    GND @T6G_MB_LIB.T6G(SCH_1):GND    I63 @T6G_MB_LIB.T6G(SCH_1):PAGE433

C1018 Q_CAP_0201-1UF,4V,20%,X6S,CH-10KMEE00
     1 P0V9_CPU0_RT3_2A_2D @T6G_MB_LIB.T6G(SCH_1):P0V9_CPU0_RT3_2A_2D    I90 @T6G_MB_LIB.T6G(SCH_1):PAGE433
     2    GND @T6G_MB_LIB.T6G(SCH_1):GND    I90 @T6G_MB_LIB.T6G(SCH_1):PAGE433

C1019 Q_CAP_0201-1UF,4V,20%,X6S,CH-10KMEE00
     1 P0V9_CPU0_RT3_2A @T6G_MB_LIB.T6G(SCH_1):P0V9_CPU0_RT3_2A    I57 @T6G_MB_LIB.T6G(SCH_1):PAGE433
     2    GND @T6G_MB_LIB.T6G(SCH_1):GND    I57 @T6G_MB_LIB.T6G(SCH_1):PAGE433

C1020 Q_CAP_0201-1UF,4V,20%,X6S,CH-10KMEE00
     1 P0V9_CPU0_RT3_2A_2D @T6G_MB_LIB.T6G(SCH_1):P0V9_CPU0_RT3_2A_2D    I91 @T6G_MB_LIB.T6G(SCH_1):PAGE433
     2    GND @T6G_MB_LIB.T6G(SCH_1):GND    I91 @T6G_MB_LIB.T6G(SCH_1):PAGE433

C1021 Q_CAP_C0201-0.1UF,10V,10%,X7S,CH4102K6E00
     1 P0V9_CPU0_RT3_2A_2D @T6G_MB_LIB.T6G(SCH_1):P0V9_CPU0_RT3_2A_2D    I35 @T6G_MB_LIB.T6G(SCH_1):PAGE433
     2    GND @T6G_MB_LIB.T6G(SCH_1):GND    I35 @T6G_MB_LIB.T6G(SCH_1):PAGE433

C1022 Q_CAP_C0805-100UF,4V,20%,X6S,CH710KMEA01
     1 P0V9_CPU0_RT3_2A @T6G_MB_LIB.T6G(SCH_1):P0V9_CPU0_RT3_2A    I66 @T6G_MB_LIB.T6G(SCH_1):PAGE433
     2    GND @T6G_MB_LIB.T6G(SCH_1):GND    I66 @T6G_MB_LIB.T6G(SCH_1):PAGE433

C1023 Q_CAP_C0402-10UF,6.3V,20%,X6S,CH6101MEB01
     1 P0V9_CPU0_RT3_2A @T6G_MB_LIB.T6G(SCH_1):P0V9_CPU0_RT3_2A    I39 @T6G_MB_LIB.T6G(SCH_1):PAGE433
     2    GND @T6G_MB_LIB.T6G(SCH_1):GND    I39 @T6G_MB_LIB.T6G(SCH_1):PAGE433

C1024 Q_CAP_0201-1UF,4V,20%,X6S,CH-10KMEE00
     1 P0V9_CPU0_RT3_2A @T6G_MB_LIB.T6G(SCH_1):P0V9_CPU0_RT3_2A    I37 @T6G_MB_LIB.T6G(SCH_1):PAGE433
     2    GND @T6G_MB_LIB.T6G(SCH_1):GND    I37 @T6G_MB_LIB.T6G(SCH_1):PAGE433

C1025 Q_CAP_C0805-100UF,4V,20%,X6S,CH710KMEA01
     1 P0V9_CPU0_RT3_2A @T6G_MB_LIB.T6G(SCH_1):P0V9_CPU0_RT3_2A    I67 @T6G_MB_LIB.T6G(SCH_1):PAGE433
     2    GND @T6G_MB_LIB.T6G(SCH_1):GND    I67 @T6G_MB_LIB.T6G(SCH_1):PAGE433

C1026 Q_CAP_C0402-22UF,4V,20%,X6S,CH622KMEB02
     1 P0V9_CPU0_RT3_2A @T6G_MB_LIB.T6G(SCH_1):P0V9_CPU0_RT3_2A    I72 @T6G_MB_LIB.T6G(SCH_1):PAGE433
     2    GND @T6G_MB_LIB.T6G(SCH_1):GND    I72 @T6G_MB_LIB.T6G(SCH_1):PAGE433

C1027 Q_CAP_0201-1UF,4V,20%,X6S,CH-10KMEE00
     1 P0V9_CPU0_RT3_2A @T6G_MB_LIB.T6G(SCH_1):P0V9_CPU0_RT3_2A    I38 @T6G_MB_LIB.T6G(SCH_1):PAGE433
     2    GND @T6G_MB_LIB.T6G(SCH_1):GND    I38 @T6G_MB_LIB.T6G(SCH_1):PAGE433

C1028 Q_CAP_C0805-100UF,4V,20%,X6S,CH710KMEA01
     1 P0V9_CPU0_RT_2D @T6G_MB_LIB.T6G(SCH_1):P0V9_CPU0_RT_2D    I69 @T6G_MB_LIB.T6G(SCH_1):PAGE433
     2    GND @T6G_MB_LIB.T6G(SCH_1):GND    I69 @T6G_MB_LIB.T6G(SCH_1):PAGE433

C1029 Q_CAP_C0805-100UF,4V,20%,X6S,CH710KMEA01
     1 P0V9_CPU0_RT3_2A @T6G_MB_LIB.T6G(SCH_1):P0V9_CPU0_RT3_2A    I70 @T6G_MB_LIB.T6G(SCH_1):PAGE433
     2    GND @T6G_MB_LIB.T6G(SCH_1):GND    I70 @T6G_MB_LIB.T6G(SCH_1):PAGE433

C1030 Q_CAP_C0402-22UF,4V,20%,X6S,CH622KMEB02
     1 P0V9_CPU0_RT3_2A @T6G_MB_LIB.T6G(SCH_1):P0V9_CPU0_RT3_2A    I77 @T6G_MB_LIB.T6G(SCH_1):PAGE433
     2    GND @T6G_MB_LIB.T6G(SCH_1):GND    I77 @T6G_MB_LIB.T6G(SCH_1):PAGE433

C1031 Q_CAP_0201-1UF,4V,20%,X6S,CH-10KMEE00
     1 P0V9_CPU0_RT3_2A @T6G_MB_LIB.T6G(SCH_1):P0V9_CPU0_RT3_2A    I45 @T6G_MB_LIB.T6G(SCH_1):PAGE433
     2    GND @T6G_MB_LIB.T6G(SCH_1):GND    I45 @T6G_MB_LIB.T6G(SCH_1):PAGE433

C1032 Q_CAP_C0402-22UF,4V,20%,X6S,CH622KMEB02
     1 P0V9_CPU0_RT_2D @T6G_MB_LIB.T6G(SCH_1):P0V9_CPU0_RT_2D    I74 @T6G_MB_LIB.T6G(SCH_1):PAGE433
     2    GND @T6G_MB_LIB.T6G(SCH_1):GND    I74 @T6G_MB_LIB.T6G(SCH_1):PAGE433

C1033 Q_CAP_C0805-100UF,4V,20%,X6S,CH710KMEA01
     1 P0V9_CPU0_RT3_2A @T6G_MB_LIB.T6G(SCH_1):P0V9_CPU0_RT3_2A    I71 @T6G_MB_LIB.T6G(SCH_1):PAGE433
     2    GND @T6G_MB_LIB.T6G(SCH_1):GND    I71 @T6G_MB_LIB.T6G(SCH_1):PAGE433

C1034 Q_CAP_0402-4.7UF,6.3V,20%,X6S,CH5471MEB01
     1 P0V9_CPU0_RT3_2A @T6G_MB_LIB.T6G(SCH_1):P0V9_CPU0_RT3_2A    I47 @T6G_MB_LIB.T6G(SCH_1):PAGE433
     2    GND @T6G_MB_LIB.T6G(SCH_1):GND    I47 @T6G_MB_LIB.T6G(SCH_1):PAGE433

C1035 Q_CAP_C0201-0.1UF,10V,10%,X7S,CH4102K6E00
     1 P0V9_CPU0_RT3_2A @T6G_MB_LIB.T6G(SCH_1):P0V9_CPU0_RT3_2A    I44 @T6G_MB_LIB.T6G(SCH_1):PAGE433
     2    GND @T6G_MB_LIB.T6G(SCH_1):GND    I44 @T6G_MB_LIB.T6G(SCH_1):PAGE433

C1036 Q_CAP_C0402-10UF,6.3V,20%,X6S,CH6101MEB01
     1 P0V9_CPU0_RT3_2A @T6G_MB_LIB.T6G(SCH_1):P0V9_CPU0_RT3_2A    I40 @T6G_MB_LIB.T6G(SCH_1):PAGE433
     2    GND @T6G_MB_LIB.T6G(SCH_1):GND    I40 @T6G_MB_LIB.T6G(SCH_1):PAGE433

C1037 Q_CAP_C0402-10UF,6.3V,20%,X6S,CH6101MEB01
     1 P0V9_CPU0_RT3_2A @T6G_MB_LIB.T6G(SCH_1):P0V9_CPU0_RT3_2A    I79 @T6G_MB_LIB.T6G(SCH_1):PAGE433
     2    GND @T6G_MB_LIB.T6G(SCH_1):GND    I79 @T6G_MB_LIB.T6G(SCH_1):PAGE433

C1038 Q_CAP_0402-4.7UF,6.3V,20%,X6S,CH5471MEB01
     1 P0V9_CPU0_RT_2D @T6G_MB_LIB.T6G(SCH_1):P0V9_CPU0_RT_2D    I75 @T6G_MB_LIB.T6G(SCH_1):PAGE433
     2    GND @T6G_MB_LIB.T6G(SCH_1):GND    I75 @T6G_MB_LIB.T6G(SCH_1):PAGE433

C1039 Q_CAP_0201-1UF,4V,20%,X6S,CH-10KMEE00
     1 P0V9_CPU0_RT3_2A @T6G_MB_LIB.T6G(SCH_1):P0V9_CPU0_RT3_2A    I48 @T6G_MB_LIB.T6G(SCH_1):PAGE433
     2    GND @T6G_MB_LIB.T6G(SCH_1):GND    I48 @T6G_MB_LIB.T6G(SCH_1):PAGE433

C1040 Q_CAP_C0402-22UF,4V,20%,X6S,CH622KMEB02
     1 P0V9_CPU0_RT3_2A @T6G_MB_LIB.T6G(SCH_1):P0V9_CPU0_RT3_2A    I86 @T6G_MB_LIB.T6G(SCH_1):PAGE433
     2    GND @T6G_MB_LIB.T6G(SCH_1):GND    I86 @T6G_MB_LIB.T6G(SCH_1):PAGE433

C1041 Q_CAP_C0402-22UF,4V,20%,X6S,CH622KMEB02
     1 P0V9_CPU0_RT3_2A @T6G_MB_LIB.T6G(SCH_1):P0V9_CPU0_RT3_2A    I78 @T6G_MB_LIB.T6G(SCH_1):PAGE433
     2    GND @T6G_MB_LIB.T6G(SCH_1):GND    I78 @T6G_MB_LIB.T6G(SCH_1):PAGE433

C1042 Q_CAP_C0402-100NF,50V,10%,X7R,CH4106K1B01
     1 P5V_AUX @T6G_MB_LIB.T6G(SCH_1):P5V_AUX    I18 @T6G_MB_LIB.T6G(SCH_1):PAGE273
     2    GND @T6G_MB_LIB.T6G(SCH_1):GND    I18 @T6G_MB_LIB.T6G(SCH_1):PAGE273

C1043 Q_CAP_C0201-0.1UF,10V,10%,X7S,CH4102K6E00
     1 P0V9_CPU0_RT3_2A @T6G_MB_LIB.T6G(SCH_1):P0V9_CPU0_RT3_2A    I54 @T6G_MB_LIB.T6G(SCH_1):PAGE433
     2    GND @T6G_MB_LIB.T6G(SCH_1):GND    I54 @T6G_MB_LIB.T6G(SCH_1):PAGE433

C1044 Q_CAP_C0402-10UF,6.3V,20%,X6S,CH6101MEB01
     1 P0V9_CPU0_RT_2D @T6G_MB_LIB.T6G(SCH_1):P0V9_CPU0_RT_2D    I73 @T6G_MB_LIB.T6G(SCH_1):PAGE433
     2    GND @T6G_MB_LIB.T6G(SCH_1):GND    I73 @T6G_MB_LIB.T6G(SCH_1):PAGE433

C1045 Q_CAP_0402-4.7UF,6.3V,20%,X6S,CH5471MEB01
     1 P0V9_CPU0_RT3_2A @T6G_MB_LIB.T6G(SCH_1):P0V9_CPU0_RT3_2A    I87 @T6G_MB_LIB.T6G(SCH_1):PAGE433
     2    GND @T6G_MB_LIB.T6G(SCH_1):GND    I87 @T6G_MB_LIB.T6G(SCH_1):PAGE433

C1046 Q_CAP_0201-1UF,4V,20%,X6S,CH-10KMEE00
     1 P0V9_CPU0_RT3_2A @T6G_MB_LIB.T6G(SCH_1):P0V9_CPU0_RT3_2A    I59 @T6G_MB_LIB.T6G(SCH_1):PAGE433
     2    GND @T6G_MB_LIB.T6G(SCH_1):GND    I59 @T6G_MB_LIB.T6G(SCH_1):PAGE433

C1047 Q_CAP_C0201-0.1UF,10V,10%,X7S,CH4102K6E00
     1 P0V9_CPU0_RT3_2A @T6G_MB_LIB.T6G(SCH_1):P0V9_CPU0_RT3_2A    I56 @T6G_MB_LIB.T6G(SCH_1):PAGE433
     2    GND @T6G_MB_LIB.T6G(SCH_1):GND    I56 @T6G_MB_LIB.T6G(SCH_1):PAGE433

C1048 Q_CAP_C0201-0.1UF,10V,10%,X7S,CH4102K6E00
     1 P0V9_CPU0_RT_2D @T6G_MB_LIB.T6G(SCH_1):P0V9_CPU0_RT_2D    I85 @T6G_MB_LIB.T6G(SCH_1):PAGE433
     2    GND @T6G_MB_LIB.T6G(SCH_1):GND    I85 @T6G_MB_LIB.T6G(SCH_1):PAGE433

C1049 Q_CAP_C0402-10UF,6.3V,20%,X6S,CH6101MEB01
     1 P0V9_CPU0_RT3_2A @T6G_MB_LIB.T6G(SCH_1):P0V9_CPU0_RT3_2A    I80 @T6G_MB_LIB.T6G(SCH_1):PAGE433
     2    GND @T6G_MB_LIB.T6G(SCH_1):GND    I80 @T6G_MB_LIB.T6G(SCH_1):PAGE433

C1050 Q_CAP_0201-1UF,4V,20%,X6S,CH-10KMEE00
     1 P0V9_CPU0_RT3_2A @T6G_MB_LIB.T6G(SCH_1):P0V9_CPU0_RT3_2A    I60 @T6G_MB_LIB.T6G(SCH_1):PAGE433
     2    GND @T6G_MB_LIB.T6G(SCH_1):GND    I60 @T6G_MB_LIB.T6G(SCH_1):PAGE433

C1051 Q_CAP_C0201-0.1UF,10V,10%,X7S,CH4102K6E00
     1 P0V9_CPU0_RT3_2A @T6G_MB_LIB.T6G(SCH_1):P0V9_CPU0_RT3_2A    I92 @T6G_MB_LIB.T6G(SCH_1):PAGE433
     2    GND @T6G_MB_LIB.T6G(SCH_1):GND    I92 @T6G_MB_LIB.T6G(SCH_1):PAGE433

C1052 Q_CAP_C0201-0.1UF,10V,10%,X7S,CH4102K6E00
     1 P0V9_CPU0_RT3_2A @T6G_MB_LIB.T6G(SCH_1):P0V9_CPU0_RT3_2A    I42 @T6G_MB_LIB.T6G(SCH_1):PAGE433
     2    GND @T6G_MB_LIB.T6G(SCH_1):GND    I42 @T6G_MB_LIB.T6G(SCH_1):PAGE433

C1053 Q_CAP_C0201-0.1UF,10V,10%,X7S,CH4102K6E00
     1 P0V9_CPU0_RT3_2A @T6G_MB_LIB.T6G(SCH_1):P0V9_CPU0_RT3_2A    I93 @T6G_MB_LIB.T6G(SCH_1):PAGE433
     2    GND @T6G_MB_LIB.T6G(SCH_1):GND    I93 @T6G_MB_LIB.T6G(SCH_1):PAGE433

C1054 Q_CAP_0402-4.7UF,6.3V,20%,X6S,CH5471MEB01
     1 P0V9_CPU0_RT3_2A @T6G_MB_LIB.T6G(SCH_1):P0V9_CPU0_RT3_2A    I50 @T6G_MB_LIB.T6G(SCH_1):PAGE433
     2    GND @T6G_MB_LIB.T6G(SCH_1):GND    I50 @T6G_MB_LIB.T6G(SCH_1):PAGE433

C1055 Q_CAP_C0201-0.1UF,10V,10%,X7S,CH4102K6E00
     1 P0V9_CPU0_RT3_2A @T6G_MB_LIB.T6G(SCH_1):P0V9_CPU0_RT3_2A    I43 @T6G_MB_LIB.T6G(SCH_1):PAGE433
     2    GND @T6G_MB_LIB.T6G(SCH_1):GND    I43 @T6G_MB_LIB.T6G(SCH_1):PAGE433

C1056 Q_CAP_0402-4.7UF,6.3V,20%,X6S,CH5471MEB01
     1 P0V9_CPU0_RT3_2A @T6G_MB_LIB.T6G(SCH_1):P0V9_CPU0_RT3_2A    I51 @T6G_MB_LIB.T6G(SCH_1):PAGE433
     2    GND @T6G_MB_LIB.T6G(SCH_1):GND    I51 @T6G_MB_LIB.T6G(SCH_1):PAGE433

C1057 Q_CAP_C0201-0.1UF,10V,10%,X7S,CH4102K6E00
     1 P1V8_CPU0_RT_1D @T6G_MB_LIB.T6G(SCH_1):P1V8_CPU0_RT_1D    I23 @T6G_MB_LIB.T6G(SCH_1):PAGE432
     2    GND @T6G_MB_LIB.T6G(SCH_1):GND    I23 @T6G_MB_LIB.T6G(SCH_1):PAGE432

C1058 Q_CAP_0402-0.1UF,25V,10%,X7R,CH4104K1B00
     1 P3V3_AUX @T6G_MB_LIB.T6G(SCH_1):P3V3_AUX    I53 @T6G_MB_LIB.T6G(SCH_1):PAGE340
     2    GND @T6G_MB_LIB.T6G(SCH_1):GND    I53 @T6G_MB_LIB.T6G(SCH_1):PAGE340

C1059 Q_CAP_0402-0.1UF,25V,10%,X7R,CH4104K1B00
     1 P3V3_AUX @T6G_MB_LIB.T6G(SCH_1):P3V3_AUX    I40 @T6G_MB_LIB.T6G(SCH_1):PAGE340
     2    GND @T6G_MB_LIB.T6G(SCH_1):GND    I40 @T6G_MB_LIB.T6G(SCH_1):PAGE340

C1060 Q_CAP_0402-0.1UF,25V,10%,X7R,CH4104K1B00
     1 P3V3_AUX @T6G_MB_LIB.T6G(SCH_1):P3V3_AUX    I69 @T6G_MB_LIB.T6G(SCH_1):PAGE340
     2    GND @T6G_MB_LIB.T6G(SCH_1):GND    I69 @T6G_MB_LIB.T6G(SCH_1):PAGE340

C1061 Q_CAP_0402-0.1UF,25V,10%,X7R,CH4104K1B00
     1 P3V3_AUX @T6G_MB_LIB.T6G(SCH_1):P3V3_AUX     I5 @T6G_MB_LIB.T6G(SCH_1):PAGE257
     2    GND @T6G_MB_LIB.T6G(SCH_1):GND     I5 @T6G_MB_LIB.T6G(SCH_1):PAGE257

C1062 Q_CAP_0402-0.1UF,25V,10%,X7R,CH4104K1B00
     1 P3V3_AUX @T6G_MB_LIB.T6G(SCH_1):P3V3_AUX    I36 @T6G_MB_LIB.T6G(SCH_1):PAGE257
     2    GND @T6G_MB_LIB.T6G(SCH_1):GND    I36 @T6G_MB_LIB.T6G(SCH_1):PAGE257

C1063 Q_CAP_0402-0.1UF,25V,10%,X7R,CH4104K1B00
     1 P3V3_AUX @T6G_MB_LIB.T6G(SCH_1):P3V3_AUX    I55 @T6G_MB_LIB.T6G(SCH_1):PAGE257
     2    GND @T6G_MB_LIB.T6G(SCH_1):GND    I55 @T6G_MB_LIB.T6G(SCH_1):PAGE257

C1064 Q_CAP_0402-0.1UF,25V,10%,X7R,CH4104K1B00
     1 P3V3_AUX @T6G_MB_LIB.T6G(SCH_1):P3V3_AUX    I46 @T6G_MB_LIB.T6G(SCH_1):PAGE257
     2    GND @T6G_MB_LIB.T6G(SCH_1):GND    I46 @T6G_MB_LIB.T6G(SCH_1):PAGE257

C1065 Q_CAP_0402-0.1UF,25V,10%,X7R,CH4104K1B00
     1 P3V3_AUX @T6G_MB_LIB.T6G(SCH_1):P3V3_AUX    I14 @T6G_MB_LIB.T6G(SCH_1):PAGE257
     2    GND @T6G_MB_LIB.T6G(SCH_1):GND    I14 @T6G_MB_LIB.T6G(SCH_1):PAGE257

C1066 Q_CAP_C0201-0.1UF,10V,10%,X7S,CH4102K6E00
     1 P3V3_AUX @T6G_MB_LIB.T6G(SCH_1):P3V3_AUX    I48 @T6G_MB_LIB.T6G(SCH_1):PAGE376
     2    GND @T6G_MB_LIB.T6G(SCH_1):GND    I48 @T6G_MB_LIB.T6G(SCH_1):PAGE376

C1067 Q_CAP_C0201-0.1UF,10V,10%,X7S,CH4102K6E00
     1 P3V3_AUX @T6G_MB_LIB.T6G(SCH_1):P3V3_AUX    I37 @T6G_MB_LIB.T6G(SCH_1):PAGE376
     2    GND @T6G_MB_LIB.T6G(SCH_1):GND    I37 @T6G_MB_LIB.T6G(SCH_1):PAGE376

C1068 Q_CAP_C0201-0.1UF,10V,10%,X7S,CH4102K6E00
     1 P3V3_AUX @T6G_MB_LIB.T6G(SCH_1):P3V3_AUX    I65 @T6G_MB_LIB.T6G(SCH_1):PAGE376
     2    GND @T6G_MB_LIB.T6G(SCH_1):GND    I65 @T6G_MB_LIB.T6G(SCH_1):PAGE376

C1069 Q_CAP_C0201-0.1UF,10V,10%,X7S,CH4102K6E00
     1 P3V3_AUX @T6G_MB_LIB.T6G(SCH_1):P3V3_AUX    I24 @T6G_MB_LIB.T6G(SCH_1):PAGE376
     2    GND @T6G_MB_LIB.T6G(SCH_1):GND    I24 @T6G_MB_LIB.T6G(SCH_1):PAGE376

C1070 Q_CAP_C0201-0.1UF,10V,10%,X7S,CH4102K6E00
     1 P3V3_AUX @T6G_MB_LIB.T6G(SCH_1):P3V3_AUX    I99 @T6G_MB_LIB.T6G(SCH_1):PAGE376
     2    GND @T6G_MB_LIB.T6G(SCH_1):GND    I99 @T6G_MB_LIB.T6G(SCH_1):PAGE376

C1071 Q_CAP_C0201-0.1UF,10V,10%,X7S,CH4102K6E00
     1 P3V3_AUX @T6G_MB_LIB.T6G(SCH_1):P3V3_AUX   I105 @T6G_MB_LIB.T6G(SCH_1):PAGE376
     2    GND @T6G_MB_LIB.T6G(SCH_1):GND   I105 @T6G_MB_LIB.T6G(SCH_1):PAGE376

C1072 Q_CAP_C0201-0.1UF,10V,10%,X7S,CH4102K6E00
     1 P3V3_AUX @T6G_MB_LIB.T6G(SCH_1):P3V3_AUX    I84 @T6G_MB_LIB.T6G(SCH_1):PAGE376
     2    GND @T6G_MB_LIB.T6G(SCH_1):GND    I84 @T6G_MB_LIB.T6G(SCH_1):PAGE376

C1073 Q_CAP_C0201-0.1UF,10V,10%,X7S,CH4102K6E00
     1 P3V3_AUX @T6G_MB_LIB.T6G(SCH_1):P3V3_AUX    I80 @T6G_MB_LIB.T6G(SCH_1):PAGE376
     2    GND @T6G_MB_LIB.T6G(SCH_1):GND    I80 @T6G_MB_LIB.T6G(SCH_1):PAGE376

C1074 Q_CAP_0402-0.1UF,25V,10%,X7R,CH4104K1B00
     1 MAX11617_2_VREF @T6G_MB_LIB.T6G(SCH_1):MAX11617_2_VREF   I115 @T6G_MB_LIB.T6G(SCH_1):PAGE263
     2    GND @T6G_MB_LIB.T6G(SCH_1):GND   I115 @T6G_MB_LIB.T6G(SCH_1):PAGE263

C1075 Q_CAP_0402-0.1UF,25V,10%,X7R,CH4104K1B00
     1 P3V3_MAX11617_2_VDD @T6G_MB_LIB.T6G(SCH_1):P3V3_MAX11617_2_VDD   I165 @T6G_MB_LIB.T6G(SCH_1):PAGE263
     2    GND @T6G_MB_LIB.T6G(SCH_1):GND   I165 @T6G_MB_LIB.T6G(SCH_1):PAGE263

C1076 Q_CAP_C0805-10UF,16V,10%,X6S,CH6103KEA00
     1 MAX11617_2_VREF @T6G_MB_LIB.T6G(SCH_1):MAX11617_2_VREF   I152 @T6G_MB_LIB.T6G(SCH_1):PAGE263
     2    GND @T6G_MB_LIB.T6G(SCH_1):GND   I152 @T6G_MB_LIB.T6G(SCH_1):PAGE263

C1077 Q_CAP_C0805-10UF,16V,10%,X6S,CH6103KEA00
     1 P3V3_MAX11617_2_VDD @T6G_MB_LIB.T6G(SCH_1):P3V3_MAX11617_2_VDD   I166 @T6G_MB_LIB.T6G(SCH_1):PAGE263
     2    GND @T6G_MB_LIB.T6G(SCH_1):GND   I166 @T6G_MB_LIB.T6G(SCH_1):PAGE263

C1078 Q_CAP_0402-100PF,50V,5%,EMPTY,CH11006JB18
     1 P1V2_AUX_ADC_MAM @T6G_MB_LIB.T6G(SCH_1):P1V2_AUX_ADC_MAM   I173 @T6G_MB_LIB.T6G(SCH_1):PAGE263
     2    GND @T6G_MB_LIB.T6G(SCH_1):GND   I173 @T6G_MB_LIB.T6G(SCH_1):PAGE263

C1079 Q_CAP_0402-100PF,50V,5%,EMPTY,CH11006JB18
     1 P1V8_CPU0_RT_1D_ADC_MAM @T6G_MB_LIB.T6G(SCH_1):P1V8_CPU0_RT_1D_ADC_MAM   I185 @T6G_MB_LIB.T6G(SCH_1):PAGE263
     2    GND @T6G_MB_LIB.T6G(SCH_1):GND   I185 @T6G_MB_LIB.T6G(SCH_1):PAGE263

C1080 Q_CAP_0402-100PF,50V,5%,EMPTY,CH11006JB18
     1 PVDD18_S5_P0_ADC_MAM @T6G_MB_LIB.T6G(SCH_1):PVDD18_S5_P0_ADC_MAM   I221 @T6G_MB_LIB.T6G(SCH_1):PAGE263
     2    GND @T6G_MB_LIB.T6G(SCH_1):GND   I221 @T6G_MB_LIB.T6G(SCH_1):PAGE263

C1081 Q_CAP_0402-100PF,50V,5%,EMPTY,CH11006JB18
     1 PVDD18_S5_P1_ADC_MAM @T6G_MB_LIB.T6G(SCH_1):PVDD18_S5_P1_ADC_MAM   I232 @T6G_MB_LIB.T6G(SCH_1):PAGE263
     2    GND @T6G_MB_LIB.T6G(SCH_1):GND   I232 @T6G_MB_LIB.T6G(SCH_1):PAGE263

C1082 Q_CAP_0402-100PF,50V,5%,EMPTY,CH11006JB18
     1 PVDD_33_S5_ADC_MAM @T6G_MB_LIB.T6G(SCH_1):PVDD_33_S5_ADC_MAM   I209 @T6G_MB_LIB.T6G(SCH_1):PAGE263
     2    GND @T6G_MB_LIB.T6G(SCH_1):GND   I209 @T6G_MB_LIB.T6G(SCH_1):PAGE263

C1083 Q_CAP_0402-100PF,50V,5%,EMPTY,CH11006JB18
     1 P1V8_CPU1_RT_1D_ADC_MAM @T6G_MB_LIB.T6G(SCH_1):P1V8_CPU1_RT_1D_ADC_MAM   I198 @T6G_MB_LIB.T6G(SCH_1):PAGE263
     2    GND @T6G_MB_LIB.T6G(SCH_1):GND   I198 @T6G_MB_LIB.T6G(SCH_1):PAGE263

C1084 Q_CAP_0402-100PF,50V,5%,EMPTY,CH11006JB18
     1 P1V8_AUX_ADC_MAM @T6G_MB_LIB.T6G(SCH_1):P1V8_AUX_ADC_MAM    I77 @T6G_MB_LIB.T6G(SCH_1):PAGE263
     2    GND @T6G_MB_LIB.T6G(SCH_1):GND    I77 @T6G_MB_LIB.T6G(SCH_1):PAGE263

C1085 Q_CAP_0402-100PF,50V,5%,EMPTY,CH11006JB18
     1 P5V_AUX_ADC_MAM @T6G_MB_LIB.T6G(SCH_1):P5V_AUX_ADC_MAM    I45 @T6G_MB_LIB.T6G(SCH_1):PAGE263
     2    GND @T6G_MB_LIB.T6G(SCH_1):GND    I45 @T6G_MB_LIB.T6G(SCH_1):PAGE263

C1086 Q_CAP_0402-0.1UF,25V,10%,X7R,CH4104K1B00
     1 P1V2_AUX_ADC_TIC @T6G_MB_LIB.T6G(SCH_1):P1V2_AUX_ADC_TIC   I175 @T6G_MB_LIB.T6G(SCH_1):PAGE263
     2    GND @T6G_MB_LIB.T6G(SCH_1):GND   I175 @T6G_MB_LIB.T6G(SCH_1):PAGE263

C1087 Q_CAP_0402-0.1UF,25V,10%,X7R,CH4104K1B00
     1 P1V8_CPU0_RT_1D_ADC_TIC @T6G_MB_LIB.T6G(SCH_1):P1V8_CPU0_RT_1D_ADC_TIC   I187 @T6G_MB_LIB.T6G(SCH_1):PAGE263
     2    GND @T6G_MB_LIB.T6G(SCH_1):GND   I187 @T6G_MB_LIB.T6G(SCH_1):PAGE263

C1088 Q_CAP_0402-0.1UF,25V,10%,X7R,CH4104K1B00
     1 PVDD18_S5_P0_ADC_TIC @T6G_MB_LIB.T6G(SCH_1):PVDD18_S5_P0_ADC_TIC   I223 @T6G_MB_LIB.T6G(SCH_1):PAGE263
     2    GND @T6G_MB_LIB.T6G(SCH_1):GND   I223 @T6G_MB_LIB.T6G(SCH_1):PAGE263

C1089 Q_CAP_0402-0.1UF,25V,10%,X7R,CH4104K1B00
     1 PVDD_33_S5_ADC_TIC @T6G_MB_LIB.T6G(SCH_1):PVDD_33_S5_ADC_TIC   I211 @T6G_MB_LIB.T6G(SCH_1):PAGE263
     2    GND @T6G_MB_LIB.T6G(SCH_1):GND   I211 @T6G_MB_LIB.T6G(SCH_1):PAGE263

C1090 Q_CAP_0402-0.1UF,25V,10%,X7R,CH4104K1B00
     1 PVDD18_S5_P1_ADC_TIC @T6G_MB_LIB.T6G(SCH_1):PVDD18_S5_P1_ADC_TIC   I237 @T6G_MB_LIB.T6G(SCH_1):PAGE263
     2    GND @T6G_MB_LIB.T6G(SCH_1):GND   I237 @T6G_MB_LIB.T6G(SCH_1):PAGE263

C1091 Q_CAP_0402-0.1UF,25V,10%,X7R,CH4104K1B00
     1 P1V8_CPU1_RT_1D_ADC_TIC @T6G_MB_LIB.T6G(SCH_1):P1V8_CPU1_RT_1D_ADC_TIC   I200 @T6G_MB_LIB.T6G(SCH_1):PAGE263
     2    GND @T6G_MB_LIB.T6G(SCH_1):GND   I200 @T6G_MB_LIB.T6G(SCH_1):PAGE263

C1092 Q_CAP_0402-0.1UF,25V,10%,X7R,CH4104K1B00
     1 P1V8_AUX_ADC_TIC @T6G_MB_LIB.T6G(SCH_1):P1V8_AUX_ADC_TIC    I76 @T6G_MB_LIB.T6G(SCH_1):PAGE263
     2    GND @T6G_MB_LIB.T6G(SCH_1):GND    I76 @T6G_MB_LIB.T6G(SCH_1):PAGE263

C1093 Q_CAP_0402-0.1UF,25V,10%,X7R,CH4104K1B00
     1 P5V_AUX_ADC_TIC @T6G_MB_LIB.T6G(SCH_1):P5V_AUX_ADC_TIC    I43 @T6G_MB_LIB.T6G(SCH_1):PAGE263
     2    GND @T6G_MB_LIB.T6G(SCH_1):GND    I43 @T6G_MB_LIB.T6G(SCH_1):PAGE263

C1094 Q_CAP_0402-0.1UF,25V,10%,X7R,CH4104K1B00
     1 P3V3_ADC128_2_VCC @T6G_MB_LIB.T6G(SCH_1):P3V3_ADC128_2_VCC    I68 @T6G_MB_LIB.T6G(SCH_1):PAGE263
     2    GND @T6G_MB_LIB.T6G(SCH_1):GND    I68 @T6G_MB_LIB.T6G(SCH_1):PAGE263

C1095 Q_CAP_0402-0.1UF,25V,10%,X7R,CH4104K1B00
     1 P3V3_ADC128_2_VCC @T6G_MB_LIB.T6G(SCH_1):P3V3_ADC128_2_VCC   I130 @T6G_MB_LIB.T6G(SCH_1):PAGE263
     2    GND @T6G_MB_LIB.T6G(SCH_1):GND   I130 @T6G_MB_LIB.T6G(SCH_1):PAGE263

C1096 Q_CAP_0402-0.1UF,25V,10%,X7R,CH4104K1B00
     1 P3V3_AUX @T6G_MB_LIB.T6G(SCH_1):P3V3_AUX    I66 @T6G_MB_LIB.T6G(SCH_1):PAGE466
     2    GND @T6G_MB_LIB.T6G(SCH_1):GND    I66 @T6G_MB_LIB.T6G(SCH_1):PAGE466

C1097 Q_CAP_0402-0.1UF,25V,10%,X7R,CH4104K1B00
     1 P3V3_AUX @T6G_MB_LIB.T6G(SCH_1):P3V3_AUX    I19 @T6G_MB_LIB.T6G(SCH_1):PAGE466
     2    GND @T6G_MB_LIB.T6G(SCH_1):GND    I19 @T6G_MB_LIB.T6G(SCH_1):PAGE466

C1098 Q_CAP_DIFFBUS_C0201-DIFF BUS_0.22UF,6.3V,20%,X6S,SA
     1 P3E_CPU1_P4_TX_C_DP<3> @T6G_MB_LIB.T6G(SCH_1):P3E_CPU1_P4_TX_C_DP(3)   I134 @T6G_MB_LIB.T6G(SCH_1):PAGE355
     2 P3E_CPU1_P4_TX_DP<3> @T6G_MB_LIB.T6G(SCH_1):P3E_CPU1_P4_TX_DP(3)   I134 @T6G_MB_LIB.T6G(SCH_1):PAGE355

C1099 Q_CAP_DIFFBUS_C0201-DIFF BUS_0.22UF,6.3V,20%,X6S,SA
     1 P3E_CPU1_P4_TX_C_DN<3> @T6G_MB_LIB.T6G(SCH_1):P3E_CPU1_P4_TX_C_DN(3)   I133 @T6G_MB_LIB.T6G(SCH_1):PAGE355
     2 P3E_CPU1_P4_TX_DN<3> @T6G_MB_LIB.T6G(SCH_1):P3E_CPU1_P4_TX_DN(3)   I133 @T6G_MB_LIB.T6G(SCH_1):PAGE355

C1100 Q_CAP_DIFFBUS_C0201-DIFF BUS_0.22UF,6.3V,20%,X6S,SA
     1 P3E_CPU1_P4_TX_C_DP<2> @T6G_MB_LIB.T6G(SCH_1):P3E_CPU1_P4_TX_C_DP(2)   I136 @T6G_MB_LIB.T6G(SCH_1):PAGE355
     2 P3E_CPU1_P4_TX_DP<2> @T6G_MB_LIB.T6G(SCH_1):P3E_CPU1_P4_TX_DP(2)   I136 @T6G_MB_LIB.T6G(SCH_1):PAGE355

C1101 Q_CAP_DIFFBUS_C0201-DIFF BUS_0.22UF,6.3V,20%,X6S,SA
     1 P3E_CPU1_P4_TX_C_DN<2> @T6G_MB_LIB.T6G(SCH_1):P3E_CPU1_P4_TX_C_DN(2)   I135 @T6G_MB_LIB.T6G(SCH_1):PAGE355
     2 P3E_CPU1_P4_TX_DN<2> @T6G_MB_LIB.T6G(SCH_1):P3E_CPU1_P4_TX_DN(2)   I135 @T6G_MB_LIB.T6G(SCH_1):PAGE355

C1102 Q_CAP_0402-0.1UF,25V,10%,X7R,CH4104K1B00
     1 PVDD18_S5_P0 @T6G_MB_LIB.T6G(SCH_1):PVDD18_S5_P0    I53 @T6G_MB_LIB.T6G(SCH_1):PAGE76
     2    GND @T6G_MB_LIB.T6G(SCH_1):GND    I53 @T6G_MB_LIB.T6G(SCH_1):PAGE76

C1103 Q_CAP_0402-0.1UF,25V,10%,X7R,CH4104K1B00
     1 PVDD18_S5_P0 @T6G_MB_LIB.T6G(SCH_1):PVDD18_S5_P0    I65 @T6G_MB_LIB.T6G(SCH_1):PAGE76
     2    GND @T6G_MB_LIB.T6G(SCH_1):GND    I65 @T6G_MB_LIB.T6G(SCH_1):PAGE76

C1104 Q_CAP_0402-0.1UF,25V,10%,X7R,CH4104K1B00
     1 P3V3_AUX @T6G_MB_LIB.T6G(SCH_1):P3V3_AUX    I50 @T6G_MB_LIB.T6G(SCH_1):PAGE76
     2    GND @T6G_MB_LIB.T6G(SCH_1):GND    I50 @T6G_MB_LIB.T6G(SCH_1):PAGE76

C1105 Q_CAP_0402-0.1UF,25V,10%,X7R,CH4104K1B00
     1 P3V3_AUX @T6G_MB_LIB.T6G(SCH_1):P3V3_AUX    I59 @T6G_MB_LIB.T6G(SCH_1):PAGE76
     2    GND @T6G_MB_LIB.T6G(SCH_1):GND    I59 @T6G_MB_LIB.T6G(SCH_1):PAGE76

C1106 Q_CAP_0402-0.1UF,25V,10%,X7R,CH4104K1B00
     1 P3V3_AUX @T6G_MB_LIB.T6G(SCH_1):P3V3_AUX    I36 @T6G_MB_LIB.T6G(SCH_1):PAGE466
     2    GND @T6G_MB_LIB.T6G(SCH_1):GND    I36 @T6G_MB_LIB.T6G(SCH_1):PAGE466

C1107 Q_CAP_0402-0.1UF,25V,10%,X7R,CH4104K1B00
     1 P12V_E1S_0 @T6G_MB_LIB.T6G(SCH_1):P12V_E1S_0    I81 @T6G_MB_LIB.T6G(SCH_1):PAGE466
     2    GND @T6G_MB_LIB.T6G(SCH_1):GND    I81 @T6G_MB_LIB.T6G(SCH_1):PAGE466

C1108 Q_CAP_0402-0.1UF,25V,10%,X7R,CH4104K1B00
     1 P12V_OCP_SFF @T6G_MB_LIB.T6G(SCH_1):P12V_OCP_SFF     I5 @T6G_MB_LIB.T6G(SCH_1):PAGE466
     2    GND @T6G_MB_LIB.T6G(SCH_1):GND     I5 @T6G_MB_LIB.T6G(SCH_1):PAGE466

C1109 Q_CAP_0402-0.1UF,25V,10%,X7R,CH4104K1B00
     1 P12V_OCP_V3_2 @T6G_MB_LIB.T6G(SCH_1):P12V_OCP_V3_2    I51 @T6G_MB_LIB.T6G(SCH_1):PAGE466
     2    GND @T6G_MB_LIB.T6G(SCH_1):GND    I51 @T6G_MB_LIB.T6G(SCH_1):PAGE466

C1110 Q_CAP_0402-0.1UF,25V,10%,X7R,CH4104K1B00
     1 VSENSE_P12V_INA230_8_INP @T6G_MB_LIB.T6G(SCH_1):VSENSE_P12V_INA230_8_INP    I68 @T6G_MB_LIB.T6G(SCH_1):PAGE466
     2 VSENSE_P12V_INA230_8_INN @T6G_MB_LIB.T6G(SCH_1):VSENSE_P12V_INA230_8_INN    I68 @T6G_MB_LIB.T6G(SCH_1):PAGE466

C1111 Q_CAP_0402-0.1UF,25V,10%,X7R,CH4104K1B00
     1 VSENSE_P12V_INA230_6_INP @T6G_MB_LIB.T6G(SCH_1):VSENSE_P12V_INA230_6_INP    I15 @T6G_MB_LIB.T6G(SCH_1):PAGE466
     2 VSENSE_P12V_INA230_6_INN @T6G_MB_LIB.T6G(SCH_1):VSENSE_P12V_INA230_6_INN    I15 @T6G_MB_LIB.T6G(SCH_1):PAGE466

C1112 Q_CAP_0402-0.1UF,25V,10%,X7R,CH4104K1B00
     1 VSENSE_P12V_INA230_7_INP @T6G_MB_LIB.T6G(SCH_1):VSENSE_P12V_INA230_7_INP    I54 @T6G_MB_LIB.T6G(SCH_1):PAGE466
     2 VSENSE_P12V_INA230_7_INN @T6G_MB_LIB.T6G(SCH_1):VSENSE_P12V_INA230_7_INN    I54 @T6G_MB_LIB.T6G(SCH_1):PAGE466

C1113 Q_CAP_C0805-22UF,16V,20%,EMPTY,CH6223MEA00
     1 P12V_AUX_DSC_S1 @T6G_MB_LIB.T6G(SCH_1):P12V_AUX_DSC_S1     I6 @T6G_MB_LIB.T6G(SCH_1):PAGE146
     2    GND @T6G_MB_LIB.T6G(SCH_1):GND     I6 @T6G_MB_LIB.T6G(SCH_1):PAGE146

C1114 Q_CAP_C0805-22UF,16V,20%,EMPTY,CH6223MEA00
     1 P3V3_AUX_DSC_S1 @T6G_MB_LIB.T6G(SCH_1):P3V3_AUX_DSC_S1    I30 @T6G_MB_LIB.T6G(SCH_1):PAGE146
     2    GND @T6G_MB_LIB.T6G(SCH_1):GND    I30 @T6G_MB_LIB.T6G(SCH_1):PAGE146

C1115 Q_CAP_C0805-22UF,16V,20%,EMPTY,CH6223MEA00
     1 PDB_PRSNT_R_N @T6G_MB_LIB.T6G(SCH_1):PDB_PRSNT_R_N   I478 @T6G_MB_LIB.T6G(SCH_1):PAGE363
     2    GND @T6G_MB_LIB.T6G(SCH_1):GND   I478 @T6G_MB_LIB.T6G(SCH_1):PAGE363

C1126 Q_CAP_C0402-0.1UF,16V,10%,X7R,CH4103K1B08
     1 P1V8_AUX @T6G_MB_LIB.T6G(SCH_1):P1V8_AUX    I86 @T6G_MB_LIB.T6G(SCH_1):PAGE82
     2    GND @T6G_MB_LIB.T6G(SCH_1):GND    I86 @T6G_MB_LIB.T6G(SCH_1):PAGE82

C1127 Q_CAP_C0402-0.1UF,16V,10%,X7R,CH4103K1B08
     1 P1V8_AUX @T6G_MB_LIB.T6G(SCH_1):P1V8_AUX    I87 @T6G_MB_LIB.T6G(SCH_1):PAGE82
     2    GND @T6G_MB_LIB.T6G(SCH_1):GND    I87 @T6G_MB_LIB.T6G(SCH_1):PAGE82

C1128 Q_CAP_C0402-0.1UF,16V,10%,X7R,CH4103K1B08
     1 P1V8_AUX @T6G_MB_LIB.T6G(SCH_1):P1V8_AUX    I84 @T6G_MB_LIB.T6G(SCH_1):PAGE82
     2    GND @T6G_MB_LIB.T6G(SCH_1):GND    I84 @T6G_MB_LIB.T6G(SCH_1):PAGE82

C1129 Q_CAP_C0402-0.1UF,16V,10%,X7R,CH4103K1B08
     1 P1V8_AUX @T6G_MB_LIB.T6G(SCH_1):P1V8_AUX    I85 @T6G_MB_LIB.T6G(SCH_1):PAGE82
     2    GND @T6G_MB_LIB.T6G(SCH_1):GND    I85 @T6G_MB_LIB.T6G(SCH_1):PAGE82

C1131 Q_CAP_C0402-0.1UF,16V,10%,X7R,CH4103K1B08
     1 P1V8_AUX @T6G_MB_LIB.T6G(SCH_1):P1V8_AUX    I82 @T6G_MB_LIB.T6G(SCH_1):PAGE82
     2    GND @T6G_MB_LIB.T6G(SCH_1):GND    I82 @T6G_MB_LIB.T6G(SCH_1):PAGE82

C1132 Q_CAP_C0402-0.1UF,16V,10%,X7R,CH4103K1B08
     1 P1V8_AUX @T6G_MB_LIB.T6G(SCH_1):P1V8_AUX    I80 @T6G_MB_LIB.T6G(SCH_1):PAGE82
     2    GND @T6G_MB_LIB.T6G(SCH_1):GND    I80 @T6G_MB_LIB.T6G(SCH_1):PAGE82

C1133 Q_CAP_C0402-0.1UF,16V,10%,X7R,CH4103K1B08
     1 P1V8_AUX @T6G_MB_LIB.T6G(SCH_1):P1V8_AUX    I81 @T6G_MB_LIB.T6G(SCH_1):PAGE82
     2    GND @T6G_MB_LIB.T6G(SCH_1):GND    I81 @T6G_MB_LIB.T6G(SCH_1):PAGE82

C1134 Q_CAP_C0402-0.1UF,16V,10%,X7R,CH4103K1B08
     1 P1V8_AUX @T6G_MB_LIB.T6G(SCH_1):P1V8_AUX    I79 @T6G_MB_LIB.T6G(SCH_1):PAGE82
     2    GND @T6G_MB_LIB.T6G(SCH_1):GND    I79 @T6G_MB_LIB.T6G(SCH_1):PAGE82

C1170 Q_CAP_C0805-10UF,16V,10%,X6S,CH6103KEA00
     1 P5V_AUX @T6G_MB_LIB.T6G(SCH_1):P5V_AUX    I19 @T6G_MB_LIB.T6G(SCH_1):PAGE273
     2    GND @T6G_MB_LIB.T6G(SCH_1):GND    I19 @T6G_MB_LIB.T6G(SCH_1):PAGE273

C1171 Q_CAP_C0402-0.1UF,16V,10%,X7R,CH4103K1B08
     1 P3V3_AUX @T6G_MB_LIB.T6G(SCH_1):P3V3_AUX   I114 @T6G_MB_LIB.T6G(SCH_1):PAGE82
     2    GND @T6G_MB_LIB.T6G(SCH_1):GND   I114 @T6G_MB_LIB.T6G(SCH_1):PAGE82

C1172 Q_CAP_C0402-0.1UF,16V,10%,X7R,CH4103K1B08
     1 P3V3_AUX @T6G_MB_LIB.T6G(SCH_1):P3V3_AUX   I112 @T6G_MB_LIB.T6G(SCH_1):PAGE82
     2    GND @T6G_MB_LIB.T6G(SCH_1):GND   I112 @T6G_MB_LIB.T6G(SCH_1):PAGE82

C1173 Q_CAP_C0402-0.1UF,16V,10%,X7R,CH4103K1B08
     1 P3V3_AUX @T6G_MB_LIB.T6G(SCH_1):P3V3_AUX   I113 @T6G_MB_LIB.T6G(SCH_1):PAGE82
     2    GND @T6G_MB_LIB.T6G(SCH_1):GND   I113 @T6G_MB_LIB.T6G(SCH_1):PAGE82

C1174 Q_CAP_C0402-0.1UF,16V,10%,X7R,CH4103K1B08
     1 P3V3_AUX @T6G_MB_LIB.T6G(SCH_1):P3V3_AUX   I111 @T6G_MB_LIB.T6G(SCH_1):PAGE82
     2    GND @T6G_MB_LIB.T6G(SCH_1):GND   I111 @T6G_MB_LIB.T6G(SCH_1):PAGE82

C1175 Q_CAP_C0402-0.1UF,16V,10%,X7R,CH4103K1B08
     1 P3V3_AUX @T6G_MB_LIB.T6G(SCH_1):P3V3_AUX   I110 @T6G_MB_LIB.T6G(SCH_1):PAGE82
     2    GND @T6G_MB_LIB.T6G(SCH_1):GND   I110 @T6G_MB_LIB.T6G(SCH_1):PAGE82

C1176 Q_CAP_C0402-0.1UF,16V,10%,X7R,CH4103K1B08
     1 P3V3_AUX @T6G_MB_LIB.T6G(SCH_1):P3V3_AUX   I109 @T6G_MB_LIB.T6G(SCH_1):PAGE82
     2    GND @T6G_MB_LIB.T6G(SCH_1):GND   I109 @T6G_MB_LIB.T6G(SCH_1):PAGE82

C1209 Q_CAP_0402-100PF,50V,5%,NPO,CH11006JB00
     1 SCM_SYS_PWROK_R2 @T6G_MB_LIB.T6G(SCH_1):SCM_SYS_PWROK_R2    I88 @T6G_MB_LIB.T6G(SCH_1):PAGE84
     2    GND @T6G_MB_LIB.T6G(SCH_1):GND    I88 @T6G_MB_LIB.T6G(SCH_1):PAGE84

C1213 Q_CAP_C0805-22UF,16V,20%,X6S,CH6223MEA00
     1 P12V_OCP_SFF_R @T6G_MB_LIB.T6G(SCH_1):P12V_OCP_SFF_R    I87 @T6G_MB_LIB.T6G(SCH_1):PAGE335
     2    GND @T6G_MB_LIB.T6G(SCH_1):GND    I87 @T6G_MB_LIB.T6G(SCH_1):PAGE335

C1227 Q_CAP_C0402-100NF,50V,10%,X7R,CH4106K1B01
     1    P5V @T6G_MB_LIB.T6G(SCH_1):P5V    I41 @T6G_MB_LIB.T6G(SCH_1):PAGE273
     2    GND @T6G_MB_LIB.T6G(SCH_1):GND    I41 @T6G_MB_LIB.T6G(SCH_1):PAGE273

C1235 Q_CAP_0402-0.1UF,25V,10%,X7R,CH4104K1B00
     1 P12V_OCP_SFF_R @T6G_MB_LIB.T6G(SCH_1):P12V_OCP_SFF_R    I90 @T6G_MB_LIB.T6G(SCH_1):PAGE335
     2    GND @T6G_MB_LIB.T6G(SCH_1):GND    I90 @T6G_MB_LIB.T6G(SCH_1):PAGE335

C1236 Q_CAP_0402-0.1UF,25V,10%,X7R,CH4104K1B00
     1 P12V_OCP_SFF_R @T6G_MB_LIB.T6G(SCH_1):P12V_OCP_SFF_R   I164 @T6G_MB_LIB.T6G(SCH_1):PAGE335
     2    GND @T6G_MB_LIB.T6G(SCH_1):GND   I164 @T6G_MB_LIB.T6G(SCH_1):PAGE335

C1237 Q_CAP_0402-0.1UF,25V,10%,X7R,CH4104K1B00
     1 P3V3_OCP_SFF @T6G_MB_LIB.T6G(SCH_1):P3V3_OCP_SFF   I110 @T6G_MB_LIB.T6G(SCH_1):PAGE335
     2    GND @T6G_MB_LIB.T6G(SCH_1):GND   I110 @T6G_MB_LIB.T6G(SCH_1):PAGE335

C1238 Q_CAP_0402-0.1UF,25V,10%,X7R,CH4104K1B00
     1 P3V3_OCP_SFF @T6G_MB_LIB.T6G(SCH_1):P3V3_OCP_SFF   I111 @T6G_MB_LIB.T6G(SCH_1):PAGE335
     2    GND @T6G_MB_LIB.T6G(SCH_1):GND   I111 @T6G_MB_LIB.T6G(SCH_1):PAGE335

C1239 Q_CAP_0402-0.1UF,25V,10%,X7R,CH4104K1B00
     1 P3V3_OCP_SFF @T6G_MB_LIB.T6G(SCH_1):P3V3_OCP_SFF   I112 @T6G_MB_LIB.T6G(SCH_1):PAGE335
     2    GND @T6G_MB_LIB.T6G(SCH_1):GND   I112 @T6G_MB_LIB.T6G(SCH_1):PAGE335

C1240 Q_CAP_0402-0.1UF,25V,10%,X7R,CH4104K1B00
     1 P3V3_OCP_SFF @T6G_MB_LIB.T6G(SCH_1):P3V3_OCP_SFF   I114 @T6G_MB_LIB.T6G(SCH_1):PAGE335
     2    GND @T6G_MB_LIB.T6G(SCH_1):GND   I114 @T6G_MB_LIB.T6G(SCH_1):PAGE335

C1274 Q_CAP_0402-0.1UF,25V,10%,X7R,CH4104K1B00
     1 P3V3_AUX @T6G_MB_LIB.T6G(SCH_1):P3V3_AUX     I3 @T6G_MB_LIB.T6G(SCH_1):PAGE337
     2    GND @T6G_MB_LIB.T6G(SCH_1):GND     I3 @T6G_MB_LIB.T6G(SCH_1):PAGE337

C1275 Q_CAP_0402-0.1UF,25V,10%,X7R,CH4104K1B00
     1 P3V3_AUX @T6G_MB_LIB.T6G(SCH_1):P3V3_AUX    I19 @T6G_MB_LIB.T6G(SCH_1):PAGE337
     2    GND @T6G_MB_LIB.T6G(SCH_1):GND    I19 @T6G_MB_LIB.T6G(SCH_1):PAGE337

C1276 Q_CAP_C0805-22UF,16V,20%,X6S,CH6223MEA01
     1 P12V_E1S_0_R @T6G_MB_LIB.T6G(SCH_1):P12V_E1S_0_R    I66 @T6G_MB_LIB.T6G(SCH_1):PAGE297
     2    GND @T6G_MB_LIB.T6G(SCH_1):GND    I66 @T6G_MB_LIB.T6G(SCH_1):PAGE297

C1277 Q_CAP_C0805-22UF,16V,20%,X6S,CH6223MEA01
     1 P12V_E1S_0_R @T6G_MB_LIB.T6G(SCH_1):P12V_E1S_0_R    I67 @T6G_MB_LIB.T6G(SCH_1):PAGE297
     2    GND @T6G_MB_LIB.T6G(SCH_1):GND    I67 @T6G_MB_LIB.T6G(SCH_1):PAGE297

C1278 Q_CAP_0402-0.1UF,25V,10%,X7R,CH4104K1B00
     1 P12V_E1S_0_R @T6G_MB_LIB.T6G(SCH_1):P12V_E1S_0_R    I68 @T6G_MB_LIB.T6G(SCH_1):PAGE297
     2    GND @T6G_MB_LIB.T6G(SCH_1):GND    I68 @T6G_MB_LIB.T6G(SCH_1):PAGE297

C1279 Q_CAP_0402-0.1UF,25V,10%,X7R,CH4104K1B00
     1 P12V_E1S_0_R @T6G_MB_LIB.T6G(SCH_1):P12V_E1S_0_R    I74 @T6G_MB_LIB.T6G(SCH_1):PAGE297
     2    GND @T6G_MB_LIB.T6G(SCH_1):GND    I74 @T6G_MB_LIB.T6G(SCH_1):PAGE297

C1282 Q_CAP_0402-0.1UF,25V,10%,X7R,CH4104K1B00
     1 P3V3_E1S_0 @T6G_MB_LIB.T6G(SCH_1):P3V3_E1S_0    I87 @T6G_MB_LIB.T6G(SCH_1):PAGE297
     2    GND @T6G_MB_LIB.T6G(SCH_1):GND    I87 @T6G_MB_LIB.T6G(SCH_1):PAGE297

C1283 Q_CAP_0402-0.1UF,25V,10%,X7R,CH4104K1B00
     1 P3V3_E1S_0 @T6G_MB_LIB.T6G(SCH_1):P3V3_E1S_0    I88 @T6G_MB_LIB.T6G(SCH_1):PAGE297
     2    GND @T6G_MB_LIB.T6G(SCH_1):GND    I88 @T6G_MB_LIB.T6G(SCH_1):PAGE297

C1305 Q_CAP_0402-0.1UF,25V,10%,X7R,CH4104K1B00
     1 P3V3_AUX @T6G_MB_LIB.T6G(SCH_1):P3V3_AUX    I52 @T6G_MB_LIB.T6G(SCH_1):PAGE346
     2    GND @T6G_MB_LIB.T6G(SCH_1):GND    I52 @T6G_MB_LIB.T6G(SCH_1):PAGE346

C1323 Q_CAP_0402-0.1UF,25V,10%,X7R,CH4104K1B00
     1 P1V8_AUX @T6G_MB_LIB.T6G(SCH_1):P1V8_AUX    I28 @T6G_MB_LIB.T6G(SCH_1):PAGE346
     2    GND @T6G_MB_LIB.T6G(SCH_1):GND    I28 @T6G_MB_LIB.T6G(SCH_1):PAGE346

C1331 Q_CAP_C0805-10UF,16V,10%,X6S,CH6103KEA00
     1    P5V @T6G_MB_LIB.T6G(SCH_1):P5V    I43 @T6G_MB_LIB.T6G(SCH_1):PAGE273
     2    GND @T6G_MB_LIB.T6G(SCH_1):GND    I43 @T6G_MB_LIB.T6G(SCH_1):PAGE273

C1332 Q_CAP_C0402-100NF,50V,10%,X7R,CH4106K1B01
     1 P3V3_AUX @T6G_MB_LIB.T6G(SCH_1):P3V3_AUX    I48 @T6G_MB_LIB.T6G(SCH_1):PAGE273
     2    GND @T6G_MB_LIB.T6G(SCH_1):GND    I48 @T6G_MB_LIB.T6G(SCH_1):PAGE273

C1333 Q_CAP_C0805-10UF,16V,10%,X6S,CH6103KEA00
     1 P3V3_AUX @T6G_MB_LIB.T6G(SCH_1):P3V3_AUX    I49 @T6G_MB_LIB.T6G(SCH_1):PAGE273
     2    GND @T6G_MB_LIB.T6G(SCH_1):GND    I49 @T6G_MB_LIB.T6G(SCH_1):PAGE273

C1336 Q_CAP_0402-0.1UF,25V,10%,X7R,CH4104K1B00
     1 P3V3_AUX @T6G_MB_LIB.T6G(SCH_1):P3V3_AUX    I50 @T6G_MB_LIB.T6G(SCH_1):PAGE136
     2    GND @T6G_MB_LIB.T6G(SCH_1):GND    I50 @T6G_MB_LIB.T6G(SCH_1):PAGE136

C1337 Q_CAP_0402-0.1UF,25V,10%,X7R,CH4104K1B00
     1 P3V3_AUX @T6G_MB_LIB.T6G(SCH_1):P3V3_AUX    I56 @T6G_MB_LIB.T6G(SCH_1):PAGE136
     2    GND @T6G_MB_LIB.T6G(SCH_1):GND    I56 @T6G_MB_LIB.T6G(SCH_1):PAGE136

C1338 Q_CAP_0402-0.1UF,25V,10%,X7R,CH4104K1B00
     1 P3V3_AUX @T6G_MB_LIB.T6G(SCH_1):P3V3_AUX    I61 @T6G_MB_LIB.T6G(SCH_1):PAGE136
     2    GND @T6G_MB_LIB.T6G(SCH_1):GND    I61 @T6G_MB_LIB.T6G(SCH_1):PAGE136

C1339 Q_CAP_0402-0.1UF,25V,10%,X7R,CH4104K1B00
     1 P3V3_AUX @T6G_MB_LIB.T6G(SCH_1):P3V3_AUX    I66 @T6G_MB_LIB.T6G(SCH_1):PAGE136
     2    GND @T6G_MB_LIB.T6G(SCH_1):GND    I66 @T6G_MB_LIB.T6G(SCH_1):PAGE136

C1340 Q_CAP_C0805-10UF,16V,10%,X6S,CH6103KEA00
     1   P3V3 @T6G_MB_LIB.T6G(SCH_1):P3V3    I61 @T6G_MB_LIB.T6G(SCH_1):PAGE273
     2    GND @T6G_MB_LIB.T6G(SCH_1):GND    I61 @T6G_MB_LIB.T6G(SCH_1):PAGE273

C1344 Q_CAP_0402-100PF,50V,5%,EMPTY,CH11006JB18
     1 P12V_AUX_ADC_MAM @T6G_MB_LIB.T6G(SCH_1):P12V_AUX_ADC_MAM    I46 @T6G_MB_LIB.T6G(SCH_1):PAGE369
     2    GND @T6G_MB_LIB.T6G(SCH_1):GND    I46 @T6G_MB_LIB.T6G(SCH_1):PAGE369

C1347 Q_CAP_0402-0.1UF,25V,10%,X7R,CH4104K1B00
     1 MAX11617_VREF @T6G_MB_LIB.T6G(SCH_1):MAX11617_VREF   I119 @T6G_MB_LIB.T6G(SCH_1):PAGE369
     2    GND @T6G_MB_LIB.T6G(SCH_1):GND   I119 @T6G_MB_LIB.T6G(SCH_1):PAGE369

C1352 Q_CAP_0402-0.1UF,25V,10%,X7R,CH4104K1B00
     1 PVDD18_S5_P0 @T6G_MB_LIB.T6G(SCH_1):PVDD18_S5_P0   I137 @T6G_MB_LIB.T6G(SCH_1):PAGE141
     2    GND @T6G_MB_LIB.T6G(SCH_1):GND   I137 @T6G_MB_LIB.T6G(SCH_1):PAGE141

C1354 Q_CAP_0402-0.1UF,25V,10%,X7R,CH4104K1B00
     1 P3V3_AUX @T6G_MB_LIB.T6G(SCH_1):P3V3_AUX   I133 @T6G_MB_LIB.T6G(SCH_1):PAGE141
     2    GND @T6G_MB_LIB.T6G(SCH_1):GND   I133 @T6G_MB_LIB.T6G(SCH_1):PAGE141

C1503 Q_CAP_C0402-0.1UF,16V,10%,X7R,CH4103K1B08
     1 P3V3_AUX @T6G_MB_LIB.T6G(SCH_1):P3V3_AUX    I80 @T6G_MB_LIB.T6G(SCH_1):PAGE149
     2    GND @T6G_MB_LIB.T6G(SCH_1):GND    I80 @T6G_MB_LIB.T6G(SCH_1):PAGE149

C1504 Q_CAP_C0402-0.1UF,16V,10%,X7R,CH4103K1B08
     1 PVDD18_S5_P0 @T6G_MB_LIB.T6G(SCH_1):PVDD18_S5_P0    I56 @T6G_MB_LIB.T6G(SCH_1):PAGE149
     2    GND @T6G_MB_LIB.T6G(SCH_1):GND    I56 @T6G_MB_LIB.T6G(SCH_1):PAGE149

C1505 Q_CAP_C0402-0.1UF,16V,10%,X7R,CH4103K1B08
     1 PVDD18_S5_P0 @T6G_MB_LIB.T6G(SCH_1):PVDD18_S5_P0    I74 @T6G_MB_LIB.T6G(SCH_1):PAGE149
     2    GND @T6G_MB_LIB.T6G(SCH_1):GND    I74 @T6G_MB_LIB.T6G(SCH_1):PAGE149

C1506 Q_CAP_C0402-0.1UF,16V,10%,X7R,CH4103K1B08
     1 P3V3_AUX @T6G_MB_LIB.T6G(SCH_1):P3V3_AUX    I62 @T6G_MB_LIB.T6G(SCH_1):PAGE149
     2    GND @T6G_MB_LIB.T6G(SCH_1):GND    I62 @T6G_MB_LIB.T6G(SCH_1):PAGE149

C1507 Q_CAP_C0402-0.1UF,16V,10%,X7R,CH4103K1B08
     1 PVDD18_S5_P0 @T6G_MB_LIB.T6G(SCH_1):PVDD18_S5_P0    I41 @T6G_MB_LIB.T6G(SCH_1):PAGE149
     2    GND @T6G_MB_LIB.T6G(SCH_1):GND    I41 @T6G_MB_LIB.T6G(SCH_1):PAGE149

C1508 Q_CAP_C0402-0.1UF,16V,10%,X7R,CH4103K1B08
     1 PVDD18_S5_P0 @T6G_MB_LIB.T6G(SCH_1):PVDD18_S5_P0    I29 @T6G_MB_LIB.T6G(SCH_1):PAGE149
     2    GND @T6G_MB_LIB.T6G(SCH_1):GND    I29 @T6G_MB_LIB.T6G(SCH_1):PAGE149

C1509 Q_CAP_C0402-0.1UF,16V,10%,X7R,CH4103K1B08
     1 PVDD18_S5_P0 @T6G_MB_LIB.T6G(SCH_1):PVDD18_S5_P0    I10 @T6G_MB_LIB.T6G(SCH_1):PAGE149
     2    GND @T6G_MB_LIB.T6G(SCH_1):GND    I10 @T6G_MB_LIB.T6G(SCH_1):PAGE149

C1510 Q_CAP_0402-33PF,50V,5%,NPO,TMP_QCH03306JB04
     1 JTAG_TCK @T6G_MB_LIB.T6G(SCH_1):JTAG_TCK    I25 @T6G_MB_LIB.T6G(SCH_1):PAGE149
     2    GND @T6G_MB_LIB.T6G(SCH_1):GND    I25 @T6G_MB_LIB.T6G(SCH_1):PAGE149

C1511 Q_CAP_0402-33PF,50V,5%,NPO,TMP_QCH03306JB04
     1 JTAG_TRST_N @T6G_MB_LIB.T6G(SCH_1):JTAG_TRST_N    I23 @T6G_MB_LIB.T6G(SCH_1):PAGE149
     2    GND @T6G_MB_LIB.T6G(SCH_1):GND    I23 @T6G_MB_LIB.T6G(SCH_1):PAGE149

C1512 Q_CAP_0402-33PF,50V,5%,NPO,TMP_QCH03306JB04
     1 JTAG_DBREQ_N @T6G_MB_LIB.T6G(SCH_1):JTAG_DBREQ_N    I21 @T6G_MB_LIB.T6G(SCH_1):PAGE149
     2    GND @T6G_MB_LIB.T6G(SCH_1):GND    I21 @T6G_MB_LIB.T6G(SCH_1):PAGE149

C1513 Q_CAP_C0402-0.1UF,16V,10%,X7R,CH4103K1B08
     1 PVDD18_S5_P0 @T6G_MB_LIB.T6G(SCH_1):PVDD18_S5_P0    I69 @T6G_MB_LIB.T6G(SCH_1):PAGE150
     2    GND @T6G_MB_LIB.T6G(SCH_1):GND    I69 @T6G_MB_LIB.T6G(SCH_1):PAGE150

C1514 Q_CAP_C0402-0.1UF,16V,10%,X7R,CH4103K1B08
     1 PVDD18_S5_P0 @T6G_MB_LIB.T6G(SCH_1):PVDD18_S5_P0    I19 @T6G_MB_LIB.T6G(SCH_1):PAGE150
     2    GND @T6G_MB_LIB.T6G(SCH_1):GND    I19 @T6G_MB_LIB.T6G(SCH_1):PAGE150

C1515 Q_CAP_C0402-0.1UF,16V,10%,X7R,CH4103K1B08
     1 PVDD18_S5_P0 @T6G_MB_LIB.T6G(SCH_1):PVDD18_S5_P0    I43 @T6G_MB_LIB.T6G(SCH_1):PAGE150
     2    GND @T6G_MB_LIB.T6G(SCH_1):GND    I43 @T6G_MB_LIB.T6G(SCH_1):PAGE150

C1516 Q_CAP_C0402-0.1UF,16V,10%,X7R,CH4103K1B08
     1 PVDD18_S5_P0 @T6G_MB_LIB.T6G(SCH_1):PVDD18_S5_P0    I14 @T6G_MB_LIB.T6G(SCH_1):PAGE150
     2    GND @T6G_MB_LIB.T6G(SCH_1):GND    I14 @T6G_MB_LIB.T6G(SCH_1):PAGE150

C1517 Q_CAP_C0402-0.1UF,16V,10%,X7R,CH4103K1B08
     1 PVDD18_S5_P1 @T6G_MB_LIB.T6G(SCH_1):PVDD18_S5_P1    I40 @T6G_MB_LIB.T6G(SCH_1):PAGE150
     2    GND @T6G_MB_LIB.T6G(SCH_1):GND    I40 @T6G_MB_LIB.T6G(SCH_1):PAGE150

C1518 Q_CAP_C0402-0.1UF,16V,10%,X7R,CH4103K1B08
     1 PVDD18_S5_P0 @T6G_MB_LIB.T6G(SCH_1):PVDD18_S5_P0    I66 @T6G_MB_LIB.T6G(SCH_1):PAGE150
     2    GND @T6G_MB_LIB.T6G(SCH_1):GND    I66 @T6G_MB_LIB.T6G(SCH_1):PAGE150

C1519 Q_CAP_C0402-0.1UF,16V,10%,X7R,CH4103K1B08
     1 PVDD18_S5_P0 @T6G_MB_LIB.T6G(SCH_1):PVDD18_S5_P0    I15 @T6G_MB_LIB.T6G(SCH_1):PAGE151
     2    GND @T6G_MB_LIB.T6G(SCH_1):GND    I15 @T6G_MB_LIB.T6G(SCH_1):PAGE151

C1520 Q_CAP_C0402-0.01UF,50V,10%,EMPTY,CH31006KB18
     1 JTAG_CPU0_TDI @T6G_MB_LIB.T6G(SCH_1):JTAG_CPU0_TDI     I4 @T6G_MB_LIB.T6G(SCH_1):PAGE151
     2    GND @T6G_MB_LIB.T6G(SCH_1):GND     I4 @T6G_MB_LIB.T6G(SCH_1):PAGE151

C1521 Q_CAP_C0402-0.1UF,16V,10%,X7R,CH4103K1B08
     1 PVDD18_S5_P0 @T6G_MB_LIB.T6G(SCH_1):PVDD18_S5_P0    I22 @T6G_MB_LIB.T6G(SCH_1):PAGE151
     2    GND @T6G_MB_LIB.T6G(SCH_1):GND    I22 @T6G_MB_LIB.T6G(SCH_1):PAGE151

C1522 Q_CAP_C0402-0.1UF,16V,10%,X7R,CH4103K1B08
     1 PVDD18_S5_P0 @T6G_MB_LIB.T6G(SCH_1):PVDD18_S5_P0    I36 @T6G_MB_LIB.T6G(SCH_1):PAGE151
     2    GND @T6G_MB_LIB.T6G(SCH_1):GND    I36 @T6G_MB_LIB.T6G(SCH_1):PAGE151

C1523 Q_CAP_C0402-0.1UF,16V,10%,X7R,CH4103K1B08
     1 PVDD18_S5_P0 @T6G_MB_LIB.T6G(SCH_1):PVDD18_S5_P0    I42 @T6G_MB_LIB.T6G(SCH_1):PAGE151
     2    GND @T6G_MB_LIB.T6G(SCH_1):GND    I42 @T6G_MB_LIB.T6G(SCH_1):PAGE151

C1524 Q_CAP_DIFFBUS_C0201-DIFF BUS_0.22UF,6.3V,20%,X6S,SA
     1 P5E_CPU1_P3_TX_C_DN<11> @T6G_MB_LIB.T6G(SCH_1):P5E_CPU1_P3_TX_C_DN(11)    I84 @T6G_MB_LIB.T6G(SCH_1):PAGE355
     2 P5E_CPU1_P3_TX_DN<11> @T6G_MB_LIB.T6G(SCH_1):P5E_CPU1_P3_TX_DN(11)    I84 @T6G_MB_LIB.T6G(SCH_1):PAGE355

C1525 Q_CAP_DIFFBUS_C0201-DIFF BUS_0.22UF,6.3V,20%,X6S,SA
     1 P5E_CPU1_P3_TX_C_DP<11> @T6G_MB_LIB.T6G(SCH_1):P5E_CPU1_P3_TX_C_DP(11)    I83 @T6G_MB_LIB.T6G(SCH_1):PAGE355
     2 P5E_CPU1_P3_TX_DP<11> @T6G_MB_LIB.T6G(SCH_1):P5E_CPU1_P3_TX_DP(11)    I83 @T6G_MB_LIB.T6G(SCH_1):PAGE355

C1526 Q_CAP_DIFFBUS_C0201-DIFF BUS_0.22UF,6.3V,20%,X6S,SA
     1 P5E_CPU1_P3_TX_C_DN<10> @T6G_MB_LIB.T6G(SCH_1):P5E_CPU1_P3_TX_C_DN(10)    I81 @T6G_MB_LIB.T6G(SCH_1):PAGE355
     2 P5E_CPU1_P3_TX_DN<10> @T6G_MB_LIB.T6G(SCH_1):P5E_CPU1_P3_TX_DN(10)    I81 @T6G_MB_LIB.T6G(SCH_1):PAGE355

C1527 Q_CAP_DIFFBUS_C0201-DIFF BUS_0.22UF,6.3V,20%,X6S,SA
     1 P5E_CPU1_P3_TX_C_DP<10> @T6G_MB_LIB.T6G(SCH_1):P5E_CPU1_P3_TX_C_DP(10)    I82 @T6G_MB_LIB.T6G(SCH_1):PAGE355
     2 P5E_CPU1_P3_TX_DP<10> @T6G_MB_LIB.T6G(SCH_1):P5E_CPU1_P3_TX_DP(10)    I82 @T6G_MB_LIB.T6G(SCH_1):PAGE355

C1528 Q_CAP_DIFFBUS_C0201-DIFF BUS_0.22UF,6.3V,20%,X6S,SA
     1 P5E_CPU1_P3_TX_C_DN<9> @T6G_MB_LIB.T6G(SCH_1):P5E_CPU1_P3_TX_C_DN(9)    I80 @T6G_MB_LIB.T6G(SCH_1):PAGE355
     2 P5E_CPU1_P3_TX_DN<9> @T6G_MB_LIB.T6G(SCH_1):P5E_CPU1_P3_TX_DN(9)    I80 @T6G_MB_LIB.T6G(SCH_1):PAGE355

C1529 Q_CAP_DIFFBUS_C0201-DIFF BUS_0.22UF,6.3V,20%,X6S,SA
     1 P5E_CPU1_P3_TX_C_DP<9> @T6G_MB_LIB.T6G(SCH_1):P5E_CPU1_P3_TX_C_DP(9)    I79 @T6G_MB_LIB.T6G(SCH_1):PAGE355
     2 P5E_CPU1_P3_TX_DP<9> @T6G_MB_LIB.T6G(SCH_1):P5E_CPU1_P3_TX_DP(9)    I79 @T6G_MB_LIB.T6G(SCH_1):PAGE355

C1530 Q_CAP_DIFFBUS_C0201-DIFF BUS_0.22UF,6.3V,20%,X6S,SA
     1 P5E_CPU1_P3_TX_C_DN<8> @T6G_MB_LIB.T6G(SCH_1):P5E_CPU1_P3_TX_C_DN(8)    I78 @T6G_MB_LIB.T6G(SCH_1):PAGE355
     2 P5E_CPU1_P3_TX_DN<8> @T6G_MB_LIB.T6G(SCH_1):P5E_CPU1_P3_TX_DN(8)    I78 @T6G_MB_LIB.T6G(SCH_1):PAGE355

C1531 Q_CAP_DIFFBUS_C0201-DIFF BUS_0.22UF,6.3V,20%,X6S,SA
     1 P5E_CPU1_P3_TX_C_DP<8> @T6G_MB_LIB.T6G(SCH_1):P5E_CPU1_P3_TX_C_DP(8)    I77 @T6G_MB_LIB.T6G(SCH_1):PAGE355
     2 P5E_CPU1_P3_TX_DP<8> @T6G_MB_LIB.T6G(SCH_1):P5E_CPU1_P3_TX_DP(8)    I77 @T6G_MB_LIB.T6G(SCH_1):PAGE355

C1532 Q_CAP_DIFFBUS_C0201-DIFF BUS_0.22UF,6.3V,20%,X6S,SA
     1 P5E_CPU1_P3_TX_C_DN<7> @T6G_MB_LIB.T6G(SCH_1):P5E_CPU1_P3_TX_C_DN(7)    I76 @T6G_MB_LIB.T6G(SCH_1):PAGE355
     2 P5E_CPU1_P3_TX_DN<7> @T6G_MB_LIB.T6G(SCH_1):P5E_CPU1_P3_TX_DN(7)    I76 @T6G_MB_LIB.T6G(SCH_1):PAGE355

C1533 Q_CAP_DIFFBUS_C0201-DIFF BUS_0.22UF,6.3V,20%,X6S,SA
     1 P5E_CPU1_P3_TX_C_DP<7> @T6G_MB_LIB.T6G(SCH_1):P5E_CPU1_P3_TX_C_DP(7)    I75 @T6G_MB_LIB.T6G(SCH_1):PAGE355
     2 P5E_CPU1_P3_TX_DP<7> @T6G_MB_LIB.T6G(SCH_1):P5E_CPU1_P3_TX_DP(7)    I75 @T6G_MB_LIB.T6G(SCH_1):PAGE355

C1534 Q_CAP_DIFFBUS_C0201-DIFF BUS_0.22UF,6.3V,20%,X6S,SA
     1 P5E_CPU1_P3_TX_C_DN<6> @T6G_MB_LIB.T6G(SCH_1):P5E_CPU1_P3_TX_C_DN(6)    I74 @T6G_MB_LIB.T6G(SCH_1):PAGE355
     2 P5E_CPU1_P3_TX_DN<6> @T6G_MB_LIB.T6G(SCH_1):P5E_CPU1_P3_TX_DN(6)    I74 @T6G_MB_LIB.T6G(SCH_1):PAGE355

C1535 Q_CAP_DIFFBUS_C0201-DIFF BUS_0.22UF,6.3V,20%,X6S,SA
     1 P5E_CPU1_P3_TX_C_DP<6> @T6G_MB_LIB.T6G(SCH_1):P5E_CPU1_P3_TX_C_DP(6)    I73 @T6G_MB_LIB.T6G(SCH_1):PAGE355
     2 P5E_CPU1_P3_TX_DP<6> @T6G_MB_LIB.T6G(SCH_1):P5E_CPU1_P3_TX_DP(6)    I73 @T6G_MB_LIB.T6G(SCH_1):PAGE355

C1536 Q_CAP_DIFFBUS_C0201-DIFF BUS_0.22UF,6.3V,20%,X6S,SA
     1 P5E_CPU1_P3_TX_C_DN<5> @T6G_MB_LIB.T6G(SCH_1):P5E_CPU1_P3_TX_C_DN(5)    I72 @T6G_MB_LIB.T6G(SCH_1):PAGE355
     2 P5E_CPU1_P3_TX_DN<5> @T6G_MB_LIB.T6G(SCH_1):P5E_CPU1_P3_TX_DN(5)    I72 @T6G_MB_LIB.T6G(SCH_1):PAGE355

C1537 Q_CAP_DIFFBUS_C0201-DIFF BUS_0.22UF,6.3V,20%,X6S,SA
     1 P5E_CPU1_P3_TX_C_DP<5> @T6G_MB_LIB.T6G(SCH_1):P5E_CPU1_P3_TX_C_DP(5)    I71 @T6G_MB_LIB.T6G(SCH_1):PAGE355
     2 P5E_CPU1_P3_TX_DP<5> @T6G_MB_LIB.T6G(SCH_1):P5E_CPU1_P3_TX_DP(5)    I71 @T6G_MB_LIB.T6G(SCH_1):PAGE355

C1538 Q_CAP_DIFFBUS_C0201-DIFF BUS_0.22UF,6.3V,20%,X6S,SA
     1 P5E_CPU1_P3_TX_C_DN<4> @T6G_MB_LIB.T6G(SCH_1):P5E_CPU1_P3_TX_C_DN(4)    I70 @T6G_MB_LIB.T6G(SCH_1):PAGE355
     2 P5E_CPU1_P3_TX_DN<4> @T6G_MB_LIB.T6G(SCH_1):P5E_CPU1_P3_TX_DN(4)    I70 @T6G_MB_LIB.T6G(SCH_1):PAGE355

C1539 Q_CAP_DIFFBUS_C0201-DIFF BUS_0.22UF,6.3V,20%,X6S,SA
     1 P5E_CPU1_P3_TX_C_DP<4> @T6G_MB_LIB.T6G(SCH_1):P5E_CPU1_P3_TX_C_DP(4)    I69 @T6G_MB_LIB.T6G(SCH_1):PAGE355
     2 P5E_CPU1_P3_TX_DP<4> @T6G_MB_LIB.T6G(SCH_1):P5E_CPU1_P3_TX_DP(4)    I69 @T6G_MB_LIB.T6G(SCH_1):PAGE355

C1540 Q_CAP_DIFFBUS_C0201-DIFF BUS_0.22UF,6.3V,20%,X6S,SA
     1 P5E_CPU1_P3_TX_C_DN<3> @T6G_MB_LIB.T6G(SCH_1):P5E_CPU1_P3_TX_C_DN(3)    I68 @T6G_MB_LIB.T6G(SCH_1):PAGE355
     2 P5E_CPU1_P3_TX_DN<3> @T6G_MB_LIB.T6G(SCH_1):P5E_CPU1_P3_TX_DN(3)    I68 @T6G_MB_LIB.T6G(SCH_1):PAGE355

C1541 Q_CAP_DIFFBUS_C0201-DIFF BUS_0.22UF,6.3V,20%,X6S,SA
     1 P5E_CPU1_P3_TX_C_DP<3> @T6G_MB_LIB.T6G(SCH_1):P5E_CPU1_P3_TX_C_DP(3)    I67 @T6G_MB_LIB.T6G(SCH_1):PAGE355
     2 P5E_CPU1_P3_TX_DP<3> @T6G_MB_LIB.T6G(SCH_1):P5E_CPU1_P3_TX_DP(3)    I67 @T6G_MB_LIB.T6G(SCH_1):PAGE355

C1542 Q_CAP_DIFFBUS_C0201-DIFF BUS_0.22UF,6.3V,20%,X6S,SA
     1 P5E_CPU1_P3_TX_C_DN<2> @T6G_MB_LIB.T6G(SCH_1):P5E_CPU1_P3_TX_C_DN(2)    I58 @T6G_MB_LIB.T6G(SCH_1):PAGE355
     2 P5E_CPU1_P3_TX_DN<2> @T6G_MB_LIB.T6G(SCH_1):P5E_CPU1_P3_TX_DN(2)    I58 @T6G_MB_LIB.T6G(SCH_1):PAGE355

C1543 Q_CAP_DIFFBUS_C0201-DIFF BUS_0.22UF,6.3V,20%,X6S,SA
     1 P5E_CPU1_P3_TX_C_DP<2> @T6G_MB_LIB.T6G(SCH_1):P5E_CPU1_P3_TX_C_DP(2)    I57 @T6G_MB_LIB.T6G(SCH_1):PAGE355
     2 P5E_CPU1_P3_TX_DP<2> @T6G_MB_LIB.T6G(SCH_1):P5E_CPU1_P3_TX_DP(2)    I57 @T6G_MB_LIB.T6G(SCH_1):PAGE355

C1544 Q_CAP_DIFFBUS_C0201-DIFF BUS_0.22UF,6.3V,20%,X6S,SA
     1 P5E_CPU1_P3_TX_C_DN<1> @T6G_MB_LIB.T6G(SCH_1):P5E_CPU1_P3_TX_C_DN(1)    I55 @T6G_MB_LIB.T6G(SCH_1):PAGE355
     2 P5E_CPU1_P3_TX_DN<1> @T6G_MB_LIB.T6G(SCH_1):P5E_CPU1_P3_TX_DN(1)    I55 @T6G_MB_LIB.T6G(SCH_1):PAGE355

C1545 Q_CAP_DIFFBUS_C0201-DIFF BUS_0.22UF,6.3V,20%,X6S,SA
     1 P5E_CPU1_P3_TX_C_DP<1> @T6G_MB_LIB.T6G(SCH_1):P5E_CPU1_P3_TX_C_DP(1)    I56 @T6G_MB_LIB.T6G(SCH_1):PAGE355
     2 P5E_CPU1_P3_TX_DP<1> @T6G_MB_LIB.T6G(SCH_1):P5E_CPU1_P3_TX_DP(1)    I56 @T6G_MB_LIB.T6G(SCH_1):PAGE355

C1546 Q_CAP_DIFFBUS_C0201-DIFF BUS_0.22UF,6.3V,20%,X6S,SA
     1 P5E_CPU1_P3_TX_C_DN<0> @T6G_MB_LIB.T6G(SCH_1):P5E_CPU1_P3_TX_C_DN(0)    I54 @T6G_MB_LIB.T6G(SCH_1):PAGE355
     2 P5E_CPU1_P3_TX_DN<0> @T6G_MB_LIB.T6G(SCH_1):P5E_CPU1_P3_TX_DN(0)    I54 @T6G_MB_LIB.T6G(SCH_1):PAGE355

C1547 Q_CAP_DIFFBUS_C0201-DIFF BUS_0.22UF,6.3V,20%,X6S,SA
     1 P5E_CPU1_P3_TX_C_DP<0> @T6G_MB_LIB.T6G(SCH_1):P5E_CPU1_P3_TX_C_DP(0)    I53 @T6G_MB_LIB.T6G(SCH_1):PAGE355
     2 P5E_CPU1_P3_TX_DP<0> @T6G_MB_LIB.T6G(SCH_1):P5E_CPU1_P3_TX_DP(0)    I53 @T6G_MB_LIB.T6G(SCH_1):PAGE355

C1548 Q_CAP_DIFFBUS_C0201-DIFF BUS_0.22UF,6.3V,20%,X6S,SA
     1 P5E_CPU0_G3_TX_C_DN<15> @T6G_MB_LIB.T6G(SCH_1):P5E_CPU0_G3_TX_C_DN(15)   I273 @T6G_MB_LIB.T6G(SCH_1):PAGE353
     2 P5E_CPU0_G3_TX_DN<15> @T6G_MB_LIB.T6G(SCH_1):P5E_CPU0_G3_TX_DN(15)   I273 @T6G_MB_LIB.T6G(SCH_1):PAGE353

C1549 Q_CAP_DIFFBUS_C0201-DIFF BUS_0.22UF,6.3V,20%,X6S,SA
     1 P5E_CPU0_G3_TX_C_DP<15> @T6G_MB_LIB.T6G(SCH_1):P5E_CPU0_G3_TX_C_DP(15)   I274 @T6G_MB_LIB.T6G(SCH_1):PAGE353
     2 P5E_CPU0_G3_TX_DP<15> @T6G_MB_LIB.T6G(SCH_1):P5E_CPU0_G3_TX_DP(15)   I274 @T6G_MB_LIB.T6G(SCH_1):PAGE353

C1550 Q_CAP_DIFFBUS_C0201-DIFF BUS_0.22UF,6.3V,20%,X6S,SA
     1 P5E_CPU0_G3_TX_C_DN<14> @T6G_MB_LIB.T6G(SCH_1):P5E_CPU0_G3_TX_C_DN(14)   I272 @T6G_MB_LIB.T6G(SCH_1):PAGE353
     2 P5E_CPU0_G3_TX_DN<14> @T6G_MB_LIB.T6G(SCH_1):P5E_CPU0_G3_TX_DN(14)   I272 @T6G_MB_LIB.T6G(SCH_1):PAGE353

C1552 Q_CAP_DIFFBUS_C0201-DIFF BUS_0.22UF,6.3V,20%,X6S,SA
     1 P5E_CPU0_G3_TX_C_DN<13> @T6G_MB_LIB.T6G(SCH_1):P5E_CPU0_G3_TX_C_DN(13)   I270 @T6G_MB_LIB.T6G(SCH_1):PAGE353
     2 P5E_CPU0_G3_TX_DN<13> @T6G_MB_LIB.T6G(SCH_1):P5E_CPU0_G3_TX_DN(13)   I270 @T6G_MB_LIB.T6G(SCH_1):PAGE353

C1553 Q_CAP_DIFFBUS_C0201-DIFF BUS_0.22UF,6.3V,20%,X6S,SA
     1 P5E_CPU0_G3_TX_C_DP<13> @T6G_MB_LIB.T6G(SCH_1):P5E_CPU0_G3_TX_C_DP(13)   I269 @T6G_MB_LIB.T6G(SCH_1):PAGE353
     2 P5E_CPU0_G3_TX_DP<13> @T6G_MB_LIB.T6G(SCH_1):P5E_CPU0_G3_TX_DP(13)   I269 @T6G_MB_LIB.T6G(SCH_1):PAGE353

C1554 Q_CAP_C0402-0.1UF,16V,10%,X7R,CH4103K1B08
     1 P3V3_AUX @T6G_MB_LIB.T6G(SCH_1):P3V3_AUX   I293 @T6G_MB_LIB.T6G(SCH_1):PAGE148
     2    GND @T6G_MB_LIB.T6G(SCH_1):GND   I293 @T6G_MB_LIB.T6G(SCH_1):PAGE148

C1555 Q_CAP_DIFFBUS_C0201-DIFF BUS_0.22UF,6.3V,20%,X6S,SA
     1 P5E_CPU0_G3_TX_C_DP<12> @T6G_MB_LIB.T6G(SCH_1):P5E_CPU0_G3_TX_C_DP(12)   I267 @T6G_MB_LIB.T6G(SCH_1):PAGE353
     2 P5E_CPU0_G3_TX_DP<12> @T6G_MB_LIB.T6G(SCH_1):P5E_CPU0_G3_TX_DP(12)   I267 @T6G_MB_LIB.T6G(SCH_1):PAGE353

C1556 Q_CAP_DIFFBUS_C0201-DIFF BUS_0.22UF,6.3V,20%,X6S,SA
     1 P5E_CPU0_G3_TX_C_DN<11> @T6G_MB_LIB.T6G(SCH_1):P5E_CPU0_G3_TX_C_DN(11)   I265 @T6G_MB_LIB.T6G(SCH_1):PAGE353
     2 P5E_CPU0_G3_TX_DN<11> @T6G_MB_LIB.T6G(SCH_1):P5E_CPU0_G3_TX_DN(11)   I265 @T6G_MB_LIB.T6G(SCH_1):PAGE353

C1557 Q_CAP_DIFFBUS_C0201-DIFF BUS_0.22UF,6.3V,20%,X6S,SA
     1 P5E_CPU0_G3_TX_C_DP<11> @T6G_MB_LIB.T6G(SCH_1):P5E_CPU0_G3_TX_C_DP(11)   I266 @T6G_MB_LIB.T6G(SCH_1):PAGE353
     2 P5E_CPU0_G3_TX_DP<11> @T6G_MB_LIB.T6G(SCH_1):P5E_CPU0_G3_TX_DP(11)   I266 @T6G_MB_LIB.T6G(SCH_1):PAGE353

C1558 Q_CAP_DIFFBUS_C0201-DIFF BUS_0.22UF,6.3V,20%,X6S,SA
     1 P5E_CPU0_G3_TX_C_DN<10> @T6G_MB_LIB.T6G(SCH_1):P5E_CPU0_G3_TX_C_DN(10)   I264 @T6G_MB_LIB.T6G(SCH_1):PAGE353
     2 P5E_CPU0_G3_TX_DN<10> @T6G_MB_LIB.T6G(SCH_1):P5E_CPU0_G3_TX_DN(10)   I264 @T6G_MB_LIB.T6G(SCH_1):PAGE353

C1559 Q_CAP_DIFFBUS_C0201-DIFF BUS_0.22UF,6.3V,20%,X6S,SA
     1 P5E_CPU0_G3_TX_C_DP<10> @T6G_MB_LIB.T6G(SCH_1):P5E_CPU0_G3_TX_C_DP(10)   I263 @T6G_MB_LIB.T6G(SCH_1):PAGE353
     2 P5E_CPU0_G3_TX_DP<10> @T6G_MB_LIB.T6G(SCH_1):P5E_CPU0_G3_TX_DP(10)   I263 @T6G_MB_LIB.T6G(SCH_1):PAGE353

C1560 Q_CAP_DIFFBUS_C0201-DIFF BUS_0.22UF,6.3V,20%,X6S,SA
     1 P5E_CPU0_G3_TX_C_DN<9> @T6G_MB_LIB.T6G(SCH_1):P5E_CPU0_G3_TX_C_DN(9)   I262 @T6G_MB_LIB.T6G(SCH_1):PAGE353
     2 P5E_CPU0_G3_TX_DN<9> @T6G_MB_LIB.T6G(SCH_1):P5E_CPU0_G3_TX_DN(9)   I262 @T6G_MB_LIB.T6G(SCH_1):PAGE353

C1561 Q_CAP_0402-0.1UF,25V,10%,EMPTY,CH4104K1B00
     1 U206_VS @T6G_MB_LIB.T6G(SCH_1):U206_VS    I96 @T6G_MB_LIB.T6G(SCH_1):PAGE372
     2    GND @T6G_MB_LIB.T6G(SCH_1):GND    I96 @T6G_MB_LIB.T6G(SCH_1):PAGE372

C1563 Q_CAP_C0402-0.1UF,16V,10%,X7R,CH4103K1B08
     1 CLR_CMOS @T6G_MB_LIB.T6G(SCH_1):CLR_CMOS    I95 @T6G_MB_LIB.T6G(SCH_1):PAGE156
     2    GND @T6G_MB_LIB.T6G(SCH_1):GND    I95 @T6G_MB_LIB.T6G(SCH_1):PAGE156

C1564 Q_CAP_C0402-1UF,25V,10%,X6S,CH5104KEB02
     1 P1V5_BAT_OUT @T6G_MB_LIB.T6G(SCH_1):P1V5_BAT_OUT   I118 @T6G_MB_LIB.T6G(SCH_1):PAGE156
     2    GND @T6G_MB_LIB.T6G(SCH_1):GND   I118 @T6G_MB_LIB.T6G(SCH_1):PAGE156

C1565 Q_CAP_DIFFBUS_C0201-DIFF BUS_0.22UF,6.3V,20%,X6S,SA
     1 P5E_CPU0_G3_TX_C_DP<7> @T6G_MB_LIB.T6G(SCH_1):P5E_CPU0_G3_TX_C_DP(7)   I241 @T6G_MB_LIB.T6G(SCH_1):PAGE353
     2 P5E_CPU0_G3_TX_DP<7> @T6G_MB_LIB.T6G(SCH_1):P5E_CPU0_G3_TX_DP(7)   I241 @T6G_MB_LIB.T6G(SCH_1):PAGE353

C1566 Q_CAP_DIFFBUS_C0201-DIFF BUS_0.22UF,6.3V,20%,X6S,SA
     1 P5E_CPU0_G3_TX_C_DN<6> @T6G_MB_LIB.T6G(SCH_1):P5E_CPU0_G3_TX_C_DN(6)   I240 @T6G_MB_LIB.T6G(SCH_1):PAGE353
     2 P5E_CPU0_G3_TX_DN<6> @T6G_MB_LIB.T6G(SCH_1):P5E_CPU0_G3_TX_DN(6)   I240 @T6G_MB_LIB.T6G(SCH_1):PAGE353

C1567 Q_CAP_C0402-1UF,25V,10%,X6S,CH5104KEB02
     1 P1V5_BAT @T6G_MB_LIB.T6G(SCH_1):P1V5_BAT   I125 @T6G_MB_LIB.T6G(SCH_1):PAGE156
     2    GND @T6G_MB_LIB.T6G(SCH_1):GND   I125 @T6G_MB_LIB.T6G(SCH_1):PAGE156

C1568 Q_CAP_DIFFBUS_C0201-DIFF BUS_0.22UF,6.3V,20%,X6S,SA
     1 P5E_CPU0_G3_TX_C_DN<5> @T6G_MB_LIB.T6G(SCH_1):P5E_CPU0_G3_TX_C_DN(5)   I238 @T6G_MB_LIB.T6G(SCH_1):PAGE353
     2 P5E_CPU0_G3_TX_DN<5> @T6G_MB_LIB.T6G(SCH_1):P5E_CPU0_G3_TX_DN(5)   I238 @T6G_MB_LIB.T6G(SCH_1):PAGE353

C1569 Q_CAP_DIFFBUS_C0201-DIFF BUS_0.22UF,6.3V,20%,X6S,SA
     1 P5E_CPU0_G3_TX_C_DP<5> @T6G_MB_LIB.T6G(SCH_1):P5E_CPU0_G3_TX_C_DP(5)   I237 @T6G_MB_LIB.T6G(SCH_1):PAGE353
     2 P5E_CPU0_G3_TX_DP<5> @T6G_MB_LIB.T6G(SCH_1):P5E_CPU0_G3_TX_DP(5)   I237 @T6G_MB_LIB.T6G(SCH_1):PAGE353

C1570 Q_CAP_DIFFBUS_C0201-DIFF BUS_0.22UF,6.3V,20%,X6S,SA
     1 P5E_CPU0_G3_TX_C_DN<4> @T6G_MB_LIB.T6G(SCH_1):P5E_CPU0_G3_TX_C_DN(4)   I235 @T6G_MB_LIB.T6G(SCH_1):PAGE353
     2 P5E_CPU0_G3_TX_DN<4> @T6G_MB_LIB.T6G(SCH_1):P5E_CPU0_G3_TX_DN(4)   I235 @T6G_MB_LIB.T6G(SCH_1):PAGE353

C1571 Q_CAP_DIFFBUS_C0201-DIFF BUS_0.22UF,6.3V,20%,X6S,SA
     1 P5E_CPU0_G3_TX_C_DP<4> @T6G_MB_LIB.T6G(SCH_1):P5E_CPU0_G3_TX_C_DP(4)   I236 @T6G_MB_LIB.T6G(SCH_1):PAGE353
     2 P5E_CPU0_G3_TX_DP<4> @T6G_MB_LIB.T6G(SCH_1):P5E_CPU0_G3_TX_DP(4)   I236 @T6G_MB_LIB.T6G(SCH_1):PAGE353

C1572 Q_CAP_DIFFBUS_C0201-DIFF BUS_0.22UF,6.3V,20%,X6S,SA
     1 P5E_CPU0_G3_TX_C_DN<3> @T6G_MB_LIB.T6G(SCH_1):P5E_CPU0_G3_TX_C_DN(3)   I234 @T6G_MB_LIB.T6G(SCH_1):PAGE353
     2 P5E_CPU0_G3_TX_DN<3> @T6G_MB_LIB.T6G(SCH_1):P5E_CPU0_G3_TX_DN(3)   I234 @T6G_MB_LIB.T6G(SCH_1):PAGE353

C1573 Q_CAP_DIFFBUS_C0201-DIFF BUS_0.22UF,6.3V,20%,X6S,SA
     1 P5E_CPU0_G3_TX_C_DP<3> @T6G_MB_LIB.T6G(SCH_1):P5E_CPU0_G3_TX_C_DP(3)   I233 @T6G_MB_LIB.T6G(SCH_1):PAGE353
     2 P5E_CPU0_G3_TX_DP<3> @T6G_MB_LIB.T6G(SCH_1):P5E_CPU0_G3_TX_DP(3)   I233 @T6G_MB_LIB.T6G(SCH_1):PAGE353

C1574 Q_CAP_DIFFBUS_C0201-DIFF BUS_0.22UF,6.3V,20%,X6S,SA
     1 P5E_CPU0_G3_TX_C_DN<2> @T6G_MB_LIB.T6G(SCH_1):P5E_CPU0_G3_TX_C_DN(2)   I232 @T6G_MB_LIB.T6G(SCH_1):PAGE353
     2 P5E_CPU0_G3_TX_DN<2> @T6G_MB_LIB.T6G(SCH_1):P5E_CPU0_G3_TX_DN(2)   I232 @T6G_MB_LIB.T6G(SCH_1):PAGE353

C1575 Q_CAP_DIFFBUS_C0201-DIFF BUS_0.22UF,6.3V,20%,X6S,SA
     1 P5E_CPU0_G3_TX_C_DP<2> @T6G_MB_LIB.T6G(SCH_1):P5E_CPU0_G3_TX_C_DP(2)   I231 @T6G_MB_LIB.T6G(SCH_1):PAGE353
     2 P5E_CPU0_G3_TX_DP<2> @T6G_MB_LIB.T6G(SCH_1):P5E_CPU0_G3_TX_DP(2)   I231 @T6G_MB_LIB.T6G(SCH_1):PAGE353

C1576 Q_CAP_DIFFBUS_C0201-DIFF BUS_0.22UF,6.3V,20%,X6S,SA
     1 P5E_CPU0_G3_TX_C_DN<1> @T6G_MB_LIB.T6G(SCH_1):P5E_CPU0_G3_TX_C_DN(1)   I312 @T6G_MB_LIB.T6G(SCH_1):PAGE353
     2 P5E_CPU0_G3_TX_DN<1> @T6G_MB_LIB.T6G(SCH_1):P5E_CPU0_G3_TX_DN(1)   I312 @T6G_MB_LIB.T6G(SCH_1):PAGE353

C1577 Q_CAP_DIFFBUS_C0201-DIFF BUS_0.22UF,6.3V,20%,X6S,SA
     1 P5E_CPU0_G3_TX_C_DP<1> @T6G_MB_LIB.T6G(SCH_1):P5E_CPU0_G3_TX_C_DP(1)   I311 @T6G_MB_LIB.T6G(SCH_1):PAGE353
     2 P5E_CPU0_G3_TX_DP<1> @T6G_MB_LIB.T6G(SCH_1):P5E_CPU0_G3_TX_DP(1)   I311 @T6G_MB_LIB.T6G(SCH_1):PAGE353

C1578 Q_CAP_DIFFBUS_C0201-DIFF BUS_0.22UF,6.3V,20%,X6S,SA
     1 P5E_CPU0_G3_TX_C_DN<0> @T6G_MB_LIB.T6G(SCH_1):P5E_CPU0_G3_TX_C_DN(0)   I230 @T6G_MB_LIB.T6G(SCH_1):PAGE353
     2 P5E_CPU0_G3_TX_DN<0> @T6G_MB_LIB.T6G(SCH_1):P5E_CPU0_G3_TX_DN(0)   I230 @T6G_MB_LIB.T6G(SCH_1):PAGE353

C1579 Q_CAP_DIFFBUS_C0201-DIFF BUS_0.22UF,6.3V,20%,X6S,SA
     1 P5E_CPU0_G3_TX_C_DP<0> @T6G_MB_LIB.T6G(SCH_1):P5E_CPU0_G3_TX_C_DP(0)   I229 @T6G_MB_LIB.T6G(SCH_1):PAGE353
     2 P5E_CPU0_G3_TX_DP<0> @T6G_MB_LIB.T6G(SCH_1):P5E_CPU0_G3_TX_DP(0)   I229 @T6G_MB_LIB.T6G(SCH_1):PAGE353

C1592 Q_CAP_0402-0.1UF,25V,10%,X7R,CH4104K1B00
     1 P3V3_AUX @T6G_MB_LIB.T6G(SCH_1):P3V3_AUX    I36 @T6G_MB_LIB.T6G(SCH_1):PAGE297
     2    GND @T6G_MB_LIB.T6G(SCH_1):GND    I36 @T6G_MB_LIB.T6G(SCH_1):PAGE297

C1663 Q_CAP_0402-0.1UF,25V,10%,X7R,CH4104K1B00
     1 P3V3_AUX @T6G_MB_LIB.T6G(SCH_1):P3V3_AUX    I47 @T6G_MB_LIB.T6G(SCH_1):PAGE337
     2    GND @T6G_MB_LIB.T6G(SCH_1):GND    I47 @T6G_MB_LIB.T6G(SCH_1):PAGE337

C1707 Q_CAP_0402-0.1UF,25V,10%,X7R,CH4104K1B00
     1 P3V3_AUX @T6G_MB_LIB.T6G(SCH_1):P3V3_AUX    I52 @T6G_MB_LIB.T6G(SCH_1):PAGE249
     2    GND @T6G_MB_LIB.T6G(SCH_1):GND    I52 @T6G_MB_LIB.T6G(SCH_1):PAGE249

C1708 Q_CAP_0402-0.1UF,25V,10%,X7R,CH4104K1B00
     1 P3V3_AUX @T6G_MB_LIB.T6G(SCH_1):P3V3_AUX    I61 @T6G_MB_LIB.T6G(SCH_1):PAGE249
     2    GND @T6G_MB_LIB.T6G(SCH_1):GND    I61 @T6G_MB_LIB.T6G(SCH_1):PAGE249

C1713 Q_CAP_0402-0.1UF,25V,10%,X7R,CH4104K1B00
     1 P3V3_AUX @T6G_MB_LIB.T6G(SCH_1):P3V3_AUX    I61 @T6G_MB_LIB.T6G(SCH_1):PAGE246
     2    GND @T6G_MB_LIB.T6G(SCH_1):GND    I61 @T6G_MB_LIB.T6G(SCH_1):PAGE246

C1751 Q_CAP_0402-0.1UF,25V,10%,X7R,CH4104K1B00
     1 P3V3_AUX @T6G_MB_LIB.T6G(SCH_1):P3V3_AUX   I412 @T6G_MB_LIB.T6G(SCH_1):PAGE363
     2    GND @T6G_MB_LIB.T6G(SCH_1):GND   I412 @T6G_MB_LIB.T6G(SCH_1):PAGE363

C1754 Q_CAP_0402-0.1UF,25V,10%,X7R,CH4104K1B00
     1 FM_SWB_BIC_READY_ISO_N @T6G_MB_LIB.T6G(SCH_1):FM_SWB_BIC_READY_ISO_N    I92 @T6G_MB_LIB.T6G(SCH_1):PAGE333
     2    GND @T6G_MB_LIB.T6G(SCH_1):GND    I92 @T6G_MB_LIB.T6G(SCH_1):PAGE333

C1756 Q_CAP_0402-0.1UF,25V,10%,X7R,CH4104K1B00
     1 FM_GPU_PWRGD_ISO @T6G_MB_LIB.T6G(SCH_1):FM_GPU_PWRGD_ISO   I105 @T6G_MB_LIB.T6G(SCH_1):PAGE333
     2    GND @T6G_MB_LIB.T6G(SCH_1):GND   I105 @T6G_MB_LIB.T6G(SCH_1):PAGE333

C1757 Q_CAP_0402-0.1UF,25V,10%,X7R,CH4104K1B00
     1 P3V3_MAX11617_VDD @T6G_MB_LIB.T6G(SCH_1):P3V3_MAX11617_VDD   I162 @T6G_MB_LIB.T6G(SCH_1):PAGE369
     2    GND @T6G_MB_LIB.T6G(SCH_1):GND   I162 @T6G_MB_LIB.T6G(SCH_1):PAGE369

C1766 Q_CAP_0402-0.1UF,25V,10%,X7R,CH4104K1B00
     1 P3V3_AUX @T6G_MB_LIB.T6G(SCH_1):P3V3_AUX    I78 @T6G_MB_LIB.T6G(SCH_1):PAGE249
     2    GND @T6G_MB_LIB.T6G(SCH_1):GND    I78 @T6G_MB_LIB.T6G(SCH_1):PAGE249

C1767 Q_CAP_C0805-10UF,16V,10%,X6S,CH6103KEA00
     1 MAX11617_VREF @T6G_MB_LIB.T6G(SCH_1):MAX11617_VREF   I121 @T6G_MB_LIB.T6G(SCH_1):PAGE369
     2    GND @T6G_MB_LIB.T6G(SCH_1):GND   I121 @T6G_MB_LIB.T6G(SCH_1):PAGE369

C1768 Q_CAP_C0805-10UF,16V,10%,X6S,CH6103KEA00
     1 P3V3_MAX11617_VDD @T6G_MB_LIB.T6G(SCH_1):P3V3_MAX11617_VDD   I166 @T6G_MB_LIB.T6G(SCH_1):PAGE369
     2    GND @T6G_MB_LIB.T6G(SCH_1):GND   I166 @T6G_MB_LIB.T6G(SCH_1):PAGE369

C1769 Q_CAP_0402-0.1UF,25V,10%,X7R,CH4104K1B00
     1 P3V3_AUX @T6G_MB_LIB.T6G(SCH_1):P3V3_AUX    I89 @T6G_MB_LIB.T6G(SCH_1):PAGE256
     2    GND @T6G_MB_LIB.T6G(SCH_1):GND    I89 @T6G_MB_LIB.T6G(SCH_1):PAGE256

C1770 Q_CAP_0402-0.1UF,25V,10%,X7R,CH4104K1B00
     1 P3V3_AUX @T6G_MB_LIB.T6G(SCH_1):P3V3_AUX   I140 @T6G_MB_LIB.T6G(SCH_1):PAGE256
     2    GND @T6G_MB_LIB.T6G(SCH_1):GND   I140 @T6G_MB_LIB.T6G(SCH_1):PAGE256

C1772 Q_CAP_0402-0.1UF,25V,10%,X7R,CH4104K1B00
     1 RST_BMC_FROM_SWB_ISO_N @T6G_MB_LIB.T6G(SCH_1):RST_BMC_FROM_SWB_ISO_N   I116 @T6G_MB_LIB.T6G(SCH_1):PAGE333
     2    GND @T6G_MB_LIB.T6G(SCH_1):GND   I116 @T6G_MB_LIB.T6G(SCH_1):PAGE333

C1773 Q_CAP_0402-0.1UF,25V,10%,X7R,CH4104K1B00
     1 BIC_MONITER_ISO @T6G_MB_LIB.T6G(SCH_1):BIC_MONITER_ISO   I114 @T6G_MB_LIB.T6G(SCH_1):PAGE333
     2    GND @T6G_MB_LIB.T6G(SCH_1):GND   I114 @T6G_MB_LIB.T6G(SCH_1):PAGE333

C1774 Q_CAP_0402-0.1UF,25V,10%,X7R,CH4104K1B00
     1 FM_SWB_PWRGD_ISO @T6G_MB_LIB.T6G(SCH_1):FM_SWB_PWRGD_ISO   I111 @T6G_MB_LIB.T6G(SCH_1):PAGE333
     2    GND @T6G_MB_LIB.T6G(SCH_1):GND   I111 @T6G_MB_LIB.T6G(SCH_1):PAGE333

C1775 Q_CAP_0402-0.1UF,25V,10%,X7R,CH4104K1B00
     1 P3V3_AUX @T6G_MB_LIB.T6G(SCH_1):P3V3_AUX    I14 @T6G_MB_LIB.T6G(SCH_1):PAGE364
     2    GND @T6G_MB_LIB.T6G(SCH_1):GND    I14 @T6G_MB_LIB.T6G(SCH_1):PAGE364

C1786 Q_CAP_0603-1000PF,50V,10%,X7R,TMP_QCH21006K917
     1 P12V_HSC_TEMP_D+ @T6G_MB_LIB.T6G(SCH_1):P12V_HSC_TEMP_D+     I4 @T6G_MB_LIB.T6G(SCH_1):PAGE371
     2 P12V_HSC_TEMP_D- @T6G_MB_LIB.T6G(SCH_1):P12V_HSC_TEMP_D-     I4 @T6G_MB_LIB.T6G(SCH_1):PAGE371

C1787 Q_CAP_C0402-0.1UF,16V,10%,X7R,CH4103K1B08
     1 P3V3_AUX @T6G_MB_LIB.T6G(SCH_1):P3V3_AUX     I6 @T6G_MB_LIB.T6G(SCH_1):PAGE371
     2    GND @T6G_MB_LIB.T6G(SCH_1):GND     I6 @T6G_MB_LIB.T6G(SCH_1):PAGE371

C1792 Q_CAP_DIFFBUS_C0201-DIFF BUS_0.22UF,6.3V,20%,X6S,SA
     1 P5E_CPU0_G3_TX_C_DP<14> @T6G_MB_LIB.T6G(SCH_1):P5E_CPU0_G3_TX_C_DP(14)   I271 @T6G_MB_LIB.T6G(SCH_1):PAGE353
     2 P5E_CPU0_G3_TX_DP<14> @T6G_MB_LIB.T6G(SCH_1):P5E_CPU0_G3_TX_DP(14)   I271 @T6G_MB_LIB.T6G(SCH_1):PAGE353

C1793 Q_CAP_DIFFBUS_C0201-DIFF BUS_0.22UF,6.3V,20%,X6S,SA
     1 P5E_CPU0_G3_TX_C_DP<9> @T6G_MB_LIB.T6G(SCH_1):P5E_CPU0_G3_TX_C_DP(9)   I261 @T6G_MB_LIB.T6G(SCH_1):PAGE353
     2 P5E_CPU0_G3_TX_DP<9> @T6G_MB_LIB.T6G(SCH_1):P5E_CPU0_G3_TX_DP(9)   I261 @T6G_MB_LIB.T6G(SCH_1):PAGE353

C1794 Q_CAP_DIFFBUS_C0201-DIFF BUS_0.22UF,6.3V,20%,X6S,SA
     1 P5E_CPU0_G3_TX_C_DN<8> @T6G_MB_LIB.T6G(SCH_1):P5E_CPU0_G3_TX_C_DN(8)   I260 @T6G_MB_LIB.T6G(SCH_1):PAGE353
     2 P5E_CPU0_G3_TX_DN<8> @T6G_MB_LIB.T6G(SCH_1):P5E_CPU0_G3_TX_DN(8)   I260 @T6G_MB_LIB.T6G(SCH_1):PAGE353

C1796 Q_CAP_0402-0.1UF,25V,10%,X7R,CH4104K1B00
     1 P3V3_AUX @T6G_MB_LIB.T6G(SCH_1):P3V3_AUX    I32 @T6G_MB_LIB.T6G(SCH_1):PAGE249
     2    GND @T6G_MB_LIB.T6G(SCH_1):GND    I32 @T6G_MB_LIB.T6G(SCH_1):PAGE249

C1797 Q_CAP_0402-0.1UF,25V,10%,X7R,CH4104K1B00
     1 PDB_PRSNT_R_N @T6G_MB_LIB.T6G(SCH_1):PDB_PRSNT_R_N     I9 @T6G_MB_LIB.T6G(SCH_1):PAGE372
     2    GND @T6G_MB_LIB.T6G(SCH_1):GND     I9 @T6G_MB_LIB.T6G(SCH_1):PAGE372

C1802 Q_CAP_0402-0.1UF,25V,10%,X7R,CH4104K1B00
     1 FM_SMB_1_ALERT_GPU_ISO_N @T6G_MB_LIB.T6G(SCH_1):FM_SMB_1_ALERT_GPU_ISO_N   I148 @T6G_MB_LIB.T6G(SCH_1):PAGE333
     2    GND @T6G_MB_LIB.T6G(SCH_1):GND   I148 @T6G_MB_LIB.T6G(SCH_1):PAGE333

C1803 Q_CAP_0402-0.1UF,25V,10%,X7R,CH4104K1B00
     1 P3V3_AUX @T6G_MB_LIB.T6G(SCH_1):P3V3_AUX   I166 @T6G_MB_LIB.T6G(SCH_1):PAGE256
     2    GND @T6G_MB_LIB.T6G(SCH_1):GND   I166 @T6G_MB_LIB.T6G(SCH_1):PAGE256

C1804 Q_CAP_0402-0.1UF,25V,10%,X7R,CH4104K1B00
     1 FM_SMB_2_ALERT_GPU_ISO_N @T6G_MB_LIB.T6G(SCH_1):FM_SMB_2_ALERT_GPU_ISO_N   I125 @T6G_MB_LIB.T6G(SCH_1):PAGE333
     2    GND @T6G_MB_LIB.T6G(SCH_1):GND   I125 @T6G_MB_LIB.T6G(SCH_1):PAGE333

C1809 Q_CAP_0402-0.1UF,25V,10%,X7R,CH4104K1B00
     1 P3V3_AUX @T6G_MB_LIB.T6G(SCH_1):P3V3_AUX    I29 @T6G_MB_LIB.T6G(SCH_1):PAGE343
     2    GND @T6G_MB_LIB.T6G(SCH_1):GND    I29 @T6G_MB_LIB.T6G(SCH_1):PAGE343

C1810 Q_CAP_0402-0.1UF,25V,10%,X7R,CH4104K1B00
     1 P3V3_AUX @T6G_MB_LIB.T6G(SCH_1):P3V3_AUX    I23 @T6G_MB_LIB.T6G(SCH_1):PAGE343
     2    GND @T6G_MB_LIB.T6G(SCH_1):GND    I23 @T6G_MB_LIB.T6G(SCH_1):PAGE343

C1821 Q_CAP_0402-0.1UF,25V,10%,X7R,CH4104K1B00
     1 P3V3_AUX @T6G_MB_LIB.T6G(SCH_1):P3V3_AUX    I55 @T6G_MB_LIB.T6G(SCH_1):PAGE342
     2    GND @T6G_MB_LIB.T6G(SCH_1):GND    I55 @T6G_MB_LIB.T6G(SCH_1):PAGE342

C1822 Q_CAP_0402-0.1UF,25V,10%,X7R,CH4104K1B00
     1 P3V3_AUX @T6G_MB_LIB.T6G(SCH_1):P3V3_AUX    I16 @T6G_MB_LIB.T6G(SCH_1):PAGE342
     2    GND @T6G_MB_LIB.T6G(SCH_1):GND    I16 @T6G_MB_LIB.T6G(SCH_1):PAGE342

C1823 Q_CAP_0402-0.1UF,25V,10%,X7R,CH4104K1B00
     1 P3V3_AUX @T6G_MB_LIB.T6G(SCH_1):P3V3_AUX    I31 @T6G_MB_LIB.T6G(SCH_1):PAGE342
     2    GND @T6G_MB_LIB.T6G(SCH_1):GND    I31 @T6G_MB_LIB.T6G(SCH_1):PAGE342

C1824 Q_CAP_0402-0.1UF,25V,10%,X7R,CH4104K1B00
     1 P3V3_AUX @T6G_MB_LIB.T6G(SCH_1):P3V3_AUX    I41 @T6G_MB_LIB.T6G(SCH_1):PAGE342
     2    GND @T6G_MB_LIB.T6G(SCH_1):GND    I41 @T6G_MB_LIB.T6G(SCH_1):PAGE342

C1825 Q_CAP_0402-0.1UF,25V,10%,X7R,CH4104K1B00
     1 P3V3_AUX @T6G_MB_LIB.T6G(SCH_1):P3V3_AUX    I17 @T6G_MB_LIB.T6G(SCH_1):PAGE307
     2    GND @T6G_MB_LIB.T6G(SCH_1):GND    I17 @T6G_MB_LIB.T6G(SCH_1):PAGE307

C1826 Q_CAP_0402-0.1UF,25V,10%,X7R,CH4104K1B00
     1 P3V3_AUX @T6G_MB_LIB.T6G(SCH_1):P3V3_AUX    I33 @T6G_MB_LIB.T6G(SCH_1):PAGE307
     2    GND @T6G_MB_LIB.T6G(SCH_1):GND    I33 @T6G_MB_LIB.T6G(SCH_1):PAGE307

C1827 Q_CAP_0402-0.1UF,25V,10%,X7R,CH4104K1B00
     1 P3V3_AUX @T6G_MB_LIB.T6G(SCH_1):P3V3_AUX    I77 @T6G_MB_LIB.T6G(SCH_1):PAGE307
     2    GND @T6G_MB_LIB.T6G(SCH_1):GND    I77 @T6G_MB_LIB.T6G(SCH_1):PAGE307

C1829 Q_CAP_C0805-22UF,16V,20%,X6S,CH6223MEA00
     1 P12V_OCP_V3_2_R @T6G_MB_LIB.T6G(SCH_1):P12V_OCP_V3_2_R    I13 @T6G_MB_LIB.T6G(SCH_1):PAGE341
     2    GND @T6G_MB_LIB.T6G(SCH_1):GND    I13 @T6G_MB_LIB.T6G(SCH_1):PAGE341

C1830 Q_CAP_C0805-22UF,16V,20%,X6S,CH6223MEA00
     1 P12V_OCP_V3_2_R @T6G_MB_LIB.T6G(SCH_1):P12V_OCP_V3_2_R    I14 @T6G_MB_LIB.T6G(SCH_1):PAGE341
     2    GND @T6G_MB_LIB.T6G(SCH_1):GND    I14 @T6G_MB_LIB.T6G(SCH_1):PAGE341

C1831 Q_CAP_0402-0.1UF,25V,10%,X7R,CH4104K1B00
     1 P12V_OCP_V3_2_R @T6G_MB_LIB.T6G(SCH_1):P12V_OCP_V3_2_R    I15 @T6G_MB_LIB.T6G(SCH_1):PAGE341
     2    GND @T6G_MB_LIB.T6G(SCH_1):GND    I15 @T6G_MB_LIB.T6G(SCH_1):PAGE341

C1832 Q_CAP_0402-0.1UF,25V,10%,X7R,CH4104K1B00
     1 P12V_OCP_V3_2_R @T6G_MB_LIB.T6G(SCH_1):P12V_OCP_V3_2_R    I16 @T6G_MB_LIB.T6G(SCH_1):PAGE341
     2    GND @T6G_MB_LIB.T6G(SCH_1):GND    I16 @T6G_MB_LIB.T6G(SCH_1):PAGE341

C1833 Q_CAP_0402-0.1UF,25V,10%,X7R,CH4104K1B00
     1 P12V_OCP_V3_2_R @T6G_MB_LIB.T6G(SCH_1):P12V_OCP_V3_2_R    I17 @T6G_MB_LIB.T6G(SCH_1):PAGE341
     2    GND @T6G_MB_LIB.T6G(SCH_1):GND    I17 @T6G_MB_LIB.T6G(SCH_1):PAGE341

C1834 Q_CAP_0402-0.1UF,25V,10%,X7R,CH4104K1B00
     1 P12V_OCP_V3_2_R @T6G_MB_LIB.T6G(SCH_1):P12V_OCP_V3_2_R    I20 @T6G_MB_LIB.T6G(SCH_1):PAGE341
     2    GND @T6G_MB_LIB.T6G(SCH_1):GND    I20 @T6G_MB_LIB.T6G(SCH_1):PAGE341

C1835 Q_CAP_0402-0.1UF,25V,10%,X7R,CH4104K1B00
     1 P3V3_OCP_V3_2 @T6G_MB_LIB.T6G(SCH_1):P3V3_OCP_V3_2    I21 @T6G_MB_LIB.T6G(SCH_1):PAGE341
     2    GND @T6G_MB_LIB.T6G(SCH_1):GND    I21 @T6G_MB_LIB.T6G(SCH_1):PAGE341

C1836 Q_CAP_0402-0.1UF,25V,10%,X7R,CH4104K1B00
     1 P3V3_OCP_V3_2 @T6G_MB_LIB.T6G(SCH_1):P3V3_OCP_V3_2    I22 @T6G_MB_LIB.T6G(SCH_1):PAGE341
     2    GND @T6G_MB_LIB.T6G(SCH_1):GND    I22 @T6G_MB_LIB.T6G(SCH_1):PAGE341

C1837 Q_CAP_0402-0.1UF,25V,10%,X7R,CH4104K1B00
     1 P3V3_OCP_V3_2 @T6G_MB_LIB.T6G(SCH_1):P3V3_OCP_V3_2    I23 @T6G_MB_LIB.T6G(SCH_1):PAGE341
     2    GND @T6G_MB_LIB.T6G(SCH_1):GND    I23 @T6G_MB_LIB.T6G(SCH_1):PAGE341

C1838 Q_CAP_0402-0.1UF,25V,10%,X7R,CH4104K1B00
     1 P3V3_OCP_V3_2 @T6G_MB_LIB.T6G(SCH_1):P3V3_OCP_V3_2    I24 @T6G_MB_LIB.T6G(SCH_1):PAGE341
     2    GND @T6G_MB_LIB.T6G(SCH_1):GND    I24 @T6G_MB_LIB.T6G(SCH_1):PAGE341

C1839 Q_CAP_0402-0.1UF,25V,10%,X7R,CH4104K1B00
     1 P12V_OCP_V3_2_R @T6G_MB_LIB.T6G(SCH_1):P12V_OCP_V3_2_R    I18 @T6G_MB_LIB.T6G(SCH_1):PAGE341
     2    GND @T6G_MB_LIB.T6G(SCH_1):GND    I18 @T6G_MB_LIB.T6G(SCH_1):PAGE341

C1840 Q_CAP_0402-0.1UF,25V,10%,X7R,CH4104K1B00
     1 P3V3_AUX @T6G_MB_LIB.T6G(SCH_1):P3V3_AUX   I147 @T6G_MB_LIB.T6G(SCH_1):PAGE336
     2    GND @T6G_MB_LIB.T6G(SCH_1):GND   I147 @T6G_MB_LIB.T6G(SCH_1):PAGE336

C1841 Q_CAP_0402-0.1UF,25V,10%,X7R,CH4104K1B00
     1 P3V3_AUX @T6G_MB_LIB.T6G(SCH_1):P3V3_AUX    I12 @T6G_MB_LIB.T6G(SCH_1):PAGE342
     2    GND @T6G_MB_LIB.T6G(SCH_1):GND    I12 @T6G_MB_LIB.T6G(SCH_1):PAGE342

C1859 Q_CAP_0402-0.1UF,25V,10%,X7R,CH4104K1B00
     1 P3V3_AUX @T6G_MB_LIB.T6G(SCH_1):P3V3_AUX     I4 @T6G_MB_LIB.T6G(SCH_1):PAGE248
     2    GND @T6G_MB_LIB.T6G(SCH_1):GND     I4 @T6G_MB_LIB.T6G(SCH_1):PAGE248

C1860 Q_CAP_0402-0.1UF,25V,10%,X7R,CH4104K1B00
     1 P3V3_AUX @T6G_MB_LIB.T6G(SCH_1):P3V3_AUX    I15 @T6G_MB_LIB.T6G(SCH_1):PAGE248
     2    GND @T6G_MB_LIB.T6G(SCH_1):GND    I15 @T6G_MB_LIB.T6G(SCH_1):PAGE248

C1861 Q_CAP_0402-0.1UF,25V,10%,X7R,CH4104K1B00
     1 P3V3_OCP_V3_2 @T6G_MB_LIB.T6G(SCH_1):P3V3_OCP_V3_2     I9 @T6G_MB_LIB.T6G(SCH_1):PAGE248
     2    GND @T6G_MB_LIB.T6G(SCH_1):GND     I9 @T6G_MB_LIB.T6G(SCH_1):PAGE248

C1862 Q_CAP_0402-0.1UF,25V,10%,X7R,CH4104K1B00
     1 P3V3_OCP_SFF @T6G_MB_LIB.T6G(SCH_1):P3V3_OCP_SFF    I19 @T6G_MB_LIB.T6G(SCH_1):PAGE248
     2    GND @T6G_MB_LIB.T6G(SCH_1):GND    I19 @T6G_MB_LIB.T6G(SCH_1):PAGE248

C1863 Q_CAP_0402-0.1UF,25V,10%,X7R,CH4104K1B00
     1 P3V3_AUX @T6G_MB_LIB.T6G(SCH_1):P3V3_AUX    I61 @T6G_MB_LIB.T6G(SCH_1):PAGE110
     2    GND @T6G_MB_LIB.T6G(SCH_1):GND    I61 @T6G_MB_LIB.T6G(SCH_1):PAGE110

C1864 Q_CAP_0402-0.1UF,25V,10%,X7R,CH4104K1B00
     1 P3V3_AUX @T6G_MB_LIB.T6G(SCH_1):P3V3_AUX    I62 @T6G_MB_LIB.T6G(SCH_1):PAGE110
     2    GND @T6G_MB_LIB.T6G(SCH_1):GND    I62 @T6G_MB_LIB.T6G(SCH_1):PAGE110

C1865 Q_CAP_0402-0.1UF,25V,10%,X7R,CH4104K1B00
     1 P3V3_AUX @T6G_MB_LIB.T6G(SCH_1):P3V3_AUX    I64 @T6G_MB_LIB.T6G(SCH_1):PAGE110
     2    GND @T6G_MB_LIB.T6G(SCH_1):GND    I64 @T6G_MB_LIB.T6G(SCH_1):PAGE110

C1866 Q_CAP_0402-0.1UF,25V,10%,X7R,CH4104K1B00
     1 P3V3_AUX @T6G_MB_LIB.T6G(SCH_1):P3V3_AUX    I65 @T6G_MB_LIB.T6G(SCH_1):PAGE110
     2    GND @T6G_MB_LIB.T6G(SCH_1):GND    I65 @T6G_MB_LIB.T6G(SCH_1):PAGE110

C1867 Q_CAP_C0805-10UF,25V,10%,X6S,CH6104KEA00
     1 P3V3_AUX @T6G_MB_LIB.T6G(SCH_1):P3V3_AUX    I60 @T6G_MB_LIB.T6G(SCH_1):PAGE110
     2    GND @T6G_MB_LIB.T6G(SCH_1):GND    I60 @T6G_MB_LIB.T6G(SCH_1):PAGE110

C1868 Q_CAP_0402-0.1UF,25V,10%,X7R,CH4104K1B00
     1 P2E_MB_BMC_RX_BUF_C_DP<0> @T6G_MB_LIB.T6G(SCH_1):P2E_MB_BMC_RX_BUF_C_DP(0)    I11 @T6G_MB_LIB.T6G(SCH_1):PAGE112
     2 P2E_MB_BMC_RX_BUF_DP<0> @T6G_MB_LIB.T6G(SCH_1):P2E_MB_BMC_RX_BUF_DP(0)    I11 @T6G_MB_LIB.T6G(SCH_1):PAGE112

C1869 Q_CAP_0402-0.1UF,25V,10%,X7R,CH4104K1B00
     1 P2E_MB_BMC_RX_BUF_C_DN<0> @T6G_MB_LIB.T6G(SCH_1):P2E_MB_BMC_RX_BUF_C_DN(0)    I12 @T6G_MB_LIB.T6G(SCH_1):PAGE112
     2 P2E_MB_BMC_RX_BUF_DN<0> @T6G_MB_LIB.T6G(SCH_1):P2E_MB_BMC_RX_BUF_DN(0)    I12 @T6G_MB_LIB.T6G(SCH_1):PAGE112

C1870 Q_CAP_0402-0.1UF,25V,10%,X7R,CH4104K1B00
     1 P2E_MB_BMC_TX_BUF_DP<0> @T6G_MB_LIB.T6G(SCH_1):P2E_MB_BMC_TX_BUF_DP(0)    I13 @T6G_MB_LIB.T6G(SCH_1):PAGE112
     2 P2E_MB_BMC_TX_BUF_C_DP<0> @T6G_MB_LIB.T6G(SCH_1):P2E_MB_BMC_TX_BUF_C_DP(0)    I13 @T6G_MB_LIB.T6G(SCH_1):PAGE112

C1871 Q_CAP_0402-0.1UF,25V,10%,X7R,CH4104K1B00
     1 P2E_MB_BMC_TX_BUF_DN<0> @T6G_MB_LIB.T6G(SCH_1):P2E_MB_BMC_TX_BUF_DN(0)    I14 @T6G_MB_LIB.T6G(SCH_1):PAGE112
     2 P2E_MB_BMC_TX_BUF_C_DN<0> @T6G_MB_LIB.T6G(SCH_1):P2E_MB_BMC_TX_BUF_C_DN(0)    I14 @T6G_MB_LIB.T6G(SCH_1):PAGE112

C1873 Q_CAP_0402-0.1UF,25V,10%,X7R,CH4104K1B00
     1 P3V3_AUX @T6G_MB_LIB.T6G(SCH_1):P3V3_AUX    I56 @T6G_MB_LIB.T6G(SCH_1):PAGE345
     2    GND @T6G_MB_LIB.T6G(SCH_1):GND    I56 @T6G_MB_LIB.T6G(SCH_1):PAGE345

C1874 Q_CAP_0402-0.1UF,25V,10%,X7R,CH4104K1B00
     1 P3V3_AUX @T6G_MB_LIB.T6G(SCH_1):P3V3_AUX    I22 @T6G_MB_LIB.T6G(SCH_1):PAGE258
     2    GND @T6G_MB_LIB.T6G(SCH_1):GND    I22 @T6G_MB_LIB.T6G(SCH_1):PAGE258

C1875 Q_CAP_0402-0.1UF,25V,10%,X7R,CH4104K1B00
     1 P3V3_AUX @T6G_MB_LIB.T6G(SCH_1):P3V3_AUX    I21 @T6G_MB_LIB.T6G(SCH_1):PAGE258
     2    GND @T6G_MB_LIB.T6G(SCH_1):GND    I21 @T6G_MB_LIB.T6G(SCH_1):PAGE258

C1876 Q_CAP_0402-0.1UF,25V,10%,X7R,CH4104K1B00
     1 P3V3_AUX @T6G_MB_LIB.T6G(SCH_1):P3V3_AUX    I41 @T6G_MB_LIB.T6G(SCH_1):PAGE258
     2    GND @T6G_MB_LIB.T6G(SCH_1):GND    I41 @T6G_MB_LIB.T6G(SCH_1):PAGE258

C1877 Q_CAP_0402-0.1UF,25V,10%,X7R,CH4104K1B00
     1 P3V3_AUX @T6G_MB_LIB.T6G(SCH_1):P3V3_AUX    I34 @T6G_MB_LIB.T6G(SCH_1):PAGE258
     2    GND @T6G_MB_LIB.T6G(SCH_1):GND    I34 @T6G_MB_LIB.T6G(SCH_1):PAGE258

C1878 Q_CAP_0402-0.1UF,25V,10%,X7R,CH4104K1B00
     1 P3V3_AUX @T6G_MB_LIB.T6G(SCH_1):P3V3_AUX    I37 @T6G_MB_LIB.T6G(SCH_1):PAGE258
     2    GND @T6G_MB_LIB.T6G(SCH_1):GND    I37 @T6G_MB_LIB.T6G(SCH_1):PAGE258

C1879 Q_CAP_0402-0.1UF,25V,10%,X7R,CH4104K1B00
     1 P3V3_AUX @T6G_MB_LIB.T6G(SCH_1):P3V3_AUX    I31 @T6G_MB_LIB.T6G(SCH_1):PAGE258
     2    GND @T6G_MB_LIB.T6G(SCH_1):GND    I31 @T6G_MB_LIB.T6G(SCH_1):PAGE258

C1880 Q_CAP_0402-0.1UF,25V,10%,X7R,CH4104K1B00
     1 P3V3_AUX @T6G_MB_LIB.T6G(SCH_1):P3V3_AUX    I27 @T6G_MB_LIB.T6G(SCH_1):PAGE258
     2    GND @T6G_MB_LIB.T6G(SCH_1):GND    I27 @T6G_MB_LIB.T6G(SCH_1):PAGE258

C1881 Q_CAP_0402-0.1UF,25V,10%,X7R,CH4104K1B00
     1 GPU_FPGA_READY_ISO @T6G_MB_LIB.T6G(SCH_1):GPU_FPGA_READY_ISO   I156 @T6G_MB_LIB.T6G(SCH_1):PAGE333
     2    GND @T6G_MB_LIB.T6G(SCH_1):GND   I156 @T6G_MB_LIB.T6G(SCH_1):PAGE333

C1882 Q_CAP_0402-0.1UF,25V,10%,X7R,CH4104K1B00
     1 P3V3_AUX @T6G_MB_LIB.T6G(SCH_1):P3V3_AUX    I28 @T6G_MB_LIB.T6G(SCH_1):PAGE232
     2    GND @T6G_MB_LIB.T6G(SCH_1):GND    I28 @T6G_MB_LIB.T6G(SCH_1):PAGE232

C1883 Q_CAP_C0805-10UF,25V,10%,X6S,CH6104KEA00
     1 VFG3P3_CLK_GEN @T6G_MB_LIB.T6G(SCH_1):VFG3P3_CLK_GEN    I36 @T6G_MB_LIB.T6G(SCH_1):PAGE232
     2    GND @T6G_MB_LIB.T6G(SCH_1):GND    I36 @T6G_MB_LIB.T6G(SCH_1):PAGE232

C1884 Q_CAP_C0402-1UF,25V,10%,X6S,CH5104KEB02
     1 VFG_3P3A_CLK_GEN @T6G_MB_LIB.T6G(SCH_1):VFG_3P3A_CLK_GEN    I68 @T6G_MB_LIB.T6G(SCH_1):PAGE232
     2    GND @T6G_MB_LIB.T6G(SCH_1):GND    I68 @T6G_MB_LIB.T6G(SCH_1):PAGE232

C1886 Q_CAP_0402-0.1UF,25V,10%,X7R,CH4104K1B00
     1 VFG3P3_CLK_GEN @T6G_MB_LIB.T6G(SCH_1):VFG3P3_CLK_GEN    I40 @T6G_MB_LIB.T6G(SCH_1):PAGE232
     2    GND @T6G_MB_LIB.T6G(SCH_1):GND    I40 @T6G_MB_LIB.T6G(SCH_1):PAGE232

C1889 Q_CAP_0402-0.1UF,25V,10%,X7R,CH4104K1B00
     1 VFG3P3_CLK_GEN @T6G_MB_LIB.T6G(SCH_1):VFG3P3_CLK_GEN    I41 @T6G_MB_LIB.T6G(SCH_1):PAGE232
     2    GND @T6G_MB_LIB.T6G(SCH_1):GND    I41 @T6G_MB_LIB.T6G(SCH_1):PAGE232

C1920 Q_CAP_C0603-22UF,6.3V,20%,X6S,CH6221ME900
     1 P3V3_M2_0 @T6G_MB_LIB.T6G(SCH_1):P3V3_M2_0    I77 @T6G_MB_LIB.T6G(SCH_1):PAGE345
     2    GND @T6G_MB_LIB.T6G(SCH_1):GND    I77 @T6G_MB_LIB.T6G(SCH_1):PAGE345

C1921 Q_CAP_C0603-22UF,6.3V,20%,X6S,CH6221ME900
     1 P3V3_M2_0 @T6G_MB_LIB.T6G(SCH_1):P3V3_M2_0    I78 @T6G_MB_LIB.T6G(SCH_1):PAGE345
     2    GND @T6G_MB_LIB.T6G(SCH_1):GND    I78 @T6G_MB_LIB.T6G(SCH_1):PAGE345

C1922 Q_CAP_C0402-22UF,4V,20%,X6S,CH622KMEB02
     1 PVDDCR_CPU0_P0 @T6G_MB_LIB.T6G(SCH_1):PVDDCR_CPU0_P0    I45 @T6G_MB_LIB.T6G(SCH_1):PAGE68
     2    GND @T6G_MB_LIB.T6G(SCH_1):GND    I45 @T6G_MB_LIB.T6G(SCH_1):PAGE68

C1923 Q_CAP_0402-0.1UF,25V,10%,X7R,CH4104K1B00
     1 P3V3_M2_0 @T6G_MB_LIB.T6G(SCH_1):P3V3_M2_0    I84 @T6G_MB_LIB.T6G(SCH_1):PAGE345
     2    GND @T6G_MB_LIB.T6G(SCH_1):GND    I84 @T6G_MB_LIB.T6G(SCH_1):PAGE345

C1924 Q_CAP_0402-0.1UF,25V,10%,X7R,CH4104K1B00
     1 P3V3_M2_0 @T6G_MB_LIB.T6G(SCH_1):P3V3_M2_0    I85 @T6G_MB_LIB.T6G(SCH_1):PAGE345
     2    GND @T6G_MB_LIB.T6G(SCH_1):GND    I85 @T6G_MB_LIB.T6G(SCH_1):PAGE345

C1925 Q_CAP_0402-0.1UF,25V,10%,X7R,CH4104K1B00
     1 P3V3_M2_0 @T6G_MB_LIB.T6G(SCH_1):P3V3_M2_0    I86 @T6G_MB_LIB.T6G(SCH_1):PAGE345
     2    GND @T6G_MB_LIB.T6G(SCH_1):GND    I86 @T6G_MB_LIB.T6G(SCH_1):PAGE345

C1957 Q_CAP_0402-0.1UF,25V,10%,X7R,CH4104K1B00
     1 P3V3_AUX @T6G_MB_LIB.T6G(SCH_1):P3V3_AUX   I148 @T6G_MB_LIB.T6G(SCH_1):PAGE334
     2    GND @T6G_MB_LIB.T6G(SCH_1):GND   I148 @T6G_MB_LIB.T6G(SCH_1):PAGE334

C1958 Q_CAP_0402-0.1UF,25V,10%,X7R,CH4104K1B00
     1 P3V3_AUX @T6G_MB_LIB.T6G(SCH_1):P3V3_AUX    I29 @T6G_MB_LIB.T6G(SCH_1):PAGE334
     2    GND @T6G_MB_LIB.T6G(SCH_1):GND    I29 @T6G_MB_LIB.T6G(SCH_1):PAGE334

C1963 Q_CAP_0402-0.1UF,25V,10%,X7R,CH4104K1B00
     1 P3V3_AUX @T6G_MB_LIB.T6G(SCH_1):P3V3_AUX    I13 @T6G_MB_LIB.T6G(SCH_1):PAGE255
     2    GND @T6G_MB_LIB.T6G(SCH_1):GND    I13 @T6G_MB_LIB.T6G(SCH_1):PAGE255

C1973 Q_CAP_0402-0.1UF,25V,10%,X7R,CH4104K1B00
     1 GPU_BASE_HMC_READY_ISO @T6G_MB_LIB.T6G(SCH_1):GPU_BASE_HMC_READY_ISO    I71 @T6G_MB_LIB.T6G(SCH_1):PAGE299
     2    GND @T6G_MB_LIB.T6G(SCH_1):GND    I71 @T6G_MB_LIB.T6G(SCH_1):PAGE299

C1974 Q_CAP_0402-0.1UF,25V,10%,X7R,CH4104K1B00
     1 GPU_FPGA_THERM_OVERT_ISO_N @T6G_MB_LIB.T6G(SCH_1):GPU_FPGA_THERM_OVERT_ISO_N    I74 @T6G_MB_LIB.T6G(SCH_1):PAGE299
     2    GND @T6G_MB_LIB.T6G(SCH_1):GND    I74 @T6G_MB_LIB.T6G(SCH_1):PAGE299

C1975 Q_CAP_0402-0.1UF,25V,10%,X7R,CH4104K1B00
     1 GPU_HMC_PRSNT_ISO_N @T6G_MB_LIB.T6G(SCH_1):GPU_HMC_PRSNT_ISO_N   I129 @T6G_MB_LIB.T6G(SCH_1):PAGE299
     2    GND @T6G_MB_LIB.T6G(SCH_1):GND   I129 @T6G_MB_LIB.T6G(SCH_1):PAGE299

C1976 Q_CAP_0402-0.1UF,25V,10%,X7R,CH4104K1B00
     1 GPU_FPGA_OVERT_ISO_N @T6G_MB_LIB.T6G(SCH_1):GPU_FPGA_OVERT_ISO_N    I30 @T6G_MB_LIB.T6G(SCH_1):PAGE299
     2    GND @T6G_MB_LIB.T6G(SCH_1):GND    I30 @T6G_MB_LIB.T6G(SCH_1):PAGE299

C1977 Q_CAP_0402-0.1UF,25V,10%,X7R,CH4104K1B00
     1 P3V3_AUX @T6G_MB_LIB.T6G(SCH_1):P3V3_AUX   I175 @T6G_MB_LIB.T6G(SCH_1):PAGE334
     2    GND @T6G_MB_LIB.T6G(SCH_1):GND   I175 @T6G_MB_LIB.T6G(SCH_1):PAGE334

C1978 Q_CAP_0402-0.1UF,25V,10%,X7R,CH4104K1B00
     1 GPU_PRSNT_N_ISO @T6G_MB_LIB.T6G(SCH_1):GPU_PRSNT_N_ISO   I152 @T6G_MB_LIB.T6G(SCH_1):PAGE299
     2    GND @T6G_MB_LIB.T6G(SCH_1):GND   I152 @T6G_MB_LIB.T6G(SCH_1):PAGE299

C1979 Q_CAP_0402-0.1UF,25V,10%,X7R,CH4104K1B00
     1 P3V3_AUX @T6G_MB_LIB.T6G(SCH_1):P3V3_AUX    I67 @T6G_MB_LIB.T6G(SCH_1):PAGE255
     2    GND @T6G_MB_LIB.T6G(SCH_1):GND    I67 @T6G_MB_LIB.T6G(SCH_1):PAGE255

C1988 Q_CAP_0402-0.1UF,25V,10%,X7R,CH4104K1B00
     1 GPU_FPGA_EROT_FATALERR_ISO_N @T6G_MB_LIB.T6G(SCH_1):GPU_FPGA_EROT_FATALERR_ISO_N   I171 @T6G_MB_LIB.T6G(SCH_1):PAGE299
     2    GND @T6G_MB_LIB.T6G(SCH_1):GND   I171 @T6G_MB_LIB.T6G(SCH_1):PAGE299

C1989 Q_CAP_DIFFBUS_C0201-DIFF BUS_0.22UF,6.3V,20%,X6S,SA
     1 P3E_CPU0_P4_TX_C_DP<3> @T6G_MB_LIB.T6G(SCH_1):P3E_CPU0_P4_TX_C_DP(3)     I8 @T6G_MB_LIB.T6G(SCH_1):PAGE355
     2 P3E_CPU0_P4_TX_DP<3> @T6G_MB_LIB.T6G(SCH_1):P3E_CPU0_P4_TX_DP(3)     I8 @T6G_MB_LIB.T6G(SCH_1):PAGE355

C1990 Q_CAP_DIFFBUS_C0201-DIFF BUS_0.22UF,6.3V,20%,X6S,SA
     1 P3E_CPU0_P4_TX_C_DN<3> @T6G_MB_LIB.T6G(SCH_1):P3E_CPU0_P4_TX_C_DN(3)     I7 @T6G_MB_LIB.T6G(SCH_1):PAGE355
     2 P3E_CPU0_P4_TX_DN<3> @T6G_MB_LIB.T6G(SCH_1):P3E_CPU0_P4_TX_DN(3)     I7 @T6G_MB_LIB.T6G(SCH_1):PAGE355

C1991 Q_CAP_DIFFBUS_C0201-DIFF BUS_0.22UF,6.3V,20%,X6S,SA
     1 P3E_CPU0_P4_TX_C_DP<2> @T6G_MB_LIB.T6G(SCH_1):P3E_CPU0_P4_TX_C_DP(2)    I10 @T6G_MB_LIB.T6G(SCH_1):PAGE355
     2 P3E_CPU0_P4_TX_DP<2> @T6G_MB_LIB.T6G(SCH_1):P3E_CPU0_P4_TX_DP(2)    I10 @T6G_MB_LIB.T6G(SCH_1):PAGE355

C1992 Q_CAP_DIFFBUS_C0201-DIFF BUS_0.22UF,6.3V,20%,X6S,SA
     1 P3E_CPU0_P4_TX_C_DN<2> @T6G_MB_LIB.T6G(SCH_1):P3E_CPU0_P4_TX_C_DN(2)     I9 @T6G_MB_LIB.T6G(SCH_1):PAGE355
     2 P3E_CPU0_P4_TX_DN<2> @T6G_MB_LIB.T6G(SCH_1):P3E_CPU0_P4_TX_DN(2)     I9 @T6G_MB_LIB.T6G(SCH_1):PAGE355

C1993 Q_CAP_DIFFBUS_C0201-DIFF BUS_0.22UF,6.3V,20%,X6S,SA
     1 P3E_CPU0_P4_TX_C_DP<1> @T6G_MB_LIB.T6G(SCH_1):P3E_CPU0_P4_TX_C_DP(1)    I12 @T6G_MB_LIB.T6G(SCH_1):PAGE355
     2 P3E_CPU0_P4_TX_DP<1> @T6G_MB_LIB.T6G(SCH_1):P3E_CPU0_P4_TX_DP(1)    I12 @T6G_MB_LIB.T6G(SCH_1):PAGE355

C1994 Q_CAP_DIFFBUS_C0201-DIFF BUS_0.22UF,6.3V,20%,X6S,SA
     1 P3E_CPU0_P4_TX_C_DN<1> @T6G_MB_LIB.T6G(SCH_1):P3E_CPU0_P4_TX_C_DN(1)    I11 @T6G_MB_LIB.T6G(SCH_1):PAGE355
     2 P3E_CPU0_P4_TX_DN<1> @T6G_MB_LIB.T6G(SCH_1):P3E_CPU0_P4_TX_DN(1)    I11 @T6G_MB_LIB.T6G(SCH_1):PAGE355

C1995 Q_CAP_DIFFBUS_C0201-DIFF BUS_0.22UF,6.3V,20%,X6S,SA
     1 P3E_CPU0_P4_TX_C_DP<0> @T6G_MB_LIB.T6G(SCH_1):P3E_CPU0_P4_TX_C_DP(0)    I52 @T6G_MB_LIB.T6G(SCH_1):PAGE355
     2 P3E_CPU0_P4_TX_DP<0> @T6G_MB_LIB.T6G(SCH_1):P3E_CPU0_P4_TX_DP(0)    I52 @T6G_MB_LIB.T6G(SCH_1):PAGE355

C1996 Q_CAP_DIFFBUS_C0201-DIFF BUS_0.22UF,6.3V,20%,X6S,SA
     1 P3E_CPU0_P4_TX_C_DN<0> @T6G_MB_LIB.T6G(SCH_1):P3E_CPU0_P4_TX_C_DN(0)    I51 @T6G_MB_LIB.T6G(SCH_1):PAGE355
     2 P3E_CPU0_P4_TX_DN<0> @T6G_MB_LIB.T6G(SCH_1):P3E_CPU0_P4_TX_DN(0)    I51 @T6G_MB_LIB.T6G(SCH_1):PAGE355

C1997 Q_CAP_0402-0.1UF,25V,10%,X7R,CH4104K1B00
     1 P3V3_AUX @T6G_MB_LIB.T6G(SCH_1):P3V3_AUX    I89 @T6G_MB_LIB.T6G(SCH_1):PAGE346
     2    GND @T6G_MB_LIB.T6G(SCH_1):GND    I89 @T6G_MB_LIB.T6G(SCH_1):PAGE346

C1998 Q_CAP_0402-0.1UF,25V,10%,X7R,CH4104K1B00
     1 P3V3_E1S_0 @T6G_MB_LIB.T6G(SCH_1):P3V3_E1S_0    I82 @T6G_MB_LIB.T6G(SCH_1):PAGE346
     2    GND @T6G_MB_LIB.T6G(SCH_1):GND    I82 @T6G_MB_LIB.T6G(SCH_1):PAGE346

C2007 Q_CAP_C0402-1UF,25V,10%,X6S,CH5104KEB02
     1 P3V3_AUX @T6G_MB_LIB.T6G(SCH_1):P3V3_AUX     I6 @T6G_MB_LIB.T6G(SCH_1):PAGE345
     2    GND @T6G_MB_LIB.T6G(SCH_1):GND     I6 @T6G_MB_LIB.T6G(SCH_1):PAGE345

C2010 Q_CAP_0402-0.1UF,25V,10%,X7R,CH4104K1B00
     1 P3V3_AUX @T6G_MB_LIB.T6G(SCH_1):P3V3_AUX    I16 @T6G_MB_LIB.T6G(SCH_1):PAGE359
     2    GND @T6G_MB_LIB.T6G(SCH_1):GND    I16 @T6G_MB_LIB.T6G(SCH_1):PAGE359

C2012 Q_CAP_0402-0.1UF,25V,10%,X7R,CH4104K1B00
     1 P3V3_AUX @T6G_MB_LIB.T6G(SCH_1):P3V3_AUX    I98 @T6G_MB_LIB.T6G(SCH_1):PAGE360
     2    GND @T6G_MB_LIB.T6G(SCH_1):GND    I98 @T6G_MB_LIB.T6G(SCH_1):PAGE360

C2013 Q_CAP_0402-0.1UF,25V,10%,X7R,CH4104K1B00
     1 P3V3_AUX @T6G_MB_LIB.T6G(SCH_1):P3V3_AUX    I42 @T6G_MB_LIB.T6G(SCH_1):PAGE360
     2    GND @T6G_MB_LIB.T6G(SCH_1):GND    I42 @T6G_MB_LIB.T6G(SCH_1):PAGE360

C2014 Q_CAP_0402-0.1UF,25V,10%,X7R,CH4104K1B00
     1 P3V3_AUX @T6G_MB_LIB.T6G(SCH_1):P3V3_AUX    I65 @T6G_MB_LIB.T6G(SCH_1):PAGE360
     2    GND @T6G_MB_LIB.T6G(SCH_1):GND    I65 @T6G_MB_LIB.T6G(SCH_1):PAGE360

C2015 Q_CAP_0402-0.1UF,25V,10%,X7R,CH4104K1B00
     1 P3V3_AUX @T6G_MB_LIB.T6G(SCH_1):P3V3_AUX    I34 @T6G_MB_LIB.T6G(SCH_1):PAGE295
     2    GND @T6G_MB_LIB.T6G(SCH_1):GND    I34 @T6G_MB_LIB.T6G(SCH_1):PAGE295

C2017 Q_CAP_0402-0.1UF,25V,10%,X7R,CH4104K1B00
     1 P3V3_OCP_V3_2_R @T6G_MB_LIB.T6G(SCH_1):P3V3_OCP_V3_2_R   I114 @T6G_MB_LIB.T6G(SCH_1):PAGE360
     2    GND @T6G_MB_LIB.T6G(SCH_1):GND   I114 @T6G_MB_LIB.T6G(SCH_1):PAGE360

C2018 Q_CAP_0402-0.1UF,25V,10%,X7R,CH4104K1B00
     1   P3V3 @T6G_MB_LIB.T6G(SCH_1):P3V3    I26 @T6G_MB_LIB.T6G(SCH_1):PAGE360
     2    GND @T6G_MB_LIB.T6G(SCH_1):GND    I26 @T6G_MB_LIB.T6G(SCH_1):PAGE360

C2019 Q_CAP_0402-0.1UF,25V,10%,X7R,CH4104K1B00
     1 P12V_SCM_R @T6G_MB_LIB.T6G(SCH_1):P12V_SCM_R    I49 @T6G_MB_LIB.T6G(SCH_1):PAGE360
     2    GND @T6G_MB_LIB.T6G(SCH_1):GND    I49 @T6G_MB_LIB.T6G(SCH_1):PAGE360

C2020 Q_CAP_0402-0.1UF,25V,10%,X7R,CH4104K1B00
     1 VSENSE_P12V_INA230_3_INP @T6G_MB_LIB.T6G(SCH_1):VSENSE_P12V_INA230_3_INP   I108 @T6G_MB_LIB.T6G(SCH_1):PAGE360
     2 VSENSE_P12V_INA230_3_INN @T6G_MB_LIB.T6G(SCH_1):VSENSE_P12V_INA230_3_INN   I108 @T6G_MB_LIB.T6G(SCH_1):PAGE360

C2021 Q_CAP_0402-0.1UF,25V,10%,X7R,CH4104K1B00
     1 VSENSE_P12V_INA230_4_INP @T6G_MB_LIB.T6G(SCH_1):VSENSE_P12V_INA230_4_INP    I71 @T6G_MB_LIB.T6G(SCH_1):PAGE360
     2 VSENSE_P12V_INA230_4_INN @T6G_MB_LIB.T6G(SCH_1):VSENSE_P12V_INA230_4_INN    I71 @T6G_MB_LIB.T6G(SCH_1):PAGE360

C2022 Q_CAP_0402-0.1UF,25V,10%,X7R,CH4104K1B00
     1 VSENSE_P12V_INA230_5_INP @T6G_MB_LIB.T6G(SCH_1):VSENSE_P12V_INA230_5_INP    I72 @T6G_MB_LIB.T6G(SCH_1):PAGE360
     2 VSENSE_P12V_INA230_5_INN @T6G_MB_LIB.T6G(SCH_1):VSENSE_P12V_INA230_5_INN    I72 @T6G_MB_LIB.T6G(SCH_1):PAGE360

C2024 Q_CAP_0402-0.1UF,25V,10%,X7R,CH4104K1B00
     1 P3V3_OCP_SFF_R @T6G_MB_LIB.T6G(SCH_1):P3V3_OCP_SFF_R    I50 @T6G_MB_LIB.T6G(SCH_1):PAGE295
     2    GND @T6G_MB_LIB.T6G(SCH_1):GND    I50 @T6G_MB_LIB.T6G(SCH_1):PAGE295

C2027 Q_CAP_0402-0.1UF,25V,10%,X7R,CH4104K1B00
     1 VSENSE_P3V3_INA230_1_INP @T6G_MB_LIB.T6G(SCH_1):VSENSE_P3V3_INA230_1_INP    I77 @T6G_MB_LIB.T6G(SCH_1):PAGE295
     2 VSENSE_P3V3_INA230_1_INN @T6G_MB_LIB.T6G(SCH_1):VSENSE_P3V3_INA230_1_INN    I77 @T6G_MB_LIB.T6G(SCH_1):PAGE295

C2029 Q_CAP_0402-15PF,50V,5%,C0G,CH01506JB06
     1 USB_HUB_XTAL_IN @T6G_MB_LIB.T6G(SCH_1):USB_HUB_XTAL_IN   I212 @T6G_MB_LIB.T6G(SCH_1):PAGE358
     2    GND @T6G_MB_LIB.T6G(SCH_1):GND   I212 @T6G_MB_LIB.T6G(SCH_1):PAGE358

C2030 Q_CAP_0402-15PF,50V,5%,C0G,CH01506JB06
     1 USB_HUB_XTAL_OUT @T6G_MB_LIB.T6G(SCH_1):USB_HUB_XTAL_OUT   I211 @T6G_MB_LIB.T6G(SCH_1):PAGE358
     2    GND @T6G_MB_LIB.T6G(SCH_1):GND   I211 @T6G_MB_LIB.T6G(SCH_1):PAGE358

C2031 Q_CAP_C0402-1UF,25V,10%,X6S,CH5104KEB02
     1 P3V3_AUX_USB_HUB @T6G_MB_LIB.T6G(SCH_1):P3V3_AUX_USB_HUB   I148 @T6G_MB_LIB.T6G(SCH_1):PAGE358
     2    GND @T6G_MB_LIB.T6G(SCH_1):GND   I148 @T6G_MB_LIB.T6G(SCH_1):PAGE358

C2032 Q_CAP_0402-0.1UF,25V,10%,X7R,CH4104K1B00
     1 P3V3_AUX_USB_HUB @T6G_MB_LIB.T6G(SCH_1):P3V3_AUX_USB_HUB   I145 @T6G_MB_LIB.T6G(SCH_1):PAGE358
     2    GND @T6G_MB_LIB.T6G(SCH_1):GND   I145 @T6G_MB_LIB.T6G(SCH_1):PAGE358

C2033 Q_CAP_0402-0.1UF,25V,10%,X7R,CH4104K1B00
     1 P3V3_AUX_USB_HUB @T6G_MB_LIB.T6G(SCH_1):P3V3_AUX_USB_HUB   I143 @T6G_MB_LIB.T6G(SCH_1):PAGE358
     2    GND @T6G_MB_LIB.T6G(SCH_1):GND   I143 @T6G_MB_LIB.T6G(SCH_1):PAGE358

C2034 Q_CAP_0402-0.1UF,25V,10%,X7R,CH4104K1B00
     1 P3V3_AUX_USB_HUB @T6G_MB_LIB.T6G(SCH_1):P3V3_AUX_USB_HUB   I142 @T6G_MB_LIB.T6G(SCH_1):PAGE358
     2    GND @T6G_MB_LIB.T6G(SCH_1):GND   I142 @T6G_MB_LIB.T6G(SCH_1):PAGE358

C2035 Q_CAP_C0402-1UF,25V,10%,X6S,CH5104KEB02
     1 P3V3_AUX_USB_HUB @T6G_MB_LIB.T6G(SCH_1):P3V3_AUX_USB_HUB   I147 @T6G_MB_LIB.T6G(SCH_1):PAGE358
     2    GND @T6G_MB_LIB.T6G(SCH_1):GND   I147 @T6G_MB_LIB.T6G(SCH_1):PAGE358

C2038 Q_CAP_C0402-10UF,6.3V,20%,X6S,CH6101MEB01
     1 P3V3_AUX_USB_HUB @T6G_MB_LIB.T6G(SCH_1):P3V3_AUX_USB_HUB   I164 @T6G_MB_LIB.T6G(SCH_1):PAGE358
     2    GND @T6G_MB_LIB.T6G(SCH_1):GND   I164 @T6G_MB_LIB.T6G(SCH_1):PAGE358

C2039 Q_CAP_0402-0.1UF,25V,10%,X7R,CH4104K1B00
     1 P3V3_AUX_USB_HUB @T6G_MB_LIB.T6G(SCH_1):P3V3_AUX_USB_HUB   I163 @T6G_MB_LIB.T6G(SCH_1):PAGE358
     2    GND @T6G_MB_LIB.T6G(SCH_1):GND   I163 @T6G_MB_LIB.T6G(SCH_1):PAGE358

C2040 Q_CAP_0402-0.1UF,25V,10%,X7R,CH4104K1B00
     1 P3V3_AUX_USB_HUB @T6G_MB_LIB.T6G(SCH_1):P3V3_AUX_USB_HUB   I162 @T6G_MB_LIB.T6G(SCH_1):PAGE358
     2    GND @T6G_MB_LIB.T6G(SCH_1):GND   I162 @T6G_MB_LIB.T6G(SCH_1):PAGE358

C2041 Q_CAP_C0402-1UF,25V,10%,X6S,CH5104KEB02
     1 RST_USB_HUB_R_N @T6G_MB_LIB.T6G(SCH_1):RST_USB_HUB_R_N   I158 @T6G_MB_LIB.T6G(SCH_1):PAGE358
     2    GND @T6G_MB_LIB.T6G(SCH_1):GND   I158 @T6G_MB_LIB.T6G(SCH_1):PAGE358

C2042 Q_CAP_0402-100PF,50V,5%,EMPTY,CH11006JB18
     1 P3V3_AUX_ADC_MAM @T6G_MB_LIB.T6G(SCH_1):P3V3_AUX_ADC_MAM    I99 @T6G_MB_LIB.T6G(SCH_1):PAGE369
     2    GND @T6G_MB_LIB.T6G(SCH_1):GND    I99 @T6G_MB_LIB.T6G(SCH_1):PAGE369

C2043 Q_CAP_0402-100PF,50V,5%,EMPTY,CH11006JB18
     1 P3V3_ADC_MAM @T6G_MB_LIB.T6G(SCH_1):P3V3_ADC_MAM    I55 @T6G_MB_LIB.T6G(SCH_1):PAGE369
     2    GND @T6G_MB_LIB.T6G(SCH_1):GND    I55 @T6G_MB_LIB.T6G(SCH_1):PAGE369

C2044 Q_CAP_0402-100PF,50V,5%,EMPTY,CH11006JB18
     1 P5V_ADC_MAM @T6G_MB_LIB.T6G(SCH_1):P5V_ADC_MAM    I52 @T6G_MB_LIB.T6G(SCH_1):PAGE369
     2    GND @T6G_MB_LIB.T6G(SCH_1):GND    I52 @T6G_MB_LIB.T6G(SCH_1):PAGE369

C2045 Q_CAP_0402-100PF,50V,5%,EMPTY,CH11006JB18
     1 P3V3_PDB_AUX_ADC_MAM @T6G_MB_LIB.T6G(SCH_1):P3V3_PDB_AUX_ADC_MAM    I36 @T6G_MB_LIB.T6G(SCH_1):PAGE369
     2    GND @T6G_MB_LIB.T6G(SCH_1):GND    I36 @T6G_MB_LIB.T6G(SCH_1):PAGE369

C2046 Q_CAP_0402-0.1UF,25V,10%,X7R,CH4104K1B00
     1 P12V_AUX_ADC_TIC @T6G_MB_LIB.T6G(SCH_1):P12V_AUX_ADC_TIC    I44 @T6G_MB_LIB.T6G(SCH_1):PAGE369
     2    GND @T6G_MB_LIB.T6G(SCH_1):GND    I44 @T6G_MB_LIB.T6G(SCH_1):PAGE369

C2047 Q_CAP_0402-0.1UF,25V,10%,X7R,CH4104K1B00
     1 P3V3_AUX_ADC_TIC @T6G_MB_LIB.T6G(SCH_1):P3V3_AUX_ADC_TIC    I98 @T6G_MB_LIB.T6G(SCH_1):PAGE369
     2    GND @T6G_MB_LIB.T6G(SCH_1):GND    I98 @T6G_MB_LIB.T6G(SCH_1):PAGE369

C2048 Q_CAP_0402-0.1UF,25V,10%,X7R,CH4104K1B00
     1 P3V3_ADC_TIC @T6G_MB_LIB.T6G(SCH_1):P3V3_ADC_TIC    I32 @T6G_MB_LIB.T6G(SCH_1):PAGE369
     2    GND @T6G_MB_LIB.T6G(SCH_1):GND    I32 @T6G_MB_LIB.T6G(SCH_1):PAGE369

C2049 Q_CAP_0402-0.1UF,25V,10%,X7R,CH4104K1B00
     1 P5V_ADC_TIC @T6G_MB_LIB.T6G(SCH_1):P5V_ADC_TIC    I17 @T6G_MB_LIB.T6G(SCH_1):PAGE369
     2    GND @T6G_MB_LIB.T6G(SCH_1):GND    I17 @T6G_MB_LIB.T6G(SCH_1):PAGE369

C2050 Q_CAP_0402-0.1UF,25V,10%,X7R,CH4104K1B00
     1 P3V3_PDB_AUX_ADC_TIC @T6G_MB_LIB.T6G(SCH_1):P3V3_PDB_AUX_ADC_TIC    I34 @T6G_MB_LIB.T6G(SCH_1):PAGE369
     2    GND @T6G_MB_LIB.T6G(SCH_1):GND    I34 @T6G_MB_LIB.T6G(SCH_1):PAGE369

C2051 Q_CAP_0402-0.1UF,25V,10%,X7R,CH4104K1B00
     1 P3V3_ADC128_VCC @T6G_MB_LIB.T6G(SCH_1):P3V3_ADC128_VCC    I71 @T6G_MB_LIB.T6G(SCH_1):PAGE369
     2    GND @T6G_MB_LIB.T6G(SCH_1):GND    I71 @T6G_MB_LIB.T6G(SCH_1):PAGE369

C2052 Q_CAP_0402-0.1UF,25V,10%,X7R,CH4104K1B00
     1 P3V3_ADC128_VCC @T6G_MB_LIB.T6G(SCH_1):P3V3_ADC128_VCC    I72 @T6G_MB_LIB.T6G(SCH_1):PAGE369
     2    GND @T6G_MB_LIB.T6G(SCH_1):GND    I72 @T6G_MB_LIB.T6G(SCH_1):PAGE369

C2056 Q_CAP_0402-0.1UF,25V,10%,X7R,CH4104K1B00
     1 P3V3_AUX @T6G_MB_LIB.T6G(SCH_1):P3V3_AUX    I38 @T6G_MB_LIB.T6G(SCH_1):PAGE251
     2    GND @T6G_MB_LIB.T6G(SCH_1):GND    I38 @T6G_MB_LIB.T6G(SCH_1):PAGE251

C2067 Q_CAP_0402-0.1UF,25V,10%,X7R,CH4104K1B00
     1 P3V3_AUX @T6G_MB_LIB.T6G(SCH_1):P3V3_AUX   I125 @T6G_MB_LIB.T6G(SCH_1):PAGE295
     2    GND @T6G_MB_LIB.T6G(SCH_1):GND   I125 @T6G_MB_LIB.T6G(SCH_1):PAGE295

C2069 Q_CAP_0402-0.1UF,25V,10%,X7R,CH4104K1B00
     1 P3V3_E1S_0_R @T6G_MB_LIB.T6G(SCH_1):P3V3_E1S_0_R   I142 @T6G_MB_LIB.T6G(SCH_1):PAGE295
     2    GND @T6G_MB_LIB.T6G(SCH_1):GND   I142 @T6G_MB_LIB.T6G(SCH_1):PAGE295

C2071 Q_CAP_0402-0.1UF,25V,10%,X7R,CH4104K1B00
     1 VSENSE_P3V3_INA230_2_INP @T6G_MB_LIB.T6G(SCH_1):VSENSE_P3V3_INA230_2_INP   I133 @T6G_MB_LIB.T6G(SCH_1):PAGE295
     2 VSENSE_P3V3_INA230_2_INN @T6G_MB_LIB.T6G(SCH_1):VSENSE_P3V3_INA230_2_INN   I133 @T6G_MB_LIB.T6G(SCH_1):PAGE295

C2073 Q_CAP_DIFFBUS_C0201-DIFF BUS_0.22UF,6.3V,20%,X6S,SA
     1 P3E_CPU1_P5_TX_C_DP<1> @T6G_MB_LIB.T6G(SCH_1):P3E_CPU1_P5_TX_C_DP(1)   I132 @T6G_MB_LIB.T6G(SCH_1):PAGE53
     2 P3E_CPU1_P5_TX_DP<1> @T6G_MB_LIB.T6G(SCH_1):P3E_CPU1_P5_TX_DP(1)   I132 @T6G_MB_LIB.T6G(SCH_1):PAGE53

C2074 Q_CAP_DIFFBUS_C0201-DIFF BUS_0.22UF,6.3V,20%,X6S,SA
     1 P3E_CPU1_P5_TX_C_DN<1> @T6G_MB_LIB.T6G(SCH_1):P3E_CPU1_P5_TX_C_DN(1)   I133 @T6G_MB_LIB.T6G(SCH_1):PAGE53
     2 P3E_CPU1_P5_TX_DN<1> @T6G_MB_LIB.T6G(SCH_1):P3E_CPU1_P5_TX_DN(1)   I133 @T6G_MB_LIB.T6G(SCH_1):PAGE53

C2075 Q_CAP_DIFFBUS_C0201-DIFF BUS_0.22UF,6.3V,20%,X6S,SA
     1 P3E_CPU1_P5_TX_C_DP<0> @T6G_MB_LIB.T6G(SCH_1):P3E_CPU1_P5_TX_C_DP(0)   I135 @T6G_MB_LIB.T6G(SCH_1):PAGE53
     2 P3E_CPU1_P5_TX_DP<0> @T6G_MB_LIB.T6G(SCH_1):P3E_CPU1_P5_TX_DP(0)   I135 @T6G_MB_LIB.T6G(SCH_1):PAGE53

C2076 Q_CAP_DIFFBUS_C0201-DIFF BUS_0.22UF,6.3V,20%,X6S,SA
     1 P3E_CPU1_P5_TX_C_DN<0> @T6G_MB_LIB.T6G(SCH_1):P3E_CPU1_P5_TX_C_DN(0)   I134 @T6G_MB_LIB.T6G(SCH_1):PAGE53
     2 P3E_CPU1_P5_TX_DN<0> @T6G_MB_LIB.T6G(SCH_1):P3E_CPU1_P5_TX_DN(0)   I134 @T6G_MB_LIB.T6G(SCH_1):PAGE53

C2077 Q_CAP_DIFFBUS_C0201-DIFF BUS_0.22UF,6.3V,20%,X6S,SA
     1 P2E_CPU0_P5_TX_DP @T6G_MB_LIB.T6G(SCH_1):P2E_CPU0_P5_TX_DP   I156 @T6G_MB_LIB.T6G(SCH_1):PAGE26
     2 P2E_CPU0_P5_TX_C_DP @T6G_MB_LIB.T6G(SCH_1):P2E_CPU0_P5_TX_C_DP   I156 @T6G_MB_LIB.T6G(SCH_1):PAGE26

C2078 Q_CAP_DIFFBUS_C0201-DIFF BUS_0.22UF,6.3V,20%,X6S,SA
     1 P2E_CPU0_P5_TX_DN @T6G_MB_LIB.T6G(SCH_1):P2E_CPU0_P5_TX_DN   I157 @T6G_MB_LIB.T6G(SCH_1):PAGE26
     2 P2E_CPU0_P5_TX_C_DN @T6G_MB_LIB.T6G(SCH_1):P2E_CPU0_P5_TX_C_DN   I157 @T6G_MB_LIB.T6G(SCH_1):PAGE26

C2102 Q_CAP_C0402-22UF,4V,20%,X6S,CH622KMEB02
     1 PVDDIO_P1 @T6G_MB_LIB.T6G(SCH_1):PVDDIO_P1   I140 @T6G_MB_LIB.T6G(SCH_1):PAGE73
     2    GND @T6G_MB_LIB.T6G(SCH_1):GND   I140 @T6G_MB_LIB.T6G(SCH_1):PAGE73

C2103 Q_CAP_C0402-22UF,4V,20%,X6S,CH622KMEB02
     1 PVDDIO_P1 @T6G_MB_LIB.T6G(SCH_1):PVDDIO_P1   I137 @T6G_MB_LIB.T6G(SCH_1):PAGE73
     2    GND @T6G_MB_LIB.T6G(SCH_1):GND   I137 @T6G_MB_LIB.T6G(SCH_1):PAGE73

C2104 Q_CAP_C0402-22UF,4V,20%,X6S,CH622KMEB02
     1 PVDDIO_P1 @T6G_MB_LIB.T6G(SCH_1):PVDDIO_P1   I142 @T6G_MB_LIB.T6G(SCH_1):PAGE73
     2    GND @T6G_MB_LIB.T6G(SCH_1):GND   I142 @T6G_MB_LIB.T6G(SCH_1):PAGE73

C2105 Q_CAP_C0402-22UF,4V,20%,X6S,CH622KMEB02
     1 PVDDIO_P1 @T6G_MB_LIB.T6G(SCH_1):PVDDIO_P1   I141 @T6G_MB_LIB.T6G(SCH_1):PAGE73
     2    GND @T6G_MB_LIB.T6G(SCH_1):GND   I141 @T6G_MB_LIB.T6G(SCH_1):PAGE73

C2106 Q_CAP_C0402-22UF,4V,20%,X6S,CH622KMEB02
     1 PVDDIO_P1 @T6G_MB_LIB.T6G(SCH_1):PVDDIO_P1   I138 @T6G_MB_LIB.T6G(SCH_1):PAGE73
     2    GND @T6G_MB_LIB.T6G(SCH_1):GND   I138 @T6G_MB_LIB.T6G(SCH_1):PAGE73

C2107 Q_CAP_C0402-22UF,4V,20%,X6S,CH622KMEB02
     1 PVDDIO_P1 @T6G_MB_LIB.T6G(SCH_1):PVDDIO_P1   I145 @T6G_MB_LIB.T6G(SCH_1):PAGE73
     2    GND @T6G_MB_LIB.T6G(SCH_1):GND   I145 @T6G_MB_LIB.T6G(SCH_1):PAGE73

C2108 Q_CAP_C0402-22UF,4V,20%,X6S,CH622KMEB02
     1 PVDDIO_P1 @T6G_MB_LIB.T6G(SCH_1):PVDDIO_P1   I144 @T6G_MB_LIB.T6G(SCH_1):PAGE73
     2    GND @T6G_MB_LIB.T6G(SCH_1):GND   I144 @T6G_MB_LIB.T6G(SCH_1):PAGE73

C2109 Q_CAP_C0402-22UF,4V,20%,X6S,CH622KMEB02
     1 PVDDIO_P1 @T6G_MB_LIB.T6G(SCH_1):PVDDIO_P1   I148 @T6G_MB_LIB.T6G(SCH_1):PAGE73
     2    GND @T6G_MB_LIB.T6G(SCH_1):GND   I148 @T6G_MB_LIB.T6G(SCH_1):PAGE73

C2110 Q_CAP_C0402-22UF,4V,20%,X6S,CH622KMEB02
     1 PVDDIO_P1 @T6G_MB_LIB.T6G(SCH_1):PVDDIO_P1   I151 @T6G_MB_LIB.T6G(SCH_1):PAGE73
     2    GND @T6G_MB_LIB.T6G(SCH_1):GND   I151 @T6G_MB_LIB.T6G(SCH_1):PAGE73

C2111 Q_CAP_C0402-22UF,4V,20%,X6S,CH622KMEB02
     1 PVDDIO_P1 @T6G_MB_LIB.T6G(SCH_1):PVDDIO_P1   I149 @T6G_MB_LIB.T6G(SCH_1):PAGE73
     2    GND @T6G_MB_LIB.T6G(SCH_1):GND   I149 @T6G_MB_LIB.T6G(SCH_1):PAGE73

C2112 Q_CAP_C0402-22UF,4V,20%,X6S,CH622KMEB02
     1 PVDDIO_P1 @T6G_MB_LIB.T6G(SCH_1):PVDDIO_P1   I150 @T6G_MB_LIB.T6G(SCH_1):PAGE73
     2    GND @T6G_MB_LIB.T6G(SCH_1):GND   I150 @T6G_MB_LIB.T6G(SCH_1):PAGE73

C2113 Q_CAP_C0402-22UF,4V,20%,X6S,CH622KMEB02
     1 PVDD11_S3_P1 @T6G_MB_LIB.T6G(SCH_1):PVDD11_S3_P1   I119 @T6G_MB_LIB.T6G(SCH_1):PAGE73
     2    GND @T6G_MB_LIB.T6G(SCH_1):GND   I119 @T6G_MB_LIB.T6G(SCH_1):PAGE73

C2114 Q_CAP_C0402-22UF,4V,20%,X6S,CH622KMEB02
     1 PVDD11_S3_P1 @T6G_MB_LIB.T6G(SCH_1):PVDD11_S3_P1   I120 @T6G_MB_LIB.T6G(SCH_1):PAGE73
     2    GND @T6G_MB_LIB.T6G(SCH_1):GND   I120 @T6G_MB_LIB.T6G(SCH_1):PAGE73

C2115 Q_CAP_C0402-22UF,4V,20%,X6S,CH622KMEB02
     1 PVDD11_S3_P1 @T6G_MB_LIB.T6G(SCH_1):PVDD11_S3_P1   I108 @T6G_MB_LIB.T6G(SCH_1):PAGE73
     2    GND @T6G_MB_LIB.T6G(SCH_1):GND   I108 @T6G_MB_LIB.T6G(SCH_1):PAGE73

C2116 Q_CAP_C0402-22UF,4V,20%,X6S,CH622KMEB02
     1 PVDDIO_P1 @T6G_MB_LIB.T6G(SCH_1):PVDDIO_P1   I154 @T6G_MB_LIB.T6G(SCH_1):PAGE73
     2    GND @T6G_MB_LIB.T6G(SCH_1):GND   I154 @T6G_MB_LIB.T6G(SCH_1):PAGE73

C2117 Q_CAP_C0402-22UF,4V,20%,X6S,CH622KMEB02
     1 PVDDIO_P1 @T6G_MB_LIB.T6G(SCH_1):PVDDIO_P1   I153 @T6G_MB_LIB.T6G(SCH_1):PAGE73
     2    GND @T6G_MB_LIB.T6G(SCH_1):GND   I153 @T6G_MB_LIB.T6G(SCH_1):PAGE73

C2118 Q_CAP_C0402-22UF,4V,20%,X6S,CH622KMEB02
     1 PVDD11_S3_P1 @T6G_MB_LIB.T6G(SCH_1):PVDD11_S3_P1   I125 @T6G_MB_LIB.T6G(SCH_1):PAGE73
     2    GND @T6G_MB_LIB.T6G(SCH_1):GND   I125 @T6G_MB_LIB.T6G(SCH_1):PAGE73

C2119 Q_CAP_C0402-22UF,4V,20%,X6S,CH622KMEB02
     1 PVDD11_S3_P1 @T6G_MB_LIB.T6G(SCH_1):PVDD11_S3_P1   I122 @T6G_MB_LIB.T6G(SCH_1):PAGE73
     2    GND @T6G_MB_LIB.T6G(SCH_1):GND   I122 @T6G_MB_LIB.T6G(SCH_1):PAGE73

C2120 Q_CAP_C0402-22UF,4V,20%,X6S,CH622KMEB02
     1 PVDD11_S3_P1 @T6G_MB_LIB.T6G(SCH_1):PVDD11_S3_P1   I121 @T6G_MB_LIB.T6G(SCH_1):PAGE73
     2    GND @T6G_MB_LIB.T6G(SCH_1):GND   I121 @T6G_MB_LIB.T6G(SCH_1):PAGE73

C2121 Q_CAP_C0402-22UF,4V,20%,X6S,CH622KMEB02
     1 PVDD11_S3_P1 @T6G_MB_LIB.T6G(SCH_1):PVDD11_S3_P1   I109 @T6G_MB_LIB.T6G(SCH_1):PAGE73
     2    GND @T6G_MB_LIB.T6G(SCH_1):GND   I109 @T6G_MB_LIB.T6G(SCH_1):PAGE73

C2122 Q_CAP_C0402-22UF,4V,20%,X6S,CH622KMEB02
     1 PVDDIO_P1 @T6G_MB_LIB.T6G(SCH_1):PVDDIO_P1   I169 @T6G_MB_LIB.T6G(SCH_1):PAGE73
     2    GND @T6G_MB_LIB.T6G(SCH_1):GND   I169 @T6G_MB_LIB.T6G(SCH_1):PAGE73

C2123 Q_CAP_C0402-22UF,4V,20%,X6S,CH622KMEB02
     1 PVDDIO_P1 @T6G_MB_LIB.T6G(SCH_1):PVDDIO_P1   I168 @T6G_MB_LIB.T6G(SCH_1):PAGE73
     2    GND @T6G_MB_LIB.T6G(SCH_1):GND   I168 @T6G_MB_LIB.T6G(SCH_1):PAGE73

C2124 Q_CAP_C0402-22UF,4V,20%,X6S,CH622KMEB02
     1 PVDD11_S3_P1 @T6G_MB_LIB.T6G(SCH_1):PVDD11_S3_P1   I164 @T6G_MB_LIB.T6G(SCH_1):PAGE73
     2    GND @T6G_MB_LIB.T6G(SCH_1):GND   I164 @T6G_MB_LIB.T6G(SCH_1):PAGE73

C2125 Q_CAP_C0402-22UF,4V,20%,X6S,CH622KMEB02
     1 PVDD11_S3_P1 @T6G_MB_LIB.T6G(SCH_1):PVDD11_S3_P1   I160 @T6G_MB_LIB.T6G(SCH_1):PAGE73
     2    GND @T6G_MB_LIB.T6G(SCH_1):GND   I160 @T6G_MB_LIB.T6G(SCH_1):PAGE73

C2126 Q_CAP_C0402-22UF,4V,20%,X6S,CH622KMEB02
     1 PVDD11_S3_P1 @T6G_MB_LIB.T6G(SCH_1):PVDD11_S3_P1   I159 @T6G_MB_LIB.T6G(SCH_1):PAGE73
     2    GND @T6G_MB_LIB.T6G(SCH_1):GND   I159 @T6G_MB_LIB.T6G(SCH_1):PAGE73

C2127 Q_CAP_C0402-22UF,4V,20%,X6S,CH622KMEB02
     1 PVDDIO_P1 @T6G_MB_LIB.T6G(SCH_1):PVDDIO_P1   I172 @T6G_MB_LIB.T6G(SCH_1):PAGE73
     2    GND @T6G_MB_LIB.T6G(SCH_1):GND   I172 @T6G_MB_LIB.T6G(SCH_1):PAGE73

C2128 Q_CAP_C0402-22UF,4V,20%,X6S,CH622KMEB02
     1 PVDD11_S3_P1 @T6G_MB_LIB.T6G(SCH_1):PVDD11_S3_P1   I166 @T6G_MB_LIB.T6G(SCH_1):PAGE73
     2    GND @T6G_MB_LIB.T6G(SCH_1):GND   I166 @T6G_MB_LIB.T6G(SCH_1):PAGE73

C2129 Q_CAP_C0402-22UF,4V,20%,X6S,CH622KMEB02
     1 PVDDCR_SOC_P0 @T6G_MB_LIB.T6G(SCH_1):PVDDCR_SOC_P0    I89 @T6G_MB_LIB.T6G(SCH_1):PAGE67
     2    GND @T6G_MB_LIB.T6G(SCH_1):GND    I89 @T6G_MB_LIB.T6G(SCH_1):PAGE67

C2130 Q_CAP_C0402-22UF,4V,20%,X6S,CH622KMEB02
     1 PVDDCR_SOC_P0 @T6G_MB_LIB.T6G(SCH_1):PVDDCR_SOC_P0    I85 @T6G_MB_LIB.T6G(SCH_1):PAGE67
     2    GND @T6G_MB_LIB.T6G(SCH_1):GND    I85 @T6G_MB_LIB.T6G(SCH_1):PAGE67

C2131 Q_CAP_C0402-22UF,4V,20%,X6S,CH622KMEB02
     1 PVDDIO_P0 @T6G_MB_LIB.T6G(SCH_1):PVDDIO_P0   I135 @T6G_MB_LIB.T6G(SCH_1):PAGE67
     2    GND @T6G_MB_LIB.T6G(SCH_1):GND   I135 @T6G_MB_LIB.T6G(SCH_1):PAGE67

C2132 Q_CAP_C0402-22UF,4V,20%,X6S,CH622KMEB02
     1 PVDD11_S3_P0 @T6G_MB_LIB.T6G(SCH_1):PVDD11_S3_P0   I113 @T6G_MB_LIB.T6G(SCH_1):PAGE67
     2    GND @T6G_MB_LIB.T6G(SCH_1):GND   I113 @T6G_MB_LIB.T6G(SCH_1):PAGE67

C2133 Q_CAP_C0402-22UF,4V,20%,X6S,CH622KMEB02
     1 PVDD11_S3_P0 @T6G_MB_LIB.T6G(SCH_1):PVDD11_S3_P0   I110 @T6G_MB_LIB.T6G(SCH_1):PAGE67
     2    GND @T6G_MB_LIB.T6G(SCH_1):GND   I110 @T6G_MB_LIB.T6G(SCH_1):PAGE67

C2134 Q_CAP_C0402-22UF,4V,20%,X6S,CH622KMEB02
     1 PVDDCR_SOC_P0 @T6G_MB_LIB.T6G(SCH_1):PVDDCR_SOC_P0    I90 @T6G_MB_LIB.T6G(SCH_1):PAGE67
     2    GND @T6G_MB_LIB.T6G(SCH_1):GND    I90 @T6G_MB_LIB.T6G(SCH_1):PAGE67

C2135 Q_CAP_C0402-22UF,4V,20%,X6S,CH622KMEB02
     1 PVDDCR_SOC_P0 @T6G_MB_LIB.T6G(SCH_1):PVDDCR_SOC_P0    I87 @T6G_MB_LIB.T6G(SCH_1):PAGE67
     2    GND @T6G_MB_LIB.T6G(SCH_1):GND    I87 @T6G_MB_LIB.T6G(SCH_1):PAGE67

C2136 Q_CAP_C0402-22UF,4V,20%,X6S,CH622KMEB02
     1 PVDDIO_P0 @T6G_MB_LIB.T6G(SCH_1):PVDDIO_P0   I136 @T6G_MB_LIB.T6G(SCH_1):PAGE67
     2    GND @T6G_MB_LIB.T6G(SCH_1):GND   I136 @T6G_MB_LIB.T6G(SCH_1):PAGE67

C2137 Q_CAP_C0402-22UF,4V,20%,X6S,CH622KMEB02
     1 PVDD11_S3_P0 @T6G_MB_LIB.T6G(SCH_1):PVDD11_S3_P0   I115 @T6G_MB_LIB.T6G(SCH_1):PAGE67
     2    GND @T6G_MB_LIB.T6G(SCH_1):GND   I115 @T6G_MB_LIB.T6G(SCH_1):PAGE67

C2138 Q_CAP_C0402-22UF,4V,20%,X6S,CH622KMEB02
     1 PVDD11_S3_P0 @T6G_MB_LIB.T6G(SCH_1):PVDD11_S3_P0   I112 @T6G_MB_LIB.T6G(SCH_1):PAGE67
     2    GND @T6G_MB_LIB.T6G(SCH_1):GND   I112 @T6G_MB_LIB.T6G(SCH_1):PAGE67

C2139 Q_CAP_C0402-22UF,4V,20%,X6S,CH622KMEB02
     1 PVDDCR_SOC_P0 @T6G_MB_LIB.T6G(SCH_1):PVDDCR_SOC_P0    I95 @T6G_MB_LIB.T6G(SCH_1):PAGE67
     2    GND @T6G_MB_LIB.T6G(SCH_1):GND    I95 @T6G_MB_LIB.T6G(SCH_1):PAGE67

C2140 Q_CAP_C0402-22UF,4V,20%,X6S,CH622KMEB02
     1 PVDDCR_SOC_P0 @T6G_MB_LIB.T6G(SCH_1):PVDDCR_SOC_P0    I92 @T6G_MB_LIB.T6G(SCH_1):PAGE67
     2    GND @T6G_MB_LIB.T6G(SCH_1):GND    I92 @T6G_MB_LIB.T6G(SCH_1):PAGE67

C2141 Q_CAP_C0402-22UF,4V,20%,X6S,CH622KMEB02
     1 PVDDIO_P0 @T6G_MB_LIB.T6G(SCH_1):PVDDIO_P0   I137 @T6G_MB_LIB.T6G(SCH_1):PAGE67
     2    GND @T6G_MB_LIB.T6G(SCH_1):GND   I137 @T6G_MB_LIB.T6G(SCH_1):PAGE67

C2142 Q_CAP_C0402-22UF,4V,20%,X6S,CH622KMEB02
     1 PVDD11_S3_P0 @T6G_MB_LIB.T6G(SCH_1):PVDD11_S3_P0   I121 @T6G_MB_LIB.T6G(SCH_1):PAGE67
     2    GND @T6G_MB_LIB.T6G(SCH_1):GND   I121 @T6G_MB_LIB.T6G(SCH_1):PAGE67

C2143 Q_CAP_C0402-22UF,4V,20%,X6S,CH622KMEB02
     1 PVDDCR_SOC_P0 @T6G_MB_LIB.T6G(SCH_1):PVDDCR_SOC_P0    I96 @T6G_MB_LIB.T6G(SCH_1):PAGE67
     2    GND @T6G_MB_LIB.T6G(SCH_1):GND    I96 @T6G_MB_LIB.T6G(SCH_1):PAGE67

C2144 Q_CAP_C0402-22UF,4V,20%,X6S,CH622KMEB02
     1 PVDDCR_SOC_P0 @T6G_MB_LIB.T6G(SCH_1):PVDDCR_SOC_P0    I93 @T6G_MB_LIB.T6G(SCH_1):PAGE67
     2    GND @T6G_MB_LIB.T6G(SCH_1):GND    I93 @T6G_MB_LIB.T6G(SCH_1):PAGE67

C2145 Q_CAP_C0402-22UF,4V,20%,X6S,CH622KMEB02
     1 PVDDIO_P0 @T6G_MB_LIB.T6G(SCH_1):PVDDIO_P0   I138 @T6G_MB_LIB.T6G(SCH_1):PAGE67
     2    GND @T6G_MB_LIB.T6G(SCH_1):GND   I138 @T6G_MB_LIB.T6G(SCH_1):PAGE67

C2146 Q_CAP_C0402-22UF,4V,20%,X6S,CH622KMEB02
     1 PVDD11_S3_P0 @T6G_MB_LIB.T6G(SCH_1):PVDD11_S3_P0   I122 @T6G_MB_LIB.T6G(SCH_1):PAGE67
     2    GND @T6G_MB_LIB.T6G(SCH_1):GND   I122 @T6G_MB_LIB.T6G(SCH_1):PAGE67

C2147 Q_CAP_C0402-22UF,4V,20%,X6S,CH622KMEB02
     1 PVDDCR_SOC_P0 @T6G_MB_LIB.T6G(SCH_1):PVDDCR_SOC_P0   I109 @T6G_MB_LIB.T6G(SCH_1):PAGE67
     2    GND @T6G_MB_LIB.T6G(SCH_1):GND   I109 @T6G_MB_LIB.T6G(SCH_1):PAGE67

C2148 Q_CAP_C0402-22UF,4V,20%,X6S,CH622KMEB02
     1 PVDDCR_SOC_P0 @T6G_MB_LIB.T6G(SCH_1):PVDDCR_SOC_P0    I94 @T6G_MB_LIB.T6G(SCH_1):PAGE67
     2    GND @T6G_MB_LIB.T6G(SCH_1):GND    I94 @T6G_MB_LIB.T6G(SCH_1):PAGE67

C2149 Q_CAP_C0402-22UF,4V,20%,X6S,CH622KMEB02
     1 PVDDIO_P0 @T6G_MB_LIB.T6G(SCH_1):PVDDIO_P0   I139 @T6G_MB_LIB.T6G(SCH_1):PAGE67
     2    GND @T6G_MB_LIB.T6G(SCH_1):GND   I139 @T6G_MB_LIB.T6G(SCH_1):PAGE67

C2150 Q_CAP_C0402-22UF,4V,20%,X6S,CH622KMEB02
     1 PVDD11_S3_P0 @T6G_MB_LIB.T6G(SCH_1):PVDD11_S3_P0   I123 @T6G_MB_LIB.T6G(SCH_1):PAGE67
     2    GND @T6G_MB_LIB.T6G(SCH_1):GND   I123 @T6G_MB_LIB.T6G(SCH_1):PAGE67

C2151 Q_CAP_C0402-22UF,4V,20%,X6S,CH622KMEB02
     1 PVDDCR_SOC_P0 @T6G_MB_LIB.T6G(SCH_1):PVDDCR_SOC_P0    I99 @T6G_MB_LIB.T6G(SCH_1):PAGE67
     2    GND @T6G_MB_LIB.T6G(SCH_1):GND    I99 @T6G_MB_LIB.T6G(SCH_1):PAGE67

C2152 Q_CAP_C0402-22UF,4V,20%,X6S,CH622KMEB02
     1 PVDDCR_SOC_P0 @T6G_MB_LIB.T6G(SCH_1):PVDDCR_SOC_P0    I97 @T6G_MB_LIB.T6G(SCH_1):PAGE67
     2    GND @T6G_MB_LIB.T6G(SCH_1):GND    I97 @T6G_MB_LIB.T6G(SCH_1):PAGE67

C2153 Q_CAP_C0402-22UF,4V,20%,X6S,CH622KMEB02
     1 PVDD11_S3_P0 @T6G_MB_LIB.T6G(SCH_1):PVDD11_S3_P0   I124 @T6G_MB_LIB.T6G(SCH_1):PAGE67
     2    GND @T6G_MB_LIB.T6G(SCH_1):GND   I124 @T6G_MB_LIB.T6G(SCH_1):PAGE67

C2154 Q_CAP_C0402-22UF,4V,20%,X6S,CH622KMEB02
     1 PVDDCR_SOC_P0 @T6G_MB_LIB.T6G(SCH_1):PVDDCR_SOC_P0   I100 @T6G_MB_LIB.T6G(SCH_1):PAGE67
     2    GND @T6G_MB_LIB.T6G(SCH_1):GND   I100 @T6G_MB_LIB.T6G(SCH_1):PAGE67

C2155 Q_CAP_C0402-22UF,4V,20%,X6S,CH622KMEB02
     1 PVDDCR_SOC_P0 @T6G_MB_LIB.T6G(SCH_1):PVDDCR_SOC_P0    I98 @T6G_MB_LIB.T6G(SCH_1):PAGE67
     2    GND @T6G_MB_LIB.T6G(SCH_1):GND    I98 @T6G_MB_LIB.T6G(SCH_1):PAGE67

C2156 Q_CAP_C0402-22UF,4V,20%,X6S,CH622KMEB02
     1 PVDD11_S3_P0 @T6G_MB_LIB.T6G(SCH_1):PVDD11_S3_P0   I125 @T6G_MB_LIB.T6G(SCH_1):PAGE67
     2    GND @T6G_MB_LIB.T6G(SCH_1):GND   I125 @T6G_MB_LIB.T6G(SCH_1):PAGE67

C2157 Q_CAP_C0402-22UF,4V,20%,X6S,CH622KMEB02
     1 PVDDCR_SOC_P0 @T6G_MB_LIB.T6G(SCH_1):PVDDCR_SOC_P0   I103 @T6G_MB_LIB.T6G(SCH_1):PAGE67
     2    GND @T6G_MB_LIB.T6G(SCH_1):GND   I103 @T6G_MB_LIB.T6G(SCH_1):PAGE67

C2158 Q_CAP_C0402-22UF,4V,20%,X6S,CH622KMEB02
     1 PVDD11_S3_P0 @T6G_MB_LIB.T6G(SCH_1):PVDD11_S3_P0   I127 @T6G_MB_LIB.T6G(SCH_1):PAGE67
     2    GND @T6G_MB_LIB.T6G(SCH_1):GND   I127 @T6G_MB_LIB.T6G(SCH_1):PAGE67

C2159 Q_CAP_C0402-22UF,4V,20%,X6S,CH622KMEB02
     1 PVDDCR_SOC_P0 @T6G_MB_LIB.T6G(SCH_1):PVDDCR_SOC_P0   I104 @T6G_MB_LIB.T6G(SCH_1):PAGE67
     2    GND @T6G_MB_LIB.T6G(SCH_1):GND   I104 @T6G_MB_LIB.T6G(SCH_1):PAGE67

C2160 Q_CAP_C0402-22UF,4V,20%,X6S,CH622KMEB02
     1 PVDD11_S3_P0 @T6G_MB_LIB.T6G(SCH_1):PVDD11_S3_P0   I128 @T6G_MB_LIB.T6G(SCH_1):PAGE67
     2    GND @T6G_MB_LIB.T6G(SCH_1):GND   I128 @T6G_MB_LIB.T6G(SCH_1):PAGE67

C2161 Q_CAP_C0402-22UF,4V,20%,X6S,CH622KMEB02
     1 PVDDCR_SOC_P0 @T6G_MB_LIB.T6G(SCH_1):PVDDCR_SOC_P0   I108 @T6G_MB_LIB.T6G(SCH_1):PAGE67
     2    GND @T6G_MB_LIB.T6G(SCH_1):GND   I108 @T6G_MB_LIB.T6G(SCH_1):PAGE67

C2162 Q_CAP_C0402-22UF,4V,20%,X6S,CH622KMEB02
     1 PVDD11_S3_P0 @T6G_MB_LIB.T6G(SCH_1):PVDD11_S3_P0   I129 @T6G_MB_LIB.T6G(SCH_1):PAGE67
     2    GND @T6G_MB_LIB.T6G(SCH_1):GND   I129 @T6G_MB_LIB.T6G(SCH_1):PAGE67

C2163 Q_CAP_C0402-22UF,4V,20%,X6S,CH622KMEB02
     1 PVDD18_S5_P0 @T6G_MB_LIB.T6G(SCH_1):PVDD18_S5_P0   I131 @T6G_MB_LIB.T6G(SCH_1):PAGE67
     2    GND @T6G_MB_LIB.T6G(SCH_1):GND   I131 @T6G_MB_LIB.T6G(SCH_1):PAGE67

C2164 Q_CAP_C0402-22UF,4V,20%,X6S,CH622KMEB02
     1 PVDD18_S5_P0 @T6G_MB_LIB.T6G(SCH_1):PVDD18_S5_P0   I133 @T6G_MB_LIB.T6G(SCH_1):PAGE67
     2    GND @T6G_MB_LIB.T6G(SCH_1):GND   I133 @T6G_MB_LIB.T6G(SCH_1):PAGE67

C2165 Q_CAP_C0402-22UF,4V,20%,X6S,CH622KMEB02
     1 PVDDCR_CPU0_P0 @T6G_MB_LIB.T6G(SCH_1):PVDDCR_CPU0_P0     I7 @T6G_MB_LIB.T6G(SCH_1):PAGE68
     2    GND @T6G_MB_LIB.T6G(SCH_1):GND     I7 @T6G_MB_LIB.T6G(SCH_1):PAGE68

C2166 Q_CAP_C0402-22UF,4V,20%,X6S,CH622KMEB02
     1 PVDDCR_CPU0_P0 @T6G_MB_LIB.T6G(SCH_1):PVDDCR_CPU0_P0     I4 @T6G_MB_LIB.T6G(SCH_1):PAGE68
     2    GND @T6G_MB_LIB.T6G(SCH_1):GND     I4 @T6G_MB_LIB.T6G(SCH_1):PAGE68

C2167 Q_CAP_C0402-22UF,4V,20%,X6S,CH622KMEB02
     1 PVDDCR_CPU0_P0 @T6G_MB_LIB.T6G(SCH_1):PVDDCR_CPU0_P0     I1 @T6G_MB_LIB.T6G(SCH_1):PAGE68
     2    GND @T6G_MB_LIB.T6G(SCH_1):GND     I1 @T6G_MB_LIB.T6G(SCH_1):PAGE68

C2169 Q_CAP_C0402-22UF,4V,20%,X6S,CH622KMEB02
     1 PVDDCR_CPU0_P0 @T6G_MB_LIB.T6G(SCH_1):PVDDCR_CPU0_P0     I9 @T6G_MB_LIB.T6G(SCH_1):PAGE68
     2    GND @T6G_MB_LIB.T6G(SCH_1):GND     I9 @T6G_MB_LIB.T6G(SCH_1):PAGE68

C2170 Q_CAP_C0402-22UF,4V,20%,X6S,CH622KMEB02
     1 PVDDCR_CPU0_P0 @T6G_MB_LIB.T6G(SCH_1):PVDDCR_CPU0_P0     I5 @T6G_MB_LIB.T6G(SCH_1):PAGE68
     2    GND @T6G_MB_LIB.T6G(SCH_1):GND     I5 @T6G_MB_LIB.T6G(SCH_1):PAGE68

C2171 Q_CAP_C0402-22UF,4V,20%,X6S,CH622KMEB02
     1 PVDDCR_CPU0_P0 @T6G_MB_LIB.T6G(SCH_1):PVDDCR_CPU0_P0     I2 @T6G_MB_LIB.T6G(SCH_1):PAGE68
     2    GND @T6G_MB_LIB.T6G(SCH_1):GND     I2 @T6G_MB_LIB.T6G(SCH_1):PAGE68

C2173 Q_CAP_C0402-22UF,4V,20%,X6S,CH622KMEB02
     1 PVDDCR_CPU0_P0 @T6G_MB_LIB.T6G(SCH_1):PVDDCR_CPU0_P0    I22 @T6G_MB_LIB.T6G(SCH_1):PAGE68
     2    GND @T6G_MB_LIB.T6G(SCH_1):GND    I22 @T6G_MB_LIB.T6G(SCH_1):PAGE68

C2174 Q_CAP_C0402-22UF,4V,20%,X6S,CH622KMEB02
     1 PVDDCR_CPU0_P0 @T6G_MB_LIB.T6G(SCH_1):PVDDCR_CPU0_P0    I20 @T6G_MB_LIB.T6G(SCH_1):PAGE68
     2    GND @T6G_MB_LIB.T6G(SCH_1):GND    I20 @T6G_MB_LIB.T6G(SCH_1):PAGE68

C2175 Q_CAP_C0402-22UF,4V,20%,X6S,CH622KMEB02
     1 PVDDCR_CPU0_P0 @T6G_MB_LIB.T6G(SCH_1):PVDDCR_CPU0_P0    I16 @T6G_MB_LIB.T6G(SCH_1):PAGE68
     2    GND @T6G_MB_LIB.T6G(SCH_1):GND    I16 @T6G_MB_LIB.T6G(SCH_1):PAGE68

C2176 Q_CAP_0402-100PF,50V,5%,EMPTY,CH11006JB18
     1 P12V_OCP_SFF_ISENSE_MAM @T6G_MB_LIB.T6G(SCH_1):P12V_OCP_SFF_ISENSE_MAM   I114 @T6G_MB_LIB.T6G(SCH_1):PAGE369
     2    GND @T6G_MB_LIB.T6G(SCH_1):GND   I114 @T6G_MB_LIB.T6G(SCH_1):PAGE369

C2177 Q_CAP_C0402-22UF,4V,20%,X6S,CH622KMEB02
     1 PVDDCR_CPU0_P0 @T6G_MB_LIB.T6G(SCH_1):PVDDCR_CPU0_P0    I23 @T6G_MB_LIB.T6G(SCH_1):PAGE68
     2    GND @T6G_MB_LIB.T6G(SCH_1):GND    I23 @T6G_MB_LIB.T6G(SCH_1):PAGE68

C2178 Q_CAP_C0402-22UF,4V,20%,X6S,CH622KMEB02
     1 PVDDCR_CPU0_P0 @T6G_MB_LIB.T6G(SCH_1):PVDDCR_CPU0_P0    I21 @T6G_MB_LIB.T6G(SCH_1):PAGE68
     2    GND @T6G_MB_LIB.T6G(SCH_1):GND    I21 @T6G_MB_LIB.T6G(SCH_1):PAGE68

C2179 Q_CAP_C0402-100NF,50V,10%,X7R,CH4106K1B01
     1 HSC_EN @T6G_MB_LIB.T6G(SCH_1):HSC_EN    I22 @T6G_MB_LIB.T6G(SCH_1):PAGE372
     2    GND @T6G_MB_LIB.T6G(SCH_1):GND    I22 @T6G_MB_LIB.T6G(SCH_1):PAGE372

C2181 Q_CAP_C0402-22UF,4V,20%,X6S,CH622KMEB02
     1 PVDDCR_CPU0_P0 @T6G_MB_LIB.T6G(SCH_1):PVDDCR_CPU0_P0    I25 @T6G_MB_LIB.T6G(SCH_1):PAGE68
     2    GND @T6G_MB_LIB.T6G(SCH_1):GND    I25 @T6G_MB_LIB.T6G(SCH_1):PAGE68

C2182 Q_CAP_C0402-22UF,4V,20%,X6S,CH622KMEB02
     1 PVDDCR_CPU0_P0 @T6G_MB_LIB.T6G(SCH_1):PVDDCR_CPU0_P0    I24 @T6G_MB_LIB.T6G(SCH_1):PAGE68
     2    GND @T6G_MB_LIB.T6G(SCH_1):GND    I24 @T6G_MB_LIB.T6G(SCH_1):PAGE68

C2183 Q_CAP_C0402-22UF,4V,20%,X6S,CH622KMEB02
     1 PVDDCR_CPU0_P0 @T6G_MB_LIB.T6G(SCH_1):PVDDCR_CPU0_P0    I19 @T6G_MB_LIB.T6G(SCH_1):PAGE68
     2    GND @T6G_MB_LIB.T6G(SCH_1):GND    I19 @T6G_MB_LIB.T6G(SCH_1):PAGE68

C2185 Q_CAP_C0402-22UF,4V,20%,X6S,CH622KMEB02
     1 PVDDCR_CPU0_P0 @T6G_MB_LIB.T6G(SCH_1):PVDDCR_CPU0_P0    I28 @T6G_MB_LIB.T6G(SCH_1):PAGE68
     2    GND @T6G_MB_LIB.T6G(SCH_1):GND    I28 @T6G_MB_LIB.T6G(SCH_1):PAGE68

C2186 Q_CAP_C0402-22UF,4V,20%,X6S,CH622KMEB02
     1 PVDDCR_CPU0_P0 @T6G_MB_LIB.T6G(SCH_1):PVDDCR_CPU0_P0    I26 @T6G_MB_LIB.T6G(SCH_1):PAGE68
     2    GND @T6G_MB_LIB.T6G(SCH_1):GND    I26 @T6G_MB_LIB.T6G(SCH_1):PAGE68

C2189 Q_CAP_C0402-22UF,4V,20%,X6S,CH622KMEB02
     1 PVDDCR_CPU0_P0 @T6G_MB_LIB.T6G(SCH_1):PVDDCR_CPU0_P0    I29 @T6G_MB_LIB.T6G(SCH_1):PAGE68
     2    GND @T6G_MB_LIB.T6G(SCH_1):GND    I29 @T6G_MB_LIB.T6G(SCH_1):PAGE68

C2190 Q_CAP_C0402-22UF,4V,20%,X6S,CH622KMEB02
     1 PVDDCR_CPU0_P0 @T6G_MB_LIB.T6G(SCH_1):PVDDCR_CPU0_P0    I27 @T6G_MB_LIB.T6G(SCH_1):PAGE68
     2    GND @T6G_MB_LIB.T6G(SCH_1):GND    I27 @T6G_MB_LIB.T6G(SCH_1):PAGE68

C2192 Q_CAP_C0402-22UF,4V,20%,X6S,CH622KMEB02
     1 PVDDCR_CPU0_P0 @T6G_MB_LIB.T6G(SCH_1):PVDDCR_CPU0_P0    I33 @T6G_MB_LIB.T6G(SCH_1):PAGE68
     2    GND @T6G_MB_LIB.T6G(SCH_1):GND    I33 @T6G_MB_LIB.T6G(SCH_1):PAGE68

C2193 Q_CAP_C0402-22UF,4V,20%,X6S,CH622KMEB02
     1 PVDDCR_CPU0_P0 @T6G_MB_LIB.T6G(SCH_1):PVDDCR_CPU0_P0    I31 @T6G_MB_LIB.T6G(SCH_1):PAGE68
     2    GND @T6G_MB_LIB.T6G(SCH_1):GND    I31 @T6G_MB_LIB.T6G(SCH_1):PAGE68

C2194 Q_CAP_0402-0.1UF,25V,10%,X7R,CH4104K1B00
     1 P12V_E1S_0_ISENSE_TIC @T6G_MB_LIB.T6G(SCH_1):P12V_E1S_0_ISENSE_TIC    I76 @T6G_MB_LIB.T6G(SCH_1):PAGE369
     2    GND @T6G_MB_LIB.T6G(SCH_1):GND    I76 @T6G_MB_LIB.T6G(SCH_1):PAGE369

C2195 Q_CAP_C0402-22UF,4V,20%,X6S,CH622KMEB02
     1 PVDDCR_CPU0_P0 @T6G_MB_LIB.T6G(SCH_1):PVDDCR_CPU0_P0    I34 @T6G_MB_LIB.T6G(SCH_1):PAGE68
     2    GND @T6G_MB_LIB.T6G(SCH_1):GND    I34 @T6G_MB_LIB.T6G(SCH_1):PAGE68

C2196 Q_CAP_C0402-22UF,4V,20%,X6S,CH622KMEB02
     1 PVDDCR_CPU0_P0 @T6G_MB_LIB.T6G(SCH_1):PVDDCR_CPU0_P0    I32 @T6G_MB_LIB.T6G(SCH_1):PAGE68
     2    GND @T6G_MB_LIB.T6G(SCH_1):GND    I32 @T6G_MB_LIB.T6G(SCH_1):PAGE68

C2198 Q_CAP_C0402-22UF,4V,20%,X6S,CH622KMEB02
     1 PVDDCR_CPU0_P0 @T6G_MB_LIB.T6G(SCH_1):PVDDCR_CPU0_P0    I40 @T6G_MB_LIB.T6G(SCH_1):PAGE68
     2    GND @T6G_MB_LIB.T6G(SCH_1):GND    I40 @T6G_MB_LIB.T6G(SCH_1):PAGE68

C2199 Q_CAP_C0402-22UF,4V,20%,X6S,CH622KMEB02
     1 PVDDCR_CPU0_P0 @T6G_MB_LIB.T6G(SCH_1):PVDDCR_CPU0_P0    I36 @T6G_MB_LIB.T6G(SCH_1):PAGE68
     2    GND @T6G_MB_LIB.T6G(SCH_1):GND    I36 @T6G_MB_LIB.T6G(SCH_1):PAGE68

C2201 Q_CAP_C0402-22UF,4V,20%,X6S,CH622KMEB02
     1 PVDDCR_CPU1_P0 @T6G_MB_LIB.T6G(SCH_1):PVDDCR_CPU1_P0    I63 @T6G_MB_LIB.T6G(SCH_1):PAGE68
     2    GND @T6G_MB_LIB.T6G(SCH_1):GND    I63 @T6G_MB_LIB.T6G(SCH_1):PAGE68

C2202 Q_CAP_C0402-22UF,4V,20%,X6S,CH622KMEB02
     1 PVDDCR_CPU1_P0 @T6G_MB_LIB.T6G(SCH_1):PVDDCR_CPU1_P0    I60 @T6G_MB_LIB.T6G(SCH_1):PAGE68
     2    GND @T6G_MB_LIB.T6G(SCH_1):GND    I60 @T6G_MB_LIB.T6G(SCH_1):PAGE68

C2203 Q_CAP_C0402-22UF,4V,20%,X6S,CH622KMEB02
     1 PVDDCR_CPU1_P0 @T6G_MB_LIB.T6G(SCH_1):PVDDCR_CPU1_P0    I43 @T6G_MB_LIB.T6G(SCH_1):PAGE68
     2    GND @T6G_MB_LIB.T6G(SCH_1):GND    I43 @T6G_MB_LIB.T6G(SCH_1):PAGE68

C2204 Q_CAP_C0402-22UF,4V,20%,X6S,CH622KMEB02
     1 PVDDCR_CPU1_P0 @T6G_MB_LIB.T6G(SCH_1):PVDDCR_CPU1_P0    I38 @T6G_MB_LIB.T6G(SCH_1):PAGE68
     2    GND @T6G_MB_LIB.T6G(SCH_1):GND    I38 @T6G_MB_LIB.T6G(SCH_1):PAGE68

C2205 Q_CAP_C0402-22UF,4V,20%,X6S,CH622KMEB02
     1 PVDDCR_CPU1_P0 @T6G_MB_LIB.T6G(SCH_1):PVDDCR_CPU1_P0    I30 @T6G_MB_LIB.T6G(SCH_1):PAGE68
     2    GND @T6G_MB_LIB.T6G(SCH_1):GND    I30 @T6G_MB_LIB.T6G(SCH_1):PAGE68

C2207 Q_CAP_C0402-22UF,4V,20%,X6S,CH622KMEB02
     1 PVDDCR_CPU1_P0 @T6G_MB_LIB.T6G(SCH_1):PVDDCR_CPU1_P0    I93 @T6G_MB_LIB.T6G(SCH_1):PAGE68
     2    GND @T6G_MB_LIB.T6G(SCH_1):GND    I93 @T6G_MB_LIB.T6G(SCH_1):PAGE68

C2208 Q_CAP_C0402-22UF,4V,20%,X6S,CH622KMEB02
     1 PVDDCR_CPU1_P0 @T6G_MB_LIB.T6G(SCH_1):PVDDCR_CPU1_P0    I91 @T6G_MB_LIB.T6G(SCH_1):PAGE68
     2    GND @T6G_MB_LIB.T6G(SCH_1):GND    I91 @T6G_MB_LIB.T6G(SCH_1):PAGE68

C2209 Q_CAP_C0402-22UF,4V,20%,X6S,CH622KMEB02
     1 PVDDCR_CPU1_P0 @T6G_MB_LIB.T6G(SCH_1):PVDDCR_CPU1_P0    I72 @T6G_MB_LIB.T6G(SCH_1):PAGE68
     2    GND @T6G_MB_LIB.T6G(SCH_1):GND    I72 @T6G_MB_LIB.T6G(SCH_1):PAGE68

C2210 Q_CAP_C0402-22UF,4V,20%,X6S,CH622KMEB02
     1 PVDDCR_CPU1_P0 @T6G_MB_LIB.T6G(SCH_1):PVDDCR_CPU1_P0    I70 @T6G_MB_LIB.T6G(SCH_1):PAGE68
     2    GND @T6G_MB_LIB.T6G(SCH_1):GND    I70 @T6G_MB_LIB.T6G(SCH_1):PAGE68

C2211 Q_CAP_C0402-22UF,4V,20%,X6S,CH622KMEB02
     1 PVDDCR_CPU1_P0 @T6G_MB_LIB.T6G(SCH_1):PVDDCR_CPU1_P0    I65 @T6G_MB_LIB.T6G(SCH_1):PAGE68
     2    GND @T6G_MB_LIB.T6G(SCH_1):GND    I65 @T6G_MB_LIB.T6G(SCH_1):PAGE68

C2213 Q_CAP_C0402-22UF,4V,20%,X6S,CH622KMEB02
     1 PVDDCR_CPU1_P0 @T6G_MB_LIB.T6G(SCH_1):PVDDCR_CPU1_P0    I94 @T6G_MB_LIB.T6G(SCH_1):PAGE68
     2    GND @T6G_MB_LIB.T6G(SCH_1):GND    I94 @T6G_MB_LIB.T6G(SCH_1):PAGE68

C2214 Q_CAP_C0402-22UF,4V,20%,X6S,CH622KMEB02
     1 PVDDCR_CPU1_P0 @T6G_MB_LIB.T6G(SCH_1):PVDDCR_CPU1_P0    I92 @T6G_MB_LIB.T6G(SCH_1):PAGE68
     2    GND @T6G_MB_LIB.T6G(SCH_1):GND    I92 @T6G_MB_LIB.T6G(SCH_1):PAGE68

C2215 Q_CAP_C0402-22UF,4V,20%,X6S,CH622KMEB02
     1 PVDDCR_CPU1_P0 @T6G_MB_LIB.T6G(SCH_1):PVDDCR_CPU1_P0    I73 @T6G_MB_LIB.T6G(SCH_1):PAGE68
     2    GND @T6G_MB_LIB.T6G(SCH_1):GND    I73 @T6G_MB_LIB.T6G(SCH_1):PAGE68

C2216 Q_CAP_C0402-22UF,4V,20%,X6S,CH622KMEB02
     1 PVDDCR_CPU1_P0 @T6G_MB_LIB.T6G(SCH_1):PVDDCR_CPU1_P0    I71 @T6G_MB_LIB.T6G(SCH_1):PAGE68
     2    GND @T6G_MB_LIB.T6G(SCH_1):GND    I71 @T6G_MB_LIB.T6G(SCH_1):PAGE68

C2217 Q_CAP_C0402-22UF,4V,20%,X6S,CH622KMEB02
     1 PVDDCR_CPU1_P0 @T6G_MB_LIB.T6G(SCH_1):PVDDCR_CPU1_P0    I66 @T6G_MB_LIB.T6G(SCH_1):PAGE68
     2    GND @T6G_MB_LIB.T6G(SCH_1):GND    I66 @T6G_MB_LIB.T6G(SCH_1):PAGE68

C2219 Q_CAP_C0402-22UF,4V,20%,X6S,CH622KMEB02
     1 PVDDCR_CPU1_P0 @T6G_MB_LIB.T6G(SCH_1):PVDDCR_CPU1_P0    I98 @T6G_MB_LIB.T6G(SCH_1):PAGE68
     2    GND @T6G_MB_LIB.T6G(SCH_1):GND    I98 @T6G_MB_LIB.T6G(SCH_1):PAGE68

C2220 Q_CAP_C0402-22UF,4V,20%,X6S,CH622KMEB02
     1 PVDDCR_CPU1_P0 @T6G_MB_LIB.T6G(SCH_1):PVDDCR_CPU1_P0    I95 @T6G_MB_LIB.T6G(SCH_1):PAGE68
     2    GND @T6G_MB_LIB.T6G(SCH_1):GND    I95 @T6G_MB_LIB.T6G(SCH_1):PAGE68

C2221 Q_CAP_C0402-22UF,4V,20%,X6S,CH622KMEB02
     1 PVDDCR_CPU1_P0 @T6G_MB_LIB.T6G(SCH_1):PVDDCR_CPU1_P0    I77 @T6G_MB_LIB.T6G(SCH_1):PAGE68
     2    GND @T6G_MB_LIB.T6G(SCH_1):GND    I77 @T6G_MB_LIB.T6G(SCH_1):PAGE68

C2222 Q_CAP_C0402-22UF,4V,20%,X6S,CH622KMEB02
     1 PVDDCR_CPU1_P0 @T6G_MB_LIB.T6G(SCH_1):PVDDCR_CPU1_P0    I74 @T6G_MB_LIB.T6G(SCH_1):PAGE68
     2    GND @T6G_MB_LIB.T6G(SCH_1):GND    I74 @T6G_MB_LIB.T6G(SCH_1):PAGE68

C2223 Q_CAP_C0402-22UF,4V,20%,X6S,CH622KMEB02
     1 PVDDCR_CPU1_P0 @T6G_MB_LIB.T6G(SCH_1):PVDDCR_CPU1_P0    I67 @T6G_MB_LIB.T6G(SCH_1):PAGE68
     2    GND @T6G_MB_LIB.T6G(SCH_1):GND    I67 @T6G_MB_LIB.T6G(SCH_1):PAGE68

C2225 Q_CAP_C0402-22UF,4V,20%,X6S,CH622KMEB02
     1 PVDDCR_CPU1_P0 @T6G_MB_LIB.T6G(SCH_1):PVDDCR_CPU1_P0    I99 @T6G_MB_LIB.T6G(SCH_1):PAGE68
     2    GND @T6G_MB_LIB.T6G(SCH_1):GND    I99 @T6G_MB_LIB.T6G(SCH_1):PAGE68

C2226 Q_CAP_C0402-22UF,4V,20%,X6S,CH622KMEB02
     1 PVDDCR_CPU1_P0 @T6G_MB_LIB.T6G(SCH_1):PVDDCR_CPU1_P0    I96 @T6G_MB_LIB.T6G(SCH_1):PAGE68
     2    GND @T6G_MB_LIB.T6G(SCH_1):GND    I96 @T6G_MB_LIB.T6G(SCH_1):PAGE68

C2227 Q_CAP_C0402-22UF,4V,20%,X6S,CH622KMEB02
     1 PVDDCR_CPU1_P0 @T6G_MB_LIB.T6G(SCH_1):PVDDCR_CPU1_P0    I78 @T6G_MB_LIB.T6G(SCH_1):PAGE68
     2    GND @T6G_MB_LIB.T6G(SCH_1):GND    I78 @T6G_MB_LIB.T6G(SCH_1):PAGE68

C2228 Q_CAP_C0402-22UF,4V,20%,X6S,CH622KMEB02
     1 PVDDCR_CPU1_P0 @T6G_MB_LIB.T6G(SCH_1):PVDDCR_CPU1_P0    I75 @T6G_MB_LIB.T6G(SCH_1):PAGE68
     2    GND @T6G_MB_LIB.T6G(SCH_1):GND    I75 @T6G_MB_LIB.T6G(SCH_1):PAGE68

C2229 Q_CAP_C0402-22UF,4V,20%,X6S,CH622KMEB02
     1 PVDDCR_CPU1_P0 @T6G_MB_LIB.T6G(SCH_1):PVDDCR_CPU1_P0    I69 @T6G_MB_LIB.T6G(SCH_1):PAGE68
     2    GND @T6G_MB_LIB.T6G(SCH_1):GND    I69 @T6G_MB_LIB.T6G(SCH_1):PAGE68

C2231 Q_CAP_C0402-22UF,4V,20%,X6S,CH622KMEB02
     1 PVDDCR_CPU1_P0 @T6G_MB_LIB.T6G(SCH_1):PVDDCR_CPU1_P0   I100 @T6G_MB_LIB.T6G(SCH_1):PAGE68
     2    GND @T6G_MB_LIB.T6G(SCH_1):GND   I100 @T6G_MB_LIB.T6G(SCH_1):PAGE68

C2232 Q_CAP_C0402-22UF,4V,20%,X6S,CH622KMEB02
     1 PVDDCR_CPU1_P0 @T6G_MB_LIB.T6G(SCH_1):PVDDCR_CPU1_P0    I97 @T6G_MB_LIB.T6G(SCH_1):PAGE68
     2    GND @T6G_MB_LIB.T6G(SCH_1):GND    I97 @T6G_MB_LIB.T6G(SCH_1):PAGE68

C2233 Q_CAP_C0402-22UF,4V,20%,X6S,CH622KMEB02
     1 PVDDCR_CPU1_P0 @T6G_MB_LIB.T6G(SCH_1):PVDDCR_CPU1_P0    I79 @T6G_MB_LIB.T6G(SCH_1):PAGE68
     2    GND @T6G_MB_LIB.T6G(SCH_1):GND    I79 @T6G_MB_LIB.T6G(SCH_1):PAGE68

C2234 Q_CAP_C0402-22UF,4V,20%,X6S,CH622KMEB02
     1 PVDDCR_CPU1_P0 @T6G_MB_LIB.T6G(SCH_1):PVDDCR_CPU1_P0    I76 @T6G_MB_LIB.T6G(SCH_1):PAGE68
     2    GND @T6G_MB_LIB.T6G(SCH_1):GND    I76 @T6G_MB_LIB.T6G(SCH_1):PAGE68

C2237 Q_CAP_C0402-22UF,4V,20%,X6S,CH622KMEB02
     1 PVDDCR_CPU1_P0 @T6G_MB_LIB.T6G(SCH_1):PVDDCR_CPU1_P0   I103 @T6G_MB_LIB.T6G(SCH_1):PAGE68
     2    GND @T6G_MB_LIB.T6G(SCH_1):GND   I103 @T6G_MB_LIB.T6G(SCH_1):PAGE68

C2238 Q_CAP_C0402-22UF,4V,20%,X6S,CH622KMEB02
     1 PVDDCR_CPU1_P0 @T6G_MB_LIB.T6G(SCH_1):PVDDCR_CPU1_P0   I101 @T6G_MB_LIB.T6G(SCH_1):PAGE68
     2    GND @T6G_MB_LIB.T6G(SCH_1):GND   I101 @T6G_MB_LIB.T6G(SCH_1):PAGE68

C2239 Q_CAP_C0402-22UF,4V,20%,X6S,CH622KMEB02
     1 PVDDCR_CPU1_P0 @T6G_MB_LIB.T6G(SCH_1):PVDDCR_CPU1_P0    I82 @T6G_MB_LIB.T6G(SCH_1):PAGE68
     2    GND @T6G_MB_LIB.T6G(SCH_1):GND    I82 @T6G_MB_LIB.T6G(SCH_1):PAGE68

C2240 Q_CAP_C0402-22UF,4V,20%,X6S,CH622KMEB02
     1 PVDDCR_CPU1_P0 @T6G_MB_LIB.T6G(SCH_1):PVDDCR_CPU1_P0    I80 @T6G_MB_LIB.T6G(SCH_1):PAGE68
     2    GND @T6G_MB_LIB.T6G(SCH_1):GND    I80 @T6G_MB_LIB.T6G(SCH_1):PAGE68

C2243 Q_CAP_C0402-22UF,4V,20%,X6S,CH622KMEB02
     1 PVDDCR_CPU1_P0 @T6G_MB_LIB.T6G(SCH_1):PVDDCR_CPU1_P0   I104 @T6G_MB_LIB.T6G(SCH_1):PAGE68
     2    GND @T6G_MB_LIB.T6G(SCH_1):GND   I104 @T6G_MB_LIB.T6G(SCH_1):PAGE68

C2244 Q_CAP_C0402-22UF,4V,20%,X6S,CH622KMEB02
     1 PVDDCR_CPU1_P0 @T6G_MB_LIB.T6G(SCH_1):PVDDCR_CPU1_P0   I102 @T6G_MB_LIB.T6G(SCH_1):PAGE68
     2    GND @T6G_MB_LIB.T6G(SCH_1):GND   I102 @T6G_MB_LIB.T6G(SCH_1):PAGE68

C2245 Q_CAP_C0402-22UF,4V,20%,X6S,CH622KMEB02
     1 PVDDCR_CPU1_P0 @T6G_MB_LIB.T6G(SCH_1):PVDDCR_CPU1_P0    I83 @T6G_MB_LIB.T6G(SCH_1):PAGE68
     2    GND @T6G_MB_LIB.T6G(SCH_1):GND    I83 @T6G_MB_LIB.T6G(SCH_1):PAGE68

C2246 Q_CAP_C0402-22UF,4V,20%,X6S,CH622KMEB02
     1 PVDDCR_CPU1_P0 @T6G_MB_LIB.T6G(SCH_1):PVDDCR_CPU1_P0    I81 @T6G_MB_LIB.T6G(SCH_1):PAGE68
     2    GND @T6G_MB_LIB.T6G(SCH_1):GND    I81 @T6G_MB_LIB.T6G(SCH_1):PAGE68

C2248 Q_CAP_C0402-22UF,4V,20%,X6S,CH622KMEB02
     1 PVDDCR_CPU1_P0 @T6G_MB_LIB.T6G(SCH_1):PVDDCR_CPU1_P0   I108 @T6G_MB_LIB.T6G(SCH_1):PAGE68
     2    GND @T6G_MB_LIB.T6G(SCH_1):GND   I108 @T6G_MB_LIB.T6G(SCH_1):PAGE68

C2249 Q_CAP_C0402-22UF,4V,20%,X6S,CH622KMEB02
     1 PVDDCR_CPU1_P0 @T6G_MB_LIB.T6G(SCH_1):PVDDCR_CPU1_P0   I105 @T6G_MB_LIB.T6G(SCH_1):PAGE68
     2    GND @T6G_MB_LIB.T6G(SCH_1):GND   I105 @T6G_MB_LIB.T6G(SCH_1):PAGE68

C2250 Q_CAP_C0402-22UF,4V,20%,X6S,CH622KMEB02
     1 PVDDCR_CPU1_P0 @T6G_MB_LIB.T6G(SCH_1):PVDDCR_CPU1_P0    I87 @T6G_MB_LIB.T6G(SCH_1):PAGE68
     2    GND @T6G_MB_LIB.T6G(SCH_1):GND    I87 @T6G_MB_LIB.T6G(SCH_1):PAGE68

C2251 Q_CAP_C0402-22UF,4V,20%,X6S,CH622KMEB02
     1 PVDDCR_CPU1_P0 @T6G_MB_LIB.T6G(SCH_1):PVDDCR_CPU1_P0    I84 @T6G_MB_LIB.T6G(SCH_1):PAGE68
     2    GND @T6G_MB_LIB.T6G(SCH_1):GND    I84 @T6G_MB_LIB.T6G(SCH_1):PAGE68

C2253 Q_CAP_C0402-22UF,4V,20%,X6S,CH622KMEB02
     1 PVDDCR_CPU1_P0 @T6G_MB_LIB.T6G(SCH_1):PVDDCR_CPU1_P0   I109 @T6G_MB_LIB.T6G(SCH_1):PAGE68
     2    GND @T6G_MB_LIB.T6G(SCH_1):GND   I109 @T6G_MB_LIB.T6G(SCH_1):PAGE68

C2254 Q_CAP_C0402-22UF,4V,20%,X6S,CH622KMEB02
     1 PVDDCR_CPU1_P0 @T6G_MB_LIB.T6G(SCH_1):PVDDCR_CPU1_P0   I106 @T6G_MB_LIB.T6G(SCH_1):PAGE68
     2    GND @T6G_MB_LIB.T6G(SCH_1):GND   I106 @T6G_MB_LIB.T6G(SCH_1):PAGE68

C2255 Q_CAP_C0402-22UF,4V,20%,X6S,CH622KMEB02
     1 PVDDCR_CPU1_P0 @T6G_MB_LIB.T6G(SCH_1):PVDDCR_CPU1_P0    I89 @T6G_MB_LIB.T6G(SCH_1):PAGE68
     2    GND @T6G_MB_LIB.T6G(SCH_1):GND    I89 @T6G_MB_LIB.T6G(SCH_1):PAGE68

C2256 Q_CAP_C0402-22UF,4V,20%,X6S,CH622KMEB02
     1 PVDDCR_CPU1_P0 @T6G_MB_LIB.T6G(SCH_1):PVDDCR_CPU1_P0    I86 @T6G_MB_LIB.T6G(SCH_1):PAGE68
     2    GND @T6G_MB_LIB.T6G(SCH_1):GND    I86 @T6G_MB_LIB.T6G(SCH_1):PAGE68

C2257 Q_CAP_0402-0.1UF,25V,10%,X7R,CH4104K1B00
     1 VFG3P3_CLK_GEN @T6G_MB_LIB.T6G(SCH_1):VFG3P3_CLK_GEN    I37 @T6G_MB_LIB.T6G(SCH_1):PAGE232
     2    GND @T6G_MB_LIB.T6G(SCH_1):GND    I37 @T6G_MB_LIB.T6G(SCH_1):PAGE232

C2258 Q_CAP_C0402-22UF,4V,20%,X6S,CH622KMEB02
     1 PVDDCR_SOC_P1 @T6G_MB_LIB.T6G(SCH_1):PVDDCR_SOC_P1     I9 @T6G_MB_LIB.T6G(SCH_1):PAGE71
     2    GND @T6G_MB_LIB.T6G(SCH_1):GND     I9 @T6G_MB_LIB.T6G(SCH_1):PAGE71

C2259 Q_CAP_C0402-22UF,4V,20%,X6S,CH622KMEB02
     1 PVDDCR_SOC_P1 @T6G_MB_LIB.T6G(SCH_1):PVDDCR_SOC_P1     I7 @T6G_MB_LIB.T6G(SCH_1):PAGE71
     2    GND @T6G_MB_LIB.T6G(SCH_1):GND     I7 @T6G_MB_LIB.T6G(SCH_1):PAGE71

C2260 Q_CAP_C0402-22UF,4V,20%,X6S,CH622KMEB02
     1 PVDDIO_P1 @T6G_MB_LIB.T6G(SCH_1):PVDDIO_P1    I53 @T6G_MB_LIB.T6G(SCH_1):PAGE71
     2    GND @T6G_MB_LIB.T6G(SCH_1):GND    I53 @T6G_MB_LIB.T6G(SCH_1):PAGE71

C2261 Q_CAP_C0402-22UF,4V,20%,X6S,CH622KMEB02
     1 PVDD11_S3_P1 @T6G_MB_LIB.T6G(SCH_1):PVDD11_S3_P1     I3 @T6G_MB_LIB.T6G(SCH_1):PAGE71
     2    GND @T6G_MB_LIB.T6G(SCH_1):GND     I3 @T6G_MB_LIB.T6G(SCH_1):PAGE71

C2262 Q_CAP_C0402-22UF,4V,20%,X6S,CH622KMEB02
     1 PVDD11_S3_P1 @T6G_MB_LIB.T6G(SCH_1):PVDD11_S3_P1     I1 @T6G_MB_LIB.T6G(SCH_1):PAGE71
     2    GND @T6G_MB_LIB.T6G(SCH_1):GND     I1 @T6G_MB_LIB.T6G(SCH_1):PAGE71

C2263 Q_CAP_C0402-22UF,4V,20%,X6S,CH622KMEB02
     1 PVDDCR_SOC_P1 @T6G_MB_LIB.T6G(SCH_1):PVDDCR_SOC_P1    I31 @T6G_MB_LIB.T6G(SCH_1):PAGE71
     2    GND @T6G_MB_LIB.T6G(SCH_1):GND    I31 @T6G_MB_LIB.T6G(SCH_1):PAGE71

C2264 Q_CAP_C0402-22UF,4V,20%,X6S,CH622KMEB02
     1 PVDDCR_SOC_P1 @T6G_MB_LIB.T6G(SCH_1):PVDDCR_SOC_P1    I30 @T6G_MB_LIB.T6G(SCH_1):PAGE71
     2    GND @T6G_MB_LIB.T6G(SCH_1):GND    I30 @T6G_MB_LIB.T6G(SCH_1):PAGE71

C2265 Q_CAP_C0402-22UF,4V,20%,X6S,CH622KMEB02
     1 PVDDIO_P1 @T6G_MB_LIB.T6G(SCH_1):PVDDIO_P1    I54 @T6G_MB_LIB.T6G(SCH_1):PAGE71
     2    GND @T6G_MB_LIB.T6G(SCH_1):GND    I54 @T6G_MB_LIB.T6G(SCH_1):PAGE71

C2266 Q_CAP_C0402-22UF,4V,20%,X6S,CH622KMEB02
     1 PVDD11_S3_P1 @T6G_MB_LIB.T6G(SCH_1):PVDD11_S3_P1    I13 @T6G_MB_LIB.T6G(SCH_1):PAGE71
     2    GND @T6G_MB_LIB.T6G(SCH_1):GND    I13 @T6G_MB_LIB.T6G(SCH_1):PAGE71

C2267 Q_CAP_C0402-22UF,4V,20%,X6S,CH622KMEB02
     1 PVDD11_S3_P1 @T6G_MB_LIB.T6G(SCH_1):PVDD11_S3_P1    I11 @T6G_MB_LIB.T6G(SCH_1):PAGE71
     2    GND @T6G_MB_LIB.T6G(SCH_1):GND    I11 @T6G_MB_LIB.T6G(SCH_1):PAGE71

C2268 Q_CAP_C0402-22UF,4V,20%,X6S,CH622KMEB02
     1 PVDDCR_SOC_P1 @T6G_MB_LIB.T6G(SCH_1):PVDDCR_SOC_P1    I33 @T6G_MB_LIB.T6G(SCH_1):PAGE71
     2    GND @T6G_MB_LIB.T6G(SCH_1):GND    I33 @T6G_MB_LIB.T6G(SCH_1):PAGE71

C2269 Q_CAP_C0402-22UF,4V,20%,X6S,CH622KMEB02
     1 PVDDCR_SOC_P1 @T6G_MB_LIB.T6G(SCH_1):PVDDCR_SOC_P1    I32 @T6G_MB_LIB.T6G(SCH_1):PAGE71
     2    GND @T6G_MB_LIB.T6G(SCH_1):GND    I32 @T6G_MB_LIB.T6G(SCH_1):PAGE71

C2270 Q_CAP_C0402-22UF,4V,20%,X6S,CH622KMEB02
     1 PVDDIO_P1 @T6G_MB_LIB.T6G(SCH_1):PVDDIO_P1    I56 @T6G_MB_LIB.T6G(SCH_1):PAGE71
     2    GND @T6G_MB_LIB.T6G(SCH_1):GND    I56 @T6G_MB_LIB.T6G(SCH_1):PAGE71

C2271 Q_CAP_C0402-22UF,4V,20%,X6S,CH622KMEB02
     1 PVDD11_S3_P1 @T6G_MB_LIB.T6G(SCH_1):PVDD11_S3_P1    I14 @T6G_MB_LIB.T6G(SCH_1):PAGE71
     2    GND @T6G_MB_LIB.T6G(SCH_1):GND    I14 @T6G_MB_LIB.T6G(SCH_1):PAGE71

C2272 Q_CAP_C0402-22UF,4V,20%,X6S,CH622KMEB02
     1 PVDDCR_SOC_P1 @T6G_MB_LIB.T6G(SCH_1):PVDDCR_SOC_P1    I34 @T6G_MB_LIB.T6G(SCH_1):PAGE71
     2    GND @T6G_MB_LIB.T6G(SCH_1):GND    I34 @T6G_MB_LIB.T6G(SCH_1):PAGE71

C2273 Q_CAP_C0402-22UF,4V,20%,X6S,CH622KMEB02
     1 PVDDCR_SOC_P1 @T6G_MB_LIB.T6G(SCH_1):PVDDCR_SOC_P1    I35 @T6G_MB_LIB.T6G(SCH_1):PAGE71
     2    GND @T6G_MB_LIB.T6G(SCH_1):GND    I35 @T6G_MB_LIB.T6G(SCH_1):PAGE71

C2274 Q_CAP_C0402-22UF,4V,20%,X6S,CH622KMEB02
     1 PVDDIO_P1 @T6G_MB_LIB.T6G(SCH_1):PVDDIO_P1    I57 @T6G_MB_LIB.T6G(SCH_1):PAGE71
     2    GND @T6G_MB_LIB.T6G(SCH_1):GND    I57 @T6G_MB_LIB.T6G(SCH_1):PAGE71

C2275 Q_CAP_C0402-22UF,4V,20%,X6S,CH622KMEB02
     1 PVDD11_S3_P1 @T6G_MB_LIB.T6G(SCH_1):PVDD11_S3_P1    I19 @T6G_MB_LIB.T6G(SCH_1):PAGE71
     2    GND @T6G_MB_LIB.T6G(SCH_1):GND    I19 @T6G_MB_LIB.T6G(SCH_1):PAGE71

C2276 Q_CAP_C0402-22UF,4V,20%,X6S,CH622KMEB02
     1 PVDDCR_SOC_P1 @T6G_MB_LIB.T6G(SCH_1):PVDDCR_SOC_P1    I62 @T6G_MB_LIB.T6G(SCH_1):PAGE71
     2    GND @T6G_MB_LIB.T6G(SCH_1):GND    I62 @T6G_MB_LIB.T6G(SCH_1):PAGE71

C2277 Q_CAP_C0402-22UF,4V,20%,X6S,CH622KMEB02
     1 PVDDCR_SOC_P1 @T6G_MB_LIB.T6G(SCH_1):PVDDCR_SOC_P1    I36 @T6G_MB_LIB.T6G(SCH_1):PAGE71
     2    GND @T6G_MB_LIB.T6G(SCH_1):GND    I36 @T6G_MB_LIB.T6G(SCH_1):PAGE71

C2278 Q_CAP_C0402-22UF,4V,20%,X6S,CH622KMEB02
     1 PVDDIO_P1 @T6G_MB_LIB.T6G(SCH_1):PVDDIO_P1    I58 @T6G_MB_LIB.T6G(SCH_1):PAGE71
     2    GND @T6G_MB_LIB.T6G(SCH_1):GND    I58 @T6G_MB_LIB.T6G(SCH_1):PAGE71

C2279 Q_CAP_C0402-22UF,4V,20%,X6S,CH622KMEB02
     1 PVDD11_S3_P1 @T6G_MB_LIB.T6G(SCH_1):PVDD11_S3_P1    I20 @T6G_MB_LIB.T6G(SCH_1):PAGE71
     2    GND @T6G_MB_LIB.T6G(SCH_1):GND    I20 @T6G_MB_LIB.T6G(SCH_1):PAGE71

C2280 Q_CAP_C0402-22UF,4V,20%,X6S,CH622KMEB02
     1 PVDDCR_SOC_P1 @T6G_MB_LIB.T6G(SCH_1):PVDDCR_SOC_P1    I38 @T6G_MB_LIB.T6G(SCH_1):PAGE71
     2    GND @T6G_MB_LIB.T6G(SCH_1):GND    I38 @T6G_MB_LIB.T6G(SCH_1):PAGE71

C2281 Q_CAP_C0402-22UF,4V,20%,X6S,CH622KMEB02
     1 PVDDCR_SOC_P1 @T6G_MB_LIB.T6G(SCH_1):PVDDCR_SOC_P1    I37 @T6G_MB_LIB.T6G(SCH_1):PAGE71
     2    GND @T6G_MB_LIB.T6G(SCH_1):GND    I37 @T6G_MB_LIB.T6G(SCH_1):PAGE71

C2282 Q_CAP_C0402-22UF,4V,20%,X6S,CH622KMEB02
     1 PVDD11_S3_P1 @T6G_MB_LIB.T6G(SCH_1):PVDD11_S3_P1    I21 @T6G_MB_LIB.T6G(SCH_1):PAGE71
     2    GND @T6G_MB_LIB.T6G(SCH_1):GND    I21 @T6G_MB_LIB.T6G(SCH_1):PAGE71

C2283 Q_CAP_C0402-22UF,4V,20%,X6S,CH622KMEB02
     1 PVDDCR_SOC_P1 @T6G_MB_LIB.T6G(SCH_1):PVDDCR_SOC_P1    I40 @T6G_MB_LIB.T6G(SCH_1):PAGE71
     2    GND @T6G_MB_LIB.T6G(SCH_1):GND    I40 @T6G_MB_LIB.T6G(SCH_1):PAGE71

C2284 Q_CAP_C0402-22UF,4V,20%,X6S,CH622KMEB02
     1 PVDDCR_SOC_P1 @T6G_MB_LIB.T6G(SCH_1):PVDDCR_SOC_P1    I39 @T6G_MB_LIB.T6G(SCH_1):PAGE71
     2    GND @T6G_MB_LIB.T6G(SCH_1):GND    I39 @T6G_MB_LIB.T6G(SCH_1):PAGE71

C2285 Q_CAP_C0402-22UF,4V,20%,X6S,CH622KMEB02
     1 PVDD11_S3_P1 @T6G_MB_LIB.T6G(SCH_1):PVDD11_S3_P1    I24 @T6G_MB_LIB.T6G(SCH_1):PAGE71
     2    GND @T6G_MB_LIB.T6G(SCH_1):GND    I24 @T6G_MB_LIB.T6G(SCH_1):PAGE71

C2286 Q_CAP_C0402-22UF,4V,20%,X6S,CH622KMEB02
     1 PVDDCR_SOC_P1 @T6G_MB_LIB.T6G(SCH_1):PVDDCR_SOC_P1    I42 @T6G_MB_LIB.T6G(SCH_1):PAGE71
     2    GND @T6G_MB_LIB.T6G(SCH_1):GND    I42 @T6G_MB_LIB.T6G(SCH_1):PAGE71

C2287 Q_CAP_C0402-22UF,4V,20%,X6S,CH622KMEB02
     1 PVDD11_S3_P1 @T6G_MB_LIB.T6G(SCH_1):PVDD11_S3_P1    I25 @T6G_MB_LIB.T6G(SCH_1):PAGE71
     2    GND @T6G_MB_LIB.T6G(SCH_1):GND    I25 @T6G_MB_LIB.T6G(SCH_1):PAGE71

C2288 Q_CAP_C0402-22UF,4V,20%,X6S,CH622KMEB02
     1 PVDDCR_SOC_P1 @T6G_MB_LIB.T6G(SCH_1):PVDDCR_SOC_P1    I44 @T6G_MB_LIB.T6G(SCH_1):PAGE71
     2    GND @T6G_MB_LIB.T6G(SCH_1):GND    I44 @T6G_MB_LIB.T6G(SCH_1):PAGE71

C2289 Q_CAP_C0402-22UF,4V,20%,X6S,CH622KMEB02
     1 PVDD11_S3_P1 @T6G_MB_LIB.T6G(SCH_1):PVDD11_S3_P1    I26 @T6G_MB_LIB.T6G(SCH_1):PAGE71
     2    GND @T6G_MB_LIB.T6G(SCH_1):GND    I26 @T6G_MB_LIB.T6G(SCH_1):PAGE71

C2290 Q_CAP_C0402-22UF,4V,20%,X6S,CH622KMEB02
     1 PVDDCR_SOC_P1 @T6G_MB_LIB.T6G(SCH_1):PVDDCR_SOC_P1    I47 @T6G_MB_LIB.T6G(SCH_1):PAGE71
     2    GND @T6G_MB_LIB.T6G(SCH_1):GND    I47 @T6G_MB_LIB.T6G(SCH_1):PAGE71

C2291 Q_CAP_C0402-22UF,4V,20%,X6S,CH622KMEB02
     1 PVDD11_S3_P1 @T6G_MB_LIB.T6G(SCH_1):PVDD11_S3_P1    I28 @T6G_MB_LIB.T6G(SCH_1):PAGE71
     2    GND @T6G_MB_LIB.T6G(SCH_1):GND    I28 @T6G_MB_LIB.T6G(SCH_1):PAGE71

C2292 Q_CAP_C0402-22UF,4V,20%,X6S,CH622KMEB02
     1 PVDD18_S5_P1 @T6G_MB_LIB.T6G(SCH_1):PVDD18_S5_P1    I49 @T6G_MB_LIB.T6G(SCH_1):PAGE71
     2    GND @T6G_MB_LIB.T6G(SCH_1):GND    I49 @T6G_MB_LIB.T6G(SCH_1):PAGE71

C2293 Q_CAP_C0402-22UF,4V,20%,X6S,CH622KMEB02
     1 PVDD18_S5_P1 @T6G_MB_LIB.T6G(SCH_1):PVDD18_S5_P1    I50 @T6G_MB_LIB.T6G(SCH_1):PAGE71
     2    GND @T6G_MB_LIB.T6G(SCH_1):GND    I50 @T6G_MB_LIB.T6G(SCH_1):PAGE71

C2294 Q_CAP_C0402-22UF,4V,20%,X6S,CH622KMEB02
     1 PVDDCR_CPU0_P1 @T6G_MB_LIB.T6G(SCH_1):PVDDCR_CPU0_P1    I17 @T6G_MB_LIB.T6G(SCH_1):PAGE72
     2    GND @T6G_MB_LIB.T6G(SCH_1):GND    I17 @T6G_MB_LIB.T6G(SCH_1):PAGE72

C2295 Q_CAP_C0402-22UF,4V,20%,X6S,CH622KMEB02
     1 PVDDCR_CPU0_P1 @T6G_MB_LIB.T6G(SCH_1):PVDDCR_CPU0_P1     I9 @T6G_MB_LIB.T6G(SCH_1):PAGE72
     2    GND @T6G_MB_LIB.T6G(SCH_1):GND     I9 @T6G_MB_LIB.T6G(SCH_1):PAGE72

C2296 Q_CAP_C0402-22UF,4V,20%,X6S,CH622KMEB02
     1 PVDDCR_CPU0_P1 @T6G_MB_LIB.T6G(SCH_1):PVDDCR_CPU0_P1     I7 @T6G_MB_LIB.T6G(SCH_1):PAGE72
     2    GND @T6G_MB_LIB.T6G(SCH_1):GND     I7 @T6G_MB_LIB.T6G(SCH_1):PAGE72

C2297 Q_CAP_C0402-22UF,4V,20%,X6S,CH622KMEB02
     1 PVDDCR_CPU0_P1 @T6G_MB_LIB.T6G(SCH_1):PVDDCR_CPU0_P1     I5 @T6G_MB_LIB.T6G(SCH_1):PAGE72
     2    GND @T6G_MB_LIB.T6G(SCH_1):GND     I5 @T6G_MB_LIB.T6G(SCH_1):PAGE72

C2298 Q_CAP_C0402-22UF,4V,20%,X6S,CH622KMEB02
     1 PVDDCR_CPU0_P1 @T6G_MB_LIB.T6G(SCH_1):PVDDCR_CPU0_P1     I1 @T6G_MB_LIB.T6G(SCH_1):PAGE72
     2    GND @T6G_MB_LIB.T6G(SCH_1):GND     I1 @T6G_MB_LIB.T6G(SCH_1):PAGE72

C2300 Q_CAP_C0402-22UF,4V,20%,X6S,CH622KMEB02
     1 PVDDCR_CPU0_P1 @T6G_MB_LIB.T6G(SCH_1):PVDDCR_CPU0_P1    I19 @T6G_MB_LIB.T6G(SCH_1):PAGE72
     2    GND @T6G_MB_LIB.T6G(SCH_1):GND    I19 @T6G_MB_LIB.T6G(SCH_1):PAGE72

C2301 Q_CAP_C0402-22UF,4V,20%,X6S,CH622KMEB02
     1 PVDDCR_CPU0_P1 @T6G_MB_LIB.T6G(SCH_1):PVDDCR_CPU0_P1    I13 @T6G_MB_LIB.T6G(SCH_1):PAGE72
     2    GND @T6G_MB_LIB.T6G(SCH_1):GND    I13 @T6G_MB_LIB.T6G(SCH_1):PAGE72

C2302 Q_CAP_C0402-22UF,4V,20%,X6S,CH622KMEB02
     1 PVDDCR_CPU0_P1 @T6G_MB_LIB.T6G(SCH_1):PVDDCR_CPU0_P1    I12 @T6G_MB_LIB.T6G(SCH_1):PAGE72
     2    GND @T6G_MB_LIB.T6G(SCH_1):GND    I12 @T6G_MB_LIB.T6G(SCH_1):PAGE72

C2303 Q_CAP_C0402-22UF,4V,20%,X6S,CH622KMEB02
     1 PVDDCR_CPU0_P1 @T6G_MB_LIB.T6G(SCH_1):PVDDCR_CPU0_P1    I10 @T6G_MB_LIB.T6G(SCH_1):PAGE72
     2    GND @T6G_MB_LIB.T6G(SCH_1):GND    I10 @T6G_MB_LIB.T6G(SCH_1):PAGE72

C2304 Q_CAP_C0402-22UF,4V,20%,X6S,CH622KMEB02
     1 PVDDCR_CPU0_P1 @T6G_MB_LIB.T6G(SCH_1):PVDDCR_CPU0_P1     I3 @T6G_MB_LIB.T6G(SCH_1):PAGE72
     2    GND @T6G_MB_LIB.T6G(SCH_1):GND     I3 @T6G_MB_LIB.T6G(SCH_1):PAGE72

C2306 Q_CAP_C0402-22UF,4V,20%,X6S,CH622KMEB02
     1 PVDDCR_CPU0_P1 @T6G_MB_LIB.T6G(SCH_1):PVDDCR_CPU0_P1    I20 @T6G_MB_LIB.T6G(SCH_1):PAGE72
     2    GND @T6G_MB_LIB.T6G(SCH_1):GND    I20 @T6G_MB_LIB.T6G(SCH_1):PAGE72

C2307 Q_CAP_C0402-22UF,4V,20%,X6S,CH622KMEB02
     1 PVDDCR_CPU0_P1 @T6G_MB_LIB.T6G(SCH_1):PVDDCR_CPU0_P1    I15 @T6G_MB_LIB.T6G(SCH_1):PAGE72
     2    GND @T6G_MB_LIB.T6G(SCH_1):GND    I15 @T6G_MB_LIB.T6G(SCH_1):PAGE72

C2308 Q_CAP_C0402-22UF,4V,20%,X6S,CH622KMEB02
     1 PVDDCR_CPU0_P1 @T6G_MB_LIB.T6G(SCH_1):PVDDCR_CPU0_P1    I14 @T6G_MB_LIB.T6G(SCH_1):PAGE72
     2    GND @T6G_MB_LIB.T6G(SCH_1):GND    I14 @T6G_MB_LIB.T6G(SCH_1):PAGE72

C2309 Q_CAP_C0402-22UF,4V,20%,X6S,CH622KMEB02
     1 PVDDCR_CPU0_P1 @T6G_MB_LIB.T6G(SCH_1):PVDDCR_CPU0_P1    I11 @T6G_MB_LIB.T6G(SCH_1):PAGE72
     2    GND @T6G_MB_LIB.T6G(SCH_1):GND    I11 @T6G_MB_LIB.T6G(SCH_1):PAGE72

C2310 Q_CAP_C0402-22UF,4V,20%,X6S,CH622KMEB02
     1 PVDDCR_CPU0_P1 @T6G_MB_LIB.T6G(SCH_1):PVDDCR_CPU0_P1     I4 @T6G_MB_LIB.T6G(SCH_1):PAGE72
     2    GND @T6G_MB_LIB.T6G(SCH_1):GND     I4 @T6G_MB_LIB.T6G(SCH_1):PAGE72

C2312 Q_CAP_C0402-22UF,4V,20%,X6S,CH622KMEB02
     1 PVDDCR_CPU0_P1 @T6G_MB_LIB.T6G(SCH_1):PVDDCR_CPU0_P1    I59 @T6G_MB_LIB.T6G(SCH_1):PAGE72
     2    GND @T6G_MB_LIB.T6G(SCH_1):GND    I59 @T6G_MB_LIB.T6G(SCH_1):PAGE72

C2313 Q_CAP_C0402-22UF,4V,20%,X6S,CH622KMEB02
     1 PVDDCR_CPU0_P1 @T6G_MB_LIB.T6G(SCH_1):PVDDCR_CPU0_P1    I28 @T6G_MB_LIB.T6G(SCH_1):PAGE72
     2    GND @T6G_MB_LIB.T6G(SCH_1):GND    I28 @T6G_MB_LIB.T6G(SCH_1):PAGE72

C2314 Q_CAP_C0402-22UF,4V,20%,X6S,CH622KMEB02
     1 PVDDCR_CPU0_P1 @T6G_MB_LIB.T6G(SCH_1):PVDDCR_CPU0_P1    I27 @T6G_MB_LIB.T6G(SCH_1):PAGE72
     2    GND @T6G_MB_LIB.T6G(SCH_1):GND    I27 @T6G_MB_LIB.T6G(SCH_1):PAGE72

C2315 Q_CAP_C0402-22UF,4V,20%,X6S,CH622KMEB02
     1 PVDDCR_CPU0_P1 @T6G_MB_LIB.T6G(SCH_1):PVDDCR_CPU0_P1    I24 @T6G_MB_LIB.T6G(SCH_1):PAGE72
     2    GND @T6G_MB_LIB.T6G(SCH_1):GND    I24 @T6G_MB_LIB.T6G(SCH_1):PAGE72

C2316 Q_CAP_C0402-22UF,4V,20%,X6S,CH622KMEB02
     1 PVDDCR_CPU0_P1 @T6G_MB_LIB.T6G(SCH_1):PVDDCR_CPU0_P1    I21 @T6G_MB_LIB.T6G(SCH_1):PAGE72
     2    GND @T6G_MB_LIB.T6G(SCH_1):GND    I21 @T6G_MB_LIB.T6G(SCH_1):PAGE72

C2317 Q_CAP_C0402-1UF,25V,10%,X6S,CH5104KEB02
     1 RST_USB_CPU0_HUB1_R_N @T6G_MB_LIB.T6G(SCH_1):RST_USB_CPU0_HUB1_R_N    I25 @T6G_MB_LIB.T6G(SCH_1):PAGE153
     2    GND @T6G_MB_LIB.T6G(SCH_1):GND    I25 @T6G_MB_LIB.T6G(SCH_1):PAGE153

C2318 Q_CAP_C0402-22UF,4V,20%,X6S,CH622KMEB02
     1 PVDDCR_CPU0_P1 @T6G_MB_LIB.T6G(SCH_1):PVDDCR_CPU0_P1    I60 @T6G_MB_LIB.T6G(SCH_1):PAGE72
     2    GND @T6G_MB_LIB.T6G(SCH_1):GND    I60 @T6G_MB_LIB.T6G(SCH_1):PAGE72

C2319 Q_CAP_C0402-22UF,4V,20%,X6S,CH622KMEB02
     1 PVDDCR_CPU0_P1 @T6G_MB_LIB.T6G(SCH_1):PVDDCR_CPU0_P1    I31 @T6G_MB_LIB.T6G(SCH_1):PAGE72
     2    GND @T6G_MB_LIB.T6G(SCH_1):GND    I31 @T6G_MB_LIB.T6G(SCH_1):PAGE72

C2320 Q_CAP_C0402-22UF,4V,20%,X6S,CH622KMEB02
     1 PVDDCR_CPU0_P1 @T6G_MB_LIB.T6G(SCH_1):PVDDCR_CPU0_P1    I29 @T6G_MB_LIB.T6G(SCH_1):PAGE72
     2    GND @T6G_MB_LIB.T6G(SCH_1):GND    I29 @T6G_MB_LIB.T6G(SCH_1):PAGE72

C2321 Q_CAP_C0402-22UF,4V,20%,X6S,CH622KMEB02
     1 PVDDCR_CPU0_P1 @T6G_MB_LIB.T6G(SCH_1):PVDDCR_CPU0_P1    I25 @T6G_MB_LIB.T6G(SCH_1):PAGE72
     2    GND @T6G_MB_LIB.T6G(SCH_1):GND    I25 @T6G_MB_LIB.T6G(SCH_1):PAGE72

C2322 Q_CAP_C0402-22UF,4V,20%,X6S,CH622KMEB02
     1 PVDDCR_CPU0_P1 @T6G_MB_LIB.T6G(SCH_1):PVDDCR_CPU0_P1    I23 @T6G_MB_LIB.T6G(SCH_1):PAGE72
     2    GND @T6G_MB_LIB.T6G(SCH_1):GND    I23 @T6G_MB_LIB.T6G(SCH_1):PAGE72

C2324 Q_CAP_C0402-22UF,4V,20%,X6S,CH622KMEB02
     1 PVDDCR_CPU0_P1 @T6G_MB_LIB.T6G(SCH_1):PVDDCR_CPU0_P1    I61 @T6G_MB_LIB.T6G(SCH_1):PAGE72
     2    GND @T6G_MB_LIB.T6G(SCH_1):GND    I61 @T6G_MB_LIB.T6G(SCH_1):PAGE72

C2325 Q_CAP_C0402-22UF,4V,20%,X6S,CH622KMEB02
     1 PVDDCR_CPU0_P1 @T6G_MB_LIB.T6G(SCH_1):PVDDCR_CPU0_P1    I32 @T6G_MB_LIB.T6G(SCH_1):PAGE72
     2    GND @T6G_MB_LIB.T6G(SCH_1):GND    I32 @T6G_MB_LIB.T6G(SCH_1):PAGE72

C2326 Q_CAP_C0402-22UF,4V,20%,X6S,CH622KMEB02
     1 PVDDCR_CPU0_P1 @T6G_MB_LIB.T6G(SCH_1):PVDDCR_CPU0_P1    I30 @T6G_MB_LIB.T6G(SCH_1):PAGE72
     2    GND @T6G_MB_LIB.T6G(SCH_1):GND    I30 @T6G_MB_LIB.T6G(SCH_1):PAGE72

C2327 Q_CAP_C0402-22UF,4V,20%,X6S,CH622KMEB02
     1 PVDDCR_CPU0_P1 @T6G_MB_LIB.T6G(SCH_1):PVDDCR_CPU0_P1    I26 @T6G_MB_LIB.T6G(SCH_1):PAGE72
     2    GND @T6G_MB_LIB.T6G(SCH_1):GND    I26 @T6G_MB_LIB.T6G(SCH_1):PAGE72

C2328 Q_CAP_C0402-10UF,6.3V,20%,X6S,CH6101MEB01
     1 P3V3_9ZXL045_P0_VDD @T6G_MB_LIB.T6G(SCH_1):P3V3_9ZXL045_P0_VDD    I71 @T6G_MB_LIB.T6G(SCH_1):PAGE160
     2    GND @T6G_MB_LIB.T6G(SCH_1):GND    I71 @T6G_MB_LIB.T6G(SCH_1):PAGE160

C2329 Q_CAP_0402-0.1UF,25V,10%,X7R,CH4104K1B00
     1 P3V3_9ZXL045_P0_VDD @T6G_MB_LIB.T6G(SCH_1):P3V3_9ZXL045_P0_VDD    I40 @T6G_MB_LIB.T6G(SCH_1):PAGE160
     2    GND @T6G_MB_LIB.T6G(SCH_1):GND    I40 @T6G_MB_LIB.T6G(SCH_1):PAGE160

C2330 Q_CAP_C0402-22UF,4V,20%,X6S,CH622KMEB02
     1 PVDDCR_CPU0_P1 @T6G_MB_LIB.T6G(SCH_1):PVDDCR_CPU0_P1    I62 @T6G_MB_LIB.T6G(SCH_1):PAGE72
     2    GND @T6G_MB_LIB.T6G(SCH_1):GND    I62 @T6G_MB_LIB.T6G(SCH_1):PAGE72

C2331 Q_CAP_C0402-22UF,4V,20%,X6S,CH622KMEB02
     1 PVDDCR_CPU0_P1 @T6G_MB_LIB.T6G(SCH_1):PVDDCR_CPU0_P1    I36 @T6G_MB_LIB.T6G(SCH_1):PAGE72
     2    GND @T6G_MB_LIB.T6G(SCH_1):GND    I36 @T6G_MB_LIB.T6G(SCH_1):PAGE72

C2332 Q_CAP_C0402-22UF,4V,20%,X6S,CH622KMEB02
     1 PVDDCR_CPU0_P1 @T6G_MB_LIB.T6G(SCH_1):PVDDCR_CPU0_P1    I35 @T6G_MB_LIB.T6G(SCH_1):PAGE72
     2    GND @T6G_MB_LIB.T6G(SCH_1):GND    I35 @T6G_MB_LIB.T6G(SCH_1):PAGE72

C2333 Q_CAP_C0402-22UF,4V,20%,X6S,CH622KMEB02
     1 PVDDCR_CPU0_P1 @T6G_MB_LIB.T6G(SCH_1):PVDDCR_CPU0_P1    I33 @T6G_MB_LIB.T6G(SCH_1):PAGE72
     2    GND @T6G_MB_LIB.T6G(SCH_1):GND    I33 @T6G_MB_LIB.T6G(SCH_1):PAGE72

C2334 Q_CAP_0402-0.1UF,25V,10%,X7R,CH4104K1B00
     1 P3V3_9ZXL045_P0_VDDA @T6G_MB_LIB.T6G(SCH_1):P3V3_9ZXL045_P0_VDDA    I20 @T6G_MB_LIB.T6G(SCH_1):PAGE160
     2    GND @T6G_MB_LIB.T6G(SCH_1):GND    I20 @T6G_MB_LIB.T6G(SCH_1):PAGE160

C2335 Q_CAP_C0402-22UF,4V,20%,X6S,CH622KMEB02
     1 PVDDCR_CPU0_P1 @T6G_MB_LIB.T6G(SCH_1):PVDDCR_CPU0_P1    I63 @T6G_MB_LIB.T6G(SCH_1):PAGE72
     2    GND @T6G_MB_LIB.T6G(SCH_1):GND    I63 @T6G_MB_LIB.T6G(SCH_1):PAGE72

C2336 Q_CAP_C0402-22UF,4V,20%,X6S,CH622KMEB02
     1 PVDDCR_CPU0_P1 @T6G_MB_LIB.T6G(SCH_1):PVDDCR_CPU0_P1    I38 @T6G_MB_LIB.T6G(SCH_1):PAGE72
     2    GND @T6G_MB_LIB.T6G(SCH_1):GND    I38 @T6G_MB_LIB.T6G(SCH_1):PAGE72

C2337 Q_CAP_C0402-22UF,4V,20%,X6S,CH622KMEB02
     1 PVDDCR_CPU0_P1 @T6G_MB_LIB.T6G(SCH_1):PVDDCR_CPU0_P1    I37 @T6G_MB_LIB.T6G(SCH_1):PAGE72
     2    GND @T6G_MB_LIB.T6G(SCH_1):GND    I37 @T6G_MB_LIB.T6G(SCH_1):PAGE72

C2338 Q_CAP_C0402-22UF,4V,20%,X6S,CH622KMEB02
     1 PVDDCR_CPU0_P1 @T6G_MB_LIB.T6G(SCH_1):PVDDCR_CPU0_P1    I34 @T6G_MB_LIB.T6G(SCH_1):PAGE72
     2    GND @T6G_MB_LIB.T6G(SCH_1):GND    I34 @T6G_MB_LIB.T6G(SCH_1):PAGE72

C2339 Q_CAP_0402-0.1UF,25V,10%,X7R,CH4104K1B00
     1 P3V3_9ZXL045_P0_VDD @T6G_MB_LIB.T6G(SCH_1):P3V3_9ZXL045_P0_VDD    I47 @T6G_MB_LIB.T6G(SCH_1):PAGE160
     2    GND @T6G_MB_LIB.T6G(SCH_1):GND    I47 @T6G_MB_LIB.T6G(SCH_1):PAGE160

C2340 Q_CAP_C0402-22UF,4V,20%,X6S,CH622KMEB02
     1 PVDDCR_CPU0_P1 @T6G_MB_LIB.T6G(SCH_1):PVDDCR_CPU0_P1    I64 @T6G_MB_LIB.T6G(SCH_1):PAGE72
     2    GND @T6G_MB_LIB.T6G(SCH_1):GND    I64 @T6G_MB_LIB.T6G(SCH_1):PAGE72

C2341 Q_CAP_C0402-22UF,4V,20%,X6S,CH622KMEB02
     1 PVDDCR_CPU0_P1 @T6G_MB_LIB.T6G(SCH_1):PVDDCR_CPU0_P1    I47 @T6G_MB_LIB.T6G(SCH_1):PAGE72
     2    GND @T6G_MB_LIB.T6G(SCH_1):GND    I47 @T6G_MB_LIB.T6G(SCH_1):PAGE72

C2342 Q_CAP_C0402-22UF,4V,20%,X6S,CH622KMEB02
     1 PVDDCR_CPU0_P1 @T6G_MB_LIB.T6G(SCH_1):PVDDCR_CPU0_P1    I46 @T6G_MB_LIB.T6G(SCH_1):PAGE72
     2    GND @T6G_MB_LIB.T6G(SCH_1):GND    I46 @T6G_MB_LIB.T6G(SCH_1):PAGE72

C2343 Q_CAP_C0402-22UF,4V,20%,X6S,CH622KMEB02
     1 PVDDCR_CPU0_P1 @T6G_MB_LIB.T6G(SCH_1):PVDDCR_CPU0_P1    I42 @T6G_MB_LIB.T6G(SCH_1):PAGE72
     2    GND @T6G_MB_LIB.T6G(SCH_1):GND    I42 @T6G_MB_LIB.T6G(SCH_1):PAGE72

C2344 Q_CAP_0402-0.1UF,25V,10%,X7R,CH4104K1B00
     1 P3V3_AUX @T6G_MB_LIB.T6G(SCH_1):P3V3_AUX    I53 @T6G_MB_LIB.T6G(SCH_1):PAGE337
     2    GND @T6G_MB_LIB.T6G(SCH_1):GND    I53 @T6G_MB_LIB.T6G(SCH_1):PAGE337

C2345 Q_CAP_C0402-22UF,4V,20%,X6S,CH622KMEB02
     1 PVDDCR_CPU0_P1 @T6G_MB_LIB.T6G(SCH_1):PVDDCR_CPU0_P1    I66 @T6G_MB_LIB.T6G(SCH_1):PAGE72
     2    GND @T6G_MB_LIB.T6G(SCH_1):GND    I66 @T6G_MB_LIB.T6G(SCH_1):PAGE72

C2346 Q_CAP_C0402-22UF,4V,20%,X6S,CH622KMEB02
     1 PVDDCR_CPU0_P1 @T6G_MB_LIB.T6G(SCH_1):PVDDCR_CPU0_P1    I50 @T6G_MB_LIB.T6G(SCH_1):PAGE72
     2    GND @T6G_MB_LIB.T6G(SCH_1):GND    I50 @T6G_MB_LIB.T6G(SCH_1):PAGE72

C2347 Q_CAP_C0402-22UF,4V,20%,X6S,CH622KMEB02
     1 PVDDCR_CPU0_P1 @T6G_MB_LIB.T6G(SCH_1):PVDDCR_CPU0_P1    I48 @T6G_MB_LIB.T6G(SCH_1):PAGE72
     2    GND @T6G_MB_LIB.T6G(SCH_1):GND    I48 @T6G_MB_LIB.T6G(SCH_1):PAGE72

C2348 Q_CAP_C0402-22UF,4V,20%,X6S,CH622KMEB02
     1 PVDDCR_CPU0_P1 @T6G_MB_LIB.T6G(SCH_1):PVDDCR_CPU0_P1    I44 @T6G_MB_LIB.T6G(SCH_1):PAGE72
     2    GND @T6G_MB_LIB.T6G(SCH_1):GND    I44 @T6G_MB_LIB.T6G(SCH_1):PAGE72

C2350 Q_CAP_C0402-22UF,4V,20%,X6S,CH622KMEB02
     1 PVDDCR_CPU1_P1 @T6G_MB_LIB.T6G(SCH_1):PVDDCR_CPU1_P1   I110 @T6G_MB_LIB.T6G(SCH_1):PAGE72
     2    GND @T6G_MB_LIB.T6G(SCH_1):GND   I110 @T6G_MB_LIB.T6G(SCH_1):PAGE72

C2351 Q_CAP_C0402-22UF,4V,20%,X6S,CH622KMEB02
     1 PVDDCR_CPU1_P1 @T6G_MB_LIB.T6G(SCH_1):PVDDCR_CPU1_P1    I56 @T6G_MB_LIB.T6G(SCH_1):PAGE72
     2    GND @T6G_MB_LIB.T6G(SCH_1):GND    I56 @T6G_MB_LIB.T6G(SCH_1):PAGE72

C2352 Q_CAP_C0402-22UF,4V,20%,X6S,CH622KMEB02
     1 PVDDCR_CPU1_P1 @T6G_MB_LIB.T6G(SCH_1):PVDDCR_CPU1_P1    I55 @T6G_MB_LIB.T6G(SCH_1):PAGE72
     2    GND @T6G_MB_LIB.T6G(SCH_1):GND    I55 @T6G_MB_LIB.T6G(SCH_1):PAGE72

C2353 Q_CAP_C0402-22UF,4V,20%,X6S,CH622KMEB02
     1 PVDDCR_CPU1_P1 @T6G_MB_LIB.T6G(SCH_1):PVDDCR_CPU1_P1    I51 @T6G_MB_LIB.T6G(SCH_1):PAGE72
     2    GND @T6G_MB_LIB.T6G(SCH_1):GND    I51 @T6G_MB_LIB.T6G(SCH_1):PAGE72

C2354 Q_CAP_C0402-22UF,4V,20%,X6S,CH622KMEB02
     1 PVDDCR_CPU1_P1 @T6G_MB_LIB.T6G(SCH_1):PVDDCR_CPU1_P1    I40 @T6G_MB_LIB.T6G(SCH_1):PAGE72
     2    GND @T6G_MB_LIB.T6G(SCH_1):GND    I40 @T6G_MB_LIB.T6G(SCH_1):PAGE72

C2356 Q_CAP_C0402-22UF,4V,20%,X6S,CH622KMEB02
     1 PVDDCR_CPU1_P1 @T6G_MB_LIB.T6G(SCH_1):PVDDCR_CPU1_P1    I68 @T6G_MB_LIB.T6G(SCH_1):PAGE72
     2    GND @T6G_MB_LIB.T6G(SCH_1):GND    I68 @T6G_MB_LIB.T6G(SCH_1):PAGE72

C2357 Q_CAP_C0402-22UF,4V,20%,X6S,CH622KMEB02
     1 PVDDCR_CPU1_P1 @T6G_MB_LIB.T6G(SCH_1):PVDDCR_CPU1_P1    I58 @T6G_MB_LIB.T6G(SCH_1):PAGE72
     2    GND @T6G_MB_LIB.T6G(SCH_1):GND    I58 @T6G_MB_LIB.T6G(SCH_1):PAGE72

C2358 Q_CAP_C0402-22UF,4V,20%,X6S,CH622KMEB02
     1 PVDDCR_CPU1_P1 @T6G_MB_LIB.T6G(SCH_1):PVDDCR_CPU1_P1    I57 @T6G_MB_LIB.T6G(SCH_1):PAGE72
     2    GND @T6G_MB_LIB.T6G(SCH_1):GND    I57 @T6G_MB_LIB.T6G(SCH_1):PAGE72

C2359 Q_CAP_C0402-22UF,4V,20%,X6S,CH622KMEB02
     1 PVDDCR_CPU1_P1 @T6G_MB_LIB.T6G(SCH_1):PVDDCR_CPU1_P1    I53 @T6G_MB_LIB.T6G(SCH_1):PAGE72
     2    GND @T6G_MB_LIB.T6G(SCH_1):GND    I53 @T6G_MB_LIB.T6G(SCH_1):PAGE72

C2360 Q_CAP_C0402-22UF,4V,20%,X6S,CH622KMEB02
     1 PVDDCR_CPU1_P1 @T6G_MB_LIB.T6G(SCH_1):PVDDCR_CPU1_P1    I41 @T6G_MB_LIB.T6G(SCH_1):PAGE72
     2    GND @T6G_MB_LIB.T6G(SCH_1):GND    I41 @T6G_MB_LIB.T6G(SCH_1):PAGE72

C2362 Q_CAP_C0402-22UF,4V,20%,X6S,CH622KMEB02
     1 PVDDCR_CPU1_P1 @T6G_MB_LIB.T6G(SCH_1):PVDDCR_CPU1_P1   I101 @T6G_MB_LIB.T6G(SCH_1):PAGE72
     2    GND @T6G_MB_LIB.T6G(SCH_1):GND   I101 @T6G_MB_LIB.T6G(SCH_1):PAGE72

C2363 Q_CAP_C0402-22UF,4V,20%,X6S,CH622KMEB02
     1 PVDDCR_CPU1_P1 @T6G_MB_LIB.T6G(SCH_1):PVDDCR_CPU1_P1    I77 @T6G_MB_LIB.T6G(SCH_1):PAGE72
     2    GND @T6G_MB_LIB.T6G(SCH_1):GND    I77 @T6G_MB_LIB.T6G(SCH_1):PAGE72

C2364 Q_CAP_C0402-22UF,4V,20%,X6S,CH622KMEB02
     1 PVDDCR_CPU1_P1 @T6G_MB_LIB.T6G(SCH_1):PVDDCR_CPU1_P1    I76 @T6G_MB_LIB.T6G(SCH_1):PAGE72
     2    GND @T6G_MB_LIB.T6G(SCH_1):GND    I76 @T6G_MB_LIB.T6G(SCH_1):PAGE72

C2365 Q_CAP_C0402-22UF,4V,20%,X6S,CH622KMEB02
     1 PVDDCR_CPU1_P1 @T6G_MB_LIB.T6G(SCH_1):PVDDCR_CPU1_P1    I74 @T6G_MB_LIB.T6G(SCH_1):PAGE72
     2    GND @T6G_MB_LIB.T6G(SCH_1):GND    I74 @T6G_MB_LIB.T6G(SCH_1):PAGE72

C2366 Q_CAP_C0402-22UF,4V,20%,X6S,CH622KMEB02
     1 PVDDCR_CPU1_P1 @T6G_MB_LIB.T6G(SCH_1):PVDDCR_CPU1_P1    I70 @T6G_MB_LIB.T6G(SCH_1):PAGE72
     2    GND @T6G_MB_LIB.T6G(SCH_1):GND    I70 @T6G_MB_LIB.T6G(SCH_1):PAGE72

C2368 Q_CAP_C0402-22UF,4V,20%,X6S,CH622KMEB02
     1 PVDDCR_CPU1_P1 @T6G_MB_LIB.T6G(SCH_1):PVDDCR_CPU1_P1   I102 @T6G_MB_LIB.T6G(SCH_1):PAGE72
     2    GND @T6G_MB_LIB.T6G(SCH_1):GND   I102 @T6G_MB_LIB.T6G(SCH_1):PAGE72

C2369 Q_CAP_C0402-22UF,4V,20%,X6S,CH622KMEB02
     1 PVDDCR_CPU1_P1 @T6G_MB_LIB.T6G(SCH_1):PVDDCR_CPU1_P1    I79 @T6G_MB_LIB.T6G(SCH_1):PAGE72
     2    GND @T6G_MB_LIB.T6G(SCH_1):GND    I79 @T6G_MB_LIB.T6G(SCH_1):PAGE72

C2370 Q_CAP_C0402-22UF,4V,20%,X6S,CH622KMEB02
     1 PVDDCR_CPU1_P1 @T6G_MB_LIB.T6G(SCH_1):PVDDCR_CPU1_P1    I78 @T6G_MB_LIB.T6G(SCH_1):PAGE72
     2    GND @T6G_MB_LIB.T6G(SCH_1):GND    I78 @T6G_MB_LIB.T6G(SCH_1):PAGE72

C2371 Q_CAP_C0402-22UF,4V,20%,X6S,CH622KMEB02
     1 PVDDCR_CPU1_P1 @T6G_MB_LIB.T6G(SCH_1):PVDDCR_CPU1_P1    I75 @T6G_MB_LIB.T6G(SCH_1):PAGE72
     2    GND @T6G_MB_LIB.T6G(SCH_1):GND    I75 @T6G_MB_LIB.T6G(SCH_1):PAGE72

C2372 Q_CAP_C0402-22UF,4V,20%,X6S,CH622KMEB02
     1 PVDDCR_CPU1_P1 @T6G_MB_LIB.T6G(SCH_1):PVDDCR_CPU1_P1    I71 @T6G_MB_LIB.T6G(SCH_1):PAGE72
     2    GND @T6G_MB_LIB.T6G(SCH_1):GND    I71 @T6G_MB_LIB.T6G(SCH_1):PAGE72

C2374 Q_CAP_C0402-22UF,4V,20%,X6S,CH622KMEB02
     1 PVDDCR_CPU1_P1 @T6G_MB_LIB.T6G(SCH_1):PVDDCR_CPU1_P1   I103 @T6G_MB_LIB.T6G(SCH_1):PAGE72
     2    GND @T6G_MB_LIB.T6G(SCH_1):GND   I103 @T6G_MB_LIB.T6G(SCH_1):PAGE72

C2375 Q_CAP_C0402-22UF,4V,20%,X6S,CH622KMEB02
     1 PVDDCR_CPU1_P1 @T6G_MB_LIB.T6G(SCH_1):PVDDCR_CPU1_P1    I85 @T6G_MB_LIB.T6G(SCH_1):PAGE72
     2    GND @T6G_MB_LIB.T6G(SCH_1):GND    I85 @T6G_MB_LIB.T6G(SCH_1):PAGE72

C2376 Q_CAP_C0402-22UF,4V,20%,X6S,CH622KMEB02
     1 PVDDCR_CPU1_P1 @T6G_MB_LIB.T6G(SCH_1):PVDDCR_CPU1_P1    I80 @T6G_MB_LIB.T6G(SCH_1):PAGE72
     2    GND @T6G_MB_LIB.T6G(SCH_1):GND    I80 @T6G_MB_LIB.T6G(SCH_1):PAGE72

C2377 Q_CAP_C0402-22UF,4V,20%,X6S,CH622KMEB02
     1 PVDDCR_CPU1_P1 @T6G_MB_LIB.T6G(SCH_1):PVDDCR_CPU1_P1    I81 @T6G_MB_LIB.T6G(SCH_1):PAGE72
     2    GND @T6G_MB_LIB.T6G(SCH_1):GND    I81 @T6G_MB_LIB.T6G(SCH_1):PAGE72

C2378 Q_CAP_C0402-22UF,4V,20%,X6S,CH622KMEB02
     1 PVDDCR_CPU1_P1 @T6G_MB_LIB.T6G(SCH_1):PVDDCR_CPU1_P1    I72 @T6G_MB_LIB.T6G(SCH_1):PAGE72
     2    GND @T6G_MB_LIB.T6G(SCH_1):GND    I72 @T6G_MB_LIB.T6G(SCH_1):PAGE72

C2380 Q_CAP_C0402-22UF,4V,20%,X6S,CH622KMEB02
     1 PVDDCR_CPU1_P1 @T6G_MB_LIB.T6G(SCH_1):PVDDCR_CPU1_P1   I104 @T6G_MB_LIB.T6G(SCH_1):PAGE72
     2    GND @T6G_MB_LIB.T6G(SCH_1):GND   I104 @T6G_MB_LIB.T6G(SCH_1):PAGE72

C2381 Q_CAP_C0402-22UF,4V,20%,X6S,CH622KMEB02
     1 PVDDCR_CPU1_P1 @T6G_MB_LIB.T6G(SCH_1):PVDDCR_CPU1_P1    I86 @T6G_MB_LIB.T6G(SCH_1):PAGE72
     2    GND @T6G_MB_LIB.T6G(SCH_1):GND    I86 @T6G_MB_LIB.T6G(SCH_1):PAGE72

C2382 Q_CAP_C0402-22UF,4V,20%,X6S,CH622KMEB02
     1 PVDDCR_CPU1_P1 @T6G_MB_LIB.T6G(SCH_1):PVDDCR_CPU1_P1    I84 @T6G_MB_LIB.T6G(SCH_1):PAGE72
     2    GND @T6G_MB_LIB.T6G(SCH_1):GND    I84 @T6G_MB_LIB.T6G(SCH_1):PAGE72

C2383 Q_CAP_C0402-22UF,4V,20%,X6S,CH622KMEB02
     1 PVDDCR_CPU1_P1 @T6G_MB_LIB.T6G(SCH_1):PVDDCR_CPU1_P1    I82 @T6G_MB_LIB.T6G(SCH_1):PAGE72
     2    GND @T6G_MB_LIB.T6G(SCH_1):GND    I82 @T6G_MB_LIB.T6G(SCH_1):PAGE72

C2386 Q_CAP_C0402-22UF,4V,20%,X6S,CH622KMEB02
     1 PVDDCR_CPU1_P1 @T6G_MB_LIB.T6G(SCH_1):PVDDCR_CPU1_P1   I105 @T6G_MB_LIB.T6G(SCH_1):PAGE72
     2    GND @T6G_MB_LIB.T6G(SCH_1):GND   I105 @T6G_MB_LIB.T6G(SCH_1):PAGE72

C2387 Q_CAP_C0402-22UF,4V,20%,X6S,CH622KMEB02
     1 PVDDCR_CPU1_P1 @T6G_MB_LIB.T6G(SCH_1):PVDDCR_CPU1_P1    I88 @T6G_MB_LIB.T6G(SCH_1):PAGE72
     2    GND @T6G_MB_LIB.T6G(SCH_1):GND    I88 @T6G_MB_LIB.T6G(SCH_1):PAGE72

C2388 Q_CAP_C0402-22UF,4V,20%,X6S,CH622KMEB02
     1 PVDDCR_CPU1_P1 @T6G_MB_LIB.T6G(SCH_1):PVDDCR_CPU1_P1    I87 @T6G_MB_LIB.T6G(SCH_1):PAGE72
     2    GND @T6G_MB_LIB.T6G(SCH_1):GND    I87 @T6G_MB_LIB.T6G(SCH_1):PAGE72

C2389 Q_CAP_C0402-22UF,4V,20%,X6S,CH622KMEB02
     1 PVDDCR_CPU1_P1 @T6G_MB_LIB.T6G(SCH_1):PVDDCR_CPU1_P1    I83 @T6G_MB_LIB.T6G(SCH_1):PAGE72
     2    GND @T6G_MB_LIB.T6G(SCH_1):GND    I83 @T6G_MB_LIB.T6G(SCH_1):PAGE72

C2392 Q_CAP_C0402-22UF,4V,20%,X6S,CH622KMEB02
     1 PVDDCR_CPU1_P1 @T6G_MB_LIB.T6G(SCH_1):PVDDCR_CPU1_P1   I106 @T6G_MB_LIB.T6G(SCH_1):PAGE72
     2    GND @T6G_MB_LIB.T6G(SCH_1):GND   I106 @T6G_MB_LIB.T6G(SCH_1):PAGE72

C2393 Q_CAP_C0402-22UF,4V,20%,X6S,CH622KMEB02
     1 PVDDCR_CPU1_P1 @T6G_MB_LIB.T6G(SCH_1):PVDDCR_CPU1_P1    I92 @T6G_MB_LIB.T6G(SCH_1):PAGE72
     2    GND @T6G_MB_LIB.T6G(SCH_1):GND    I92 @T6G_MB_LIB.T6G(SCH_1):PAGE72

C2394 Q_CAP_C0402-22UF,4V,20%,X6S,CH622KMEB02
     1 PVDDCR_CPU1_P1 @T6G_MB_LIB.T6G(SCH_1):PVDDCR_CPU1_P1    I91 @T6G_MB_LIB.T6G(SCH_1):PAGE72
     2    GND @T6G_MB_LIB.T6G(SCH_1):GND    I91 @T6G_MB_LIB.T6G(SCH_1):PAGE72

C2395 Q_CAP_C0402-22UF,4V,20%,X6S,CH622KMEB02
     1 PVDDCR_CPU1_P1 @T6G_MB_LIB.T6G(SCH_1):PVDDCR_CPU1_P1    I89 @T6G_MB_LIB.T6G(SCH_1):PAGE72
     2    GND @T6G_MB_LIB.T6G(SCH_1):GND    I89 @T6G_MB_LIB.T6G(SCH_1):PAGE72

C2397 Q_CAP_C0402-22UF,4V,20%,X6S,CH622KMEB02
     1 PVDDCR_CPU1_P1 @T6G_MB_LIB.T6G(SCH_1):PVDDCR_CPU1_P1   I107 @T6G_MB_LIB.T6G(SCH_1):PAGE72
     2    GND @T6G_MB_LIB.T6G(SCH_1):GND   I107 @T6G_MB_LIB.T6G(SCH_1):PAGE72

C2398 Q_CAP_C0402-22UF,4V,20%,X6S,CH622KMEB02
     1 PVDDCR_CPU1_P1 @T6G_MB_LIB.T6G(SCH_1):PVDDCR_CPU1_P1    I94 @T6G_MB_LIB.T6G(SCH_1):PAGE72
     2    GND @T6G_MB_LIB.T6G(SCH_1):GND    I94 @T6G_MB_LIB.T6G(SCH_1):PAGE72

C2399 Q_CAP_C0402-22UF,4V,20%,X6S,CH622KMEB02
     1 PVDDCR_CPU1_P1 @T6G_MB_LIB.T6G(SCH_1):PVDDCR_CPU1_P1    I93 @T6G_MB_LIB.T6G(SCH_1):PAGE72
     2    GND @T6G_MB_LIB.T6G(SCH_1):GND    I93 @T6G_MB_LIB.T6G(SCH_1):PAGE72

C2400 Q_CAP_C0402-22UF,4V,20%,X6S,CH622KMEB02
     1 PVDDCR_CPU1_P1 @T6G_MB_LIB.T6G(SCH_1):PVDDCR_CPU1_P1    I90 @T6G_MB_LIB.T6G(SCH_1):PAGE72
     2    GND @T6G_MB_LIB.T6G(SCH_1):GND    I90 @T6G_MB_LIB.T6G(SCH_1):PAGE72

C2402 Q_CAP_C0402-22UF,4V,20%,X6S,CH622KMEB02
     1 PVDDCR_CPU1_P1 @T6G_MB_LIB.T6G(SCH_1):PVDDCR_CPU1_P1   I109 @T6G_MB_LIB.T6G(SCH_1):PAGE72
     2    GND @T6G_MB_LIB.T6G(SCH_1):GND   I109 @T6G_MB_LIB.T6G(SCH_1):PAGE72

C2403 Q_CAP_C0402-22UF,4V,20%,X6S,CH622KMEB02
     1 PVDDCR_CPU1_P1 @T6G_MB_LIB.T6G(SCH_1):PVDDCR_CPU1_P1   I100 @T6G_MB_LIB.T6G(SCH_1):PAGE72
     2    GND @T6G_MB_LIB.T6G(SCH_1):GND   I100 @T6G_MB_LIB.T6G(SCH_1):PAGE72

C2404 Q_CAP_C0402-22UF,4V,20%,X6S,CH622KMEB02
     1 PVDDCR_CPU1_P1 @T6G_MB_LIB.T6G(SCH_1):PVDDCR_CPU1_P1    I98 @T6G_MB_LIB.T6G(SCH_1):PAGE72
     2    GND @T6G_MB_LIB.T6G(SCH_1):GND    I98 @T6G_MB_LIB.T6G(SCH_1):PAGE72

C2405 Q_CAP_C0402-22UF,4V,20%,X6S,CH622KMEB02
     1 PVDDCR_CPU1_P1 @T6G_MB_LIB.T6G(SCH_1):PVDDCR_CPU1_P1    I96 @T6G_MB_LIB.T6G(SCH_1):PAGE72
     2    GND @T6G_MB_LIB.T6G(SCH_1):GND    I96 @T6G_MB_LIB.T6G(SCH_1):PAGE72

C2407 Q_CAP_C0402-22UF,4V,20%,X6S,CH622KMEB02
     1 PVDDCR_SOC_P1 @T6G_MB_LIB.T6G(SCH_1):PVDDCR_SOC_P1    I55 @T6G_MB_LIB.T6G(SCH_1):PAGE73
     2    GND @T6G_MB_LIB.T6G(SCH_1):GND    I55 @T6G_MB_LIB.T6G(SCH_1):PAGE73

C2408 Q_CAP_C0402-22UF,4V,20%,X6S,CH622KMEB02
     1 PVDDCR_SOC_P1 @T6G_MB_LIB.T6G(SCH_1):PVDDCR_SOC_P1    I53 @T6G_MB_LIB.T6G(SCH_1):PAGE73
     2    GND @T6G_MB_LIB.T6G(SCH_1):GND    I53 @T6G_MB_LIB.T6G(SCH_1):PAGE73

C2409 Q_CAP_C0402-22UF,4V,20%,X6S,CH622KMEB02
     1 PVDDCR_SOC_P1 @T6G_MB_LIB.T6G(SCH_1):PVDDCR_SOC_P1    I50 @T6G_MB_LIB.T6G(SCH_1):PAGE73
     2    GND @T6G_MB_LIB.T6G(SCH_1):GND    I50 @T6G_MB_LIB.T6G(SCH_1):PAGE73

C2410 Q_CAP_C0402-22UF,4V,20%,X6S,CH622KMEB02
     1 PVDDCR_SOC_P1 @T6G_MB_LIB.T6G(SCH_1):PVDDCR_SOC_P1    I16 @T6G_MB_LIB.T6G(SCH_1):PAGE73
     2    GND @T6G_MB_LIB.T6G(SCH_1):GND    I16 @T6G_MB_LIB.T6G(SCH_1):PAGE73

C2411 Q_CAP_C0402-22UF,4V,20%,X6S,CH622KMEB02
     1 PVDDCR_SOC_P1 @T6G_MB_LIB.T6G(SCH_1):PVDDCR_SOC_P1    I14 @T6G_MB_LIB.T6G(SCH_1):PAGE73
     2    GND @T6G_MB_LIB.T6G(SCH_1):GND    I14 @T6G_MB_LIB.T6G(SCH_1):PAGE73

C2412 Q_CAP_C0402-22UF,4V,20%,X6S,CH622KMEB02
     1 PVDDCR_SOC_P1 @T6G_MB_LIB.T6G(SCH_1):PVDDCR_SOC_P1    I11 @T6G_MB_LIB.T6G(SCH_1):PAGE73
     2    GND @T6G_MB_LIB.T6G(SCH_1):GND    I11 @T6G_MB_LIB.T6G(SCH_1):PAGE73

C2413 Q_CAP_C0402-22UF,4V,20%,X6S,CH622KMEB02
     1 PVDDCR_SOC_P1 @T6G_MB_LIB.T6G(SCH_1):PVDDCR_SOC_P1     I3 @T6G_MB_LIB.T6G(SCH_1):PAGE73
     2    GND @T6G_MB_LIB.T6G(SCH_1):GND     I3 @T6G_MB_LIB.T6G(SCH_1):PAGE73

C2414 Q_CAP_C0402-22UF,4V,20%,X6S,CH622KMEB02
     1 PVDDCR_SOC_P1 @T6G_MB_LIB.T6G(SCH_1):PVDDCR_SOC_P1    I57 @T6G_MB_LIB.T6G(SCH_1):PAGE73
     2    GND @T6G_MB_LIB.T6G(SCH_1):GND    I57 @T6G_MB_LIB.T6G(SCH_1):PAGE73

C2415 Q_CAP_C0402-22UF,4V,20%,X6S,CH622KMEB02
     1 PVDDCR_SOC_P1 @T6G_MB_LIB.T6G(SCH_1):PVDDCR_SOC_P1    I56 @T6G_MB_LIB.T6G(SCH_1):PAGE73
     2    GND @T6G_MB_LIB.T6G(SCH_1):GND    I56 @T6G_MB_LIB.T6G(SCH_1):PAGE73

C2416 Q_CAP_C0402-22UF,4V,20%,X6S,CH622KMEB02
     1 PVDDCR_SOC_P1 @T6G_MB_LIB.T6G(SCH_1):PVDDCR_SOC_P1    I52 @T6G_MB_LIB.T6G(SCH_1):PAGE73
     2    GND @T6G_MB_LIB.T6G(SCH_1):GND    I52 @T6G_MB_LIB.T6G(SCH_1):PAGE73

C2417 Q_CAP_C0402-22UF,4V,20%,X6S,CH622KMEB02
     1 PVDDCR_SOC_P1 @T6G_MB_LIB.T6G(SCH_1):PVDDCR_SOC_P1    I18 @T6G_MB_LIB.T6G(SCH_1):PAGE73
     2    GND @T6G_MB_LIB.T6G(SCH_1):GND    I18 @T6G_MB_LIB.T6G(SCH_1):PAGE73

C2418 Q_CAP_C0402-22UF,4V,20%,X6S,CH622KMEB02
     1 PVDDCR_SOC_P1 @T6G_MB_LIB.T6G(SCH_1):PVDDCR_SOC_P1    I17 @T6G_MB_LIB.T6G(SCH_1):PAGE73
     2    GND @T6G_MB_LIB.T6G(SCH_1):GND    I17 @T6G_MB_LIB.T6G(SCH_1):PAGE73

C2419 Q_CAP_C0402-22UF,4V,20%,X6S,CH622KMEB02
     1 PVDDCR_SOC_P1 @T6G_MB_LIB.T6G(SCH_1):PVDDCR_SOC_P1    I13 @T6G_MB_LIB.T6G(SCH_1):PAGE73
     2    GND @T6G_MB_LIB.T6G(SCH_1):GND    I13 @T6G_MB_LIB.T6G(SCH_1):PAGE73

C2420 Q_CAP_C0402-22UF,4V,20%,X6S,CH622KMEB02
     1 PVDDCR_SOC_P1 @T6G_MB_LIB.T6G(SCH_1):PVDDCR_SOC_P1     I5 @T6G_MB_LIB.T6G(SCH_1):PAGE73
     2    GND @T6G_MB_LIB.T6G(SCH_1):GND     I5 @T6G_MB_LIB.T6G(SCH_1):PAGE73

C2421 Q_CAP_C0402-22UF,4V,20%,X6S,CH622KMEB02
     1 PVDDCR_SOC_P1 @T6G_MB_LIB.T6G(SCH_1):PVDDCR_SOC_P1    I61 @T6G_MB_LIB.T6G(SCH_1):PAGE73
     2    GND @T6G_MB_LIB.T6G(SCH_1):GND    I61 @T6G_MB_LIB.T6G(SCH_1):PAGE73

C2422 Q_CAP_C0402-22UF,4V,20%,X6S,CH622KMEB02
     1 PVDDCR_SOC_P1 @T6G_MB_LIB.T6G(SCH_1):PVDDCR_SOC_P1    I60 @T6G_MB_LIB.T6G(SCH_1):PAGE73
     2    GND @T6G_MB_LIB.T6G(SCH_1):GND    I60 @T6G_MB_LIB.T6G(SCH_1):PAGE73

C2423 Q_CAP_C0402-22UF,4V,20%,X6S,CH622KMEB02
     1 PVDDCR_SOC_P1 @T6G_MB_LIB.T6G(SCH_1):PVDDCR_SOC_P1    I58 @T6G_MB_LIB.T6G(SCH_1):PAGE73
     2    GND @T6G_MB_LIB.T6G(SCH_1):GND    I58 @T6G_MB_LIB.T6G(SCH_1):PAGE73

C2424 Q_CAP_C0402-22UF,4V,20%,X6S,CH622KMEB02
     1 PVDDCR_SOC_P1 @T6G_MB_LIB.T6G(SCH_1):PVDDCR_SOC_P1    I22 @T6G_MB_LIB.T6G(SCH_1):PAGE73
     2    GND @T6G_MB_LIB.T6G(SCH_1):GND    I22 @T6G_MB_LIB.T6G(SCH_1):PAGE73

C2425 Q_CAP_C0402-22UF,4V,20%,X6S,CH622KMEB02
     1 PVDDCR_SOC_P1 @T6G_MB_LIB.T6G(SCH_1):PVDDCR_SOC_P1    I21 @T6G_MB_LIB.T6G(SCH_1):PAGE73
     2    GND @T6G_MB_LIB.T6G(SCH_1):GND    I21 @T6G_MB_LIB.T6G(SCH_1):PAGE73

C2426 Q_CAP_C0402-22UF,4V,20%,X6S,CH622KMEB02
     1 PVDDCR_SOC_P1 @T6G_MB_LIB.T6G(SCH_1):PVDDCR_SOC_P1    I19 @T6G_MB_LIB.T6G(SCH_1):PAGE73
     2    GND @T6G_MB_LIB.T6G(SCH_1):GND    I19 @T6G_MB_LIB.T6G(SCH_1):PAGE73

C2427 Q_CAP_C0402-22UF,4V,20%,X6S,CH622KMEB02
     1 PVDDCR_SOC_P1 @T6G_MB_LIB.T6G(SCH_1):PVDDCR_SOC_P1     I7 @T6G_MB_LIB.T6G(SCH_1):PAGE73
     2    GND @T6G_MB_LIB.T6G(SCH_1):GND     I7 @T6G_MB_LIB.T6G(SCH_1):PAGE73

C2428 Q_CAP_C0402-22UF,4V,20%,X6S,CH622KMEB02
     1 PVDDCR_SOC_P1 @T6G_MB_LIB.T6G(SCH_1):PVDDCR_SOC_P1   I175 @T6G_MB_LIB.T6G(SCH_1):PAGE73
     2    GND @T6G_MB_LIB.T6G(SCH_1):GND   I175 @T6G_MB_LIB.T6G(SCH_1):PAGE73

C2429 Q_CAP_C0402-22UF,4V,20%,X6S,CH622KMEB02
     1 PVDDCR_SOC_P1 @T6G_MB_LIB.T6G(SCH_1):PVDDCR_SOC_P1    I62 @T6G_MB_LIB.T6G(SCH_1):PAGE73
     2    GND @T6G_MB_LIB.T6G(SCH_1):GND    I62 @T6G_MB_LIB.T6G(SCH_1):PAGE73

C2430 Q_CAP_C0402-22UF,4V,20%,X6S,CH622KMEB02
     1 PVDDCR_SOC_P1 @T6G_MB_LIB.T6G(SCH_1):PVDDCR_SOC_P1    I59 @T6G_MB_LIB.T6G(SCH_1):PAGE73
     2    GND @T6G_MB_LIB.T6G(SCH_1):GND    I59 @T6G_MB_LIB.T6G(SCH_1):PAGE73

C2431 Q_CAP_C0402-22UF,4V,20%,X6S,CH622KMEB02
     1 PVDDCR_SOC_P1 @T6G_MB_LIB.T6G(SCH_1):PVDDCR_SOC_P1    I24 @T6G_MB_LIB.T6G(SCH_1):PAGE73
     2    GND @T6G_MB_LIB.T6G(SCH_1):GND    I24 @T6G_MB_LIB.T6G(SCH_1):PAGE73

C2432 Q_CAP_C0402-22UF,4V,20%,X6S,CH622KMEB02
     1 PVDDCR_SOC_P1 @T6G_MB_LIB.T6G(SCH_1):PVDDCR_SOC_P1    I23 @T6G_MB_LIB.T6G(SCH_1):PAGE73
     2    GND @T6G_MB_LIB.T6G(SCH_1):GND    I23 @T6G_MB_LIB.T6G(SCH_1):PAGE73

C2433 Q_CAP_C0402-22UF,4V,20%,X6S,CH622KMEB02
     1 PVDDCR_SOC_P1 @T6G_MB_LIB.T6G(SCH_1):PVDDCR_SOC_P1    I20 @T6G_MB_LIB.T6G(SCH_1):PAGE73
     2    GND @T6G_MB_LIB.T6G(SCH_1):GND    I20 @T6G_MB_LIB.T6G(SCH_1):PAGE73

C2434 Q_CAP_C0402-22UF,4V,20%,X6S,CH622KMEB02
     1 PVDDCR_SOC_P1 @T6G_MB_LIB.T6G(SCH_1):PVDDCR_SOC_P1     I9 @T6G_MB_LIB.T6G(SCH_1):PAGE73
     2    GND @T6G_MB_LIB.T6G(SCH_1):GND     I9 @T6G_MB_LIB.T6G(SCH_1):PAGE73

C2435 Q_CAP_C0402-22UF,4V,20%,X6S,CH622KMEB02
     1 PVDDCR_SOC_P1 @T6G_MB_LIB.T6G(SCH_1):PVDDCR_SOC_P1   I174 @T6G_MB_LIB.T6G(SCH_1):PAGE73
     2    GND @T6G_MB_LIB.T6G(SCH_1):GND   I174 @T6G_MB_LIB.T6G(SCH_1):PAGE73

C2436 Q_CAP_C0402-22UF,4V,20%,X6S,CH622KMEB02
     1 PVDDCR_SOC_P1 @T6G_MB_LIB.T6G(SCH_1):PVDDCR_SOC_P1    I66 @T6G_MB_LIB.T6G(SCH_1):PAGE73
     2    GND @T6G_MB_LIB.T6G(SCH_1):GND    I66 @T6G_MB_LIB.T6G(SCH_1):PAGE73

C2437 Q_CAP_C0402-22UF,4V,20%,X6S,CH622KMEB02
     1 PVDDCR_SOC_P1 @T6G_MB_LIB.T6G(SCH_1):PVDDCR_SOC_P1    I64 @T6G_MB_LIB.T6G(SCH_1):PAGE73
     2    GND @T6G_MB_LIB.T6G(SCH_1):GND    I64 @T6G_MB_LIB.T6G(SCH_1):PAGE73

C2438 Q_CAP_C0402-22UF,4V,20%,X6S,CH622KMEB02
     1 PVDDCR_SOC_P1 @T6G_MB_LIB.T6G(SCH_1):PVDDCR_SOC_P1    I37 @T6G_MB_LIB.T6G(SCH_1):PAGE73
     2    GND @T6G_MB_LIB.T6G(SCH_1):GND    I37 @T6G_MB_LIB.T6G(SCH_1):PAGE73

C2439 Q_CAP_C0402-22UF,4V,20%,X6S,CH622KMEB02
     1 PVDDCR_SOC_P1 @T6G_MB_LIB.T6G(SCH_1):PVDDCR_SOC_P1    I36 @T6G_MB_LIB.T6G(SCH_1):PAGE73
     2    GND @T6G_MB_LIB.T6G(SCH_1):GND    I36 @T6G_MB_LIB.T6G(SCH_1):PAGE73

C2440 Q_CAP_C0402-22UF,4V,20%,X6S,CH622KMEB02
     1 PVDDCR_SOC_P1 @T6G_MB_LIB.T6G(SCH_1):PVDDCR_SOC_P1    I34 @T6G_MB_LIB.T6G(SCH_1):PAGE73
     2    GND @T6G_MB_LIB.T6G(SCH_1):GND    I34 @T6G_MB_LIB.T6G(SCH_1):PAGE73

C2441 Q_CAP_C0402-22UF,4V,20%,X6S,CH622KMEB02
     1 PVDDCR_SOC_P1 @T6G_MB_LIB.T6G(SCH_1):PVDDCR_SOC_P1    I26 @T6G_MB_LIB.T6G(SCH_1):PAGE73
     2    GND @T6G_MB_LIB.T6G(SCH_1):GND    I26 @T6G_MB_LIB.T6G(SCH_1):PAGE73

C2442 Q_CAP_C0402-22UF,4V,20%,X6S,CH622KMEB02
     1 PVDDCR_SOC_P1 @T6G_MB_LIB.T6G(SCH_1):PVDDCR_SOC_P1   I173 @T6G_MB_LIB.T6G(SCH_1):PAGE73
     2    GND @T6G_MB_LIB.T6G(SCH_1):GND   I173 @T6G_MB_LIB.T6G(SCH_1):PAGE73

C2443 Q_CAP_C0402-22UF,4V,20%,X6S,CH622KMEB02
     1 PVDDCR_SOC_P1 @T6G_MB_LIB.T6G(SCH_1):PVDDCR_SOC_P1    I67 @T6G_MB_LIB.T6G(SCH_1):PAGE73
     2    GND @T6G_MB_LIB.T6G(SCH_1):GND    I67 @T6G_MB_LIB.T6G(SCH_1):PAGE73

C2444 Q_CAP_C0402-22UF,4V,20%,X6S,CH622KMEB02
     1 PVDDCR_SOC_P1 @T6G_MB_LIB.T6G(SCH_1):PVDDCR_SOC_P1    I65 @T6G_MB_LIB.T6G(SCH_1):PAGE73
     2    GND @T6G_MB_LIB.T6G(SCH_1):GND    I65 @T6G_MB_LIB.T6G(SCH_1):PAGE73

C2445 Q_CAP_C0402-22UF,4V,20%,X6S,CH622KMEB02
     1 PVDDCR_SOC_P1 @T6G_MB_LIB.T6G(SCH_1):PVDDCR_SOC_P1    I39 @T6G_MB_LIB.T6G(SCH_1):PAGE73
     2    GND @T6G_MB_LIB.T6G(SCH_1):GND    I39 @T6G_MB_LIB.T6G(SCH_1):PAGE73

C2446 Q_CAP_C0402-22UF,4V,20%,X6S,CH622KMEB02
     1 PVDDCR_SOC_P1 @T6G_MB_LIB.T6G(SCH_1):PVDDCR_SOC_P1    I38 @T6G_MB_LIB.T6G(SCH_1):PAGE73
     2    GND @T6G_MB_LIB.T6G(SCH_1):GND    I38 @T6G_MB_LIB.T6G(SCH_1):PAGE73

C2447 Q_CAP_C0402-22UF,4V,20%,X6S,CH622KMEB02
     1 PVDDCR_SOC_P1 @T6G_MB_LIB.T6G(SCH_1):PVDDCR_SOC_P1    I35 @T6G_MB_LIB.T6G(SCH_1):PAGE73
     2    GND @T6G_MB_LIB.T6G(SCH_1):GND    I35 @T6G_MB_LIB.T6G(SCH_1):PAGE73

C2448 Q_CAP_C0402-22UF,4V,20%,X6S,CH622KMEB02
     1 PVDDCR_SOC_P1 @T6G_MB_LIB.T6G(SCH_1):PVDDCR_SOC_P1    I28 @T6G_MB_LIB.T6G(SCH_1):PAGE73
     2    GND @T6G_MB_LIB.T6G(SCH_1):GND    I28 @T6G_MB_LIB.T6G(SCH_1):PAGE73

C2449 Q_CAP_C0402-22UF,4V,20%,X6S,CH622KMEB02
     1 PVDDCR_SOC_P1 @T6G_MB_LIB.T6G(SCH_1):PVDDCR_SOC_P1    I68 @T6G_MB_LIB.T6G(SCH_1):PAGE73
     2    GND @T6G_MB_LIB.T6G(SCH_1):GND    I68 @T6G_MB_LIB.T6G(SCH_1):PAGE73

C2450 Q_CAP_C0402-22UF,4V,20%,X6S,CH622KMEB02
     1 PVDDCR_SOC_P1 @T6G_MB_LIB.T6G(SCH_1):PVDDCR_SOC_P1    I69 @T6G_MB_LIB.T6G(SCH_1):PAGE73
     2    GND @T6G_MB_LIB.T6G(SCH_1):GND    I69 @T6G_MB_LIB.T6G(SCH_1):PAGE73

C2451 Q_CAP_C0402-22UF,4V,20%,X6S,CH622KMEB02
     1 PVDDCR_SOC_P1 @T6G_MB_LIB.T6G(SCH_1):PVDDCR_SOC_P1    I70 @T6G_MB_LIB.T6G(SCH_1):PAGE73
     2    GND @T6G_MB_LIB.T6G(SCH_1):GND    I70 @T6G_MB_LIB.T6G(SCH_1):PAGE73

C2452 Q_CAP_C0402-22UF,4V,20%,X6S,CH622KMEB02
     1 PVDDCR_SOC_P1 @T6G_MB_LIB.T6G(SCH_1):PVDDCR_SOC_P1    I40 @T6G_MB_LIB.T6G(SCH_1):PAGE73
     2    GND @T6G_MB_LIB.T6G(SCH_1):GND    I40 @T6G_MB_LIB.T6G(SCH_1):PAGE73

C2453 Q_CAP_C0402-22UF,4V,20%,X6S,CH622KMEB02
     1 PVDDCR_SOC_P1 @T6G_MB_LIB.T6G(SCH_1):PVDDCR_SOC_P1    I41 @T6G_MB_LIB.T6G(SCH_1):PAGE73
     2    GND @T6G_MB_LIB.T6G(SCH_1):GND    I41 @T6G_MB_LIB.T6G(SCH_1):PAGE73

C2454 Q_CAP_C0402-22UF,4V,20%,X6S,CH622KMEB02
     1 PVDDCR_SOC_P1 @T6G_MB_LIB.T6G(SCH_1):PVDDCR_SOC_P1    I42 @T6G_MB_LIB.T6G(SCH_1):PAGE73
     2    GND @T6G_MB_LIB.T6G(SCH_1):GND    I42 @T6G_MB_LIB.T6G(SCH_1):PAGE73

C2455 Q_CAP_C0402-22UF,4V,20%,X6S,CH622KMEB02
     1 PVDDCR_SOC_P1 @T6G_MB_LIB.T6G(SCH_1):PVDDCR_SOC_P1    I29 @T6G_MB_LIB.T6G(SCH_1):PAGE73
     2    GND @T6G_MB_LIB.T6G(SCH_1):GND    I29 @T6G_MB_LIB.T6G(SCH_1):PAGE73

C2456 Q_CAP_C0402-22UF,4V,20%,X6S,CH622KMEB02
     1 PVDDCR_SOC_P1 @T6G_MB_LIB.T6G(SCH_1):PVDDCR_SOC_P1    I74 @T6G_MB_LIB.T6G(SCH_1):PAGE73
     2    GND @T6G_MB_LIB.T6G(SCH_1):GND    I74 @T6G_MB_LIB.T6G(SCH_1):PAGE73

C2457 Q_CAP_C0402-22UF,4V,20%,X6S,CH622KMEB02
     1 PVDDCR_SOC_P1 @T6G_MB_LIB.T6G(SCH_1):PVDDCR_SOC_P1    I73 @T6G_MB_LIB.T6G(SCH_1):PAGE73
     2    GND @T6G_MB_LIB.T6G(SCH_1):GND    I73 @T6G_MB_LIB.T6G(SCH_1):PAGE73

C2458 Q_CAP_C0402-22UF,4V,20%,X6S,CH622KMEB02
     1 PVDDCR_SOC_P1 @T6G_MB_LIB.T6G(SCH_1):PVDDCR_SOC_P1    I71 @T6G_MB_LIB.T6G(SCH_1):PAGE73
     2    GND @T6G_MB_LIB.T6G(SCH_1):GND    I71 @T6G_MB_LIB.T6G(SCH_1):PAGE73

C2459 Q_CAP_C0402-22UF,4V,20%,X6S,CH622KMEB02
     1 PVDDCR_SOC_P1 @T6G_MB_LIB.T6G(SCH_1):PVDDCR_SOC_P1    I46 @T6G_MB_LIB.T6G(SCH_1):PAGE73
     2    GND @T6G_MB_LIB.T6G(SCH_1):GND    I46 @T6G_MB_LIB.T6G(SCH_1):PAGE73

C2460 Q_CAP_C0402-22UF,4V,20%,X6S,CH622KMEB02
     1 PVDDCR_SOC_P1 @T6G_MB_LIB.T6G(SCH_1):PVDDCR_SOC_P1    I45 @T6G_MB_LIB.T6G(SCH_1):PAGE73
     2    GND @T6G_MB_LIB.T6G(SCH_1):GND    I45 @T6G_MB_LIB.T6G(SCH_1):PAGE73

C2461 Q_CAP_C0402-22UF,4V,20%,X6S,CH622KMEB02
     1 PVDDCR_SOC_P1 @T6G_MB_LIB.T6G(SCH_1):PVDDCR_SOC_P1    I43 @T6G_MB_LIB.T6G(SCH_1):PAGE73
     2    GND @T6G_MB_LIB.T6G(SCH_1):GND    I43 @T6G_MB_LIB.T6G(SCH_1):PAGE73

C2462 Q_CAP_C0402-22UF,4V,20%,X6S,CH622KMEB02
     1 PVDDCR_SOC_P1 @T6G_MB_LIB.T6G(SCH_1):PVDDCR_SOC_P1    I32 @T6G_MB_LIB.T6G(SCH_1):PAGE73
     2    GND @T6G_MB_LIB.T6G(SCH_1):GND    I32 @T6G_MB_LIB.T6G(SCH_1):PAGE73

C2463 Q_CAP_C0402-22UF,4V,20%,X6S,CH622KMEB02
     1 PVDDCR_SOC_P1 @T6G_MB_LIB.T6G(SCH_1):PVDDCR_SOC_P1    I76 @T6G_MB_LIB.T6G(SCH_1):PAGE73
     2    GND @T6G_MB_LIB.T6G(SCH_1):GND    I76 @T6G_MB_LIB.T6G(SCH_1):PAGE73

C2464 Q_CAP_C0402-22UF,4V,20%,X6S,CH622KMEB02
     1 PVDDCR_SOC_P1 @T6G_MB_LIB.T6G(SCH_1):PVDDCR_SOC_P1    I75 @T6G_MB_LIB.T6G(SCH_1):PAGE73
     2    GND @T6G_MB_LIB.T6G(SCH_1):GND    I75 @T6G_MB_LIB.T6G(SCH_1):PAGE73

C2465 Q_CAP_C0402-22UF,4V,20%,X6S,CH622KMEB02
     1 PVDDCR_SOC_P1 @T6G_MB_LIB.T6G(SCH_1):PVDDCR_SOC_P1    I72 @T6G_MB_LIB.T6G(SCH_1):PAGE73
     2    GND @T6G_MB_LIB.T6G(SCH_1):GND    I72 @T6G_MB_LIB.T6G(SCH_1):PAGE73

C2466 Q_CAP_C0402-22UF,4V,20%,X6S,CH622KMEB02
     1 PVDDCR_SOC_P1 @T6G_MB_LIB.T6G(SCH_1):PVDDCR_SOC_P1    I48 @T6G_MB_LIB.T6G(SCH_1):PAGE73
     2    GND @T6G_MB_LIB.T6G(SCH_1):GND    I48 @T6G_MB_LIB.T6G(SCH_1):PAGE73

C2467 Q_CAP_C0402-22UF,4V,20%,X6S,CH622KMEB02
     1 PVDDCR_SOC_P1 @T6G_MB_LIB.T6G(SCH_1):PVDDCR_SOC_P1    I47 @T6G_MB_LIB.T6G(SCH_1):PAGE73
     2    GND @T6G_MB_LIB.T6G(SCH_1):GND    I47 @T6G_MB_LIB.T6G(SCH_1):PAGE73

C2468 Q_CAP_C0402-22UF,4V,20%,X6S,CH622KMEB02
     1 PVDDCR_SOC_P1 @T6G_MB_LIB.T6G(SCH_1):PVDDCR_SOC_P1    I44 @T6G_MB_LIB.T6G(SCH_1):PAGE73
     2    GND @T6G_MB_LIB.T6G(SCH_1):GND    I44 @T6G_MB_LIB.T6G(SCH_1):PAGE73

C2469 Q_CAP_C0402-22UF,4V,20%,X6S,CH622KMEB02
     1 PVDDCR_SOC_P1 @T6G_MB_LIB.T6G(SCH_1):PVDDCR_SOC_P1    I33 @T6G_MB_LIB.T6G(SCH_1):PAGE73
     2    GND @T6G_MB_LIB.T6G(SCH_1):GND    I33 @T6G_MB_LIB.T6G(SCH_1):PAGE73

C2470 Q_CAP_C0402-22UF,4V,20%,X6S,CH622KMEB02
     1 PVDDCR_SOC_P1 @T6G_MB_LIB.T6G(SCH_1):PVDDCR_SOC_P1   I133 @T6G_MB_LIB.T6G(SCH_1):PAGE73
     2    GND @T6G_MB_LIB.T6G(SCH_1):GND   I133 @T6G_MB_LIB.T6G(SCH_1):PAGE73

C2471 Q_CAP_C0402-22UF,4V,20%,X6S,CH622KMEB02
     1 PVDDCR_SOC_P1 @T6G_MB_LIB.T6G(SCH_1):PVDDCR_SOC_P1   I131 @T6G_MB_LIB.T6G(SCH_1):PAGE73
     2    GND @T6G_MB_LIB.T6G(SCH_1):GND   I131 @T6G_MB_LIB.T6G(SCH_1):PAGE73

C2472 Q_CAP_C0402-22UF,4V,20%,X6S,CH622KMEB02
     1 PVDDCR_SOC_P1 @T6G_MB_LIB.T6G(SCH_1):PVDDCR_SOC_P1   I127 @T6G_MB_LIB.T6G(SCH_1):PAGE73
     2    GND @T6G_MB_LIB.T6G(SCH_1):GND   I127 @T6G_MB_LIB.T6G(SCH_1):PAGE73

C2473 Q_CAP_C0402-22UF,4V,20%,X6S,CH622KMEB02
     1 PVDDCR_SOC_P1 @T6G_MB_LIB.T6G(SCH_1):PVDDCR_SOC_P1    I96 @T6G_MB_LIB.T6G(SCH_1):PAGE73
     2    GND @T6G_MB_LIB.T6G(SCH_1):GND    I96 @T6G_MB_LIB.T6G(SCH_1):PAGE73

C2474 Q_CAP_C0402-22UF,4V,20%,X6S,CH622KMEB02
     1 PVDDCR_SOC_P1 @T6G_MB_LIB.T6G(SCH_1):PVDDCR_SOC_P1    I94 @T6G_MB_LIB.T6G(SCH_1):PAGE73
     2    GND @T6G_MB_LIB.T6G(SCH_1):GND    I94 @T6G_MB_LIB.T6G(SCH_1):PAGE73

C2475 Q_CAP_C0402-22UF,4V,20%,X6S,CH622KMEB02
     1 PVDDCR_SOC_P1 @T6G_MB_LIB.T6G(SCH_1):PVDDCR_SOC_P1    I88 @T6G_MB_LIB.T6G(SCH_1):PAGE73
     2    GND @T6G_MB_LIB.T6G(SCH_1):GND    I88 @T6G_MB_LIB.T6G(SCH_1):PAGE73

C2476 Q_CAP_C0402-22UF,4V,20%,X6S,CH622KMEB02
     1 PVDDCR_SOC_P1 @T6G_MB_LIB.T6G(SCH_1):PVDDCR_SOC_P1    I79 @T6G_MB_LIB.T6G(SCH_1):PAGE73
     2    GND @T6G_MB_LIB.T6G(SCH_1):GND    I79 @T6G_MB_LIB.T6G(SCH_1):PAGE73

C2477 Q_CAP_C0402-22UF,4V,20%,X6S,CH622KMEB02
     1 PVDDIO_P1 @T6G_MB_LIB.T6G(SCH_1):PVDDIO_P1   I136 @T6G_MB_LIB.T6G(SCH_1):PAGE73
     2    GND @T6G_MB_LIB.T6G(SCH_1):GND   I136 @T6G_MB_LIB.T6G(SCH_1):PAGE73

C2478 Q_CAP_C0402-22UF,4V,20%,X6S,CH622KMEB02
     1 PVDDIO_P1 @T6G_MB_LIB.T6G(SCH_1):PVDDIO_P1   I134 @T6G_MB_LIB.T6G(SCH_1):PAGE73
     2    GND @T6G_MB_LIB.T6G(SCH_1):GND   I134 @T6G_MB_LIB.T6G(SCH_1):PAGE73

C2479 Q_CAP_C0402-22UF,4V,20%,X6S,CH622KMEB02
     1 PVDDIO_P1 @T6G_MB_LIB.T6G(SCH_1):PVDDIO_P1   I129 @T6G_MB_LIB.T6G(SCH_1):PAGE73
     2    GND @T6G_MB_LIB.T6G(SCH_1):GND   I129 @T6G_MB_LIB.T6G(SCH_1):PAGE73

C2480 Q_CAP_C0402-22UF,4V,20%,X6S,CH622KMEB02
     1 PVDD11_S3_P1 @T6G_MB_LIB.T6G(SCH_1):PVDD11_S3_P1    I97 @T6G_MB_LIB.T6G(SCH_1):PAGE73
     2    GND @T6G_MB_LIB.T6G(SCH_1):GND    I97 @T6G_MB_LIB.T6G(SCH_1):PAGE73

C2481 Q_CAP_C0402-22UF,4V,20%,X6S,CH622KMEB02
     1 PVDD11_S3_P1 @T6G_MB_LIB.T6G(SCH_1):PVDD11_S3_P1    I92 @T6G_MB_LIB.T6G(SCH_1):PAGE73
     2    GND @T6G_MB_LIB.T6G(SCH_1):GND    I92 @T6G_MB_LIB.T6G(SCH_1):PAGE73

C2482 Q_CAP_C0402-22UF,4V,20%,X6S,CH622KMEB02
     1 PVDD11_S3_P1 @T6G_MB_LIB.T6G(SCH_1):PVDD11_S3_P1    I90 @T6G_MB_LIB.T6G(SCH_1):PAGE73
     2    GND @T6G_MB_LIB.T6G(SCH_1):GND    I90 @T6G_MB_LIB.T6G(SCH_1):PAGE73

C2483 Q_CAP_C0402-22UF,4V,20%,X6S,CH622KMEB02
     1 PVDD11_S3_P1 @T6G_MB_LIB.T6G(SCH_1):PVDD11_S3_P1    I81 @T6G_MB_LIB.T6G(SCH_1):PAGE73
     2    GND @T6G_MB_LIB.T6G(SCH_1):GND    I81 @T6G_MB_LIB.T6G(SCH_1):PAGE73

C2484 Q_CAP_C0402-22UF,4V,20%,X6S,CH622KMEB02
     1 PVDDIO_P1 @T6G_MB_LIB.T6G(SCH_1):PVDDIO_P1   I139 @T6G_MB_LIB.T6G(SCH_1):PAGE73
     2    GND @T6G_MB_LIB.T6G(SCH_1):GND   I139 @T6G_MB_LIB.T6G(SCH_1):PAGE73

C2485 Q_CAP_C0402-22UF,4V,20%,X6S,CH622KMEB02
     1 PVDD11_S3_P1 @T6G_MB_LIB.T6G(SCH_1):PVDD11_S3_P1   I103 @T6G_MB_LIB.T6G(SCH_1):PAGE73
     2    GND @T6G_MB_LIB.T6G(SCH_1):GND   I103 @T6G_MB_LIB.T6G(SCH_1):PAGE73

C2486 Q_CAP_C0402-22UF,4V,20%,X6S,CH622KMEB02
     1 PVDD11_S3_P1 @T6G_MB_LIB.T6G(SCH_1):PVDD11_S3_P1   I100 @T6G_MB_LIB.T6G(SCH_1):PAGE73
     2    GND @T6G_MB_LIB.T6G(SCH_1):GND   I100 @T6G_MB_LIB.T6G(SCH_1):PAGE73

C2487 Q_CAP_C0402-22UF,4V,20%,X6S,CH622KMEB02
     1 PVDD11_S3_P1 @T6G_MB_LIB.T6G(SCH_1):PVDD11_S3_P1    I99 @T6G_MB_LIB.T6G(SCH_1):PAGE73
     2    GND @T6G_MB_LIB.T6G(SCH_1):GND    I99 @T6G_MB_LIB.T6G(SCH_1):PAGE73

C2488 Q_CAP_C0402-22UF,4V,20%,X6S,CH622KMEB02
     1 PVDD11_S3_P1 @T6G_MB_LIB.T6G(SCH_1):PVDD11_S3_P1    I85 @T6G_MB_LIB.T6G(SCH_1):PAGE73
     2    GND @T6G_MB_LIB.T6G(SCH_1):GND    I85 @T6G_MB_LIB.T6G(SCH_1):PAGE73

C2489 Q_CAP_C0402-22UF,4V,20%,X6S,CH622KMEB02
     1 PVDD11_S3_P1 @T6G_MB_LIB.T6G(SCH_1):PVDD11_S3_P1   I104 @T6G_MB_LIB.T6G(SCH_1):PAGE73
     2    GND @T6G_MB_LIB.T6G(SCH_1):GND   I104 @T6G_MB_LIB.T6G(SCH_1):PAGE73

C2490 Q_CAP_C0402-22UF,4V,20%,X6S,CH622KMEB02
     1 PVDD11_S3_P1 @T6G_MB_LIB.T6G(SCH_1):PVDD11_S3_P1   I102 @T6G_MB_LIB.T6G(SCH_1):PAGE73
     2    GND @T6G_MB_LIB.T6G(SCH_1):GND   I102 @T6G_MB_LIB.T6G(SCH_1):PAGE73

C2491 Q_CAP_C0402-22UF,4V,20%,X6S,CH622KMEB02
     1 PVDD11_S3_P1 @T6G_MB_LIB.T6G(SCH_1):PVDD11_S3_P1   I101 @T6G_MB_LIB.T6G(SCH_1):PAGE73
     2    GND @T6G_MB_LIB.T6G(SCH_1):GND   I101 @T6G_MB_LIB.T6G(SCH_1):PAGE73

C2492 Q_CAP_C0402-22UF,4V,20%,X6S,CH622KMEB02
     1 PVDD11_S3_P1 @T6G_MB_LIB.T6G(SCH_1):PVDD11_S3_P1    I86 @T6G_MB_LIB.T6G(SCH_1):PAGE73
     2    GND @T6G_MB_LIB.T6G(SCH_1):GND    I86 @T6G_MB_LIB.T6G(SCH_1):PAGE73

C2493 Q_CAP_C0402-22UF,4V,20%,X6S,CH622KMEB02
     1 PVDDIO_P1 @T6G_MB_LIB.T6G(SCH_1):PVDDIO_P1   I146 @T6G_MB_LIB.T6G(SCH_1):PAGE73
     2    GND @T6G_MB_LIB.T6G(SCH_1):GND   I146 @T6G_MB_LIB.T6G(SCH_1):PAGE73

C2494 Q_CAP_C0402-22UF,4V,20%,X6S,CH622KMEB02
     1 PVDD11_S3_P1 @T6G_MB_LIB.T6G(SCH_1):PVDD11_S3_P1   I114 @T6G_MB_LIB.T6G(SCH_1):PAGE73
     2    GND @T6G_MB_LIB.T6G(SCH_1):GND   I114 @T6G_MB_LIB.T6G(SCH_1):PAGE73

C2495 Q_CAP_C0402-22UF,4V,20%,X6S,CH622KMEB02
     1 PVDD11_S3_P1 @T6G_MB_LIB.T6G(SCH_1):PVDD11_S3_P1   I111 @T6G_MB_LIB.T6G(SCH_1):PAGE73
     2    GND @T6G_MB_LIB.T6G(SCH_1):GND   I111 @T6G_MB_LIB.T6G(SCH_1):PAGE73

C2496 Q_CAP_C0402-22UF,4V,20%,X6S,CH622KMEB02
     1 PVDD11_S3_P1 @T6G_MB_LIB.T6G(SCH_1):PVDD11_S3_P1   I110 @T6G_MB_LIB.T6G(SCH_1):PAGE73
     2    GND @T6G_MB_LIB.T6G(SCH_1):GND   I110 @T6G_MB_LIB.T6G(SCH_1):PAGE73

C2497 Q_CAP_C0402-22UF,4V,20%,X6S,CH622KMEB02
     1 PVDD11_S3_P1 @T6G_MB_LIB.T6G(SCH_1):PVDD11_S3_P1   I105 @T6G_MB_LIB.T6G(SCH_1):PAGE73
     2    GND @T6G_MB_LIB.T6G(SCH_1):GND   I105 @T6G_MB_LIB.T6G(SCH_1):PAGE73

C2498 Q_CAP_C0402-22UF,4V,20%,X6S,CH622KMEB02
     1 PVDDIO_P1 @T6G_MB_LIB.T6G(SCH_1):PVDDIO_P1   I147 @T6G_MB_LIB.T6G(SCH_1):PAGE73
     2    GND @T6G_MB_LIB.T6G(SCH_1):GND   I147 @T6G_MB_LIB.T6G(SCH_1):PAGE73

C2499 Q_CAP_C0402-22UF,4V,20%,X6S,CH622KMEB02
     1 PVDD11_S3_P1 @T6G_MB_LIB.T6G(SCH_1):PVDD11_S3_P1   I116 @T6G_MB_LIB.T6G(SCH_1):PAGE73
     2    GND @T6G_MB_LIB.T6G(SCH_1):GND   I116 @T6G_MB_LIB.T6G(SCH_1):PAGE73

C2500 Q_CAP_C0402-22UF,4V,20%,X6S,CH622KMEB02
     1 PVDD11_S3_P1 @T6G_MB_LIB.T6G(SCH_1):PVDD11_S3_P1   I113 @T6G_MB_LIB.T6G(SCH_1):PAGE73
     2    GND @T6G_MB_LIB.T6G(SCH_1):GND   I113 @T6G_MB_LIB.T6G(SCH_1):PAGE73

C2501 Q_CAP_C0402-22UF,4V,20%,X6S,CH622KMEB02
     1 PVDD11_S3_P1 @T6G_MB_LIB.T6G(SCH_1):PVDD11_S3_P1   I112 @T6G_MB_LIB.T6G(SCH_1):PAGE73
     2    GND @T6G_MB_LIB.T6G(SCH_1):GND   I112 @T6G_MB_LIB.T6G(SCH_1):PAGE73

C2502 Q_CAP_C0402-22UF,4V,20%,X6S,CH622KMEB02
     1 PVDD11_S3_P1 @T6G_MB_LIB.T6G(SCH_1):PVDD11_S3_P1   I106 @T6G_MB_LIB.T6G(SCH_1):PAGE73
     2    GND @T6G_MB_LIB.T6G(SCH_1):GND   I106 @T6G_MB_LIB.T6G(SCH_1):PAGE73

C2503 Q_CAP_C0402-22UF,4V,20%,X6S,CH622KMEB02
     1 PVDD11_S3_P1 @T6G_MB_LIB.T6G(SCH_1):PVDD11_S3_P1   I123 @T6G_MB_LIB.T6G(SCH_1):PAGE73
     2    GND @T6G_MB_LIB.T6G(SCH_1):GND   I123 @T6G_MB_LIB.T6G(SCH_1):PAGE73

C2504 Q_CAP_C0402-22UF,4V,20%,X6S,CH622KMEB02
     1 PVDD11_S3_P1 @T6G_MB_LIB.T6G(SCH_1):PVDD11_S3_P1   I118 @T6G_MB_LIB.T6G(SCH_1):PAGE73
     2    GND @T6G_MB_LIB.T6G(SCH_1):GND   I118 @T6G_MB_LIB.T6G(SCH_1):PAGE73

C2505 Q_CAP_C0402-22UF,4V,20%,X6S,CH622KMEB02
     1 PVDD11_S3_P1 @T6G_MB_LIB.T6G(SCH_1):PVDD11_S3_P1   I117 @T6G_MB_LIB.T6G(SCH_1):PAGE73
     2    GND @T6G_MB_LIB.T6G(SCH_1):GND   I117 @T6G_MB_LIB.T6G(SCH_1):PAGE73

C2506 Q_CAP_C0402-22UF,4V,20%,X6S,CH622KMEB02
     1 PVDD11_S3_P1 @T6G_MB_LIB.T6G(SCH_1):PVDD11_S3_P1   I107 @T6G_MB_LIB.T6G(SCH_1):PAGE73
     2    GND @T6G_MB_LIB.T6G(SCH_1):GND   I107 @T6G_MB_LIB.T6G(SCH_1):PAGE73

C2507 Q_CAP_C0402-22UF,4V,20%,X6S,CH622KMEB02
     1 PVDDIO_P1 @T6G_MB_LIB.T6G(SCH_1):PVDDIO_P1   I152 @T6G_MB_LIB.T6G(SCH_1):PAGE73
     2    GND @T6G_MB_LIB.T6G(SCH_1):GND   I152 @T6G_MB_LIB.T6G(SCH_1):PAGE73

C2508 Q_CAP_C0402-22UF,4V,20%,X6S,CH622KMEB02
     1 PVDD11_S3_P1 @T6G_MB_LIB.T6G(SCH_1):PVDD11_S3_P1   I124 @T6G_MB_LIB.T6G(SCH_1):PAGE73
     2    GND @T6G_MB_LIB.T6G(SCH_1):GND   I124 @T6G_MB_LIB.T6G(SCH_1):PAGE73

C2509 Q_CAP_C0402-22UF,4V,20%,X6S,CH622KMEB02
     1 PVDDIO_P1 @T6G_MB_LIB.T6G(SCH_1):PVDDIO_P1   I170 @T6G_MB_LIB.T6G(SCH_1):PAGE73
     2    GND @T6G_MB_LIB.T6G(SCH_1):GND   I170 @T6G_MB_LIB.T6G(SCH_1):PAGE73

C2510 Q_CAP_C0402-22UF,4V,20%,X6S,CH622KMEB02
     1 PVDD11_S3_P1 @T6G_MB_LIB.T6G(SCH_1):PVDD11_S3_P1   I163 @T6G_MB_LIB.T6G(SCH_1):PAGE73
     2    GND @T6G_MB_LIB.T6G(SCH_1):GND   I163 @T6G_MB_LIB.T6G(SCH_1):PAGE73

C2511 Q_CAP_C0402-22UF,4V,20%,X6S,CH622KMEB02
     1 PVDD11_S3_P1 @T6G_MB_LIB.T6G(SCH_1):PVDD11_S3_P1   I161 @T6G_MB_LIB.T6G(SCH_1):PAGE73
     2    GND @T6G_MB_LIB.T6G(SCH_1):GND   I161 @T6G_MB_LIB.T6G(SCH_1):PAGE73

C2512 Q_CAP_C0402-10UF,6.3V,20%,X6S,CH6101MEB01
     1 PVDD_33_S5 @T6G_MB_LIB.T6G(SCH_1):PVDD_33_S5    I26 @T6G_MB_LIB.T6G(SCH_1):PAGE70
     2    GND @T6G_MB_LIB.T6G(SCH_1):GND    I26 @T6G_MB_LIB.T6G(SCH_1):PAGE70

C2513 Q_CAP_C0402-22UF,4V,20%,X6S,CH622KMEB02
     1 PVDD18_S5_P0 @T6G_MB_LIB.T6G(SCH_1):PVDD18_S5_P0     I3 @T6G_MB_LIB.T6G(SCH_1):PAGE70
     2    GND @T6G_MB_LIB.T6G(SCH_1):GND     I3 @T6G_MB_LIB.T6G(SCH_1):PAGE70

C2514 Q_CAP_C0402-22UF,4V,20%,X6S,CH622KMEB02
     1 PVDD18_S5_P0 @T6G_MB_LIB.T6G(SCH_1):PVDD18_S5_P0     I1 @T6G_MB_LIB.T6G(SCH_1):PAGE70
     2    GND @T6G_MB_LIB.T6G(SCH_1):GND     I1 @T6G_MB_LIB.T6G(SCH_1):PAGE70

C2515 Q_CAP_C0402-10UF,6.3V,20%,X6S,CH6101MEB01
     1 PVDD_33_S5 @T6G_MB_LIB.T6G(SCH_1):PVDD_33_S5    I25 @T6G_MB_LIB.T6G(SCH_1):PAGE70
     2    GND @T6G_MB_LIB.T6G(SCH_1):GND    I25 @T6G_MB_LIB.T6G(SCH_1):PAGE70

C2516 Q_CAP_C0402-22UF,4V,20%,X6S,CH622KMEB02
     1 PVDD18_S5_P0 @T6G_MB_LIB.T6G(SCH_1):PVDD18_S5_P0     I9 @T6G_MB_LIB.T6G(SCH_1):PAGE70
     2    GND @T6G_MB_LIB.T6G(SCH_1):GND     I9 @T6G_MB_LIB.T6G(SCH_1):PAGE70

C2517 Q_CAP_C0402-22UF,4V,20%,X6S,CH622KMEB02
     1 PVDD18_S5_P0 @T6G_MB_LIB.T6G(SCH_1):PVDD18_S5_P0     I8 @T6G_MB_LIB.T6G(SCH_1):PAGE70
     2    GND @T6G_MB_LIB.T6G(SCH_1):GND     I8 @T6G_MB_LIB.T6G(SCH_1):PAGE70

C2518 Q_CAP_C0402-22UF,4V,20%,X6S,CH622KMEB02
     1 PVDD18_S5_P0 @T6G_MB_LIB.T6G(SCH_1):PVDD18_S5_P0    I10 @T6G_MB_LIB.T6G(SCH_1):PAGE70
     2    GND @T6G_MB_LIB.T6G(SCH_1):GND    I10 @T6G_MB_LIB.T6G(SCH_1):PAGE70

C2520 Q_CAP_C0402-22UF,4V,20%,X6S,CH622KMEB02
     1 PVDD18_S5_P0 @T6G_MB_LIB.T6G(SCH_1):PVDD18_S5_P0    I11 @T6G_MB_LIB.T6G(SCH_1):PAGE70
     2    GND @T6G_MB_LIB.T6G(SCH_1):GND    I11 @T6G_MB_LIB.T6G(SCH_1):PAGE70

C2521 Q_CAP_C0402-22UF,4V,20%,X6S,CH622KMEB02
     1 PVDD18_S5_P0 @T6G_MB_LIB.T6G(SCH_1):PVDD18_S5_P0    I12 @T6G_MB_LIB.T6G(SCH_1):PAGE70
     2    GND @T6G_MB_LIB.T6G(SCH_1):GND    I12 @T6G_MB_LIB.T6G(SCH_1):PAGE70

C2522 Q_CAP_C0402-22UF,4V,20%,X6S,CH622KMEB02
     1 PVDD18_S5_P0 @T6G_MB_LIB.T6G(SCH_1):PVDD18_S5_P0    I13 @T6G_MB_LIB.T6G(SCH_1):PAGE70
     2    GND @T6G_MB_LIB.T6G(SCH_1):GND    I13 @T6G_MB_LIB.T6G(SCH_1):PAGE70

C2523 Q_CAP_C0402-22UF,4V,20%,X6S,CH622KMEB02
     1 PVDD18_S5_P0 @T6G_MB_LIB.T6G(SCH_1):PVDD18_S5_P0    I14 @T6G_MB_LIB.T6G(SCH_1):PAGE70
     2    GND @T6G_MB_LIB.T6G(SCH_1):GND    I14 @T6G_MB_LIB.T6G(SCH_1):PAGE70

C2524 Q_CAP_C0402-22UF,4V,20%,X6S,CH622KMEB02
     1 PVDD18_S5_P0 @T6G_MB_LIB.T6G(SCH_1):PVDD18_S5_P0    I15 @T6G_MB_LIB.T6G(SCH_1):PAGE70
     2    GND @T6G_MB_LIB.T6G(SCH_1):GND    I15 @T6G_MB_LIB.T6G(SCH_1):PAGE70

C2525 Q_CAP_C0402-22UF,4V,20%,X6S,CH622KMEB02
     1 PVDD18_S5_P0 @T6G_MB_LIB.T6G(SCH_1):PVDD18_S5_P0    I16 @T6G_MB_LIB.T6G(SCH_1):PAGE70
     2    GND @T6G_MB_LIB.T6G(SCH_1):GND    I16 @T6G_MB_LIB.T6G(SCH_1):PAGE70

C2526 Q_CAP_C0402-22UF,4V,20%,X6S,CH622KMEB02
     1 PVDD18_S5_P0 @T6G_MB_LIB.T6G(SCH_1):PVDD18_S5_P0    I18 @T6G_MB_LIB.T6G(SCH_1):PAGE70
     2    GND @T6G_MB_LIB.T6G(SCH_1):GND    I18 @T6G_MB_LIB.T6G(SCH_1):PAGE70

C2527 Q_CAP_C0402-22UF,4V,20%,X6S,CH622KMEB02
     1 PVDDCR_SOC_P0 @T6G_MB_LIB.T6G(SCH_1):PVDDCR_SOC_P0    I22 @T6G_MB_LIB.T6G(SCH_1):PAGE69
     2    GND @T6G_MB_LIB.T6G(SCH_1):GND    I22 @T6G_MB_LIB.T6G(SCH_1):PAGE69

C2528 Q_CAP_C0402-22UF,4V,20%,X6S,CH622KMEB02
     1 PVDDCR_SOC_P0 @T6G_MB_LIB.T6G(SCH_1):PVDDCR_SOC_P0    I18 @T6G_MB_LIB.T6G(SCH_1):PAGE69
     2    GND @T6G_MB_LIB.T6G(SCH_1):GND    I18 @T6G_MB_LIB.T6G(SCH_1):PAGE69

C2529 Q_CAP_C0402-22UF,4V,20%,X6S,CH622KMEB02
     1 PVDDCR_SOC_P0 @T6G_MB_LIB.T6G(SCH_1):PVDDCR_SOC_P0    I16 @T6G_MB_LIB.T6G(SCH_1):PAGE69
     2    GND @T6G_MB_LIB.T6G(SCH_1):GND    I16 @T6G_MB_LIB.T6G(SCH_1):PAGE69

C2530 Q_CAP_C0402-22UF,4V,20%,X6S,CH622KMEB02
     1 PVDDCR_SOC_P0 @T6G_MB_LIB.T6G(SCH_1):PVDDCR_SOC_P0    I13 @T6G_MB_LIB.T6G(SCH_1):PAGE69
     2    GND @T6G_MB_LIB.T6G(SCH_1):GND    I13 @T6G_MB_LIB.T6G(SCH_1):PAGE69

C2531 Q_CAP_C0402-22UF,4V,20%,X6S,CH622KMEB02
     1 PVDDCR_SOC_P0 @T6G_MB_LIB.T6G(SCH_1):PVDDCR_SOC_P0     I9 @T6G_MB_LIB.T6G(SCH_1):PAGE69
     2    GND @T6G_MB_LIB.T6G(SCH_1):GND     I9 @T6G_MB_LIB.T6G(SCH_1):PAGE69

C2532 Q_CAP_C0402-22UF,4V,20%,X6S,CH622KMEB02
     1 PVDDCR_SOC_P0 @T6G_MB_LIB.T6G(SCH_1):PVDDCR_SOC_P0     I7 @T6G_MB_LIB.T6G(SCH_1):PAGE69
     2    GND @T6G_MB_LIB.T6G(SCH_1):GND     I7 @T6G_MB_LIB.T6G(SCH_1):PAGE69

C2533 Q_CAP_C0402-22UF,4V,20%,X6S,CH622KMEB02
     1 PVDDCR_SOC_P0 @T6G_MB_LIB.T6G(SCH_1):PVDDCR_SOC_P0     I4 @T6G_MB_LIB.T6G(SCH_1):PAGE69
     2    GND @T6G_MB_LIB.T6G(SCH_1):GND     I4 @T6G_MB_LIB.T6G(SCH_1):PAGE69

C2534 Q_CAP_C0402-22UF,4V,20%,X6S,CH622KMEB02
     1 PVDDCR_SOC_P0 @T6G_MB_LIB.T6G(SCH_1):PVDDCR_SOC_P0    I24 @T6G_MB_LIB.T6G(SCH_1):PAGE69
     2    GND @T6G_MB_LIB.T6G(SCH_1):GND    I24 @T6G_MB_LIB.T6G(SCH_1):PAGE69

C2535 Q_CAP_C0402-22UF,4V,20%,X6S,CH622KMEB02
     1 PVDDCR_SOC_P0 @T6G_MB_LIB.T6G(SCH_1):PVDDCR_SOC_P0    I20 @T6G_MB_LIB.T6G(SCH_1):PAGE69
     2    GND @T6G_MB_LIB.T6G(SCH_1):GND    I20 @T6G_MB_LIB.T6G(SCH_1):PAGE69

C2536 Q_CAP_C0402-22UF,4V,20%,X6S,CH622KMEB02
     1 PVDDCR_SOC_P0 @T6G_MB_LIB.T6G(SCH_1):PVDDCR_SOC_P0    I19 @T6G_MB_LIB.T6G(SCH_1):PAGE69
     2    GND @T6G_MB_LIB.T6G(SCH_1):GND    I19 @T6G_MB_LIB.T6G(SCH_1):PAGE69

C2537 Q_CAP_C0402-22UF,4V,20%,X6S,CH622KMEB02
     1 PVDDCR_SOC_P0 @T6G_MB_LIB.T6G(SCH_1):PVDDCR_SOC_P0    I15 @T6G_MB_LIB.T6G(SCH_1):PAGE69
     2    GND @T6G_MB_LIB.T6G(SCH_1):GND    I15 @T6G_MB_LIB.T6G(SCH_1):PAGE69

C2538 Q_CAP_C0402-22UF,4V,20%,X6S,CH622KMEB02
     1 PVDDCR_SOC_P0 @T6G_MB_LIB.T6G(SCH_1):PVDDCR_SOC_P0    I11 @T6G_MB_LIB.T6G(SCH_1):PAGE69
     2    GND @T6G_MB_LIB.T6G(SCH_1):GND    I11 @T6G_MB_LIB.T6G(SCH_1):PAGE69

C2539 Q_CAP_C0402-22UF,4V,20%,X6S,CH622KMEB02
     1 PVDDCR_SOC_P0 @T6G_MB_LIB.T6G(SCH_1):PVDDCR_SOC_P0    I10 @T6G_MB_LIB.T6G(SCH_1):PAGE69
     2    GND @T6G_MB_LIB.T6G(SCH_1):GND    I10 @T6G_MB_LIB.T6G(SCH_1):PAGE69

C2540 Q_CAP_C0402-22UF,4V,20%,X6S,CH622KMEB02
     1 PVDDCR_SOC_P0 @T6G_MB_LIB.T6G(SCH_1):PVDDCR_SOC_P0     I6 @T6G_MB_LIB.T6G(SCH_1):PAGE69
     2    GND @T6G_MB_LIB.T6G(SCH_1):GND     I6 @T6G_MB_LIB.T6G(SCH_1):PAGE69

C2541 Q_CAP_C0402-22UF,4V,20%,X6S,CH622KMEB02
     1 PVDDCR_SOC_P0 @T6G_MB_LIB.T6G(SCH_1):PVDDCR_SOC_P0    I84 @T6G_MB_LIB.T6G(SCH_1):PAGE69
     2    GND @T6G_MB_LIB.T6G(SCH_1):GND    I84 @T6G_MB_LIB.T6G(SCH_1):PAGE69

C2542 Q_CAP_C0402-22UF,4V,20%,X6S,CH622KMEB02
     1 PVDDCR_SOC_P0 @T6G_MB_LIB.T6G(SCH_1):PVDDCR_SOC_P0    I79 @T6G_MB_LIB.T6G(SCH_1):PAGE69
     2    GND @T6G_MB_LIB.T6G(SCH_1):GND    I79 @T6G_MB_LIB.T6G(SCH_1):PAGE69

C2543 Q_CAP_C0402-22UF,4V,20%,X6S,CH622KMEB02
     1 PVDDCR_SOC_P0 @T6G_MB_LIB.T6G(SCH_1):PVDDCR_SOC_P0    I78 @T6G_MB_LIB.T6G(SCH_1):PAGE69
     2    GND @T6G_MB_LIB.T6G(SCH_1):GND    I78 @T6G_MB_LIB.T6G(SCH_1):PAGE69

C2544 Q_CAP_C0402-22UF,4V,20%,X6S,CH622KMEB02
     1 PVDDCR_SOC_P0 @T6G_MB_LIB.T6G(SCH_1):PVDDCR_SOC_P0    I42 @T6G_MB_LIB.T6G(SCH_1):PAGE69
     2    GND @T6G_MB_LIB.T6G(SCH_1):GND    I42 @T6G_MB_LIB.T6G(SCH_1):PAGE69

C2545 Q_CAP_C0402-22UF,4V,20%,X6S,CH622KMEB02
     1 PVDDCR_SOC_P0 @T6G_MB_LIB.T6G(SCH_1):PVDDCR_SOC_P0    I37 @T6G_MB_LIB.T6G(SCH_1):PAGE69
     2    GND @T6G_MB_LIB.T6G(SCH_1):GND    I37 @T6G_MB_LIB.T6G(SCH_1):PAGE69

C2546 Q_CAP_C0402-22UF,4V,20%,X6S,CH622KMEB02
     1 PVDDCR_SOC_P0 @T6G_MB_LIB.T6G(SCH_1):PVDDCR_SOC_P0    I36 @T6G_MB_LIB.T6G(SCH_1):PAGE69
     2    GND @T6G_MB_LIB.T6G(SCH_1):GND    I36 @T6G_MB_LIB.T6G(SCH_1):PAGE69

C2547 Q_CAP_C0402-22UF,4V,20%,X6S,CH622KMEB02
     1 PVDDCR_SOC_P0 @T6G_MB_LIB.T6G(SCH_1):PVDDCR_SOC_P0    I28 @T6G_MB_LIB.T6G(SCH_1):PAGE69
     2    GND @T6G_MB_LIB.T6G(SCH_1):GND    I28 @T6G_MB_LIB.T6G(SCH_1):PAGE69

C2548 Q_CAP_C0402-22UF,4V,20%,X6S,CH622KMEB02
     1 PVDDCR_SOC_P0 @T6G_MB_LIB.T6G(SCH_1):PVDDCR_SOC_P0    I85 @T6G_MB_LIB.T6G(SCH_1):PAGE69
     2    GND @T6G_MB_LIB.T6G(SCH_1):GND    I85 @T6G_MB_LIB.T6G(SCH_1):PAGE69

C2549 Q_CAP_C0402-22UF,4V,20%,X6S,CH622KMEB02
     1 PVDDCR_SOC_P0 @T6G_MB_LIB.T6G(SCH_1):PVDDCR_SOC_P0    I81 @T6G_MB_LIB.T6G(SCH_1):PAGE69
     2    GND @T6G_MB_LIB.T6G(SCH_1):GND    I81 @T6G_MB_LIB.T6G(SCH_1):PAGE69

C2550 Q_CAP_C0402-22UF,4V,20%,X6S,CH622KMEB02
     1 PVDDCR_SOC_P0 @T6G_MB_LIB.T6G(SCH_1):PVDDCR_SOC_P0    I80 @T6G_MB_LIB.T6G(SCH_1):PAGE69
     2    GND @T6G_MB_LIB.T6G(SCH_1):GND    I80 @T6G_MB_LIB.T6G(SCH_1):PAGE69

C2551 Q_CAP_C0402-22UF,4V,20%,X6S,CH622KMEB02
     1 PVDDCR_SOC_P0 @T6G_MB_LIB.T6G(SCH_1):PVDDCR_SOC_P0    I43 @T6G_MB_LIB.T6G(SCH_1):PAGE69
     2    GND @T6G_MB_LIB.T6G(SCH_1):GND    I43 @T6G_MB_LIB.T6G(SCH_1):PAGE69

C2552 Q_CAP_C0402-22UF,4V,20%,X6S,CH622KMEB02
     1 PVDDCR_SOC_P0 @T6G_MB_LIB.T6G(SCH_1):PVDDCR_SOC_P0    I40 @T6G_MB_LIB.T6G(SCH_1):PAGE69
     2    GND @T6G_MB_LIB.T6G(SCH_1):GND    I40 @T6G_MB_LIB.T6G(SCH_1):PAGE69

C2553 Q_CAP_C0402-22UF,4V,20%,X6S,CH622KMEB02
     1 PVDDCR_SOC_P0 @T6G_MB_LIB.T6G(SCH_1):PVDDCR_SOC_P0    I38 @T6G_MB_LIB.T6G(SCH_1):PAGE69
     2    GND @T6G_MB_LIB.T6G(SCH_1):GND    I38 @T6G_MB_LIB.T6G(SCH_1):PAGE69

C2554 Q_CAP_C0402-22UF,4V,20%,X6S,CH622KMEB02
     1 PVDDCR_SOC_P0 @T6G_MB_LIB.T6G(SCH_1):PVDDCR_SOC_P0    I29 @T6G_MB_LIB.T6G(SCH_1):PAGE69
     2    GND @T6G_MB_LIB.T6G(SCH_1):GND    I29 @T6G_MB_LIB.T6G(SCH_1):PAGE69

C2555 Q_CAP_C0402-22UF,4V,20%,X6S,CH622KMEB02
     1 PVDDCR_SOC_P0 @T6G_MB_LIB.T6G(SCH_1):PVDDCR_SOC_P0    I86 @T6G_MB_LIB.T6G(SCH_1):PAGE69
     2    GND @T6G_MB_LIB.T6G(SCH_1):GND    I86 @T6G_MB_LIB.T6G(SCH_1):PAGE69

C2556 Q_CAP_C0402-22UF,4V,20%,X6S,CH622KMEB02
     1 PVDDCR_SOC_P0 @T6G_MB_LIB.T6G(SCH_1):PVDDCR_SOC_P0    I83 @T6G_MB_LIB.T6G(SCH_1):PAGE69
     2    GND @T6G_MB_LIB.T6G(SCH_1):GND    I83 @T6G_MB_LIB.T6G(SCH_1):PAGE69

C2557 Q_CAP_C0402-22UF,4V,20%,X6S,CH622KMEB02
     1 PVDDCR_SOC_P0 @T6G_MB_LIB.T6G(SCH_1):PVDDCR_SOC_P0    I82 @T6G_MB_LIB.T6G(SCH_1):PAGE69
     2    GND @T6G_MB_LIB.T6G(SCH_1):GND    I82 @T6G_MB_LIB.T6G(SCH_1):PAGE69

C2558 Q_CAP_C0402-22UF,4V,20%,X6S,CH622KMEB02
     1 PVDDCR_SOC_P0 @T6G_MB_LIB.T6G(SCH_1):PVDDCR_SOC_P0    I44 @T6G_MB_LIB.T6G(SCH_1):PAGE69
     2    GND @T6G_MB_LIB.T6G(SCH_1):GND    I44 @T6G_MB_LIB.T6G(SCH_1):PAGE69

C2559 Q_CAP_C0402-22UF,4V,20%,X6S,CH622KMEB02
     1 PVDDCR_SOC_P0 @T6G_MB_LIB.T6G(SCH_1):PVDDCR_SOC_P0    I41 @T6G_MB_LIB.T6G(SCH_1):PAGE69
     2    GND @T6G_MB_LIB.T6G(SCH_1):GND    I41 @T6G_MB_LIB.T6G(SCH_1):PAGE69

C2560 Q_CAP_C0402-22UF,4V,20%,X6S,CH622KMEB02
     1 PVDDCR_SOC_P0 @T6G_MB_LIB.T6G(SCH_1):PVDDCR_SOC_P0    I39 @T6G_MB_LIB.T6G(SCH_1):PAGE69
     2    GND @T6G_MB_LIB.T6G(SCH_1):GND    I39 @T6G_MB_LIB.T6G(SCH_1):PAGE69

C2561 Q_CAP_C0402-22UF,4V,20%,X6S,CH622KMEB02
     1 PVDDCR_SOC_P0 @T6G_MB_LIB.T6G(SCH_1):PVDDCR_SOC_P0    I30 @T6G_MB_LIB.T6G(SCH_1):PAGE69
     2    GND @T6G_MB_LIB.T6G(SCH_1):GND    I30 @T6G_MB_LIB.T6G(SCH_1):PAGE69

C2562 Q_CAP_C0402-22UF,4V,20%,X6S,CH622KMEB02
     1 PVDDCR_SOC_P0 @T6G_MB_LIB.T6G(SCH_1):PVDDCR_SOC_P0    I91 @T6G_MB_LIB.T6G(SCH_1):PAGE69
     2    GND @T6G_MB_LIB.T6G(SCH_1):GND    I91 @T6G_MB_LIB.T6G(SCH_1):PAGE69

C2563 Q_CAP_C0402-22UF,4V,20%,X6S,CH622KMEB02
     1 PVDDCR_SOC_P0 @T6G_MB_LIB.T6G(SCH_1):PVDDCR_SOC_P0    I88 @T6G_MB_LIB.T6G(SCH_1):PAGE69
     2    GND @T6G_MB_LIB.T6G(SCH_1):GND    I88 @T6G_MB_LIB.T6G(SCH_1):PAGE69

C2564 Q_CAP_C0402-22UF,4V,20%,X6S,CH622KMEB02
     1 PVDDCR_SOC_P0 @T6G_MB_LIB.T6G(SCH_1):PVDDCR_SOC_P0    I87 @T6G_MB_LIB.T6G(SCH_1):PAGE69
     2    GND @T6G_MB_LIB.T6G(SCH_1):GND    I87 @T6G_MB_LIB.T6G(SCH_1):PAGE69

C2565 Q_CAP_C0402-22UF,4V,20%,X6S,CH622KMEB02
     1 PVDDCR_SOC_P0 @T6G_MB_LIB.T6G(SCH_1):PVDDCR_SOC_P0    I49 @T6G_MB_LIB.T6G(SCH_1):PAGE69
     2    GND @T6G_MB_LIB.T6G(SCH_1):GND    I49 @T6G_MB_LIB.T6G(SCH_1):PAGE69

C2566 Q_CAP_C0402-22UF,4V,20%,X6S,CH622KMEB02
     1 PVDDCR_SOC_P0 @T6G_MB_LIB.T6G(SCH_1):PVDDCR_SOC_P0    I46 @T6G_MB_LIB.T6G(SCH_1):PAGE69
     2    GND @T6G_MB_LIB.T6G(SCH_1):GND    I46 @T6G_MB_LIB.T6G(SCH_1):PAGE69

C2567 Q_CAP_C0402-22UF,4V,20%,X6S,CH622KMEB02
     1 PVDDCR_SOC_P0 @T6G_MB_LIB.T6G(SCH_1):PVDDCR_SOC_P0    I45 @T6G_MB_LIB.T6G(SCH_1):PAGE69
     2    GND @T6G_MB_LIB.T6G(SCH_1):GND    I45 @T6G_MB_LIB.T6G(SCH_1):PAGE69

C2568 Q_CAP_C0402-22UF,4V,20%,X6S,CH622KMEB02
     1 PVDDCR_SOC_P0 @T6G_MB_LIB.T6G(SCH_1):PVDDCR_SOC_P0    I34 @T6G_MB_LIB.T6G(SCH_1):PAGE69
     2    GND @T6G_MB_LIB.T6G(SCH_1):GND    I34 @T6G_MB_LIB.T6G(SCH_1):PAGE69

C2569 Q_CAP_C0402-22UF,4V,20%,X6S,CH622KMEB02
     1 PVDDCR_SOC_P0 @T6G_MB_LIB.T6G(SCH_1):PVDDCR_SOC_P0    I92 @T6G_MB_LIB.T6G(SCH_1):PAGE69
     2    GND @T6G_MB_LIB.T6G(SCH_1):GND    I92 @T6G_MB_LIB.T6G(SCH_1):PAGE69

C2570 Q_CAP_C0402-22UF,4V,20%,X6S,CH622KMEB02
     1 PVDDCR_SOC_P0 @T6G_MB_LIB.T6G(SCH_1):PVDDCR_SOC_P0    I90 @T6G_MB_LIB.T6G(SCH_1):PAGE69
     2    GND @T6G_MB_LIB.T6G(SCH_1):GND    I90 @T6G_MB_LIB.T6G(SCH_1):PAGE69

C2571 Q_CAP_C0402-22UF,4V,20%,X6S,CH622KMEB02
     1 PVDDCR_SOC_P0 @T6G_MB_LIB.T6G(SCH_1):PVDDCR_SOC_P0    I89 @T6G_MB_LIB.T6G(SCH_1):PAGE69
     2    GND @T6G_MB_LIB.T6G(SCH_1):GND    I89 @T6G_MB_LIB.T6G(SCH_1):PAGE69

C2572 Q_CAP_C0402-22UF,4V,20%,X6S,CH622KMEB02
     1 PVDDCR_SOC_P0 @T6G_MB_LIB.T6G(SCH_1):PVDDCR_SOC_P0    I50 @T6G_MB_LIB.T6G(SCH_1):PAGE69
     2    GND @T6G_MB_LIB.T6G(SCH_1):GND    I50 @T6G_MB_LIB.T6G(SCH_1):PAGE69

C2573 Q_CAP_C0402-22UF,4V,20%,X6S,CH622KMEB02
     1 PVDDCR_SOC_P0 @T6G_MB_LIB.T6G(SCH_1):PVDDCR_SOC_P0    I48 @T6G_MB_LIB.T6G(SCH_1):PAGE69
     2    GND @T6G_MB_LIB.T6G(SCH_1):GND    I48 @T6G_MB_LIB.T6G(SCH_1):PAGE69

C2574 Q_CAP_C0402-22UF,4V,20%,X6S,CH622KMEB02
     1 PVDDCR_SOC_P0 @T6G_MB_LIB.T6G(SCH_1):PVDDCR_SOC_P0    I47 @T6G_MB_LIB.T6G(SCH_1):PAGE69
     2    GND @T6G_MB_LIB.T6G(SCH_1):GND    I47 @T6G_MB_LIB.T6G(SCH_1):PAGE69

C2575 Q_CAP_C0402-22UF,4V,20%,X6S,CH622KMEB02
     1 PVDDCR_SOC_P0 @T6G_MB_LIB.T6G(SCH_1):PVDDCR_SOC_P0    I35 @T6G_MB_LIB.T6G(SCH_1):PAGE69
     2    GND @T6G_MB_LIB.T6G(SCH_1):GND    I35 @T6G_MB_LIB.T6G(SCH_1):PAGE69

C2576 Q_CAP_C0402-22UF,4V,20%,X6S,CH622KMEB02
     1 PVDDCR_SOC_P0 @T6G_MB_LIB.T6G(SCH_1):PVDDCR_SOC_P0    I97 @T6G_MB_LIB.T6G(SCH_1):PAGE69
     2    GND @T6G_MB_LIB.T6G(SCH_1):GND    I97 @T6G_MB_LIB.T6G(SCH_1):PAGE69

C2577 Q_CAP_C0402-22UF,4V,20%,X6S,CH622KMEB02
     1 PVDDCR_SOC_P0 @T6G_MB_LIB.T6G(SCH_1):PVDDCR_SOC_P0    I94 @T6G_MB_LIB.T6G(SCH_1):PAGE69
     2    GND @T6G_MB_LIB.T6G(SCH_1):GND    I94 @T6G_MB_LIB.T6G(SCH_1):PAGE69

C2578 Q_CAP_C0402-22UF,4V,20%,X6S,CH622KMEB02
     1 PVDDCR_SOC_P0 @T6G_MB_LIB.T6G(SCH_1):PVDDCR_SOC_P0    I93 @T6G_MB_LIB.T6G(SCH_1):PAGE69
     2    GND @T6G_MB_LIB.T6G(SCH_1):GND    I93 @T6G_MB_LIB.T6G(SCH_1):PAGE69

C2579 Q_CAP_C0402-22UF,4V,20%,X6S,CH622KMEB02
     1 PVDDCR_SOC_P0 @T6G_MB_LIB.T6G(SCH_1):PVDDCR_SOC_P0    I65 @T6G_MB_LIB.T6G(SCH_1):PAGE69
     2    GND @T6G_MB_LIB.T6G(SCH_1):GND    I65 @T6G_MB_LIB.T6G(SCH_1):PAGE69

C2580 Q_CAP_C0402-22UF,4V,20%,X6S,CH622KMEB02
     1 PVDDCR_SOC_P0 @T6G_MB_LIB.T6G(SCH_1):PVDDCR_SOC_P0    I62 @T6G_MB_LIB.T6G(SCH_1):PAGE69
     2    GND @T6G_MB_LIB.T6G(SCH_1):GND    I62 @T6G_MB_LIB.T6G(SCH_1):PAGE69

C2581 Q_CAP_C0402-22UF,4V,20%,X6S,CH622KMEB02
     1 PVDDCR_SOC_P0 @T6G_MB_LIB.T6G(SCH_1):PVDDCR_SOC_P0    I61 @T6G_MB_LIB.T6G(SCH_1):PAGE69
     2    GND @T6G_MB_LIB.T6G(SCH_1):GND    I61 @T6G_MB_LIB.T6G(SCH_1):PAGE69

C2582 Q_CAP_C0402-22UF,4V,20%,X6S,CH622KMEB02
     1 PVDDCR_SOC_P0 @T6G_MB_LIB.T6G(SCH_1):PVDDCR_SOC_P0    I51 @T6G_MB_LIB.T6G(SCH_1):PAGE69
     2    GND @T6G_MB_LIB.T6G(SCH_1):GND    I51 @T6G_MB_LIB.T6G(SCH_1):PAGE69

C2583 Q_CAP_C0402-22UF,4V,20%,X6S,CH622KMEB02
     1 PVDDCR_SOC_P0 @T6G_MB_LIB.T6G(SCH_1):PVDDCR_SOC_P0    I98 @T6G_MB_LIB.T6G(SCH_1):PAGE69
     2    GND @T6G_MB_LIB.T6G(SCH_1):GND    I98 @T6G_MB_LIB.T6G(SCH_1):PAGE69

C2584 Q_CAP_C0402-22UF,4V,20%,X6S,CH622KMEB02
     1 PVDDCR_SOC_P0 @T6G_MB_LIB.T6G(SCH_1):PVDDCR_SOC_P0    I96 @T6G_MB_LIB.T6G(SCH_1):PAGE69
     2    GND @T6G_MB_LIB.T6G(SCH_1):GND    I96 @T6G_MB_LIB.T6G(SCH_1):PAGE69

C2585 Q_CAP_C0402-22UF,4V,20%,X6S,CH622KMEB02
     1 PVDDCR_SOC_P0 @T6G_MB_LIB.T6G(SCH_1):PVDDCR_SOC_P0    I95 @T6G_MB_LIB.T6G(SCH_1):PAGE69
     2    GND @T6G_MB_LIB.T6G(SCH_1):GND    I95 @T6G_MB_LIB.T6G(SCH_1):PAGE69

C2586 Q_CAP_C0402-22UF,4V,20%,X6S,CH622KMEB02
     1 PVDDCR_SOC_P0 @T6G_MB_LIB.T6G(SCH_1):PVDDCR_SOC_P0    I66 @T6G_MB_LIB.T6G(SCH_1):PAGE69
     2    GND @T6G_MB_LIB.T6G(SCH_1):GND    I66 @T6G_MB_LIB.T6G(SCH_1):PAGE69

C2587 Q_CAP_C0402-22UF,4V,20%,X6S,CH622KMEB02
     1 PVDDCR_SOC_P0 @T6G_MB_LIB.T6G(SCH_1):PVDDCR_SOC_P0    I64 @T6G_MB_LIB.T6G(SCH_1):PAGE69
     2    GND @T6G_MB_LIB.T6G(SCH_1):GND    I64 @T6G_MB_LIB.T6G(SCH_1):PAGE69

C2588 Q_CAP_C0402-22UF,4V,20%,X6S,CH622KMEB02
     1 PVDDCR_SOC_P0 @T6G_MB_LIB.T6G(SCH_1):PVDDCR_SOC_P0    I63 @T6G_MB_LIB.T6G(SCH_1):PAGE69
     2    GND @T6G_MB_LIB.T6G(SCH_1):GND    I63 @T6G_MB_LIB.T6G(SCH_1):PAGE69

C2589 Q_CAP_C0402-22UF,4V,20%,X6S,CH622KMEB02
     1 PVDDCR_SOC_P0 @T6G_MB_LIB.T6G(SCH_1):PVDDCR_SOC_P0    I52 @T6G_MB_LIB.T6G(SCH_1):PAGE69
     2    GND @T6G_MB_LIB.T6G(SCH_1):GND    I52 @T6G_MB_LIB.T6G(SCH_1):PAGE69

C2590 Q_CAP_C0402-22UF,4V,20%,X6S,CH622KMEB02
     1 PVDDCR_SOC_P0 @T6G_MB_LIB.T6G(SCH_1):PVDDCR_SOC_P0   I106 @T6G_MB_LIB.T6G(SCH_1):PAGE69
     2    GND @T6G_MB_LIB.T6G(SCH_1):GND   I106 @T6G_MB_LIB.T6G(SCH_1):PAGE69

C2591 Q_CAP_C0402-22UF,4V,20%,X6S,CH622KMEB02
     1 PVDDCR_SOC_P0 @T6G_MB_LIB.T6G(SCH_1):PVDDCR_SOC_P0   I101 @T6G_MB_LIB.T6G(SCH_1):PAGE69
     2    GND @T6G_MB_LIB.T6G(SCH_1):GND   I101 @T6G_MB_LIB.T6G(SCH_1):PAGE69

C2592 Q_CAP_C0402-22UF,4V,20%,X6S,CH622KMEB02
     1 PVDDCR_SOC_P0 @T6G_MB_LIB.T6G(SCH_1):PVDDCR_SOC_P0    I99 @T6G_MB_LIB.T6G(SCH_1):PAGE69
     2    GND @T6G_MB_LIB.T6G(SCH_1):GND    I99 @T6G_MB_LIB.T6G(SCH_1):PAGE69

C2593 Q_CAP_C0402-22UF,4V,20%,X6S,CH622KMEB02
     1 PVDDCR_SOC_P0 @T6G_MB_LIB.T6G(SCH_1):PVDDCR_SOC_P0    I74 @T6G_MB_LIB.T6G(SCH_1):PAGE69
     2    GND @T6G_MB_LIB.T6G(SCH_1):GND    I74 @T6G_MB_LIB.T6G(SCH_1):PAGE69

C2594 Q_CAP_C0402-22UF,4V,20%,X6S,CH622KMEB02
     1 PVDDCR_SOC_P0 @T6G_MB_LIB.T6G(SCH_1):PVDDCR_SOC_P0    I69 @T6G_MB_LIB.T6G(SCH_1):PAGE69
     2    GND @T6G_MB_LIB.T6G(SCH_1):GND    I69 @T6G_MB_LIB.T6G(SCH_1):PAGE69

C2595 Q_CAP_C0402-22UF,4V,20%,X6S,CH622KMEB02
     1 PVDDCR_SOC_P0 @T6G_MB_LIB.T6G(SCH_1):PVDDCR_SOC_P0    I67 @T6G_MB_LIB.T6G(SCH_1):PAGE69
     2    GND @T6G_MB_LIB.T6G(SCH_1):GND    I67 @T6G_MB_LIB.T6G(SCH_1):PAGE69

C2596 Q_CAP_C0402-22UF,4V,20%,X6S,CH622KMEB02
     1 PVDDCR_SOC_P0 @T6G_MB_LIB.T6G(SCH_1):PVDDCR_SOC_P0    I56 @T6G_MB_LIB.T6G(SCH_1):PAGE69
     2    GND @T6G_MB_LIB.T6G(SCH_1):GND    I56 @T6G_MB_LIB.T6G(SCH_1):PAGE69

C2597 Q_CAP_C0402-22UF,4V,20%,X6S,CH622KMEB02
     1 PVDDIO_P0 @T6G_MB_LIB.T6G(SCH_1):PVDDIO_P0   I108 @T6G_MB_LIB.T6G(SCH_1):PAGE69
     2    GND @T6G_MB_LIB.T6G(SCH_1):GND   I108 @T6G_MB_LIB.T6G(SCH_1):PAGE69

C2598 Q_CAP_C0402-22UF,4V,20%,X6S,CH622KMEB02
     1 PVDDIO_P0 @T6G_MB_LIB.T6G(SCH_1):PVDDIO_P0   I104 @T6G_MB_LIB.T6G(SCH_1):PAGE69
     2    GND @T6G_MB_LIB.T6G(SCH_1):GND   I104 @T6G_MB_LIB.T6G(SCH_1):PAGE69

C2599 Q_CAP_C0402-22UF,4V,20%,X6S,CH622KMEB02
     1 PVDDIO_P0 @T6G_MB_LIB.T6G(SCH_1):PVDDIO_P0   I102 @T6G_MB_LIB.T6G(SCH_1):PAGE69
     2    GND @T6G_MB_LIB.T6G(SCH_1):GND   I102 @T6G_MB_LIB.T6G(SCH_1):PAGE69

C2600 Q_CAP_C0402-22UF,4V,20%,X6S,CH622KMEB02
     1 PVDD11_S3_P0 @T6G_MB_LIB.T6G(SCH_1):PVDD11_S3_P0    I76 @T6G_MB_LIB.T6G(SCH_1):PAGE69
     2    GND @T6G_MB_LIB.T6G(SCH_1):GND    I76 @T6G_MB_LIB.T6G(SCH_1):PAGE69

C2601 Q_CAP_C0402-22UF,4V,20%,X6S,CH622KMEB02
     1 PVDD11_S3_P0 @T6G_MB_LIB.T6G(SCH_1):PVDD11_S3_P0    I71 @T6G_MB_LIB.T6G(SCH_1):PAGE69
     2    GND @T6G_MB_LIB.T6G(SCH_1):GND    I71 @T6G_MB_LIB.T6G(SCH_1):PAGE69

C2602 Q_CAP_C0402-22UF,4V,20%,X6S,CH622KMEB02
     1 PVDD11_S3_P0 @T6G_MB_LIB.T6G(SCH_1):PVDD11_S3_P0    I60 @T6G_MB_LIB.T6G(SCH_1):PAGE69
     2    GND @T6G_MB_LIB.T6G(SCH_1):GND    I60 @T6G_MB_LIB.T6G(SCH_1):PAGE69

C2603 Q_CAP_C0402-22UF,4V,20%,X6S,CH622KMEB02
     1 PVDD11_S3_P0 @T6G_MB_LIB.T6G(SCH_1):PVDD11_S3_P0    I58 @T6G_MB_LIB.T6G(SCH_1):PAGE69
     2    GND @T6G_MB_LIB.T6G(SCH_1):GND    I58 @T6G_MB_LIB.T6G(SCH_1):PAGE69

C2604 Q_CAP_C0402-22UF,4V,20%,X6S,CH622KMEB02
     1 PVDDIO_P0 @T6G_MB_LIB.T6G(SCH_1):PVDDIO_P0   I158 @T6G_MB_LIB.T6G(SCH_1):PAGE69
     2    GND @T6G_MB_LIB.T6G(SCH_1):GND   I158 @T6G_MB_LIB.T6G(SCH_1):PAGE69

C2605 Q_CAP_C0402-22UF,4V,20%,X6S,CH622KMEB02
     1 PVDDIO_P0 @T6G_MB_LIB.T6G(SCH_1):PVDDIO_P0   I154 @T6G_MB_LIB.T6G(SCH_1):PAGE69
     2    GND @T6G_MB_LIB.T6G(SCH_1):GND   I154 @T6G_MB_LIB.T6G(SCH_1):PAGE69

C2606 Q_CAP_C0402-22UF,4V,20%,X6S,CH622KMEB02
     1 PVDDIO_P0 @T6G_MB_LIB.T6G(SCH_1):PVDDIO_P0   I153 @T6G_MB_LIB.T6G(SCH_1):PAGE69
     2    GND @T6G_MB_LIB.T6G(SCH_1):GND   I153 @T6G_MB_LIB.T6G(SCH_1):PAGE69

C2607 Q_CAP_C0402-22UF,4V,20%,X6S,CH622KMEB02
     1 PVDD11_S3_P0 @T6G_MB_LIB.T6G(SCH_1):PVDD11_S3_P0   I124 @T6G_MB_LIB.T6G(SCH_1):PAGE69
     2    GND @T6G_MB_LIB.T6G(SCH_1):GND   I124 @T6G_MB_LIB.T6G(SCH_1):PAGE69

C2608 Q_CAP_C0402-22UF,4V,20%,X6S,CH622KMEB02
     1 PVDD11_S3_P0 @T6G_MB_LIB.T6G(SCH_1):PVDD11_S3_P0   I122 @T6G_MB_LIB.T6G(SCH_1):PAGE69
     2    GND @T6G_MB_LIB.T6G(SCH_1):GND   I122 @T6G_MB_LIB.T6G(SCH_1):PAGE69

C2609 Q_CAP_C0402-22UF,4V,20%,X6S,CH622KMEB02
     1 PVDD11_S3_P0 @T6G_MB_LIB.T6G(SCH_1):PVDD11_S3_P0   I113 @T6G_MB_LIB.T6G(SCH_1):PAGE69
     2    GND @T6G_MB_LIB.T6G(SCH_1):GND   I113 @T6G_MB_LIB.T6G(SCH_1):PAGE69

C2610 Q_CAP_C0402-22UF,4V,20%,X6S,CH622KMEB02
     1 PVDD11_S3_P0 @T6G_MB_LIB.T6G(SCH_1):PVDD11_S3_P0   I112 @T6G_MB_LIB.T6G(SCH_1):PAGE69
     2    GND @T6G_MB_LIB.T6G(SCH_1):GND   I112 @T6G_MB_LIB.T6G(SCH_1):PAGE69

C2611 Q_CAP_C0402-22UF,4V,20%,X6S,CH622KMEB02
     1 PVDDIO_P0 @T6G_MB_LIB.T6G(SCH_1):PVDDIO_P0   I159 @T6G_MB_LIB.T6G(SCH_1):PAGE69
     2    GND @T6G_MB_LIB.T6G(SCH_1):GND   I159 @T6G_MB_LIB.T6G(SCH_1):PAGE69

C2612 Q_CAP_C0402-22UF,4V,20%,X6S,CH622KMEB02
     1 PVDDIO_P0 @T6G_MB_LIB.T6G(SCH_1):PVDDIO_P0   I156 @T6G_MB_LIB.T6G(SCH_1):PAGE69
     2    GND @T6G_MB_LIB.T6G(SCH_1):GND   I156 @T6G_MB_LIB.T6G(SCH_1):PAGE69

C2613 Q_CAP_C0402-22UF,4V,20%,X6S,CH622KMEB02
     1 PVDDIO_P0 @T6G_MB_LIB.T6G(SCH_1):PVDDIO_P0   I155 @T6G_MB_LIB.T6G(SCH_1):PAGE69
     2    GND @T6G_MB_LIB.T6G(SCH_1):GND   I155 @T6G_MB_LIB.T6G(SCH_1):PAGE69

C2614 Q_CAP_C0402-22UF,4V,20%,X6S,CH622KMEB02
     1 PVDD11_S3_P0 @T6G_MB_LIB.T6G(SCH_1):PVDD11_S3_P0   I125 @T6G_MB_LIB.T6G(SCH_1):PAGE69
     2    GND @T6G_MB_LIB.T6G(SCH_1):GND   I125 @T6G_MB_LIB.T6G(SCH_1):PAGE69

C2615 Q_CAP_C0402-22UF,4V,20%,X6S,CH622KMEB02
     1 PVDD11_S3_P0 @T6G_MB_LIB.T6G(SCH_1):PVDD11_S3_P0   I123 @T6G_MB_LIB.T6G(SCH_1):PAGE69
     2    GND @T6G_MB_LIB.T6G(SCH_1):GND   I123 @T6G_MB_LIB.T6G(SCH_1):PAGE69

C2616 Q_CAP_C0402-22UF,4V,20%,X6S,CH622KMEB02
     1 PVDD11_S3_P0 @T6G_MB_LIB.T6G(SCH_1):PVDD11_S3_P0   I115 @T6G_MB_LIB.T6G(SCH_1):PAGE69
     2    GND @T6G_MB_LIB.T6G(SCH_1):GND   I115 @T6G_MB_LIB.T6G(SCH_1):PAGE69

C2617 Q_CAP_C0402-22UF,4V,20%,X6S,CH622KMEB02
     1 PVDD11_S3_P0 @T6G_MB_LIB.T6G(SCH_1):PVDD11_S3_P0   I114 @T6G_MB_LIB.T6G(SCH_1):PAGE69
     2    GND @T6G_MB_LIB.T6G(SCH_1):GND   I114 @T6G_MB_LIB.T6G(SCH_1):PAGE69

C2618 Q_CAP_C0402-22UF,4V,20%,X6S,CH622KMEB02
     1 PVDDIO_P0 @T6G_MB_LIB.T6G(SCH_1):PVDDIO_P0   I160 @T6G_MB_LIB.T6G(SCH_1):PAGE69
     2    GND @T6G_MB_LIB.T6G(SCH_1):GND   I160 @T6G_MB_LIB.T6G(SCH_1):PAGE69

C2619 Q_CAP_C0402-22UF,4V,20%,X6S,CH622KMEB02
     1 PVDDIO_P0 @T6G_MB_LIB.T6G(SCH_1):PVDDIO_P0   I157 @T6G_MB_LIB.T6G(SCH_1):PAGE69
     2    GND @T6G_MB_LIB.T6G(SCH_1):GND   I157 @T6G_MB_LIB.T6G(SCH_1):PAGE69

C2620 Q_CAP_C0402-22UF,4V,20%,X6S,CH622KMEB02
     1 PVDDIO_P0 @T6G_MB_LIB.T6G(SCH_1):PVDDIO_P0   I161 @T6G_MB_LIB.T6G(SCH_1):PAGE69
     2    GND @T6G_MB_LIB.T6G(SCH_1):GND   I161 @T6G_MB_LIB.T6G(SCH_1):PAGE69

C2621 Q_CAP_C0402-22UF,4V,20%,X6S,CH622KMEB02
     1 PVDD11_S3_P0 @T6G_MB_LIB.T6G(SCH_1):PVDD11_S3_P0   I127 @T6G_MB_LIB.T6G(SCH_1):PAGE69
     2    GND @T6G_MB_LIB.T6G(SCH_1):GND   I127 @T6G_MB_LIB.T6G(SCH_1):PAGE69

C2622 Q_CAP_C0402-22UF,4V,20%,X6S,CH622KMEB02
     1 PVDD11_S3_P0 @T6G_MB_LIB.T6G(SCH_1):PVDD11_S3_P0   I126 @T6G_MB_LIB.T6G(SCH_1):PAGE69
     2    GND @T6G_MB_LIB.T6G(SCH_1):GND   I126 @T6G_MB_LIB.T6G(SCH_1):PAGE69

C2623 Q_CAP_C0402-22UF,4V,20%,X6S,CH622KMEB02
     1 PVDD11_S3_P0 @T6G_MB_LIB.T6G(SCH_1):PVDD11_S3_P0   I117 @T6G_MB_LIB.T6G(SCH_1):PAGE69
     2    GND @T6G_MB_LIB.T6G(SCH_1):GND   I117 @T6G_MB_LIB.T6G(SCH_1):PAGE69

C2624 Q_CAP_C0402-22UF,4V,20%,X6S,CH622KMEB02
     1 PVDD11_S3_P0 @T6G_MB_LIB.T6G(SCH_1):PVDD11_S3_P0   I116 @T6G_MB_LIB.T6G(SCH_1):PAGE69
     2    GND @T6G_MB_LIB.T6G(SCH_1):GND   I116 @T6G_MB_LIB.T6G(SCH_1):PAGE69

C2625 Q_CAP_C0402-22UF,4V,20%,X6S,CH622KMEB02
     1 PVDDIO_P0 @T6G_MB_LIB.T6G(SCH_1):PVDDIO_P0   I164 @T6G_MB_LIB.T6G(SCH_1):PAGE69
     2    GND @T6G_MB_LIB.T6G(SCH_1):GND   I164 @T6G_MB_LIB.T6G(SCH_1):PAGE69

C2626 Q_CAP_C0402-22UF,4V,20%,X6S,CH622KMEB02
     1 PVDDIO_P0 @T6G_MB_LIB.T6G(SCH_1):PVDDIO_P0   I162 @T6G_MB_LIB.T6G(SCH_1):PAGE69
     2    GND @T6G_MB_LIB.T6G(SCH_1):GND   I162 @T6G_MB_LIB.T6G(SCH_1):PAGE69

C2627 Q_CAP_C0402-22UF,4V,20%,X6S,CH622KMEB02
     1 PVDD11_S3_P0 @T6G_MB_LIB.T6G(SCH_1):PVDD11_S3_P0   I131 @T6G_MB_LIB.T6G(SCH_1):PAGE69
     2    GND @T6G_MB_LIB.T6G(SCH_1):GND   I131 @T6G_MB_LIB.T6G(SCH_1):PAGE69

C2628 Q_CAP_C0402-22UF,4V,20%,X6S,CH622KMEB02
     1 PVDD11_S3_P0 @T6G_MB_LIB.T6G(SCH_1):PVDD11_S3_P0   I129 @T6G_MB_LIB.T6G(SCH_1):PAGE69
     2    GND @T6G_MB_LIB.T6G(SCH_1):GND   I129 @T6G_MB_LIB.T6G(SCH_1):PAGE69

C2629 Q_CAP_C0402-22UF,4V,20%,X6S,CH622KMEB02
     1 PVDD11_S3_P0 @T6G_MB_LIB.T6G(SCH_1):PVDD11_S3_P0   I119 @T6G_MB_LIB.T6G(SCH_1):PAGE69
     2    GND @T6G_MB_LIB.T6G(SCH_1):GND   I119 @T6G_MB_LIB.T6G(SCH_1):PAGE69

C2630 Q_CAP_C0402-22UF,4V,20%,X6S,CH622KMEB02
     1 PVDD11_S3_P0 @T6G_MB_LIB.T6G(SCH_1):PVDD11_S3_P0   I118 @T6G_MB_LIB.T6G(SCH_1):PAGE69
     2    GND @T6G_MB_LIB.T6G(SCH_1):GND   I118 @T6G_MB_LIB.T6G(SCH_1):PAGE69

C2631 Q_CAP_C0402-22UF,4V,20%,X6S,CH622KMEB02
     1 PVDDIO_P0 @T6G_MB_LIB.T6G(SCH_1):PVDDIO_P0   I165 @T6G_MB_LIB.T6G(SCH_1):PAGE69
     2    GND @T6G_MB_LIB.T6G(SCH_1):GND   I165 @T6G_MB_LIB.T6G(SCH_1):PAGE69

C2632 Q_CAP_C0402-22UF,4V,20%,X6S,CH622KMEB02
     1 PVDDIO_P0 @T6G_MB_LIB.T6G(SCH_1):PVDDIO_P0   I163 @T6G_MB_LIB.T6G(SCH_1):PAGE69
     2    GND @T6G_MB_LIB.T6G(SCH_1):GND   I163 @T6G_MB_LIB.T6G(SCH_1):PAGE69

C2633 Q_CAP_C0402-22UF,4V,20%,X6S,CH622KMEB02
     1 PVDD11_S3_P0 @T6G_MB_LIB.T6G(SCH_1):PVDD11_S3_P0   I132 @T6G_MB_LIB.T6G(SCH_1):PAGE69
     2    GND @T6G_MB_LIB.T6G(SCH_1):GND   I132 @T6G_MB_LIB.T6G(SCH_1):PAGE69

C2634 Q_CAP_C0402-22UF,4V,20%,X6S,CH622KMEB02
     1 PVDD11_S3_P0 @T6G_MB_LIB.T6G(SCH_1):PVDD11_S3_P0   I130 @T6G_MB_LIB.T6G(SCH_1):PAGE69
     2    GND @T6G_MB_LIB.T6G(SCH_1):GND   I130 @T6G_MB_LIB.T6G(SCH_1):PAGE69

C2635 Q_CAP_C0402-22UF,4V,20%,X6S,CH622KMEB02
     1 PVDD11_S3_P0 @T6G_MB_LIB.T6G(SCH_1):PVDD11_S3_P0   I121 @T6G_MB_LIB.T6G(SCH_1):PAGE69
     2    GND @T6G_MB_LIB.T6G(SCH_1):GND   I121 @T6G_MB_LIB.T6G(SCH_1):PAGE69

C2636 Q_CAP_C0402-22UF,4V,20%,X6S,CH622KMEB02
     1 PVDD11_S3_P0 @T6G_MB_LIB.T6G(SCH_1):PVDD11_S3_P0   I120 @T6G_MB_LIB.T6G(SCH_1):PAGE69
     2    GND @T6G_MB_LIB.T6G(SCH_1):GND   I120 @T6G_MB_LIB.T6G(SCH_1):PAGE69

C2637 Q_CAP_C0402-22UF,4V,20%,X6S,CH622KMEB02
     1 PVDDIO_P0 @T6G_MB_LIB.T6G(SCH_1):PVDDIO_P0   I168 @T6G_MB_LIB.T6G(SCH_1):PAGE69
     2    GND @T6G_MB_LIB.T6G(SCH_1):GND   I168 @T6G_MB_LIB.T6G(SCH_1):PAGE69

C2638 Q_CAP_C0402-22UF,4V,20%,X6S,CH622KMEB02
     1 PVDDIO_P0 @T6G_MB_LIB.T6G(SCH_1):PVDDIO_P0   I166 @T6G_MB_LIB.T6G(SCH_1):PAGE69
     2    GND @T6G_MB_LIB.T6G(SCH_1):GND   I166 @T6G_MB_LIB.T6G(SCH_1):PAGE69

C2639 Q_CAP_C0402-22UF,4V,20%,X6S,CH622KMEB02
     1 PVDD11_S3_P0 @T6G_MB_LIB.T6G(SCH_1):PVDD11_S3_P0   I145 @T6G_MB_LIB.T6G(SCH_1):PAGE69
     2    GND @T6G_MB_LIB.T6G(SCH_1):GND   I145 @T6G_MB_LIB.T6G(SCH_1):PAGE69

C2640 Q_CAP_C0402-22UF,4V,20%,X6S,CH622KMEB02
     1 PVDD11_S3_P0 @T6G_MB_LIB.T6G(SCH_1):PVDD11_S3_P0   I143 @T6G_MB_LIB.T6G(SCH_1):PAGE69
     2    GND @T6G_MB_LIB.T6G(SCH_1):GND   I143 @T6G_MB_LIB.T6G(SCH_1):PAGE69

C2641 Q_CAP_C0402-22UF,4V,20%,X6S,CH622KMEB02
     1 PVDD11_S3_P0 @T6G_MB_LIB.T6G(SCH_1):PVDD11_S3_P0   I134 @T6G_MB_LIB.T6G(SCH_1):PAGE69
     2    GND @T6G_MB_LIB.T6G(SCH_1):GND   I134 @T6G_MB_LIB.T6G(SCH_1):PAGE69

C2642 Q_CAP_C0402-22UF,4V,20%,X6S,CH622KMEB02
     1 PVDD11_S3_P0 @T6G_MB_LIB.T6G(SCH_1):PVDD11_S3_P0   I133 @T6G_MB_LIB.T6G(SCH_1):PAGE69
     2    GND @T6G_MB_LIB.T6G(SCH_1):GND   I133 @T6G_MB_LIB.T6G(SCH_1):PAGE69

C2643 Q_CAP_C0402-22UF,4V,20%,X6S,CH622KMEB02
     1 PVDDIO_P0 @T6G_MB_LIB.T6G(SCH_1):PVDDIO_P0   I169 @T6G_MB_LIB.T6G(SCH_1):PAGE69
     2    GND @T6G_MB_LIB.T6G(SCH_1):GND   I169 @T6G_MB_LIB.T6G(SCH_1):PAGE69

C2644 Q_CAP_C0402-22UF,4V,20%,X6S,CH622KMEB02
     1 PVDDIO_P0 @T6G_MB_LIB.T6G(SCH_1):PVDDIO_P0   I167 @T6G_MB_LIB.T6G(SCH_1):PAGE69
     2    GND @T6G_MB_LIB.T6G(SCH_1):GND   I167 @T6G_MB_LIB.T6G(SCH_1):PAGE69

C2645 Q_CAP_C0402-22UF,4V,20%,X6S,CH622KMEB02
     1 PVDD11_S3_P0 @T6G_MB_LIB.T6G(SCH_1):PVDD11_S3_P0   I146 @T6G_MB_LIB.T6G(SCH_1):PAGE69
     2    GND @T6G_MB_LIB.T6G(SCH_1):GND   I146 @T6G_MB_LIB.T6G(SCH_1):PAGE69

C2646 Q_CAP_C0402-22UF,4V,20%,X6S,CH622KMEB02
     1 PVDD11_S3_P0 @T6G_MB_LIB.T6G(SCH_1):PVDD11_S3_P0   I144 @T6G_MB_LIB.T6G(SCH_1):PAGE69
     2    GND @T6G_MB_LIB.T6G(SCH_1):GND   I144 @T6G_MB_LIB.T6G(SCH_1):PAGE69

C2647 Q_CAP_C0402-22UF,4V,20%,X6S,CH622KMEB02
     1 PVDD11_S3_P0 @T6G_MB_LIB.T6G(SCH_1):PVDD11_S3_P0   I136 @T6G_MB_LIB.T6G(SCH_1):PAGE69
     2    GND @T6G_MB_LIB.T6G(SCH_1):GND   I136 @T6G_MB_LIB.T6G(SCH_1):PAGE69

C2648 Q_CAP_C0402-22UF,4V,20%,X6S,CH622KMEB02
     1 PVDD11_S3_P0 @T6G_MB_LIB.T6G(SCH_1):PVDD11_S3_P0   I135 @T6G_MB_LIB.T6G(SCH_1):PAGE69
     2    GND @T6G_MB_LIB.T6G(SCH_1):GND   I135 @T6G_MB_LIB.T6G(SCH_1):PAGE69

C2649 Q_CAP_C0402-22UF,4V,20%,X6S,CH622KMEB02
     1 PVDDIO_P0 @T6G_MB_LIB.T6G(SCH_1):PVDDIO_P0   I173 @T6G_MB_LIB.T6G(SCH_1):PAGE69
     2    GND @T6G_MB_LIB.T6G(SCH_1):GND   I173 @T6G_MB_LIB.T6G(SCH_1):PAGE69

C2650 Q_CAP_C0402-22UF,4V,20%,X6S,CH622KMEB02
     1 PVDDIO_P0 @T6G_MB_LIB.T6G(SCH_1):PVDDIO_P0   I170 @T6G_MB_LIB.T6G(SCH_1):PAGE69
     2    GND @T6G_MB_LIB.T6G(SCH_1):GND   I170 @T6G_MB_LIB.T6G(SCH_1):PAGE69

C2651 Q_CAP_C0402-22UF,4V,20%,X6S,CH622KMEB02
     1 PVDD11_S3_P0 @T6G_MB_LIB.T6G(SCH_1):PVDD11_S3_P0   I151 @T6G_MB_LIB.T6G(SCH_1):PAGE69
     2    GND @T6G_MB_LIB.T6G(SCH_1):GND   I151 @T6G_MB_LIB.T6G(SCH_1):PAGE69

C2652 Q_CAP_C0402-22UF,4V,20%,X6S,CH622KMEB02
     1 PVDD11_S3_P0 @T6G_MB_LIB.T6G(SCH_1):PVDD11_S3_P0   I147 @T6G_MB_LIB.T6G(SCH_1):PAGE69
     2    GND @T6G_MB_LIB.T6G(SCH_1):GND   I147 @T6G_MB_LIB.T6G(SCH_1):PAGE69

C2653 Q_CAP_C0402-22UF,4V,20%,X6S,CH622KMEB02
     1 PVDD11_S3_P0 @T6G_MB_LIB.T6G(SCH_1):PVDD11_S3_P0   I139 @T6G_MB_LIB.T6G(SCH_1):PAGE69
     2    GND @T6G_MB_LIB.T6G(SCH_1):GND   I139 @T6G_MB_LIB.T6G(SCH_1):PAGE69

C2654 Q_CAP_C0402-22UF,4V,20%,X6S,CH622KMEB02
     1 PVDDIO_P0 @T6G_MB_LIB.T6G(SCH_1):PVDDIO_P0   I175 @T6G_MB_LIB.T6G(SCH_1):PAGE69
     2    GND @T6G_MB_LIB.T6G(SCH_1):GND   I175 @T6G_MB_LIB.T6G(SCH_1):PAGE69

C2655 Q_CAP_C0402-22UF,4V,20%,X6S,CH622KMEB02
     1 PVDDIO_P0 @T6G_MB_LIB.T6G(SCH_1):PVDDIO_P0   I172 @T6G_MB_LIB.T6G(SCH_1):PAGE69
     2    GND @T6G_MB_LIB.T6G(SCH_1):GND   I172 @T6G_MB_LIB.T6G(SCH_1):PAGE69

C2656 Q_CAP_C0402-22UF,4V,20%,X6S,CH622KMEB02
     1 PVDD11_S3_P0 @T6G_MB_LIB.T6G(SCH_1):PVDD11_S3_P0   I152 @T6G_MB_LIB.T6G(SCH_1):PAGE69
     2    GND @T6G_MB_LIB.T6G(SCH_1):GND   I152 @T6G_MB_LIB.T6G(SCH_1):PAGE69

C2657 Q_CAP_C0402-22UF,4V,20%,X6S,CH622KMEB02
     1 PVDD11_S3_P0 @T6G_MB_LIB.T6G(SCH_1):PVDD11_S3_P0   I149 @T6G_MB_LIB.T6G(SCH_1):PAGE69
     2    GND @T6G_MB_LIB.T6G(SCH_1):GND   I149 @T6G_MB_LIB.T6G(SCH_1):PAGE69

C2658 Q_CAP_C0402-22UF,4V,20%,X6S,CH622KMEB02
     1 PVDD11_S3_P0 @T6G_MB_LIB.T6G(SCH_1):PVDD11_S3_P0   I142 @T6G_MB_LIB.T6G(SCH_1):PAGE69
     2    GND @T6G_MB_LIB.T6G(SCH_1):GND   I142 @T6G_MB_LIB.T6G(SCH_1):PAGE69

C2659 Q_CAP_C0402-10UF,6.3V,20%,X6S,CH6101MEB01
     1 PVDD_33_S5 @T6G_MB_LIB.T6G(SCH_1):PVDD_33_S5    I26 @T6G_MB_LIB.T6G(SCH_1):PAGE74
     2    GND @T6G_MB_LIB.T6G(SCH_1):GND    I26 @T6G_MB_LIB.T6G(SCH_1):PAGE74

C2660 Q_CAP_C0402-22UF,4V,20%,X6S,CH622KMEB02
     1 PVDD18_S5_P1 @T6G_MB_LIB.T6G(SCH_1):PVDD18_S5_P1     I3 @T6G_MB_LIB.T6G(SCH_1):PAGE74
     2    GND @T6G_MB_LIB.T6G(SCH_1):GND     I3 @T6G_MB_LIB.T6G(SCH_1):PAGE74

C2661 Q_CAP_C0402-22UF,4V,20%,X6S,CH622KMEB02
     1 PVDD18_S5_P1 @T6G_MB_LIB.T6G(SCH_1):PVDD18_S5_P1     I1 @T6G_MB_LIB.T6G(SCH_1):PAGE74
     2    GND @T6G_MB_LIB.T6G(SCH_1):GND     I1 @T6G_MB_LIB.T6G(SCH_1):PAGE74

C2662 Q_CAP_C0402-10UF,6.3V,20%,X6S,CH6101MEB01
     1 PVDD_33_S5 @T6G_MB_LIB.T6G(SCH_1):PVDD_33_S5    I25 @T6G_MB_LIB.T6G(SCH_1):PAGE74
     2    GND @T6G_MB_LIB.T6G(SCH_1):GND    I25 @T6G_MB_LIB.T6G(SCH_1):PAGE74

C2663 Q_CAP_C0402-22UF,4V,20%,X6S,CH622KMEB02
     1 PVDD18_S5_P1 @T6G_MB_LIB.T6G(SCH_1):PVDD18_S5_P1     I9 @T6G_MB_LIB.T6G(SCH_1):PAGE74
     2    GND @T6G_MB_LIB.T6G(SCH_1):GND     I9 @T6G_MB_LIB.T6G(SCH_1):PAGE74

C2664 Q_CAP_C0402-22UF,4V,20%,X6S,CH622KMEB02
     1 PVDD18_S5_P1 @T6G_MB_LIB.T6G(SCH_1):PVDD18_S5_P1     I8 @T6G_MB_LIB.T6G(SCH_1):PAGE74
     2    GND @T6G_MB_LIB.T6G(SCH_1):GND     I8 @T6G_MB_LIB.T6G(SCH_1):PAGE74

C2665 Q_CAP_C0402-22UF,4V,20%,X6S,CH622KMEB02
     1 PVDD18_S5_P1 @T6G_MB_LIB.T6G(SCH_1):PVDD18_S5_P1    I10 @T6G_MB_LIB.T6G(SCH_1):PAGE74
     2    GND @T6G_MB_LIB.T6G(SCH_1):GND    I10 @T6G_MB_LIB.T6G(SCH_1):PAGE74

C2667 Q_CAP_C0402-22UF,4V,20%,X6S,CH622KMEB02
     1 PVDD18_S5_P1 @T6G_MB_LIB.T6G(SCH_1):PVDD18_S5_P1    I11 @T6G_MB_LIB.T6G(SCH_1):PAGE74
     2    GND @T6G_MB_LIB.T6G(SCH_1):GND    I11 @T6G_MB_LIB.T6G(SCH_1):PAGE74

C2668 Q_CAP_C0402-22UF,4V,20%,X6S,CH622KMEB02
     1 PVDD18_S5_P1 @T6G_MB_LIB.T6G(SCH_1):PVDD18_S5_P1    I12 @T6G_MB_LIB.T6G(SCH_1):PAGE74
     2    GND @T6G_MB_LIB.T6G(SCH_1):GND    I12 @T6G_MB_LIB.T6G(SCH_1):PAGE74

C2669 Q_CAP_C0402-22UF,4V,20%,X6S,CH622KMEB02
     1 PVDD18_S5_P1 @T6G_MB_LIB.T6G(SCH_1):PVDD18_S5_P1    I13 @T6G_MB_LIB.T6G(SCH_1):PAGE74
     2    GND @T6G_MB_LIB.T6G(SCH_1):GND    I13 @T6G_MB_LIB.T6G(SCH_1):PAGE74

C2670 Q_CAP_C0402-22UF,4V,20%,X6S,CH622KMEB02
     1 PVDD18_S5_P1 @T6G_MB_LIB.T6G(SCH_1):PVDD18_S5_P1    I14 @T6G_MB_LIB.T6G(SCH_1):PAGE74
     2    GND @T6G_MB_LIB.T6G(SCH_1):GND    I14 @T6G_MB_LIB.T6G(SCH_1):PAGE74

C2671 Q_CAP_C0402-22UF,4V,20%,X6S,CH622KMEB02
     1 PVDD18_S5_P1 @T6G_MB_LIB.T6G(SCH_1):PVDD18_S5_P1    I15 @T6G_MB_LIB.T6G(SCH_1):PAGE74
     2    GND @T6G_MB_LIB.T6G(SCH_1):GND    I15 @T6G_MB_LIB.T6G(SCH_1):PAGE74

C2672 Q_CAP_C0402-22UF,4V,20%,X6S,CH622KMEB02
     1 PVDD18_S5_P1 @T6G_MB_LIB.T6G(SCH_1):PVDD18_S5_P1    I16 @T6G_MB_LIB.T6G(SCH_1):PAGE74
     2    GND @T6G_MB_LIB.T6G(SCH_1):GND    I16 @T6G_MB_LIB.T6G(SCH_1):PAGE74

C2673 Q_CAP_C0402-22UF,4V,20%,X6S,CH622KMEB02
     1 PVDD18_S5_P1 @T6G_MB_LIB.T6G(SCH_1):PVDD18_S5_P1    I18 @T6G_MB_LIB.T6G(SCH_1):PAGE74
     2    GND @T6G_MB_LIB.T6G(SCH_1):GND    I18 @T6G_MB_LIB.T6G(SCH_1):PAGE74

C3888 Q_CAP_C0402-22UF,4V,20%,X6S,CH622KMEB02
     1 PVDDCR_SOC_P0 @T6G_MB_LIB.T6G(SCH_1):PVDDCR_SOC_P0    I83 @T6G_MB_LIB.T6G(SCH_1):PAGE67
     2    GND @T6G_MB_LIB.T6G(SCH_1):GND    I83 @T6G_MB_LIB.T6G(SCH_1):PAGE67

C3889 Q_CAP_C0402-22UF,4V,20%,X6S,CH622KMEB02
     1 PVDDCR_SOC_P0 @T6G_MB_LIB.T6G(SCH_1):PVDDCR_SOC_P0    I86 @T6G_MB_LIB.T6G(SCH_1):PAGE67
     2    GND @T6G_MB_LIB.T6G(SCH_1):GND    I86 @T6G_MB_LIB.T6G(SCH_1):PAGE67

C3890 Q_CAP_C0402-22UF,4V,20%,X6S,CH622KMEB02
     1 PVDD11_S3_P0 @T6G_MB_LIB.T6G(SCH_1):PVDD11_S3_P0   I116 @T6G_MB_LIB.T6G(SCH_1):PAGE67
     2    GND @T6G_MB_LIB.T6G(SCH_1):GND   I116 @T6G_MB_LIB.T6G(SCH_1):PAGE67

C3891 Q_CAP_C0402-22UF,4V,20%,X6S,CH622KMEB02
     1 PVDD11_S3_P0 @T6G_MB_LIB.T6G(SCH_1):PVDD11_S3_P0   I117 @T6G_MB_LIB.T6G(SCH_1):PAGE67
     2    GND @T6G_MB_LIB.T6G(SCH_1):GND   I117 @T6G_MB_LIB.T6G(SCH_1):PAGE67

C3892 Q_CAP_C0402-22UF,4V,20%,X6S,CH622KMEB02
     1 PVDD11_S3_P0 @T6G_MB_LIB.T6G(SCH_1):PVDD11_S3_P0   I118 @T6G_MB_LIB.T6G(SCH_1):PAGE67
     2    GND @T6G_MB_LIB.T6G(SCH_1):GND   I118 @T6G_MB_LIB.T6G(SCH_1):PAGE67

C3893 Q_CAP_C0402-22UF,4V,20%,X6S,CH622KMEB02
     1 PVDD11_S3_P0 @T6G_MB_LIB.T6G(SCH_1):PVDD11_S3_P0   I120 @T6G_MB_LIB.T6G(SCH_1):PAGE67
     2    GND @T6G_MB_LIB.T6G(SCH_1):GND   I120 @T6G_MB_LIB.T6G(SCH_1):PAGE67

C3894 Q_CAP_C0402-22UF,4V,20%,X6S,CH622KMEB02
     1 PVDDCR_SOC_P0 @T6G_MB_LIB.T6G(SCH_1):PVDDCR_SOC_P0   I101 @T6G_MB_LIB.T6G(SCH_1):PAGE67
     2    GND @T6G_MB_LIB.T6G(SCH_1):GND   I101 @T6G_MB_LIB.T6G(SCH_1):PAGE67

C3895 Q_CAP_C0402-22UF,4V,20%,X6S,CH622KMEB02
     1 PVDDCR_SOC_P0 @T6G_MB_LIB.T6G(SCH_1):PVDDCR_SOC_P0   I102 @T6G_MB_LIB.T6G(SCH_1):PAGE67
     2    GND @T6G_MB_LIB.T6G(SCH_1):GND   I102 @T6G_MB_LIB.T6G(SCH_1):PAGE67

C3896 Q_CAP_C0402-22UF,4V,20%,X6S,CH622KMEB02
     1 PVDDCR_SOC_P0 @T6G_MB_LIB.T6G(SCH_1):PVDDCR_SOC_P0   I106 @T6G_MB_LIB.T6G(SCH_1):PAGE67
     2    GND @T6G_MB_LIB.T6G(SCH_1):GND   I106 @T6G_MB_LIB.T6G(SCH_1):PAGE67

C3897 Q_CAP_C0402-22UF,4V,20%,X6S,CH622KMEB02
     1 PVDD18_S5_P0 @T6G_MB_LIB.T6G(SCH_1):PVDD18_S5_P0   I134 @T6G_MB_LIB.T6G(SCH_1):PAGE67
     2    GND @T6G_MB_LIB.T6G(SCH_1):GND   I134 @T6G_MB_LIB.T6G(SCH_1):PAGE67

C3898 Q_CAP_C0402-22UF,4V,20%,X6S,CH622KMEB02
     1 PVDDIO_P0 @T6G_MB_LIB.T6G(SCH_1):PVDDIO_P0   I141 @T6G_MB_LIB.T6G(SCH_1):PAGE67
     2    GND @T6G_MB_LIB.T6G(SCH_1):GND   I141 @T6G_MB_LIB.T6G(SCH_1):PAGE67

C3899 Q_CAP_C0402-22UF,4V,20%,X6S,CH622KMEB02
     1 PVDDIO_P0 @T6G_MB_LIB.T6G(SCH_1):PVDDIO_P0   I143 @T6G_MB_LIB.T6G(SCH_1):PAGE67
     2    GND @T6G_MB_LIB.T6G(SCH_1):GND   I143 @T6G_MB_LIB.T6G(SCH_1):PAGE67

C3900 Q_CAP_C0402-22UF,4V,20%,X6S,CH622KMEB02
     1 PVDDCR_SOC_P1 @T6G_MB_LIB.T6G(SCH_1):PVDDCR_SOC_P1     I5 @T6G_MB_LIB.T6G(SCH_1):PAGE71
     2    GND @T6G_MB_LIB.T6G(SCH_1):GND     I5 @T6G_MB_LIB.T6G(SCH_1):PAGE71

C3901 Q_CAP_C0402-22UF,4V,20%,X6S,CH622KMEB02
     1 PVDDCR_SOC_P1 @T6G_MB_LIB.T6G(SCH_1):PVDDCR_SOC_P1    I23 @T6G_MB_LIB.T6G(SCH_1):PAGE71
     2    GND @T6G_MB_LIB.T6G(SCH_1):GND    I23 @T6G_MB_LIB.T6G(SCH_1):PAGE71

C3902 Q_CAP_C0402-22UF,4V,20%,X6S,CH622KMEB02
     1 PVDD11_S3_P1 @T6G_MB_LIB.T6G(SCH_1):PVDD11_S3_P1    I12 @T6G_MB_LIB.T6G(SCH_1):PAGE71
     2    GND @T6G_MB_LIB.T6G(SCH_1):GND    I12 @T6G_MB_LIB.T6G(SCH_1):PAGE71

C3903 Q_CAP_C0402-22UF,4V,20%,X6S,CH622KMEB02
     1 PVDD11_S3_P1 @T6G_MB_LIB.T6G(SCH_1):PVDD11_S3_P1    I15 @T6G_MB_LIB.T6G(SCH_1):PAGE71
     2    GND @T6G_MB_LIB.T6G(SCH_1):GND    I15 @T6G_MB_LIB.T6G(SCH_1):PAGE71

C3904 Q_CAP_C0402-22UF,4V,20%,X6S,CH622KMEB02
     1 PVDD11_S3_P1 @T6G_MB_LIB.T6G(SCH_1):PVDD11_S3_P1    I16 @T6G_MB_LIB.T6G(SCH_1):PAGE71
     2    GND @T6G_MB_LIB.T6G(SCH_1):GND    I16 @T6G_MB_LIB.T6G(SCH_1):PAGE71

C3905 Q_CAP_C0402-22UF,4V,20%,X6S,CH622KMEB02
     1 PVDD11_S3_P1 @T6G_MB_LIB.T6G(SCH_1):PVDD11_S3_P1    I18 @T6G_MB_LIB.T6G(SCH_1):PAGE71
     2    GND @T6G_MB_LIB.T6G(SCH_1):GND    I18 @T6G_MB_LIB.T6G(SCH_1):PAGE71

C3906 Q_CAP_C0402-22UF,4V,20%,X6S,CH622KMEB02
     1 PVDDCR_SOC_P1 @T6G_MB_LIB.T6G(SCH_1):PVDDCR_SOC_P1    I41 @T6G_MB_LIB.T6G(SCH_1):PAGE71
     2    GND @T6G_MB_LIB.T6G(SCH_1):GND    I41 @T6G_MB_LIB.T6G(SCH_1):PAGE71

C3907 Q_CAP_C0402-22UF,4V,20%,X6S,CH622KMEB02
     1 PVDDCR_SOC_P1 @T6G_MB_LIB.T6G(SCH_1):PVDDCR_SOC_P1    I43 @T6G_MB_LIB.T6G(SCH_1):PAGE71
     2    GND @T6G_MB_LIB.T6G(SCH_1):GND    I43 @T6G_MB_LIB.T6G(SCH_1):PAGE71

C3908 Q_CAP_C0402-22UF,4V,20%,X6S,CH622KMEB02
     1 PVDDCR_SOC_P1 @T6G_MB_LIB.T6G(SCH_1):PVDDCR_SOC_P1    I45 @T6G_MB_LIB.T6G(SCH_1):PAGE71
     2    GND @T6G_MB_LIB.T6G(SCH_1):GND    I45 @T6G_MB_LIB.T6G(SCH_1):PAGE71

C3909 Q_CAP_C0402-22UF,4V,20%,X6S,CH622KMEB02
     1 PVDD18_S5_P1 @T6G_MB_LIB.T6G(SCH_1):PVDD18_S5_P1    I52 @T6G_MB_LIB.T6G(SCH_1):PAGE71
     2    GND @T6G_MB_LIB.T6G(SCH_1):GND    I52 @T6G_MB_LIB.T6G(SCH_1):PAGE71

C3910 Q_CAP_C0402-22UF,4V,20%,X6S,CH622KMEB02
     1 PVDDIO_P1 @T6G_MB_LIB.T6G(SCH_1):PVDDIO_P1    I59 @T6G_MB_LIB.T6G(SCH_1):PAGE71
     2    GND @T6G_MB_LIB.T6G(SCH_1):GND    I59 @T6G_MB_LIB.T6G(SCH_1):PAGE71

C3911 Q_CAP_C0402-22UF,4V,20%,X6S,CH622KMEB02
     1 PVDDIO_P1 @T6G_MB_LIB.T6G(SCH_1):PVDDIO_P1    I61 @T6G_MB_LIB.T6G(SCH_1):PAGE71
     2    GND @T6G_MB_LIB.T6G(SCH_1):GND    I61 @T6G_MB_LIB.T6G(SCH_1):PAGE71

C3912 Q_CAP_C0402-22UF,4V,20%,X6S,CH622KMEB02
     1 PVDDCR_SOC_P1 @T6G_MB_LIB.T6G(SCH_1):PVDDCR_SOC_P1     I1 @T6G_MB_LIB.T6G(SCH_1):PAGE73
     2    GND @T6G_MB_LIB.T6G(SCH_1):GND     I1 @T6G_MB_LIB.T6G(SCH_1):PAGE73

C3913 Q_CAP_C0402-22UF,4V,20%,X6S,CH622KMEB02
     1 PVDDCR_SOC_P1 @T6G_MB_LIB.T6G(SCH_1):PVDDCR_SOC_P1     I4 @T6G_MB_LIB.T6G(SCH_1):PAGE73
     2    GND @T6G_MB_LIB.T6G(SCH_1):GND     I4 @T6G_MB_LIB.T6G(SCH_1):PAGE73

C3914 Q_CAP_C0402-22UF,4V,20%,X6S,CH622KMEB02
     1 PVDDCR_SOC_P1 @T6G_MB_LIB.T6G(SCH_1):PVDDCR_SOC_P1     I6 @T6G_MB_LIB.T6G(SCH_1):PAGE73
     2    GND @T6G_MB_LIB.T6G(SCH_1):GND     I6 @T6G_MB_LIB.T6G(SCH_1):PAGE73

C3915 Q_CAP_C0402-22UF,4V,20%,X6S,CH622KMEB02
     1 PVDDCR_SOC_P1 @T6G_MB_LIB.T6G(SCH_1):PVDDCR_SOC_P1     I8 @T6G_MB_LIB.T6G(SCH_1):PAGE73
     2    GND @T6G_MB_LIB.T6G(SCH_1):GND     I8 @T6G_MB_LIB.T6G(SCH_1):PAGE73

C3916 Q_CAP_C0402-22UF,4V,20%,X6S,CH622KMEB02
     1 PVDDCR_SOC_P1 @T6G_MB_LIB.T6G(SCH_1):PVDDCR_SOC_P1    I25 @T6G_MB_LIB.T6G(SCH_1):PAGE73
     2    GND @T6G_MB_LIB.T6G(SCH_1):GND    I25 @T6G_MB_LIB.T6G(SCH_1):PAGE73

C3917 Q_CAP_C0402-22UF,4V,20%,X6S,CH622KMEB02
     1 PVDDCR_SOC_P1 @T6G_MB_LIB.T6G(SCH_1):PVDDCR_SOC_P1    I27 @T6G_MB_LIB.T6G(SCH_1):PAGE73
     2    GND @T6G_MB_LIB.T6G(SCH_1):GND    I27 @T6G_MB_LIB.T6G(SCH_1):PAGE73

C3918 Q_CAP_C0402-22UF,4V,20%,X6S,CH622KMEB02
     1 PVDDCR_SOC_P1 @T6G_MB_LIB.T6G(SCH_1):PVDDCR_SOC_P1    I30 @T6G_MB_LIB.T6G(SCH_1):PAGE73
     2    GND @T6G_MB_LIB.T6G(SCH_1):GND    I30 @T6G_MB_LIB.T6G(SCH_1):PAGE73

C3919 Q_CAP_C0402-22UF,4V,20%,X6S,CH622KMEB02
     1 PVDD11_S3_P1 @T6G_MB_LIB.T6G(SCH_1):PVDD11_S3_P1    I77 @T6G_MB_LIB.T6G(SCH_1):PAGE73
     2    GND @T6G_MB_LIB.T6G(SCH_1):GND    I77 @T6G_MB_LIB.T6G(SCH_1):PAGE73

C3920 Q_CAP_C0402-22UF,4V,20%,X6S,CH622KMEB02
     1 PVDD11_S3_P1 @T6G_MB_LIB.T6G(SCH_1):PVDD11_S3_P1    I84 @T6G_MB_LIB.T6G(SCH_1):PAGE73
     2    GND @T6G_MB_LIB.T6G(SCH_1):GND    I84 @T6G_MB_LIB.T6G(SCH_1):PAGE73

C3921 Q_CAP_C0402-22UF,4V,20%,X6S,CH622KMEB02
     1 PVDD11_S3_P1 @T6G_MB_LIB.T6G(SCH_1):PVDD11_S3_P1   I155 @T6G_MB_LIB.T6G(SCH_1):PAGE73
     2    GND @T6G_MB_LIB.T6G(SCH_1):GND   I155 @T6G_MB_LIB.T6G(SCH_1):PAGE73

C3922 Q_CAP_C0402-22UF,4V,20%,X6S,CH622KMEB02
     1 PVDD11_S3_P1 @T6G_MB_LIB.T6G(SCH_1):PVDD11_S3_P1   I157 @T6G_MB_LIB.T6G(SCH_1):PAGE73
     2    GND @T6G_MB_LIB.T6G(SCH_1):GND   I157 @T6G_MB_LIB.T6G(SCH_1):PAGE73

C3925 Q_CAP_C0402-22UF,4V,20%,X6S,CH622KMEB02
     1 PVDDCR_SOC_P0 @T6G_MB_LIB.T6G(SCH_1):PVDDCR_SOC_P0     I1 @T6G_MB_LIB.T6G(SCH_1):PAGE69
     2    GND @T6G_MB_LIB.T6G(SCH_1):GND     I1 @T6G_MB_LIB.T6G(SCH_1):PAGE69

C3926 Q_CAP_C0402-22UF,4V,20%,X6S,CH622KMEB02
     1 PVDDCR_SOC_P0 @T6G_MB_LIB.T6G(SCH_1):PVDDCR_SOC_P0     I3 @T6G_MB_LIB.T6G(SCH_1):PAGE69
     2    GND @T6G_MB_LIB.T6G(SCH_1):GND     I3 @T6G_MB_LIB.T6G(SCH_1):PAGE69

C3927 Q_CAP_C0402-22UF,4V,20%,X6S,CH622KMEB02
     1 PVDDCR_SOC_P0 @T6G_MB_LIB.T6G(SCH_1):PVDDCR_SOC_P0    I25 @T6G_MB_LIB.T6G(SCH_1):PAGE69
     2    GND @T6G_MB_LIB.T6G(SCH_1):GND    I25 @T6G_MB_LIB.T6G(SCH_1):PAGE69

C3928 Q_CAP_C0402-22UF,4V,20%,X6S,CH622KMEB02
     1 PVDDCR_SOC_P0 @T6G_MB_LIB.T6G(SCH_1):PVDDCR_SOC_P0    I26 @T6G_MB_LIB.T6G(SCH_1):PAGE69
     2    GND @T6G_MB_LIB.T6G(SCH_1):GND    I26 @T6G_MB_LIB.T6G(SCH_1):PAGE69

C3929 Q_CAP_C0402-22UF,4V,20%,X6S,CH622KMEB02
     1 PVDDCR_SOC_P0 @T6G_MB_LIB.T6G(SCH_1):PVDDCR_SOC_P0    I27 @T6G_MB_LIB.T6G(SCH_1):PAGE69
     2    GND @T6G_MB_LIB.T6G(SCH_1):GND    I27 @T6G_MB_LIB.T6G(SCH_1):PAGE69

C3930 Q_CAP_C0402-22UF,4V,20%,X6S,CH622KMEB02
     1 PVDDCR_SOC_P0 @T6G_MB_LIB.T6G(SCH_1):PVDDCR_SOC_P0    I31 @T6G_MB_LIB.T6G(SCH_1):PAGE69
     2    GND @T6G_MB_LIB.T6G(SCH_1):GND    I31 @T6G_MB_LIB.T6G(SCH_1):PAGE69

C3931 Q_CAP_C0402-22UF,4V,20%,X6S,CH622KMEB02
     1 PVDDCR_SOC_P0 @T6G_MB_LIB.T6G(SCH_1):PVDDCR_SOC_P0    I33 @T6G_MB_LIB.T6G(SCH_1):PAGE69
     2    GND @T6G_MB_LIB.T6G(SCH_1):GND    I33 @T6G_MB_LIB.T6G(SCH_1):PAGE69

C3932 Q_CAP_C0402-22UF,4V,20%,X6S,CH622KMEB02
     1 PVDD11_S3_P0 @T6G_MB_LIB.T6G(SCH_1):PVDD11_S3_P0    I53 @T6G_MB_LIB.T6G(SCH_1):PAGE69
     2    GND @T6G_MB_LIB.T6G(SCH_1):GND    I53 @T6G_MB_LIB.T6G(SCH_1):PAGE69

C3933 Q_CAP_C0402-22UF,4V,20%,X6S,CH622KMEB02
     1 PVDD11_S3_P0 @T6G_MB_LIB.T6G(SCH_1):PVDD11_S3_P0   I111 @T6G_MB_LIB.T6G(SCH_1):PAGE69
     2    GND @T6G_MB_LIB.T6G(SCH_1):GND   I111 @T6G_MB_LIB.T6G(SCH_1):PAGE69

C3934 Q_CAP_C0402-22UF,4V,20%,X6S,CH622KMEB02
     1 PVDD11_S3_P0 @T6G_MB_LIB.T6G(SCH_1):PVDD11_S3_P0   I138 @T6G_MB_LIB.T6G(SCH_1):PAGE69
     2    GND @T6G_MB_LIB.T6G(SCH_1):GND   I138 @T6G_MB_LIB.T6G(SCH_1):PAGE69

C3935 Q_CAP_C0402-22UF,4V,20%,X6S,CH622KMEB02
     1 PVDD11_S3_P0 @T6G_MB_LIB.T6G(SCH_1):PVDD11_S3_P0   I140 @T6G_MB_LIB.T6G(SCH_1):PAGE69
     2    GND @T6G_MB_LIB.T6G(SCH_1):GND   I140 @T6G_MB_LIB.T6G(SCH_1):PAGE69

C4178 Q_CAP_C0402-22UF,4V,20%,X6S,CH622KMEB02
     1 PVDDCR_CPU0_P0 @T6G_MB_LIB.T6G(SCH_1):PVDDCR_CPU0_P0    I47 @T6G_MB_LIB.T6G(SCH_1):PAGE68
     2    GND @T6G_MB_LIB.T6G(SCH_1):GND    I47 @T6G_MB_LIB.T6G(SCH_1):PAGE68

C4179 Q_CAP_C0402-22UF,4V,20%,X6S,CH622KMEB02
     1 PVDDCR_CPU0_P0 @T6G_MB_LIB.T6G(SCH_1):PVDDCR_CPU0_P0    I48 @T6G_MB_LIB.T6G(SCH_1):PAGE68
     2    GND @T6G_MB_LIB.T6G(SCH_1):GND    I48 @T6G_MB_LIB.T6G(SCH_1):PAGE68

C5000 Q_CAP_0402-1000PF,50V,5%,X7R,TMP_QCH21006JB10
     1 FM_BIOS_POST_CMPLT_BUF_N @T6G_MB_LIB.T6G(SCH_1):FM_BIOS_POST_CMPLT_BUF_N   I124 @T6G_MB_LIB.T6G(SCH_1):PAGE34
     2    GND @T6G_MB_LIB.T6G(SCH_1):GND   I124 @T6G_MB_LIB.T6G(SCH_1):PAGE34

C5001 Q_CAP_0402-1000PF,50V,5%,X7R,TMP_QCH21006JB10
     1 FM_PWRGD_PVDD18_S5_P0 @T6G_MB_LIB.T6G(SCH_1):FM_PWRGD_PVDD18_S5_P0    I56 @T6G_MB_LIB.T6G(SCH_1):PAGE184
     2    GND @T6G_MB_LIB.T6G(SCH_1):GND    I56 @T6G_MB_LIB.T6G(SCH_1):PAGE184

C5002 Q_CAP_0402-1000PF,50V,5%,X7R,TMP_QCH21006JB10
     1 FM_PWRGD_PVDD33_S5 @T6G_MB_LIB.T6G(SCH_1):FM_PWRGD_PVDD33_S5    I43 @T6G_MB_LIB.T6G(SCH_1):PAGE167
     2    GND @T6G_MB_LIB.T6G(SCH_1):GND    I43 @T6G_MB_LIB.T6G(SCH_1):PAGE167

C5003 Q_CAP_0402-1000PF,50V,5%,X7R,TMP_QCH21006JB10
     1    GND @T6G_MB_LIB.T6G(SCH_1):GND   I141 @T6G_MB_LIB.T6G(SCH_1):PAGE185
     2 PWRGD_PVDDCR_CPU0_P1 @T6G_MB_LIB.T6G(SCH_1):PWRGD_PVDDCR_CPU0_P1   I141 @T6G_MB_LIB.T6G(SCH_1):PAGE185

C5004 Q_CAP_0402-1000PF,50V,5%,X7R,TMP_QCH21006JB10
     1    GND @T6G_MB_LIB.T6G(SCH_1):GND   I135 @T6G_MB_LIB.T6G(SCH_1):PAGE175
     2 PWRGD_PVDDCR_CPU1_P0 @T6G_MB_LIB.T6G(SCH_1):PWRGD_PVDDCR_CPU1_P0   I135 @T6G_MB_LIB.T6G(SCH_1):PAGE175

C5005 Q_CAP_0402-1000PF,50V,5%,X7R,TMP_QCH21006JB10
     1    GND @T6G_MB_LIB.T6G(SCH_1):GND   I133 @T6G_MB_LIB.T6G(SCH_1):PAGE175
     2 PWRGD_PVDDIO_P0 @T6G_MB_LIB.T6G(SCH_1):PWRGD_PVDDIO_P0   I133 @T6G_MB_LIB.T6G(SCH_1):PAGE175

C5006 Q_CAP_0402-1000PF,50V,5%,X7R,TMP_QCH21006JB10
     1    GND @T6G_MB_LIB.T6G(SCH_1):GND   I136 @T6G_MB_LIB.T6G(SCH_1):PAGE192
     2 PWRGD_PVDDIO_P1 @T6G_MB_LIB.T6G(SCH_1):PWRGD_PVDDIO_P1   I136 @T6G_MB_LIB.T6G(SCH_1):PAGE192

C5009 Q_CAP_0402-1000PF,50V,5%,X7R,TMP_QCH21006JB10
     1 PVDD11_S3_P0_PMALERT @T6G_MB_LIB.T6G(SCH_1):PVDD11_S3_P0_PMALERT    I88 @T6G_MB_LIB.T6G(SCH_1):PAGE182
     2    GND @T6G_MB_LIB.T6G(SCH_1):GND    I88 @T6G_MB_LIB.T6G(SCH_1):PAGE182

C5010 Q_CAP_0402-1000PF,50V,5%,X7R,TMP_QCH21006JB10
     1 PVDD11_S3_P1_PMALERT @T6G_MB_LIB.T6G(SCH_1):PVDD11_S3_P1_PMALERT    I88 @T6G_MB_LIB.T6G(SCH_1):PAGE199
     2    GND @T6G_MB_LIB.T6G(SCH_1):GND    I88 @T6G_MB_LIB.T6G(SCH_1):PAGE199

C5011 Q_CAP_0402-1000PF,50V,5%,X7R,TMP_QCH21006JB10
     1 PVDDCR_CPU0_P0_PMALERT @T6G_MB_LIB.T6G(SCH_1):PVDDCR_CPU0_P0_PMALERT   I142 @T6G_MB_LIB.T6G(SCH_1):PAGE168
     2    GND @T6G_MB_LIB.T6G(SCH_1):GND   I142 @T6G_MB_LIB.T6G(SCH_1):PAGE168

C5012 Q_CAP_0402-1000PF,50V,5%,X7R,TMP_QCH21006JB10
     1 PVDDCR_CPU0_P1_PMALERT @T6G_MB_LIB.T6G(SCH_1):PVDDCR_CPU0_P1_PMALERT   I139 @T6G_MB_LIB.T6G(SCH_1):PAGE185
     2    GND @T6G_MB_LIB.T6G(SCH_1):GND   I139 @T6G_MB_LIB.T6G(SCH_1):PAGE185

C5013 Q_CAP_0402-1000PF,50V,5%,X7R,TMP_QCH21006JB10
     1 PVDDCR_CPU1_P0_SMB_ALERT @T6G_MB_LIB.T6G(SCH_1):PVDDCR_CPU1_P0_SMB_ALERT   I130 @T6G_MB_LIB.T6G(SCH_1):PAGE175
     2    GND @T6G_MB_LIB.T6G(SCH_1):GND   I130 @T6G_MB_LIB.T6G(SCH_1):PAGE175

C5014 Q_CAP_0402-1000PF,50V,5%,X7R,TMP_QCH21006JB10
     1 PWRGD_P12V_MEM_R @T6G_MB_LIB.T6G(SCH_1):PWRGD_P12V_MEM_R    I49 @T6G_MB_LIB.T6G(SCH_1):PAGE264
     2    GND @T6G_MB_LIB.T6G(SCH_1):GND    I49 @T6G_MB_LIB.T6G(SCH_1):PAGE264

C5015 Q_CAP_0402-1000PF,50V,5%,EMPTY,TMP_QCH21006JB10
     1 PWRGD_P3V3_AUX @T6G_MB_LIB.T6G(SCH_1):PWRGD_P3V3_AUX    I68 @T6G_MB_LIB.T6G(SCH_1):PAGE245
     2    GND @T6G_MB_LIB.T6G(SCH_1):GND    I68 @T6G_MB_LIB.T6G(SCH_1):PAGE245

C5016 Q_CAP_0402-1000PF,50V,5%,X7R,TMP_QCH21006JB10
     1 PWRGD_PVDD18_S5_R_P1 @T6G_MB_LIB.T6G(SCH_1):PWRGD_PVDD18_S5_R_P1    I55 @T6G_MB_LIB.T6G(SCH_1):PAGE201
     2    GND @T6G_MB_LIB.T6G(SCH_1):GND    I55 @T6G_MB_LIB.T6G(SCH_1):PAGE201

C5017 Q_CAP_0402-1000PF,50V,5%,X7R,TMP_QCH21006JB10
     1    GND @T6G_MB_LIB.T6G(SCH_1):GND   I139 @T6G_MB_LIB.T6G(SCH_1):PAGE168
     2 PWRGD_PVDDCR_CPU0_P0 @T6G_MB_LIB.T6G(SCH_1):PWRGD_PVDDCR_CPU0_P0   I139 @T6G_MB_LIB.T6G(SCH_1):PAGE168

C5018 Q_CAP_0402-1000PF,50V,5%,X7R,TMP_QCH21006JB10
     1    GND @T6G_MB_LIB.T6G(SCH_1):GND   I138 @T6G_MB_LIB.T6G(SCH_1):PAGE168
     2 PWRGD_PVDDCR_SOC_P0 @T6G_MB_LIB.T6G(SCH_1):PWRGD_PVDDCR_SOC_P0   I138 @T6G_MB_LIB.T6G(SCH_1):PAGE168

C5019 Q_CAP_0402-1000PF,50V,5%,X7R,TMP_QCH21006JB10
     1    GND @T6G_MB_LIB.T6G(SCH_1):GND   I137 @T6G_MB_LIB.T6G(SCH_1):PAGE185
     2 PWRGD_PVDDCR_SOC_P1 @T6G_MB_LIB.T6G(SCH_1):PWRGD_PVDDCR_SOC_P1   I137 @T6G_MB_LIB.T6G(SCH_1):PAGE185

C5020 Q_CAP_0402-1000PF,50V,5%,X7R,TMP_QCH21006JB10
     1    GND @T6G_MB_LIB.T6G(SCH_1):GND   I133 @T6G_MB_LIB.T6G(SCH_1):PAGE192
     2 PVDDCR_CPU1_P1_SMB_ALERT @T6G_MB_LIB.T6G(SCH_1):PVDDCR_CPU1_P1_SMB_ALERT   I133 @T6G_MB_LIB.T6G(SCH_1):PAGE192

C5022 Q_CAP_0402-1000PF,50V,5%,X7R,TMP_QCH21006JB10
     1    GND @T6G_MB_LIB.T6G(SCH_1):GND   I131 @T6G_MB_LIB.T6G(SCH_1):PAGE192
     2 PWRGD_PVDDCR_CPU1_P1 @T6G_MB_LIB.T6G(SCH_1):PWRGD_PVDDCR_CPU1_P1   I131 @T6G_MB_LIB.T6G(SCH_1):PAGE192

C5023 Q_CAP_0402-1000PF,50V,5%,X7R,TMP_QCH21006JB10
     1 RST_CPU0_RSMRST_N @T6G_MB_LIB.T6G(SCH_1):RST_CPU0_RSMRST_N   I194 @T6G_MB_LIB.T6G(SCH_1):PAGE28
     2    GND @T6G_MB_LIB.T6G(SCH_1):GND   I194 @T6G_MB_LIB.T6G(SCH_1):PAGE28

C5024 Q_CAP_0402-1000PF,50V,5%,X7R,TMP_QCH21006JB10
     1 RST_CPU1_RSMRST_N @T6G_MB_LIB.T6G(SCH_1):RST_CPU1_RSMRST_N   I388 @T6G_MB_LIB.T6G(SCH_1):PAGE55
     2    GND @T6G_MB_LIB.T6G(SCH_1):GND   I388 @T6G_MB_LIB.T6G(SCH_1):PAGE55

C5032 Q_CAP_C0805-10UF,25V,10%,X6S,CH6104KEA00
     1 P1V5_BAT @T6G_MB_LIB.T6G(SCH_1):P1V5_BAT   I126 @T6G_MB_LIB.T6G(SCH_1):PAGE156
     2    GND @T6G_MB_LIB.T6G(SCH_1):GND   I126 @T6G_MB_LIB.T6G(SCH_1):PAGE156

C5229 Q_CAP_C0402-1UF,25V,10%,EMPTY,CH5104KEB02
     1 P3V3_AUX @T6G_MB_LIB.T6G(SCH_1):P3V3_AUX    I88 @T6G_MB_LIB.T6G(SCH_1):PAGE358
     2    GND @T6G_MB_LIB.T6G(SCH_1):GND    I88 @T6G_MB_LIB.T6G(SCH_1):PAGE358

C5232 Q_CAP_C0402-0.1UF,25V,10%,EMPTY,CH4104KEB00
     1 PD_U5201_RSTN @T6G_MB_LIB.T6G(SCH_1):PD_U5201_RSTN    I81 @T6G_MB_LIB.T6G(SCH_1):PAGE358
     2    GND @T6G_MB_LIB.T6G(SCH_1):GND    I81 @T6G_MB_LIB.T6G(SCH_1):PAGE358

C5234 Q_CAP_C0402-0.1UF,25V,10%,EMPTY,CH4104KEB00
     1 P3V3_AUX @T6G_MB_LIB.T6G(SCH_1):P3V3_AUX    I92 @T6G_MB_LIB.T6G(SCH_1):PAGE358
     2    GND @T6G_MB_LIB.T6G(SCH_1):GND    I92 @T6G_MB_LIB.T6G(SCH_1):PAGE358

C5236 Q_CAP_C0402-0.1UF,25V,10%,EMPTY,CH4104KEB00
     1 PD_U5201_VREG @T6G_MB_LIB.T6G(SCH_1):PD_U5201_VREG    I87 @T6G_MB_LIB.T6G(SCH_1):PAGE358
     2    GND @T6G_MB_LIB.T6G(SCH_1):GND    I87 @T6G_MB_LIB.T6G(SCH_1):PAGE358

C6000 Q_CAP_0402-0.1UF,25V,10%,X7R,CH4104K1B00
     1 SCM_VDD_RTC @T6G_MB_LIB.T6G(SCH_1):SCM_VDD_RTC   I219 @T6G_MB_LIB.T6G(SCH_1):PAGE348
     2    GND @T6G_MB_LIB.T6G(SCH_1):GND   I219 @T6G_MB_LIB.T6G(SCH_1):PAGE348

C6003 Q_CAP_0402-0.1UF,25V,10%,X7R,CH4104K1B00
     1 USB3_CPU0_BMC_TX_DP @T6G_MB_LIB.T6G(SCH_1):USB3_CPU0_BMC_TX_DP   I144 @T6G_MB_LIB.T6G(SCH_1):PAGE158
     2 USB3_CPU0_BMC_TX_C1_DP @T6G_MB_LIB.T6G(SCH_1):USB3_CPU0_BMC_TX_C1_DP   I144 @T6G_MB_LIB.T6G(SCH_1):PAGE158

C6004 Q_CAP_0402-0.1UF,25V,10%,X7R,CH4104K1B00
     1 USB3_CPU0_BMC_TX_DN @T6G_MB_LIB.T6G(SCH_1):USB3_CPU0_BMC_TX_DN   I143 @T6G_MB_LIB.T6G(SCH_1):PAGE158
     2 USB3_CPU0_BMC_TX_C1_DN @T6G_MB_LIB.T6G(SCH_1):USB3_CPU0_BMC_TX_C1_DN   I143 @T6G_MB_LIB.T6G(SCH_1):PAGE158

C6005 Q_CAP_0402-0.1UF,25V,10%,X7R,CH4104K1B00
     1 P2E_MB_BMC_TX_BUF2_DP<0> @T6G_MB_LIB.T6G(SCH_1):P2E_MB_BMC_TX_BUF2_DP(0)    I36 @T6G_MB_LIB.T6G(SCH_1):PAGE112
     2 P2E_MB_BMC_TX_BUF_C_DP<0> @T6G_MB_LIB.T6G(SCH_1):P2E_MB_BMC_TX_BUF_C_DP(0)    I36 @T6G_MB_LIB.T6G(SCH_1):PAGE112

C6006 Q_CAP_0402-0.1UF,25V,10%,X7R,CH4104K1B00
     1 P2E_MB_BMC_TX_BUF2_DN<0> @T6G_MB_LIB.T6G(SCH_1):P2E_MB_BMC_TX_BUF2_DN(0)    I35 @T6G_MB_LIB.T6G(SCH_1):PAGE112
     2 P2E_MB_BMC_TX_BUF_C_DN<0> @T6G_MB_LIB.T6G(SCH_1):P2E_MB_BMC_TX_BUF_C_DN(0)    I35 @T6G_MB_LIB.T6G(SCH_1):PAGE112

C6007 Q_CAP_0402-0.1UF,25V,10%,X7R,CH4104K1B00
     1 P2E_MB_BMC_RX_BUF2_C_DP<0> @T6G_MB_LIB.T6G(SCH_1):P2E_MB_BMC_RX_BUF2_C_DP(0)    I43 @T6G_MB_LIB.T6G(SCH_1):PAGE112
     2 P2E_MB_BMC_RX_BUF_DP<0> @T6G_MB_LIB.T6G(SCH_1):P2E_MB_BMC_RX_BUF_DP(0)    I43 @T6G_MB_LIB.T6G(SCH_1):PAGE112

C6008 Q_CAP_0402-0.1UF,25V,10%,X7R,CH4104K1B00
     1 P2E_MB_BMC_RX_BUF2_C_DN<0> @T6G_MB_LIB.T6G(SCH_1):P2E_MB_BMC_RX_BUF2_C_DN(0)    I44 @T6G_MB_LIB.T6G(SCH_1):PAGE112
     2 P2E_MB_BMC_RX_BUF_DN<0> @T6G_MB_LIB.T6G(SCH_1):P2E_MB_BMC_RX_BUF_DN(0)    I44 @T6G_MB_LIB.T6G(SCH_1):PAGE112

C6009 Q_CAP_C0402-1UF,25V,10%,X6S,CH5104KEB02
     1 P3V3_AUX @T6G_MB_LIB.T6G(SCH_1):P3V3_AUX     I3 @T6G_MB_LIB.T6G(SCH_1):PAGE111
     2    GND @T6G_MB_LIB.T6G(SCH_1):GND     I3 @T6G_MB_LIB.T6G(SCH_1):PAGE111

C6010 Q_CAP_C0805-10UF,16V,10%,X6S,CH6103KEA00
     1 P3V3_AUX @T6G_MB_LIB.T6G(SCH_1):P3V3_AUX     I5 @T6G_MB_LIB.T6G(SCH_1):PAGE111
     2    GND @T6G_MB_LIB.T6G(SCH_1):GND     I5 @T6G_MB_LIB.T6G(SCH_1):PAGE111

C6011 Q_CAP_0402-0.1UF,25V,10%,X7R,CH4104K1B00
     1 BUF2_VDD @T6G_MB_LIB.T6G(SCH_1):BUF2_VDD     I6 @T6G_MB_LIB.T6G(SCH_1):PAGE111
     2    GND @T6G_MB_LIB.T6G(SCH_1):GND     I6 @T6G_MB_LIB.T6G(SCH_1):PAGE111

C6012 Q_CAP_0402-0.1UF,25V,10%,X7R,CH4104K1B00
     1 BUF2_VDD @T6G_MB_LIB.T6G(SCH_1):BUF2_VDD     I7 @T6G_MB_LIB.T6G(SCH_1):PAGE111
     2    GND @T6G_MB_LIB.T6G(SCH_1):GND     I7 @T6G_MB_LIB.T6G(SCH_1):PAGE111

C6013 Q_CAP_0402-0.1UF,25V,10%,X7R,CH4104K1B00
     1 USB3_CPU0_BMC_TX_DP @T6G_MB_LIB.T6G(SCH_1):USB3_CPU0_BMC_TX_DP   I142 @T6G_MB_LIB.T6G(SCH_1):PAGE158
     2 USB3_CPU0_BMC_TX_C2_DP @T6G_MB_LIB.T6G(SCH_1):USB3_CPU0_BMC_TX_C2_DP   I142 @T6G_MB_LIB.T6G(SCH_1):PAGE158

C6014 Q_CAP_0402-0.1UF,25V,10%,X7R,CH4104K1B00
     1 USB3_CPU0_BMC_TX_DN @T6G_MB_LIB.T6G(SCH_1):USB3_CPU0_BMC_TX_DN   I141 @T6G_MB_LIB.T6G(SCH_1):PAGE158
     2 USB3_CPU0_BMC_TX_C2_DN @T6G_MB_LIB.T6G(SCH_1):USB3_CPU0_BMC_TX_C2_DN   I141 @T6G_MB_LIB.T6G(SCH_1):PAGE158

C6015 Q_CAP_DIFFBUS_C0402-DIFF BUS_0.33UF,6.3V,10%,X6S,SA
     1 USB3_CPU0_BMC_RX_HUB1_DP @T6G_MB_LIB.T6G(SCH_1):USB3_CPU0_BMC_RX_HUB1_DP    I49 @T6G_MB_LIB.T6G(SCH_1):PAGE158
     2 USB3_CPU0_BMC_RX_HUB_C_DP @T6G_MB_LIB.T6G(SCH_1):USB3_CPU0_BMC_RX_HUB_C_DP    I49 @T6G_MB_LIB.T6G(SCH_1):PAGE158

C6016 Q_CAP_DIFFBUS_C0402-DIFF BUS_0.33UF,6.3V,10%,X6S,SA
     1 USB3_CPU0_BMC_RX_HUB1_DN @T6G_MB_LIB.T6G(SCH_1):USB3_CPU0_BMC_RX_HUB1_DN    I50 @T6G_MB_LIB.T6G(SCH_1):PAGE158
     2 USB3_CPU0_BMC_RX_HUB_C_DN @T6G_MB_LIB.T6G(SCH_1):USB3_CPU0_BMC_RX_HUB_C_DN    I50 @T6G_MB_LIB.T6G(SCH_1):PAGE158

C6017 Q_CAP_0402-0.1UF,25V,10%,X7R,CH4104K1B00
     1 USB3_CPU0_BMC_RX_HUB2_DP @T6G_MB_LIB.T6G(SCH_1):USB3_CPU0_BMC_RX_HUB2_DP   I148 @T6G_MB_LIB.T6G(SCH_1):PAGE158
     2 USB3_CPU0_BMC_RX_HUB_C_DP @T6G_MB_LIB.T6G(SCH_1):USB3_CPU0_BMC_RX_HUB_C_DP   I148 @T6G_MB_LIB.T6G(SCH_1):PAGE158

C6018 Q_CAP_0402-0.1UF,25V,10%,X7R,CH4104K1B00
     1 USB3_CPU0_BMC_RX_HUB2_DN @T6G_MB_LIB.T6G(SCH_1):USB3_CPU0_BMC_RX_HUB2_DN   I147 @T6G_MB_LIB.T6G(SCH_1):PAGE158
     2 USB3_CPU0_BMC_RX_HUB_C_DN @T6G_MB_LIB.T6G(SCH_1):USB3_CPU0_BMC_RX_HUB_C_DN   I147 @T6G_MB_LIB.T6G(SCH_1):PAGE158

C6019 Q_CAP_DIFFBUS_C0402-DIFF BUS_0.33UF,6.3V,10%,X6S,SA
     1 USB3_CPU0_BMC_RX_DP @T6G_MB_LIB.T6G(SCH_1):USB3_CPU0_BMC_RX_DP    I85 @T6G_MB_LIB.T6G(SCH_1):PAGE158
     2 USB3_CPU0_BMC_RX_C1_DP @T6G_MB_LIB.T6G(SCH_1):USB3_CPU0_BMC_RX_C1_DP    I85 @T6G_MB_LIB.T6G(SCH_1):PAGE158

C6020 Q_CAP_DIFFBUS_C0402-DIFF BUS_0.33UF,6.3V,10%,X6S,SA
     1 USB3_CPU0_BMC_RX_DN @T6G_MB_LIB.T6G(SCH_1):USB3_CPU0_BMC_RX_DN    I86 @T6G_MB_LIB.T6G(SCH_1):PAGE158
     2 USB3_CPU0_BMC_RX_C1_DN @T6G_MB_LIB.T6G(SCH_1):USB3_CPU0_BMC_RX_C1_DN    I86 @T6G_MB_LIB.T6G(SCH_1):PAGE158

C6021 Q_CAP_DIFFBUS_C0402-DIFF BUS_0.33UF,6.3V,10%,X6S,SA
     1 USB3_CPU0_BMC_RX_DP @T6G_MB_LIB.T6G(SCH_1):USB3_CPU0_BMC_RX_DP    I87 @T6G_MB_LIB.T6G(SCH_1):PAGE158
     2 USB3_CPU0_BMC_RX_C2_DP @T6G_MB_LIB.T6G(SCH_1):USB3_CPU0_BMC_RX_C2_DP    I87 @T6G_MB_LIB.T6G(SCH_1):PAGE158

C6022 Q_CAP_DIFFBUS_C0402-DIFF BUS_0.33UF,6.3V,10%,X6S,SA
     1 USB3_CPU0_BMC_RX_DN @T6G_MB_LIB.T6G(SCH_1):USB3_CPU0_BMC_RX_DN    I88 @T6G_MB_LIB.T6G(SCH_1):PAGE158
     2 USB3_CPU0_BMC_RX_C2_DN @T6G_MB_LIB.T6G(SCH_1):USB3_CPU0_BMC_RX_C2_DN    I88 @T6G_MB_LIB.T6G(SCH_1):PAGE158

C6023 Q_CAP_0402-0.1UF,25V,10%,X7R,CH4104K1B00
     1 USB3_CPU0_BMC_HUB1_TX_DP @T6G_MB_LIB.T6G(SCH_1):USB3_CPU0_BMC_HUB1_TX_DP   I137 @T6G_MB_LIB.T6G(SCH_1):PAGE158
     2 USB3_CPU0_BMC_TX_BUF_C_DP @T6G_MB_LIB.T6G(SCH_1):USB3_CPU0_BMC_TX_BUF_C_DP   I137 @T6G_MB_LIB.T6G(SCH_1):PAGE158

C6024 Q_CAP_0402-0.1UF,25V,10%,X7R,CH4104K1B00
     1 USB3_CPU0_BMC_HUB1_TX_DN @T6G_MB_LIB.T6G(SCH_1):USB3_CPU0_BMC_HUB1_TX_DN   I138 @T6G_MB_LIB.T6G(SCH_1):PAGE158
     2 USB3_CPU0_BMC_TX_BUF_C_DN @T6G_MB_LIB.T6G(SCH_1):USB3_CPU0_BMC_TX_BUF_C_DN   I138 @T6G_MB_LIB.T6G(SCH_1):PAGE158

C6025 Q_CAP_0402-0.1UF,25V,10%,X7R,CH4104K1B00
     1 USB3_CPU0_BMC_HUB2_TX_DP @T6G_MB_LIB.T6G(SCH_1):USB3_CPU0_BMC_HUB2_TX_DP   I139 @T6G_MB_LIB.T6G(SCH_1):PAGE158
     2 USB3_CPU0_BMC_TX_BUF_C_DP @T6G_MB_LIB.T6G(SCH_1):USB3_CPU0_BMC_TX_BUF_C_DP   I139 @T6G_MB_LIB.T6G(SCH_1):PAGE158

C6026 Q_CAP_0402-0.1UF,25V,10%,X7R,CH4104K1B00
     1 USB3_CPU0_BMC_HUB2_TX_DN @T6G_MB_LIB.T6G(SCH_1):USB3_CPU0_BMC_HUB2_TX_DN   I140 @T6G_MB_LIB.T6G(SCH_1):PAGE158
     2 USB3_CPU0_BMC_TX_BUF_C_DN @T6G_MB_LIB.T6G(SCH_1):USB3_CPU0_BMC_TX_BUF_C_DN   I140 @T6G_MB_LIB.T6G(SCH_1):PAGE158

C6027 Q_CAP_C0805-22UF,16V,20%,X6S,CH6223MEA00
     1 P5V_AUX @T6G_MB_LIB.T6G(SCH_1):P5V_AUX    I28 @T6G_MB_LIB.T6G(SCH_1):PAGE153
     2    GND @T6G_MB_LIB.T6G(SCH_1):GND    I28 @T6G_MB_LIB.T6G(SCH_1):PAGE153

C6028 Q_CAP_0402-470PF,50V,10%,X7R,TMP_QCH14706KB18
     1 P5V_AUX @T6G_MB_LIB.T6G(SCH_1):P5V_AUX    I29 @T6G_MB_LIB.T6G(SCH_1):PAGE153
     2    GND @T6G_MB_LIB.T6G(SCH_1):GND    I29 @T6G_MB_LIB.T6G(SCH_1):PAGE153

C6030 Q_CAP_C0603-22UF,6.3V,20%,X6S,CH6221ME900
     1 P1V2_CPU0_USB_DVDD12 @T6G_MB_LIB.T6G(SCH_1):P1V2_CPU0_USB_DVDD12    I27 @T6G_MB_LIB.T6G(SCH_1):PAGE154
     2    GND @T6G_MB_LIB.T6G(SCH_1):GND    I27 @T6G_MB_LIB.T6G(SCH_1):PAGE154

C6031 Q_CAP_C0402-1UF,25V,10%,X6S,CH5104KEB02
     1 P1V2_CPU0_USB_DVDD12 @T6G_MB_LIB.T6G(SCH_1):P1V2_CPU0_USB_DVDD12    I29 @T6G_MB_LIB.T6G(SCH_1):PAGE154
     2    GND @T6G_MB_LIB.T6G(SCH_1):GND    I29 @T6G_MB_LIB.T6G(SCH_1):PAGE154

C6032 Q_CAP_0402-0.1UF,25V,10%,X7R,CH4104K1B00
     1 P1V2_CPU0_USB_DVDD12 @T6G_MB_LIB.T6G(SCH_1):P1V2_CPU0_USB_DVDD12    I35 @T6G_MB_LIB.T6G(SCH_1):PAGE154
     2    GND @T6G_MB_LIB.T6G(SCH_1):GND    I35 @T6G_MB_LIB.T6G(SCH_1):PAGE154

C6033 Q_CAP_C0402-0.01UF,50V,10%,X7R,CH31006KB18
     1 P1V2_CPU0_USB_DVDD12 @T6G_MB_LIB.T6G(SCH_1):P1V2_CPU0_USB_DVDD12    I34 @T6G_MB_LIB.T6G(SCH_1):PAGE154
     2    GND @T6G_MB_LIB.T6G(SCH_1):GND    I34 @T6G_MB_LIB.T6G(SCH_1):PAGE154

C6034 Q_CAP_0402-0.1UF,25V,10%,X7R,CH4104K1B00
     1 P1V2_CPU0_USB_DVDD12 @T6G_MB_LIB.T6G(SCH_1):P1V2_CPU0_USB_DVDD12    I32 @T6G_MB_LIB.T6G(SCH_1):PAGE154
     2    GND @T6G_MB_LIB.T6G(SCH_1):GND    I32 @T6G_MB_LIB.T6G(SCH_1):PAGE154

C6035 Q_CAP_C0402-0.01UF,50V,10%,X7R,CH31006KB18
     1 P1V2_CPU0_USB_DVDD12 @T6G_MB_LIB.T6G(SCH_1):P1V2_CPU0_USB_DVDD12    I31 @T6G_MB_LIB.T6G(SCH_1):PAGE154
     2    GND @T6G_MB_LIB.T6G(SCH_1):GND    I31 @T6G_MB_LIB.T6G(SCH_1):PAGE154

C6036 Q_CAP_0402-0.1UF,25V,10%,X7R,CH4104K1B00
     1 P1V2_CPU0_USB_DVDD12 @T6G_MB_LIB.T6G(SCH_1):P1V2_CPU0_USB_DVDD12    I37 @T6G_MB_LIB.T6G(SCH_1):PAGE154
     2    GND @T6G_MB_LIB.T6G(SCH_1):GND    I37 @T6G_MB_LIB.T6G(SCH_1):PAGE154

C6037 Q_CAP_C0402-0.01UF,50V,10%,X7R,CH31006KB18
     1 P1V2_CPU0_USB_DVDD12 @T6G_MB_LIB.T6G(SCH_1):P1V2_CPU0_USB_DVDD12    I38 @T6G_MB_LIB.T6G(SCH_1):PAGE154
     2    GND @T6G_MB_LIB.T6G(SCH_1):GND    I38 @T6G_MB_LIB.T6G(SCH_1):PAGE154

C6038 Q_CAP_0402-0.1UF,25V,10%,X7R,CH4104K1B00
     1 P1V2_CPU0_USB_DVDD12 @T6G_MB_LIB.T6G(SCH_1):P1V2_CPU0_USB_DVDD12    I41 @T6G_MB_LIB.T6G(SCH_1):PAGE154
     2    GND @T6G_MB_LIB.T6G(SCH_1):GND    I41 @T6G_MB_LIB.T6G(SCH_1):PAGE154

C6039 Q_CAP_C0402-0.01UF,50V,10%,X7R,CH31006KB18
     1 P1V2_CPU0_USB_DVDD12 @T6G_MB_LIB.T6G(SCH_1):P1V2_CPU0_USB_DVDD12    I40 @T6G_MB_LIB.T6G(SCH_1):PAGE154
     2    GND @T6G_MB_LIB.T6G(SCH_1):GND    I40 @T6G_MB_LIB.T6G(SCH_1):PAGE154

C6040 Q_CAP_C0402-0.01UF,50V,10%,X7R,CH31006KB18
     1 P3V3_AUX @T6G_MB_LIB.T6G(SCH_1):P3V3_AUX     I5 @T6G_MB_LIB.T6G(SCH_1):PAGE154
     2    GND @T6G_MB_LIB.T6G(SCH_1):GND     I5 @T6G_MB_LIB.T6G(SCH_1):PAGE154

C6041 Q_CAP_0402-0.1UF,25V,10%,X7R,CH4104K1B00
     1 P3V3_AUX @T6G_MB_LIB.T6G(SCH_1):P3V3_AUX     I7 @T6G_MB_LIB.T6G(SCH_1):PAGE154
     2    GND @T6G_MB_LIB.T6G(SCH_1):GND     I7 @T6G_MB_LIB.T6G(SCH_1):PAGE154

C6042 Q_CAP_C0603-22UF,6.3V,20%,X6S,CH6221ME900
     1 P3V3_AUX_CPU0_USB_AVDD33 @T6G_MB_LIB.T6G(SCH_1):P3V3_AUX_CPU0_USB_AVDD33     I9 @T6G_MB_LIB.T6G(SCH_1):PAGE154
     2    GND @T6G_MB_LIB.T6G(SCH_1):GND     I9 @T6G_MB_LIB.T6G(SCH_1):PAGE154

C6043 Q_CAP_C0402-1UF,25V,10%,X6S,CH5104KEB02
     1 P3V3_AUX_CPU0_USB_AVDD33 @T6G_MB_LIB.T6G(SCH_1):P3V3_AUX_CPU0_USB_AVDD33    I10 @T6G_MB_LIB.T6G(SCH_1):PAGE154
     2    GND @T6G_MB_LIB.T6G(SCH_1):GND    I10 @T6G_MB_LIB.T6G(SCH_1):PAGE154

C6044 Q_CAP_0402-0.1UF,25V,10%,X7R,CH4104K1B00
     1 P3V3_AUX_CPU0_USB_AVDD33 @T6G_MB_LIB.T6G(SCH_1):P3V3_AUX_CPU0_USB_AVDD33    I12 @T6G_MB_LIB.T6G(SCH_1):PAGE154
     2    GND @T6G_MB_LIB.T6G(SCH_1):GND    I12 @T6G_MB_LIB.T6G(SCH_1):PAGE154

C6045 Q_CAP_C0402-0.01UF,50V,10%,X7R,CH31006KB18
     1 P3V3_AUX_CPU0_USB_AVDD33 @T6G_MB_LIB.T6G(SCH_1):P3V3_AUX_CPU0_USB_AVDD33    I13 @T6G_MB_LIB.T6G(SCH_1):PAGE154
     2    GND @T6G_MB_LIB.T6G(SCH_1):GND    I13 @T6G_MB_LIB.T6G(SCH_1):PAGE154

C6046 Q_CAP_C0603-22UF,6.3V,20%,X6S,CH6221ME900
     1 P3V3_AUX @T6G_MB_LIB.T6G(SCH_1):P3V3_AUX    I14 @T6G_MB_LIB.T6G(SCH_1):PAGE154
     2    GND @T6G_MB_LIB.T6G(SCH_1):GND    I14 @T6G_MB_LIB.T6G(SCH_1):PAGE154

C6047 Q_CAP_C0402-1UF,25V,10%,X6S,CH5104KEB02
     1 P3V3_AUX @T6G_MB_LIB.T6G(SCH_1):P3V3_AUX    I15 @T6G_MB_LIB.T6G(SCH_1):PAGE154
     2    GND @T6G_MB_LIB.T6G(SCH_1):GND    I15 @T6G_MB_LIB.T6G(SCH_1):PAGE154

C6048 Q_CAP_0402-0.1UF,25V,10%,X7R,CH4104K1B00
     1 P3V3_AUX @T6G_MB_LIB.T6G(SCH_1):P3V3_AUX    I17 @T6G_MB_LIB.T6G(SCH_1):PAGE154
     2    GND @T6G_MB_LIB.T6G(SCH_1):GND    I17 @T6G_MB_LIB.T6G(SCH_1):PAGE154

C6049 Q_CAP_C0402-0.01UF,50V,10%,X7R,CH31006KB18
     1 P3V3_AUX @T6G_MB_LIB.T6G(SCH_1):P3V3_AUX    I19 @T6G_MB_LIB.T6G(SCH_1):PAGE154
     2    GND @T6G_MB_LIB.T6G(SCH_1):GND    I19 @T6G_MB_LIB.T6G(SCH_1):PAGE154

C6050 Q_CAP_0402-0.1UF,25V,10%,X7R,CH4104K1B00
     1 P3V3_AUX @T6G_MB_LIB.T6G(SCH_1):P3V3_AUX    I20 @T6G_MB_LIB.T6G(SCH_1):PAGE154
     2    GND @T6G_MB_LIB.T6G(SCH_1):GND    I20 @T6G_MB_LIB.T6G(SCH_1):PAGE154

C6051 Q_CAP_C0402-0.01UF,50V,10%,X7R,CH31006KB18
     1 P3V3_AUX @T6G_MB_LIB.T6G(SCH_1):P3V3_AUX    I21 @T6G_MB_LIB.T6G(SCH_1):PAGE154
     2    GND @T6G_MB_LIB.T6G(SCH_1):GND    I21 @T6G_MB_LIB.T6G(SCH_1):PAGE154

C6052 Q_CAP_0402-0.1UF,25V,10%,X7R,CH4104K1B00
     1 P3V3_AUX @T6G_MB_LIB.T6G(SCH_1):P3V3_AUX    I23 @T6G_MB_LIB.T6G(SCH_1):PAGE154
     2    GND @T6G_MB_LIB.T6G(SCH_1):GND    I23 @T6G_MB_LIB.T6G(SCH_1):PAGE154

C6053 Q_CAP_C0402-0.01UF,50V,10%,X7R,CH31006KB18
     1 P3V3_AUX @T6G_MB_LIB.T6G(SCH_1):P3V3_AUX    I22 @T6G_MB_LIB.T6G(SCH_1):PAGE154
     2    GND @T6G_MB_LIB.T6G(SCH_1):GND    I22 @T6G_MB_LIB.T6G(SCH_1):PAGE154

C6054 Q_CAP_C0402-0.001UF,50V,10%,X7R,CH30106KB19
     1 P1V2_AUX @T6G_MB_LIB.T6G(SCH_1):P1V2_AUX    I43 @T6G_MB_LIB.T6G(SCH_1):PAGE154
     2    GND @T6G_MB_LIB.T6G(SCH_1):GND    I43 @T6G_MB_LIB.T6G(SCH_1):PAGE154

C6055 Q_CAP_C0402-0.01UF,50V,10%,X7R,CH31006KB18
     1 P1V2_AUX @T6G_MB_LIB.T6G(SCH_1):P1V2_AUX    I44 @T6G_MB_LIB.T6G(SCH_1):PAGE154
     2    GND @T6G_MB_LIB.T6G(SCH_1):GND    I44 @T6G_MB_LIB.T6G(SCH_1):PAGE154

C6056 Q_CAP_C0402-0.001UF,50V,10%,X7R,CH30106KB19
     1 P1V2_AUX @T6G_MB_LIB.T6G(SCH_1):P1V2_AUX    I46 @T6G_MB_LIB.T6G(SCH_1):PAGE154
     2    GND @T6G_MB_LIB.T6G(SCH_1):GND    I46 @T6G_MB_LIB.T6G(SCH_1):PAGE154

C6057 Q_CAP_C0402-0.01UF,50V,10%,X7R,CH31006KB18
     1 P1V2_AUX @T6G_MB_LIB.T6G(SCH_1):P1V2_AUX    I47 @T6G_MB_LIB.T6G(SCH_1):PAGE154
     2    GND @T6G_MB_LIB.T6G(SCH_1):GND    I47 @T6G_MB_LIB.T6G(SCH_1):PAGE154

C6058 Q_CAP_C0402-0.001UF,50V,10%,X7R,CH30106KB19
     1 P1V2_AUX @T6G_MB_LIB.T6G(SCH_1):P1V2_AUX    I49 @T6G_MB_LIB.T6G(SCH_1):PAGE154
     2    GND @T6G_MB_LIB.T6G(SCH_1):GND    I49 @T6G_MB_LIB.T6G(SCH_1):PAGE154

C6059 Q_CAP_C0402-0.01UF,50V,10%,X7R,CH31006KB18
     1 P1V2_AUX @T6G_MB_LIB.T6G(SCH_1):P1V2_AUX    I50 @T6G_MB_LIB.T6G(SCH_1):PAGE154
     2    GND @T6G_MB_LIB.T6G(SCH_1):GND    I50 @T6G_MB_LIB.T6G(SCH_1):PAGE154

C6060 Q_CAP_C0402-0.001UF,50V,10%,X7R,CH30106KB19
     1 P1V2_AUX @T6G_MB_LIB.T6G(SCH_1):P1V2_AUX    I52 @T6G_MB_LIB.T6G(SCH_1):PAGE154
     2    GND @T6G_MB_LIB.T6G(SCH_1):GND    I52 @T6G_MB_LIB.T6G(SCH_1):PAGE154

C6061 Q_CAP_C0402-0.01UF,50V,10%,X7R,CH31006KB18
     1 P1V2_AUX @T6G_MB_LIB.T6G(SCH_1):P1V2_AUX    I53 @T6G_MB_LIB.T6G(SCH_1):PAGE154
     2    GND @T6G_MB_LIB.T6G(SCH_1):GND    I53 @T6G_MB_LIB.T6G(SCH_1):PAGE154

C6062 Q_CAP_C0402-0.001UF,50V,10%,X7R,CH30106KB19
     1 P1V2_AUX @T6G_MB_LIB.T6G(SCH_1):P1V2_AUX    I55 @T6G_MB_LIB.T6G(SCH_1):PAGE154
     2    GND @T6G_MB_LIB.T6G(SCH_1):GND    I55 @T6G_MB_LIB.T6G(SCH_1):PAGE154

C6063 Q_CAP_C0402-0.01UF,50V,10%,X7R,CH31006KB18
     1 P1V2_AUX @T6G_MB_LIB.T6G(SCH_1):P1V2_AUX    I56 @T6G_MB_LIB.T6G(SCH_1):PAGE154
     2    GND @T6G_MB_LIB.T6G(SCH_1):GND    I56 @T6G_MB_LIB.T6G(SCH_1):PAGE154

C6064 Q_CAP_0402-0.1UF,25V,10%,X7R,CH4104K1B00
     1 P1V2_AUX @T6G_MB_LIB.T6G(SCH_1):P1V2_AUX    I58 @T6G_MB_LIB.T6G(SCH_1):PAGE154
     2    GND @T6G_MB_LIB.T6G(SCH_1):GND    I58 @T6G_MB_LIB.T6G(SCH_1):PAGE154

C6065 Q_CAP_C0402-1UF,25V,10%,X6S,CH5104KEB02
     1 P1V2_AUX @T6G_MB_LIB.T6G(SCH_1):P1V2_AUX    I59 @T6G_MB_LIB.T6G(SCH_1):PAGE154
     2    GND @T6G_MB_LIB.T6G(SCH_1):GND    I59 @T6G_MB_LIB.T6G(SCH_1):PAGE154

C6066 Q_CAP_C0603-22UF,6.3V,20%,X6S,CH6221ME900
     1 P1V2_AUX @T6G_MB_LIB.T6G(SCH_1):P1V2_AUX    I60 @T6G_MB_LIB.T6G(SCH_1):PAGE154
     2    GND @T6G_MB_LIB.T6G(SCH_1):GND    I60 @T6G_MB_LIB.T6G(SCH_1):PAGE154

C6067 Q_CAP_C0402-0.001UF,50V,10%,X7R,CH30106KB19
     1 P1V2_AUX @T6G_MB_LIB.T6G(SCH_1):P1V2_AUX    I79 @T6G_MB_LIB.T6G(SCH_1):PAGE154
     2    GND @T6G_MB_LIB.T6G(SCH_1):GND    I79 @T6G_MB_LIB.T6G(SCH_1):PAGE154

C6068 Q_CAP_C0402-0.01UF,50V,10%,X7R,CH31006KB18
     1 P1V2_AUX @T6G_MB_LIB.T6G(SCH_1):P1V2_AUX    I78 @T6G_MB_LIB.T6G(SCH_1):PAGE154
     2    GND @T6G_MB_LIB.T6G(SCH_1):GND    I78 @T6G_MB_LIB.T6G(SCH_1):PAGE154

C6069 Q_CAP_C0402-0.001UF,50V,10%,X7R,CH30106KB19
     1 P1V2_AUX @T6G_MB_LIB.T6G(SCH_1):P1V2_AUX    I63 @T6G_MB_LIB.T6G(SCH_1):PAGE154
     2    GND @T6G_MB_LIB.T6G(SCH_1):GND    I63 @T6G_MB_LIB.T6G(SCH_1):PAGE154

C6070 Q_CAP_C0402-0.01UF,50V,10%,X7R,CH31006KB18
     1 P1V2_AUX @T6G_MB_LIB.T6G(SCH_1):P1V2_AUX    I76 @T6G_MB_LIB.T6G(SCH_1):PAGE154
     2    GND @T6G_MB_LIB.T6G(SCH_1):GND    I76 @T6G_MB_LIB.T6G(SCH_1):PAGE154

C6071 Q_CAP_C0402-0.001UF,50V,10%,X7R,CH30106KB19
     1 P1V2_AUX @T6G_MB_LIB.T6G(SCH_1):P1V2_AUX    I75 @T6G_MB_LIB.T6G(SCH_1):PAGE154
     2    GND @T6G_MB_LIB.T6G(SCH_1):GND    I75 @T6G_MB_LIB.T6G(SCH_1):PAGE154

C6072 Q_CAP_C0402-0.01UF,50V,10%,X7R,CH31006KB18
     1 P1V2_AUX @T6G_MB_LIB.T6G(SCH_1):P1V2_AUX    I74 @T6G_MB_LIB.T6G(SCH_1):PAGE154
     2    GND @T6G_MB_LIB.T6G(SCH_1):GND    I74 @T6G_MB_LIB.T6G(SCH_1):PAGE154

C6073 Q_CAP_C0402-0.001UF,50V,10%,X7R,CH30106KB19
     1 P1V2_AUX @T6G_MB_LIB.T6G(SCH_1):P1V2_AUX    I73 @T6G_MB_LIB.T6G(SCH_1):PAGE154
     2    GND @T6G_MB_LIB.T6G(SCH_1):GND    I73 @T6G_MB_LIB.T6G(SCH_1):PAGE154

C6074 Q_CAP_C0402-0.01UF,50V,10%,X7R,CH31006KB18
     1 P1V2_AUX @T6G_MB_LIB.T6G(SCH_1):P1V2_AUX    I71 @T6G_MB_LIB.T6G(SCH_1):PAGE154
     2    GND @T6G_MB_LIB.T6G(SCH_1):GND    I71 @T6G_MB_LIB.T6G(SCH_1):PAGE154

C6075 Q_CAP_C0402-0.001UF,50V,10%,X7R,CH30106KB19
     1 P1V2_AUX @T6G_MB_LIB.T6G(SCH_1):P1V2_AUX    I69 @T6G_MB_LIB.T6G(SCH_1):PAGE154
     2    GND @T6G_MB_LIB.T6G(SCH_1):GND    I69 @T6G_MB_LIB.T6G(SCH_1):PAGE154

C6076 Q_CAP_C0402-0.01UF,50V,10%,X7R,CH31006KB18
     1 P1V2_AUX @T6G_MB_LIB.T6G(SCH_1):P1V2_AUX    I68 @T6G_MB_LIB.T6G(SCH_1):PAGE154
     2    GND @T6G_MB_LIB.T6G(SCH_1):GND    I68 @T6G_MB_LIB.T6G(SCH_1):PAGE154

C6077 Q_CAP_0402-0.1UF,25V,10%,X7R,CH4104K1B00
     1 P1V2_AUX @T6G_MB_LIB.T6G(SCH_1):P1V2_AUX    I66 @T6G_MB_LIB.T6G(SCH_1):PAGE154
     2    GND @T6G_MB_LIB.T6G(SCH_1):GND    I66 @T6G_MB_LIB.T6G(SCH_1):PAGE154

C6078 Q_CAP_C0402-1UF,25V,10%,X6S,CH5104KEB02
     1 P1V2_AUX @T6G_MB_LIB.T6G(SCH_1):P1V2_AUX    I65 @T6G_MB_LIB.T6G(SCH_1):PAGE154
     2    GND @T6G_MB_LIB.T6G(SCH_1):GND    I65 @T6G_MB_LIB.T6G(SCH_1):PAGE154

C6079 Q_CAP_C0603-22UF,6.3V,20%,X6S,CH6221ME900
     1 P1V2_AUX @T6G_MB_LIB.T6G(SCH_1):P1V2_AUX    I64 @T6G_MB_LIB.T6G(SCH_1):PAGE154
     2    GND @T6G_MB_LIB.T6G(SCH_1):GND    I64 @T6G_MB_LIB.T6G(SCH_1):PAGE154

C6080 Q_CAP_C0402-0.01UF,50V,10%,X7R,CH31006KB18
     1 P1V2_AUX @T6G_MB_LIB.T6G(SCH_1):P1V2_AUX    I81 @T6G_MB_LIB.T6G(SCH_1):PAGE154
     2    GND @T6G_MB_LIB.T6G(SCH_1):GND    I81 @T6G_MB_LIB.T6G(SCH_1):PAGE154

C6081 Q_CAP_0402-0.1UF,25V,10%,X7R,CH4104K1B00
     1 P1V2_AUX @T6G_MB_LIB.T6G(SCH_1):P1V2_AUX    I82 @T6G_MB_LIB.T6G(SCH_1):PAGE154
     2    GND @T6G_MB_LIB.T6G(SCH_1):GND    I82 @T6G_MB_LIB.T6G(SCH_1):PAGE154

C6082 Q_CAP_C0402-1UF,25V,10%,X6S,CH5104KEB02
     1 P1V2_AUX @T6G_MB_LIB.T6G(SCH_1):P1V2_AUX    I83 @T6G_MB_LIB.T6G(SCH_1):PAGE154
     2    GND @T6G_MB_LIB.T6G(SCH_1):GND    I83 @T6G_MB_LIB.T6G(SCH_1):PAGE154

C6083 Q_CAP_0402-0.1UF,25V,10%,X7R,CH4104K1B00
     1 P3V3_AUX @T6G_MB_LIB.T6G(SCH_1):P3V3_AUX    I75 @T6G_MB_LIB.T6G(SCH_1):PAGE153
     2    GND @T6G_MB_LIB.T6G(SCH_1):GND    I75 @T6G_MB_LIB.T6G(SCH_1):PAGE153

C6084 Q_CAP_0402-0.1UF,25V,10%,EMPTY,CH4104K1B00
     1 U142_VS @T6G_MB_LIB.T6G(SCH_1):U142_VS   I107 @T6G_MB_LIB.T6G(SCH_1):PAGE371
     2    GND @T6G_MB_LIB.T6G(SCH_1):GND   I107 @T6G_MB_LIB.T6G(SCH_1):PAGE371

C6085 Q_CAP_0402-0.1UF,25V,10%,EMPTY,CH4104K1B00
     1 PWRGD_P1V8_AUX_R @T6G_MB_LIB.T6G(SCH_1):PWRGD_P1V8_AUX_R    I41 @T6G_MB_LIB.T6G(SCH_1):PAGE380
     2    GND @T6G_MB_LIB.T6G(SCH_1):GND    I41 @T6G_MB_LIB.T6G(SCH_1):PAGE380

C6086 Q_CAP_0402-0.1UF,25V,10%,X7R,CH4104K1B00
     1 HSC_TYPE_ADC @T6G_MB_LIB.T6G(SCH_1):HSC_TYPE_ADC    I11 @T6G_MB_LIB.T6G(SCH_1):PAGE271
     2    GND @T6G_MB_LIB.T6G(SCH_1):GND    I11 @T6G_MB_LIB.T6G(SCH_1):PAGE271

C6087 Q_CAP_0402-0.1UF,25V,10%,X7R,CH4104K1B00
     1 P3V3_AUX @T6G_MB_LIB.T6G(SCH_1):P3V3_AUX    I22 @T6G_MB_LIB.T6G(SCH_1):PAGE271
     2    GND @T6G_MB_LIB.T6G(SCH_1):GND    I22 @T6G_MB_LIB.T6G(SCH_1):PAGE271

C6088 Q_CAP_C0805-10UF,16V,10%,X6S,CH6103KEA00
     1 USB_HUB2_MRP_RESET_N @T6G_MB_LIB.T6G(SCH_1):USB_HUB2_MRP_RESET_N   I127 @T6G_MB_LIB.T6G(SCH_1):PAGE155
     2    GND @T6G_MB_LIB.T6G(SCH_1):GND   I127 @T6G_MB_LIB.T6G(SCH_1):PAGE155

C6089 Q_CAP_C0402-1UF,25V,10%,X6S,CH5104KEB02
     1 USB_HUB2_TI_GRSTZ_MRP_PROG_FUNC1 @T6G_MB_LIB.T6G(SCH_1):USB_HUB2_TI_GRSTZ_MRP_PROG_FUNC1   I145 @T6G_MB_LIB.T6G(SCH_1):PAGE155
     2    GND @T6G_MB_LIB.T6G(SCH_1):GND   I145 @T6G_MB_LIB.T6G(SCH_1):PAGE155

C6090 Q_CAP_0402-27PF,50V,5%,NPO,CH02706JB06
     1 XTAL_USB_CPU0_HUB2_XOUT @T6G_MB_LIB.T6G(SCH_1):XTAL_USB_CPU0_HUB2_XOUT   I174 @T6G_MB_LIB.T6G(SCH_1):PAGE157
     2    GND @T6G_MB_LIB.T6G(SCH_1):GND   I174 @T6G_MB_LIB.T6G(SCH_1):PAGE157

C6091 Q_CAP_0402-27PF,50V,5%,NPO,CH02706JB06
     1 XTAL_USB_CPU0_HUB2_XIN @T6G_MB_LIB.T6G(SCH_1):XTAL_USB_CPU0_HUB2_XIN   I175 @T6G_MB_LIB.T6G(SCH_1):PAGE157
     2    GND @T6G_MB_LIB.T6G(SCH_1):GND   I175 @T6G_MB_LIB.T6G(SCH_1):PAGE157

C6092 Q_CAP_C0402-1UF,25V,10%,X6S,CH5104KEB02
     1 P3V3_AUX_CPU0_USB2_AVDD33 @T6G_MB_LIB.T6G(SCH_1):P3V3_AUX_CPU0_USB2_AVDD33    I21 @T6G_MB_LIB.T6G(SCH_1):PAGE157
     2    GND @T6G_MB_LIB.T6G(SCH_1):GND    I21 @T6G_MB_LIB.T6G(SCH_1):PAGE157

C6093 Q_CAP_C0402-1PF,50V,0.05P,COG,CH-106T0B00
     1 P3V3_AUX_CPU0_USB2_AVDD33 @T6G_MB_LIB.T6G(SCH_1):P3V3_AUX_CPU0_USB2_AVDD33    I24 @T6G_MB_LIB.T6G(SCH_1):PAGE157
     2    GND @T6G_MB_LIB.T6G(SCH_1):GND    I24 @T6G_MB_LIB.T6G(SCH_1):PAGE157

C6094 Q_CAP_C0402-0.01UF,50V,10%,X7R,CH31006KB18
     1 P3V3_AUX_CPU0_USB2_AVDD33 @T6G_MB_LIB.T6G(SCH_1):P3V3_AUX_CPU0_USB2_AVDD33    I22 @T6G_MB_LIB.T6G(SCH_1):PAGE157
     2    GND @T6G_MB_LIB.T6G(SCH_1):GND    I22 @T6G_MB_LIB.T6G(SCH_1):PAGE157

C6095 Q_CAP_0402-0.1UF,25V,10%,X7R,CH4104K1B00
     1 P3V3_AUX_CPU0_USB2_AVDD33 @T6G_MB_LIB.T6G(SCH_1):P3V3_AUX_CPU0_USB2_AVDD33    I23 @T6G_MB_LIB.T6G(SCH_1):PAGE157
     2    GND @T6G_MB_LIB.T6G(SCH_1):GND    I23 @T6G_MB_LIB.T6G(SCH_1):PAGE157

C6096 Q_CAP_C0402-1PF,50V,0.05P,COG,CH-106T0B00
     1 P3V3_AUX_CPU0_USB2_AVDD33 @T6G_MB_LIB.T6G(SCH_1):P3V3_AUX_CPU0_USB2_AVDD33    I27 @T6G_MB_LIB.T6G(SCH_1):PAGE157
     2    GND @T6G_MB_LIB.T6G(SCH_1):GND    I27 @T6G_MB_LIB.T6G(SCH_1):PAGE157

C6097 Q_CAP_C0402-0.01UF,50V,10%,X7R,CH31006KB18
     1 P3V3_AUX_CPU0_USB2_AVDD33 @T6G_MB_LIB.T6G(SCH_1):P3V3_AUX_CPU0_USB2_AVDD33    I26 @T6G_MB_LIB.T6G(SCH_1):PAGE157
     2    GND @T6G_MB_LIB.T6G(SCH_1):GND    I26 @T6G_MB_LIB.T6G(SCH_1):PAGE157

C6098 Q_CAP_0402-0.1UF,25V,10%,X7R,CH4104K1B00
     1 P3V3_AUX_CPU0_USB2_AVDD33 @T6G_MB_LIB.T6G(SCH_1):P3V3_AUX_CPU0_USB2_AVDD33    I25 @T6G_MB_LIB.T6G(SCH_1):PAGE157
     2    GND @T6G_MB_LIB.T6G(SCH_1):GND    I25 @T6G_MB_LIB.T6G(SCH_1):PAGE157

C6099 Q_CAP_C0402-1PF,50V,0.05P,COG,CH-106T0B00
     1 P3V3_AUX_CPU0_USB2_AVDD33 @T6G_MB_LIB.T6G(SCH_1):P3V3_AUX_CPU0_USB2_AVDD33    I30 @T6G_MB_LIB.T6G(SCH_1):PAGE157
     2    GND @T6G_MB_LIB.T6G(SCH_1):GND    I30 @T6G_MB_LIB.T6G(SCH_1):PAGE157

C6100 Q_CAP_C0402-0.01UF,50V,10%,X7R,CH31006KB18
     1 P3V3_AUX_CPU0_USB2_AVDD33 @T6G_MB_LIB.T6G(SCH_1):P3V3_AUX_CPU0_USB2_AVDD33    I29 @T6G_MB_LIB.T6G(SCH_1):PAGE157
     2    GND @T6G_MB_LIB.T6G(SCH_1):GND    I29 @T6G_MB_LIB.T6G(SCH_1):PAGE157

C6101 Q_CAP_0402-0.1UF,25V,10%,X7R,CH4104K1B00
     1 P3V3_AUX_CPU0_USB2_AVDD33 @T6G_MB_LIB.T6G(SCH_1):P3V3_AUX_CPU0_USB2_AVDD33    I28 @T6G_MB_LIB.T6G(SCH_1):PAGE157
     2    GND @T6G_MB_LIB.T6G(SCH_1):GND    I28 @T6G_MB_LIB.T6G(SCH_1):PAGE157

C6102 Q_CAP_C0402-1PF,50V,0.05P,COG,CH-106T0B00
     1 P3V3_AUX_CPU0_USB2_AVDD33 @T6G_MB_LIB.T6G(SCH_1):P3V3_AUX_CPU0_USB2_AVDD33    I33 @T6G_MB_LIB.T6G(SCH_1):PAGE157
     2    GND @T6G_MB_LIB.T6G(SCH_1):GND    I33 @T6G_MB_LIB.T6G(SCH_1):PAGE157

C6103 Q_CAP_C0402-0.01UF,50V,10%,X7R,CH31006KB18
     1 P3V3_AUX_CPU0_USB2_AVDD33 @T6G_MB_LIB.T6G(SCH_1):P3V3_AUX_CPU0_USB2_AVDD33    I32 @T6G_MB_LIB.T6G(SCH_1):PAGE157
     2    GND @T6G_MB_LIB.T6G(SCH_1):GND    I32 @T6G_MB_LIB.T6G(SCH_1):PAGE157

C6104 Q_CAP_0402-0.1UF,25V,10%,X7R,CH4104K1B00
     1 P3V3_AUX_CPU0_USB2_AVDD33 @T6G_MB_LIB.T6G(SCH_1):P3V3_AUX_CPU0_USB2_AVDD33    I31 @T6G_MB_LIB.T6G(SCH_1):PAGE157
     2    GND @T6G_MB_LIB.T6G(SCH_1):GND    I31 @T6G_MB_LIB.T6G(SCH_1):PAGE157

C6105 Q_CAP_C0805-10UF,25V,10%,X6S,CH6104KEA00
     1 P1V2_CPU0_USB2_DVDD12 @T6G_MB_LIB.T6G(SCH_1):P1V2_CPU0_USB2_DVDD12    I36 @T6G_MB_LIB.T6G(SCH_1):PAGE157
     2    GND @T6G_MB_LIB.T6G(SCH_1):GND    I36 @T6G_MB_LIB.T6G(SCH_1):PAGE157

C6106 Q_CAP_C0402-1PF,50V,0.05P,COG,CH-106T0B00
     1 P1V2_CPU0_USB2_DVDD12 @T6G_MB_LIB.T6G(SCH_1):P1V2_CPU0_USB2_DVDD12    I41 @T6G_MB_LIB.T6G(SCH_1):PAGE157
     2    GND @T6G_MB_LIB.T6G(SCH_1):GND    I41 @T6G_MB_LIB.T6G(SCH_1):PAGE157

C6107 Q_CAP_C0402-0.01UF,50V,10%,X7R,CH31006KB18
     1 P1V2_CPU0_USB2_DVDD12 @T6G_MB_LIB.T6G(SCH_1):P1V2_CPU0_USB2_DVDD12    I40 @T6G_MB_LIB.T6G(SCH_1):PAGE157
     2    GND @T6G_MB_LIB.T6G(SCH_1):GND    I40 @T6G_MB_LIB.T6G(SCH_1):PAGE157

C6108 Q_CAP_0402-0.1UF,25V,10%,X7R,CH4104K1B00
     1 P1V2_CPU0_USB2_DVDD12 @T6G_MB_LIB.T6G(SCH_1):P1V2_CPU0_USB2_DVDD12    I39 @T6G_MB_LIB.T6G(SCH_1):PAGE157
     2    GND @T6G_MB_LIB.T6G(SCH_1):GND    I39 @T6G_MB_LIB.T6G(SCH_1):PAGE157

C6109 Q_CAP_C0402-1PF,50V,0.05P,COG,CH-106T0B00
     1 P1V2_CPU0_USB2_DVDD12 @T6G_MB_LIB.T6G(SCH_1):P1V2_CPU0_USB2_DVDD12    I44 @T6G_MB_LIB.T6G(SCH_1):PAGE157
     2    GND @T6G_MB_LIB.T6G(SCH_1):GND    I44 @T6G_MB_LIB.T6G(SCH_1):PAGE157

C6110 Q_CAP_C0402-0.01UF,50V,10%,X7R,CH31006KB18
     1 P1V2_CPU0_USB2_DVDD12 @T6G_MB_LIB.T6G(SCH_1):P1V2_CPU0_USB2_DVDD12    I43 @T6G_MB_LIB.T6G(SCH_1):PAGE157
     2    GND @T6G_MB_LIB.T6G(SCH_1):GND    I43 @T6G_MB_LIB.T6G(SCH_1):PAGE157

C6111 Q_CAP_0402-0.1UF,25V,10%,X7R,CH4104K1B00
     1 P1V2_CPU0_USB2_DVDD12 @T6G_MB_LIB.T6G(SCH_1):P1V2_CPU0_USB2_DVDD12    I42 @T6G_MB_LIB.T6G(SCH_1):PAGE157
     2    GND @T6G_MB_LIB.T6G(SCH_1):GND    I42 @T6G_MB_LIB.T6G(SCH_1):PAGE157

C6112 Q_CAP_C0402-1PF,50V,0.05P,COG,CH-106T0B00
     1 P1V2_CPU0_USB2_DVDD12 @T6G_MB_LIB.T6G(SCH_1):P1V2_CPU0_USB2_DVDD12    I47 @T6G_MB_LIB.T6G(SCH_1):PAGE157
     2    GND @T6G_MB_LIB.T6G(SCH_1):GND    I47 @T6G_MB_LIB.T6G(SCH_1):PAGE157

C6113 Q_CAP_C0402-0.01UF,50V,10%,X7R,CH31006KB18
     1 P1V2_CPU0_USB2_DVDD12 @T6G_MB_LIB.T6G(SCH_1):P1V2_CPU0_USB2_DVDD12    I46 @T6G_MB_LIB.T6G(SCH_1):PAGE157
     2    GND @T6G_MB_LIB.T6G(SCH_1):GND    I46 @T6G_MB_LIB.T6G(SCH_1):PAGE157

C6114 Q_CAP_0402-0.1UF,25V,10%,X7R,CH4104K1B00
     1 P1V2_CPU0_USB2_DVDD12 @T6G_MB_LIB.T6G(SCH_1):P1V2_CPU0_USB2_DVDD12    I45 @T6G_MB_LIB.T6G(SCH_1):PAGE157
     2    GND @T6G_MB_LIB.T6G(SCH_1):GND    I45 @T6G_MB_LIB.T6G(SCH_1):PAGE157

C6115 Q_CAP_C0402-1PF,50V,0.05P,COG,CH-106T0B00
     1 P1V2_CPU0_USB2_DVDD12 @T6G_MB_LIB.T6G(SCH_1):P1V2_CPU0_USB2_DVDD12    I50 @T6G_MB_LIB.T6G(SCH_1):PAGE157
     2    GND @T6G_MB_LIB.T6G(SCH_1):GND    I50 @T6G_MB_LIB.T6G(SCH_1):PAGE157

C6116 Q_CAP_C0402-0.01UF,50V,10%,X7R,CH31006KB18
     1 P1V2_CPU0_USB2_DVDD12 @T6G_MB_LIB.T6G(SCH_1):P1V2_CPU0_USB2_DVDD12    I49 @T6G_MB_LIB.T6G(SCH_1):PAGE157
     2    GND @T6G_MB_LIB.T6G(SCH_1):GND    I49 @T6G_MB_LIB.T6G(SCH_1):PAGE157

C6117 Q_CAP_0402-0.1UF,25V,10%,X7R,CH4104K1B00
     1 P1V2_CPU0_USB2_DVDD12 @T6G_MB_LIB.T6G(SCH_1):P1V2_CPU0_USB2_DVDD12    I48 @T6G_MB_LIB.T6G(SCH_1):PAGE157
     2    GND @T6G_MB_LIB.T6G(SCH_1):GND    I48 @T6G_MB_LIB.T6G(SCH_1):PAGE157

C6118 Q_CAP_C0805-10UF,25V,10%,X6S,CH6104KEA00
     1 P1V2_CPU0_USB2_DVDD12 @T6G_MB_LIB.T6G(SCH_1):P1V2_CPU0_USB2_DVDD12    I54 @T6G_MB_LIB.T6G(SCH_1):PAGE157
     2    GND @T6G_MB_LIB.T6G(SCH_1):GND    I54 @T6G_MB_LIB.T6G(SCH_1):PAGE157

C6119 Q_CAP_C0402-1PF,50V,0.05P,COG,CH-106T0B00
     1 P1V2_CPU0_USB2_DVDD12 @T6G_MB_LIB.T6G(SCH_1):P1V2_CPU0_USB2_DVDD12    I53 @T6G_MB_LIB.T6G(SCH_1):PAGE157
     2    GND @T6G_MB_LIB.T6G(SCH_1):GND    I53 @T6G_MB_LIB.T6G(SCH_1):PAGE157

C6120 Q_CAP_C0402-0.01UF,50V,10%,X7R,CH31006KB18
     1 P1V2_CPU0_USB2_DVDD12 @T6G_MB_LIB.T6G(SCH_1):P1V2_CPU0_USB2_DVDD12    I52 @T6G_MB_LIB.T6G(SCH_1):PAGE157
     2    GND @T6G_MB_LIB.T6G(SCH_1):GND    I52 @T6G_MB_LIB.T6G(SCH_1):PAGE157

C6121 Q_CAP_0402-0.1UF,25V,10%,X7R,CH4104K1B00
     1 P1V2_CPU0_USB2_DVDD12 @T6G_MB_LIB.T6G(SCH_1):P1V2_CPU0_USB2_DVDD12    I51 @T6G_MB_LIB.T6G(SCH_1):PAGE157
     2    GND @T6G_MB_LIB.T6G(SCH_1):GND    I51 @T6G_MB_LIB.T6G(SCH_1):PAGE157

C6122 Q_CAP_C0402-100NF,50V,10%,X7R,CH4106K1B01
     1    P5V @T6G_MB_LIB.T6G(SCH_1):P5V    I79 @T6G_MB_LIB.T6G(SCH_1):PAGE273
     2    GND @T6G_MB_LIB.T6G(SCH_1):GND    I79 @T6G_MB_LIB.T6G(SCH_1):PAGE273

C6500 Q_CAP_0402-0.1UF,25V,10%,X7R,CH4104K1B00
     1   P3V3 @T6G_MB_LIB.T6G(SCH_1):P3V3   I133 @T6G_MB_LIB.T6G(SCH_1):PAGE273
     2    GND @T6G_MB_LIB.T6G(SCH_1):GND   I133 @T6G_MB_LIB.T6G(SCH_1):PAGE273

C6501 Q_CAP_DIFFBUS_C0201-DIFF BUS_0.22UF,6.3V,20%,X6S,SA
     1 P5E_CPU0_P0_TX_BUF_C_DP<0> @T6G_MB_LIB.T6G(SCH_1):P5E_CPU0_P0_TX_BUF_C_DP(0)    I77 @T6G_MB_LIB.T6G(SCH_1):PAGE384
     2 P5E_CPU0_P0_TX_BUF_DP<0> @T6G_MB_LIB.T6G(SCH_1):P5E_CPU0_P0_TX_BUF_DP(0)    I77 @T6G_MB_LIB.T6G(SCH_1):PAGE384

C6502 Q_CAP_DIFFBUS_C0201-DIFF BUS_0.22UF,6.3V,20%,X6S,SA
     1 P5E_CPU0_P0_TX_BUF_C_DN<0> @T6G_MB_LIB.T6G(SCH_1):P5E_CPU0_P0_TX_BUF_C_DN(0)    I78 @T6G_MB_LIB.T6G(SCH_1):PAGE384
     2 P5E_CPU0_P0_TX_BUF_DN<0> @T6G_MB_LIB.T6G(SCH_1):P5E_CPU0_P0_TX_BUF_DN(0)    I78 @T6G_MB_LIB.T6G(SCH_1):PAGE384

C6503 Q_CAP_DIFFBUS_C0201-DIFF BUS_0.22UF,6.3V,20%,X6S,SA
     1 P5E_CPU0_P0_TX_BUF_C_DP<1> @T6G_MB_LIB.T6G(SCH_1):P5E_CPU0_P0_TX_BUF_C_DP(1)    I75 @T6G_MB_LIB.T6G(SCH_1):PAGE384
     2 P5E_CPU0_P0_TX_BUF_DP<1> @T6G_MB_LIB.T6G(SCH_1):P5E_CPU0_P0_TX_BUF_DP(1)    I75 @T6G_MB_LIB.T6G(SCH_1):PAGE384

C6504 Q_CAP_DIFFBUS_C0201-DIFF BUS_0.22UF,6.3V,20%,X6S,SA
     1 P5E_CPU0_P0_TX_BUF_C_DN<1> @T6G_MB_LIB.T6G(SCH_1):P5E_CPU0_P0_TX_BUF_C_DN(1)    I76 @T6G_MB_LIB.T6G(SCH_1):PAGE384
     2 P5E_CPU0_P0_TX_BUF_DN<1> @T6G_MB_LIB.T6G(SCH_1):P5E_CPU0_P0_TX_BUF_DN(1)    I76 @T6G_MB_LIB.T6G(SCH_1):PAGE384

C6505 Q_CAP_DIFFBUS_C0201-DIFF BUS_0.22UF,6.3V,20%,X6S,SA
     1 P5E_CPU0_P0_TX_BUF_C_DP<2> @T6G_MB_LIB.T6G(SCH_1):P5E_CPU0_P0_TX_BUF_C_DP(2)    I74 @T6G_MB_LIB.T6G(SCH_1):PAGE384
     2 P5E_CPU0_P0_TX_BUF_DP<2> @T6G_MB_LIB.T6G(SCH_1):P5E_CPU0_P0_TX_BUF_DP(2)    I74 @T6G_MB_LIB.T6G(SCH_1):PAGE384

C6506 Q_CAP_DIFFBUS_C0201-DIFF BUS_0.22UF,6.3V,20%,X6S,SA
     1 P5E_CPU0_P0_TX_BUF_C_DN<2> @T6G_MB_LIB.T6G(SCH_1):P5E_CPU0_P0_TX_BUF_C_DN(2)    I72 @T6G_MB_LIB.T6G(SCH_1):PAGE384
     2 P5E_CPU0_P0_TX_BUF_DN<2> @T6G_MB_LIB.T6G(SCH_1):P5E_CPU0_P0_TX_BUF_DN(2)    I72 @T6G_MB_LIB.T6G(SCH_1):PAGE384

C6507 Q_CAP_DIFFBUS_C0201-DIFF BUS_0.22UF,6.3V,20%,X6S,SA
     1 P5E_CPU0_P0_TX_BUF_C_DP<3> @T6G_MB_LIB.T6G(SCH_1):P5E_CPU0_P0_TX_BUF_C_DP(3)    I73 @T6G_MB_LIB.T6G(SCH_1):PAGE384
     2 P5E_CPU0_P0_TX_BUF_DP<3> @T6G_MB_LIB.T6G(SCH_1):P5E_CPU0_P0_TX_BUF_DP(3)    I73 @T6G_MB_LIB.T6G(SCH_1):PAGE384

C6508 Q_CAP_DIFFBUS_C0201-DIFF BUS_0.22UF,6.3V,20%,X6S,SA
     1 P5E_CPU0_P0_TX_BUF_C_DN<3> @T6G_MB_LIB.T6G(SCH_1):P5E_CPU0_P0_TX_BUF_C_DN(3)    I71 @T6G_MB_LIB.T6G(SCH_1):PAGE384
     2 P5E_CPU0_P0_TX_BUF_DN<3> @T6G_MB_LIB.T6G(SCH_1):P5E_CPU0_P0_TX_BUF_DN(3)    I71 @T6G_MB_LIB.T6G(SCH_1):PAGE384

C6509 Q_CAP_DIFFBUS_C0201-DIFF BUS_0.22UF,6.3V,20%,X6S,SA
     1 P5E_CPU0_P0_TX_BUF_C_DP<4> @T6G_MB_LIB.T6G(SCH_1):P5E_CPU0_P0_TX_BUF_C_DP(4)    I65 @T6G_MB_LIB.T6G(SCH_1):PAGE384
     2 P5E_CPU0_P0_TX_BUF_DP<4> @T6G_MB_LIB.T6G(SCH_1):P5E_CPU0_P0_TX_BUF_DP(4)    I65 @T6G_MB_LIB.T6G(SCH_1):PAGE384

C6510 Q_CAP_DIFFBUS_C0201-DIFF BUS_0.22UF,6.3V,20%,X6S,SA
     1 P5E_CPU0_P0_TX_BUF_C_DN<4> @T6G_MB_LIB.T6G(SCH_1):P5E_CPU0_P0_TX_BUF_C_DN(4)    I66 @T6G_MB_LIB.T6G(SCH_1):PAGE384
     2 P5E_CPU0_P0_TX_BUF_DN<4> @T6G_MB_LIB.T6G(SCH_1):P5E_CPU0_P0_TX_BUF_DN(4)    I66 @T6G_MB_LIB.T6G(SCH_1):PAGE384

C6511 Q_CAP_DIFFBUS_C0201-DIFF BUS_0.22UF,6.3V,20%,X6S,SA
     1 P5E_CPU0_P0_TX_BUF_C_DP<5> @T6G_MB_LIB.T6G(SCH_1):P5E_CPU0_P0_TX_BUF_C_DP(5)    I63 @T6G_MB_LIB.T6G(SCH_1):PAGE384
     2 P5E_CPU0_P0_TX_BUF_DP<5> @T6G_MB_LIB.T6G(SCH_1):P5E_CPU0_P0_TX_BUF_DP(5)    I63 @T6G_MB_LIB.T6G(SCH_1):PAGE384

C6512 Q_CAP_DIFFBUS_C0201-DIFF BUS_0.22UF,6.3V,20%,X6S,SA
     1 P5E_CPU0_P0_TX_BUF_C_DN<5> @T6G_MB_LIB.T6G(SCH_1):P5E_CPU0_P0_TX_BUF_C_DN(5)    I64 @T6G_MB_LIB.T6G(SCH_1):PAGE384
     2 P5E_CPU0_P0_TX_BUF_DN<5> @T6G_MB_LIB.T6G(SCH_1):P5E_CPU0_P0_TX_BUF_DN(5)    I64 @T6G_MB_LIB.T6G(SCH_1):PAGE384

C6513 Q_CAP_DIFFBUS_C0201-DIFF BUS_0.22UF,6.3V,20%,X6S,SA
     1 P5E_CPU0_P0_TX_BUF_C_DP<6> @T6G_MB_LIB.T6G(SCH_1):P5E_CPU0_P0_TX_BUF_C_DP(6)    I60 @T6G_MB_LIB.T6G(SCH_1):PAGE384
     2 P5E_CPU0_P0_TX_BUF_DP<6> @T6G_MB_LIB.T6G(SCH_1):P5E_CPU0_P0_TX_BUF_DP(6)    I60 @T6G_MB_LIB.T6G(SCH_1):PAGE384

C6514 Q_CAP_DIFFBUS_C0201-DIFF BUS_0.22UF,6.3V,20%,X6S,SA
     1 P5E_CPU0_P0_TX_BUF_C_DN<6> @T6G_MB_LIB.T6G(SCH_1):P5E_CPU0_P0_TX_BUF_C_DN(6)    I61 @T6G_MB_LIB.T6G(SCH_1):PAGE384
     2 P5E_CPU0_P0_TX_BUF_DN<6> @T6G_MB_LIB.T6G(SCH_1):P5E_CPU0_P0_TX_BUF_DN(6)    I61 @T6G_MB_LIB.T6G(SCH_1):PAGE384

C6515 Q_CAP_DIFFBUS_C0201-DIFF BUS_0.22UF,6.3V,20%,X6S,SA
     1 P5E_CPU0_P0_TX_BUF_C_DP<7> @T6G_MB_LIB.T6G(SCH_1):P5E_CPU0_P0_TX_BUF_C_DP(7)    I62 @T6G_MB_LIB.T6G(SCH_1):PAGE384
     2 P5E_CPU0_P0_TX_BUF_DP<7> @T6G_MB_LIB.T6G(SCH_1):P5E_CPU0_P0_TX_BUF_DP(7)    I62 @T6G_MB_LIB.T6G(SCH_1):PAGE384

C6516 Q_CAP_DIFFBUS_C0201-DIFF BUS_0.22UF,6.3V,20%,X6S,SA
     1 P5E_CPU0_P0_TX_BUF_C_DN<7> @T6G_MB_LIB.T6G(SCH_1):P5E_CPU0_P0_TX_BUF_C_DN(7)    I59 @T6G_MB_LIB.T6G(SCH_1):PAGE384
     2 P5E_CPU0_P0_TX_BUF_DN<7> @T6G_MB_LIB.T6G(SCH_1):P5E_CPU0_P0_TX_BUF_DN(7)    I59 @T6G_MB_LIB.T6G(SCH_1):PAGE384

C6517 Q_CAP_DIFFBUS_C0201-DIFF BUS_0.22UF,6.3V,20%,X6S,SA
     1 P5E_CPU0_P0_TX_BUF_C_DP<8> @T6G_MB_LIB.T6G(SCH_1):P5E_CPU0_P0_TX_BUF_C_DP(8)    I99 @T6G_MB_LIB.T6G(SCH_1):PAGE384
     2 P5E_CPU0_P0_TX_BUF_DP<8> @T6G_MB_LIB.T6G(SCH_1):P5E_CPU0_P0_TX_BUF_DP(8)    I99 @T6G_MB_LIB.T6G(SCH_1):PAGE384

C6518 Q_CAP_DIFFBUS_C0201-DIFF BUS_0.22UF,6.3V,20%,X6S,SA
     1 P5E_CPU0_P0_TX_BUF_C_DN<8> @T6G_MB_LIB.T6G(SCH_1):P5E_CPU0_P0_TX_BUF_C_DN(8)   I100 @T6G_MB_LIB.T6G(SCH_1):PAGE384
     2 P5E_CPU0_P0_TX_BUF_DN<8> @T6G_MB_LIB.T6G(SCH_1):P5E_CPU0_P0_TX_BUF_DN(8)   I100 @T6G_MB_LIB.T6G(SCH_1):PAGE384

C6519 Q_CAP_DIFFBUS_C0201-DIFF BUS_0.22UF,6.3V,20%,X6S,SA
     1 P5E_CPU0_P0_TX_BUF_C_DP<9> @T6G_MB_LIB.T6G(SCH_1):P5E_CPU0_P0_TX_BUF_C_DP(9)   I102 @T6G_MB_LIB.T6G(SCH_1):PAGE384
     2 P5E_CPU0_P0_TX_BUF_DP<9> @T6G_MB_LIB.T6G(SCH_1):P5E_CPU0_P0_TX_BUF_DP(9)   I102 @T6G_MB_LIB.T6G(SCH_1):PAGE384

C6520 Q_CAP_DIFFBUS_C0201-DIFF BUS_0.22UF,6.3V,20%,X6S,SA
     1 P5E_CPU0_P0_TX_BUF_C_DN<9> @T6G_MB_LIB.T6G(SCH_1):P5E_CPU0_P0_TX_BUF_C_DN(9)   I101 @T6G_MB_LIB.T6G(SCH_1):PAGE384
     2 P5E_CPU0_P0_TX_BUF_DN<9> @T6G_MB_LIB.T6G(SCH_1):P5E_CPU0_P0_TX_BUF_DN(9)   I101 @T6G_MB_LIB.T6G(SCH_1):PAGE384

C6521 Q_CAP_DIFFBUS_C0201-DIFF BUS_0.22UF,6.3V,20%,X6S,SA
     1 P5E_CPU0_P0_TX_BUF_C_DP<10> @T6G_MB_LIB.T6G(SCH_1):P5E_CPU0_P0_TX_BUF_C_DP(10)   I119 @T6G_MB_LIB.T6G(SCH_1):PAGE384
     2 P5E_CPU0_P0_TX_BUF_DP<10> @T6G_MB_LIB.T6G(SCH_1):P5E_CPU0_P0_TX_BUF_DP(10)   I119 @T6G_MB_LIB.T6G(SCH_1):PAGE384

C6522 Q_CAP_DIFFBUS_C0201-DIFF BUS_0.22UF,6.3V,20%,X6S,SA
     1 P5E_CPU0_P0_TX_BUF_C_DN<10> @T6G_MB_LIB.T6G(SCH_1):P5E_CPU0_P0_TX_BUF_C_DN(10)   I118 @T6G_MB_LIB.T6G(SCH_1):PAGE384
     2 P5E_CPU0_P0_TX_BUF_DN<10> @T6G_MB_LIB.T6G(SCH_1):P5E_CPU0_P0_TX_BUF_DN(10)   I118 @T6G_MB_LIB.T6G(SCH_1):PAGE384

C6523 Q_CAP_DIFFBUS_C0201-DIFF BUS_0.22UF,6.3V,20%,X6S,SA
     1 P5E_CPU0_P0_TX_BUF_C_DP<11> @T6G_MB_LIB.T6G(SCH_1):P5E_CPU0_P0_TX_BUF_C_DP(11)   I120 @T6G_MB_LIB.T6G(SCH_1):PAGE384
     2 P5E_CPU0_P0_TX_BUF_DP<11> @T6G_MB_LIB.T6G(SCH_1):P5E_CPU0_P0_TX_BUF_DP(11)   I120 @T6G_MB_LIB.T6G(SCH_1):PAGE384

C6524 Q_CAP_DIFFBUS_C0201-DIFF BUS_0.22UF,6.3V,20%,X6S,SA
     1 P5E_CPU0_P0_TX_BUF_C_DN<11> @T6G_MB_LIB.T6G(SCH_1):P5E_CPU0_P0_TX_BUF_C_DN(11)   I121 @T6G_MB_LIB.T6G(SCH_1):PAGE384
     2 P5E_CPU0_P0_TX_BUF_DN<11> @T6G_MB_LIB.T6G(SCH_1):P5E_CPU0_P0_TX_BUF_DN(11)   I121 @T6G_MB_LIB.T6G(SCH_1):PAGE384

C6525 Q_CAP_DIFFBUS_C0201-DIFF BUS_0.22UF,6.3V,20%,X6S,SA
     1 P5E_CPU0_P0_TX_BUF_C_DP<12> @T6G_MB_LIB.T6G(SCH_1):P5E_CPU0_P0_TX_BUF_C_DP(12)   I123 @T6G_MB_LIB.T6G(SCH_1):PAGE384
     2 P5E_CPU0_P0_TX_BUF_DP<12> @T6G_MB_LIB.T6G(SCH_1):P5E_CPU0_P0_TX_BUF_DP(12)   I123 @T6G_MB_LIB.T6G(SCH_1):PAGE384

C6526 Q_CAP_DIFFBUS_C0201-DIFF BUS_0.22UF,6.3V,20%,X6S,SA
     1 P5E_CPU0_P0_TX_BUF_C_DN<12> @T6G_MB_LIB.T6G(SCH_1):P5E_CPU0_P0_TX_BUF_C_DN(12)   I122 @T6G_MB_LIB.T6G(SCH_1):PAGE384
     2 P5E_CPU0_P0_TX_BUF_DN<12> @T6G_MB_LIB.T6G(SCH_1):P5E_CPU0_P0_TX_BUF_DN(12)   I122 @T6G_MB_LIB.T6G(SCH_1):PAGE384

C6527 Q_CAP_DIFFBUS_C0201-DIFF BUS_0.22UF,6.3V,20%,X6S,SA
     1 P5E_CPU0_P0_TX_BUF_C_DP<13> @T6G_MB_LIB.T6G(SCH_1):P5E_CPU0_P0_TX_BUF_C_DP(13)   I124 @T6G_MB_LIB.T6G(SCH_1):PAGE384
     2 P5E_CPU0_P0_TX_BUF_DP<13> @T6G_MB_LIB.T6G(SCH_1):P5E_CPU0_P0_TX_BUF_DP(13)   I124 @T6G_MB_LIB.T6G(SCH_1):PAGE384

C6528 Q_CAP_DIFFBUS_C0201-DIFF BUS_0.22UF,6.3V,20%,X6S,SA
     1 P5E_CPU0_P0_TX_BUF_C_DN<13> @T6G_MB_LIB.T6G(SCH_1):P5E_CPU0_P0_TX_BUF_C_DN(13)   I125 @T6G_MB_LIB.T6G(SCH_1):PAGE384
     2 P5E_CPU0_P0_TX_BUF_DN<13> @T6G_MB_LIB.T6G(SCH_1):P5E_CPU0_P0_TX_BUF_DN(13)   I125 @T6G_MB_LIB.T6G(SCH_1):PAGE384

C6529 Q_CAP_DIFFBUS_C0201-DIFF BUS_0.22UF,6.3V,20%,X6S,SA
     1 P5E_CPU0_P0_TX_BUF_C_DP<14> @T6G_MB_LIB.T6G(SCH_1):P5E_CPU0_P0_TX_BUF_C_DP(14)   I126 @T6G_MB_LIB.T6G(SCH_1):PAGE384
     2 P5E_CPU0_P0_TX_BUF_DP<14> @T6G_MB_LIB.T6G(SCH_1):P5E_CPU0_P0_TX_BUF_DP(14)   I126 @T6G_MB_LIB.T6G(SCH_1):PAGE384

C6530 Q_CAP_DIFFBUS_C0201-DIFF BUS_0.22UF,6.3V,20%,X6S,SA
     1 P5E_CPU0_P0_TX_BUF_C_DN<14> @T6G_MB_LIB.T6G(SCH_1):P5E_CPU0_P0_TX_BUF_C_DN(14)   I127 @T6G_MB_LIB.T6G(SCH_1):PAGE384
     2 P5E_CPU0_P0_TX_BUF_DN<14> @T6G_MB_LIB.T6G(SCH_1):P5E_CPU0_P0_TX_BUF_DN(14)   I127 @T6G_MB_LIB.T6G(SCH_1):PAGE384

C6531 Q_CAP_DIFFBUS_C0201-DIFF BUS_0.22UF,6.3V,20%,X6S,SA
     1 P5E_CPU0_P0_TX_BUF_C_DP<15> @T6G_MB_LIB.T6G(SCH_1):P5E_CPU0_P0_TX_BUF_C_DP(15)   I129 @T6G_MB_LIB.T6G(SCH_1):PAGE384
     2 P5E_CPU0_P0_TX_BUF_DP<15> @T6G_MB_LIB.T6G(SCH_1):P5E_CPU0_P0_TX_BUF_DP(15)   I129 @T6G_MB_LIB.T6G(SCH_1):PAGE384

C6532 Q_CAP_DIFFBUS_C0201-DIFF BUS_0.22UF,6.3V,20%,X6S,SA
     1 P5E_CPU0_P0_TX_BUF_C_DN<15> @T6G_MB_LIB.T6G(SCH_1):P5E_CPU0_P0_TX_BUF_C_DN(15)   I130 @T6G_MB_LIB.T6G(SCH_1):PAGE384
     2 P5E_CPU0_P0_TX_BUF_DN<15> @T6G_MB_LIB.T6G(SCH_1):P5E_CPU0_P0_TX_BUF_DN(15)   I130 @T6G_MB_LIB.T6G(SCH_1):PAGE384

C6533 Q_CAP_DIFFBUS_C0201-DIFF BUS_0.22UF,6.3V,20%,X6S,SA
     1 P5E_CPU0_P1_TX_BUF_C_DP<0> @T6G_MB_LIB.T6G(SCH_1):P5E_CPU0_P1_TX_BUF_C_DP(0)    I46 @T6G_MB_LIB.T6G(SCH_1):PAGE407
     2 P5E_CPU0_P1_TX_BUF_DP<0> @T6G_MB_LIB.T6G(SCH_1):P5E_CPU0_P1_TX_BUF_DP(0)    I46 @T6G_MB_LIB.T6G(SCH_1):PAGE407

C6534 Q_CAP_DIFFBUS_C0201-DIFF BUS_0.22UF,6.3V,20%,X6S,SA
     1 P5E_CPU0_P1_TX_BUF_C_DN<0> @T6G_MB_LIB.T6G(SCH_1):P5E_CPU0_P1_TX_BUF_C_DN(0)    I47 @T6G_MB_LIB.T6G(SCH_1):PAGE407
     2 P5E_CPU0_P1_TX_BUF_DN<0> @T6G_MB_LIB.T6G(SCH_1):P5E_CPU0_P1_TX_BUF_DN(0)    I47 @T6G_MB_LIB.T6G(SCH_1):PAGE407

C6535 Q_CAP_DIFFBUS_C0201-DIFF BUS_0.22UF,6.3V,20%,X6S,SA
     1 P5E_CPU0_P1_TX_BUF_C_DP<1> @T6G_MB_LIB.T6G(SCH_1):P5E_CPU0_P1_TX_BUF_C_DP(1)    I45 @T6G_MB_LIB.T6G(SCH_1):PAGE407
     2 P5E_CPU0_P1_TX_BUF_DP<1> @T6G_MB_LIB.T6G(SCH_1):P5E_CPU0_P1_TX_BUF_DP(1)    I45 @T6G_MB_LIB.T6G(SCH_1):PAGE407

C6536 Q_CAP_DIFFBUS_C0201-DIFF BUS_0.22UF,6.3V,20%,X6S,SA
     1 P5E_CPU0_P1_TX_BUF_C_DN<1> @T6G_MB_LIB.T6G(SCH_1):P5E_CPU0_P1_TX_BUF_C_DN(1)    I44 @T6G_MB_LIB.T6G(SCH_1):PAGE407
     2 P5E_CPU0_P1_TX_BUF_DN<1> @T6G_MB_LIB.T6G(SCH_1):P5E_CPU0_P1_TX_BUF_DN(1)    I44 @T6G_MB_LIB.T6G(SCH_1):PAGE407

C6537 Q_CAP_DIFFBUS_C0201-DIFF BUS_0.22UF,6.3V,20%,X6S,SA
     1 P5E_CPU0_P1_TX_BUF_C_DP<2> @T6G_MB_LIB.T6G(SCH_1):P5E_CPU0_P1_TX_BUF_C_DP(2)    I27 @T6G_MB_LIB.T6G(SCH_1):PAGE407
     2 P5E_CPU0_P1_TX_BUF_DP<2> @T6G_MB_LIB.T6G(SCH_1):P5E_CPU0_P1_TX_BUF_DP(2)    I27 @T6G_MB_LIB.T6G(SCH_1):PAGE407

C6538 Q_CAP_DIFFBUS_C0201-DIFF BUS_0.22UF,6.3V,20%,X6S,SA
     1 P5E_CPU0_P1_TX_BUF_C_DN<2> @T6G_MB_LIB.T6G(SCH_1):P5E_CPU0_P1_TX_BUF_C_DN(2)    I26 @T6G_MB_LIB.T6G(SCH_1):PAGE407
     2 P5E_CPU0_P1_TX_BUF_DN<2> @T6G_MB_LIB.T6G(SCH_1):P5E_CPU0_P1_TX_BUF_DN(2)    I26 @T6G_MB_LIB.T6G(SCH_1):PAGE407

C6539 Q_CAP_DIFFBUS_C0201-DIFF BUS_0.22UF,6.3V,20%,X6S,SA
     1 P5E_CPU0_P1_TX_BUF_C_DP<3> @T6G_MB_LIB.T6G(SCH_1):P5E_CPU0_P1_TX_BUF_C_DP(3)    I25 @T6G_MB_LIB.T6G(SCH_1):PAGE407
     2 P5E_CPU0_P1_TX_BUF_DP<3> @T6G_MB_LIB.T6G(SCH_1):P5E_CPU0_P1_TX_BUF_DP(3)    I25 @T6G_MB_LIB.T6G(SCH_1):PAGE407

C6540 Q_CAP_DIFFBUS_C0201-DIFF BUS_0.22UF,6.3V,20%,X6S,SA
     1 P5E_CPU0_P1_TX_BUF_C_DN<3> @T6G_MB_LIB.T6G(SCH_1):P5E_CPU0_P1_TX_BUF_C_DN(3)    I24 @T6G_MB_LIB.T6G(SCH_1):PAGE407
     2 P5E_CPU0_P1_TX_BUF_DN<3> @T6G_MB_LIB.T6G(SCH_1):P5E_CPU0_P1_TX_BUF_DN(3)    I24 @T6G_MB_LIB.T6G(SCH_1):PAGE407

C6541 Q_CAP_DIFFBUS_C0201-DIFF BUS_0.22UF,6.3V,20%,X6S,SA
     1 P5E_CPU0_P1_TX_BUF_C_DP<4> @T6G_MB_LIB.T6G(SCH_1):P5E_CPU0_P1_TX_BUF_C_DP(4)    I22 @T6G_MB_LIB.T6G(SCH_1):PAGE407
     2 P5E_CPU0_P1_TX_BUF_DP<4> @T6G_MB_LIB.T6G(SCH_1):P5E_CPU0_P1_TX_BUF_DP(4)    I22 @T6G_MB_LIB.T6G(SCH_1):PAGE407

C6542 Q_CAP_DIFFBUS_C0201-DIFF BUS_0.22UF,6.3V,20%,X6S,SA
     1 P5E_CPU0_P1_TX_BUF_C_DN<4> @T6G_MB_LIB.T6G(SCH_1):P5E_CPU0_P1_TX_BUF_C_DN(4)    I23 @T6G_MB_LIB.T6G(SCH_1):PAGE407
     2 P5E_CPU0_P1_TX_BUF_DN<4> @T6G_MB_LIB.T6G(SCH_1):P5E_CPU0_P1_TX_BUF_DN(4)    I23 @T6G_MB_LIB.T6G(SCH_1):PAGE407

C6543 Q_CAP_DIFFBUS_C0201-DIFF BUS_0.22UF,6.3V,20%,X6S,SA
     1 P5E_CPU0_P1_TX_BUF_C_DP<5> @T6G_MB_LIB.T6G(SCH_1):P5E_CPU0_P1_TX_BUF_C_DP(5)    I20 @T6G_MB_LIB.T6G(SCH_1):PAGE407
     2 P5E_CPU0_P1_TX_BUF_DP<5> @T6G_MB_LIB.T6G(SCH_1):P5E_CPU0_P1_TX_BUF_DP(5)    I20 @T6G_MB_LIB.T6G(SCH_1):PAGE407

C6544 Q_CAP_DIFFBUS_C0201-DIFF BUS_0.22UF,6.3V,20%,X6S,SA
     1 P5E_CPU0_P1_TX_BUF_C_DN<5> @T6G_MB_LIB.T6G(SCH_1):P5E_CPU0_P1_TX_BUF_C_DN(5)    I21 @T6G_MB_LIB.T6G(SCH_1):PAGE407
     2 P5E_CPU0_P1_TX_BUF_DN<5> @T6G_MB_LIB.T6G(SCH_1):P5E_CPU0_P1_TX_BUF_DN(5)    I21 @T6G_MB_LIB.T6G(SCH_1):PAGE407

C6545 Q_CAP_DIFFBUS_C0201-DIFF BUS_0.22UF,6.3V,20%,X6S,SA
     1 P5E_CPU0_P1_TX_BUF_C_DP<6> @T6G_MB_LIB.T6G(SCH_1):P5E_CPU0_P1_TX_BUF_C_DP(6)    I18 @T6G_MB_LIB.T6G(SCH_1):PAGE407
     2 P5E_CPU0_P1_TX_BUF_DP<6> @T6G_MB_LIB.T6G(SCH_1):P5E_CPU0_P1_TX_BUF_DP(6)    I18 @T6G_MB_LIB.T6G(SCH_1):PAGE407

C6546 Q_CAP_DIFFBUS_C0201-DIFF BUS_0.22UF,6.3V,20%,X6S,SA
     1 P5E_CPU0_P1_TX_BUF_C_DN<6> @T6G_MB_LIB.T6G(SCH_1):P5E_CPU0_P1_TX_BUF_C_DN(6)    I19 @T6G_MB_LIB.T6G(SCH_1):PAGE407
     2 P5E_CPU0_P1_TX_BUF_DN<6> @T6G_MB_LIB.T6G(SCH_1):P5E_CPU0_P1_TX_BUF_DN(6)    I19 @T6G_MB_LIB.T6G(SCH_1):PAGE407

C6547 Q_CAP_DIFFBUS_C0201-DIFF BUS_0.22UF,6.3V,20%,X6S,SA
     1 P5E_CPU0_P1_TX_BUF_C_DP<7> @T6G_MB_LIB.T6G(SCH_1):P5E_CPU0_P1_TX_BUF_C_DP(7)    I16 @T6G_MB_LIB.T6G(SCH_1):PAGE407
     2 P5E_CPU0_P1_TX_BUF_DP<7> @T6G_MB_LIB.T6G(SCH_1):P5E_CPU0_P1_TX_BUF_DP(7)    I16 @T6G_MB_LIB.T6G(SCH_1):PAGE407

C6548 Q_CAP_DIFFBUS_C0201-DIFF BUS_0.22UF,6.3V,20%,X6S,SA
     1 P5E_CPU0_P1_TX_BUF_C_DN<7> @T6G_MB_LIB.T6G(SCH_1):P5E_CPU0_P1_TX_BUF_C_DN(7)    I15 @T6G_MB_LIB.T6G(SCH_1):PAGE407
     2 P5E_CPU0_P1_TX_BUF_DN<7> @T6G_MB_LIB.T6G(SCH_1):P5E_CPU0_P1_TX_BUF_DN(7)    I15 @T6G_MB_LIB.T6G(SCH_1):PAGE407

C6549 Q_CAP_DIFFBUS_C0201-DIFF BUS_0.22UF,6.3V,20%,X6S,SA
     1 P5E_CPU0_P1_TX_BUF_C_DP<8> @T6G_MB_LIB.T6G(SCH_1):P5E_CPU0_P1_TX_BUF_C_DP(8)   I105 @T6G_MB_LIB.T6G(SCH_1):PAGE407
     2 P5E_CPU0_P1_TX_BUF_DP<8> @T6G_MB_LIB.T6G(SCH_1):P5E_CPU0_P1_TX_BUF_DP(8)   I105 @T6G_MB_LIB.T6G(SCH_1):PAGE407

C6550 Q_CAP_DIFFBUS_C0201-DIFF BUS_0.22UF,6.3V,20%,X6S,SA
     1 P5E_CPU0_P1_TX_BUF_C_DN<8> @T6G_MB_LIB.T6G(SCH_1):P5E_CPU0_P1_TX_BUF_C_DN(8)   I104 @T6G_MB_LIB.T6G(SCH_1):PAGE407
     2 P5E_CPU0_P1_TX_BUF_DN<8> @T6G_MB_LIB.T6G(SCH_1):P5E_CPU0_P1_TX_BUF_DN(8)   I104 @T6G_MB_LIB.T6G(SCH_1):PAGE407

C6551 Q_CAP_DIFFBUS_C0201-DIFF BUS_0.22UF,6.3V,20%,X6S,SA
     1 P5E_CPU0_P1_TX_BUF_C_DP<9> @T6G_MB_LIB.T6G(SCH_1):P5E_CPU0_P1_TX_BUF_C_DP(9)   I102 @T6G_MB_LIB.T6G(SCH_1):PAGE407
     2 P5E_CPU0_P1_TX_BUF_DP<9> @T6G_MB_LIB.T6G(SCH_1):P5E_CPU0_P1_TX_BUF_DP(9)   I102 @T6G_MB_LIB.T6G(SCH_1):PAGE407

C6552 Q_CAP_DIFFBUS_C0201-DIFF BUS_0.22UF,6.3V,20%,X6S,SA
     1 P5E_CPU0_P1_TX_BUF_C_DN<9> @T6G_MB_LIB.T6G(SCH_1):P5E_CPU0_P1_TX_BUF_C_DN(9)   I103 @T6G_MB_LIB.T6G(SCH_1):PAGE407
     2 P5E_CPU0_P1_TX_BUF_DN<9> @T6G_MB_LIB.T6G(SCH_1):P5E_CPU0_P1_TX_BUF_DN(9)   I103 @T6G_MB_LIB.T6G(SCH_1):PAGE407

C6553 Q_CAP_DIFFBUS_C0201-DIFF BUS_0.22UF,6.3V,20%,X6S,SA
     1 P5E_CPU0_P1_TX_BUF_C_DP<10> @T6G_MB_LIB.T6G(SCH_1):P5E_CPU0_P1_TX_BUF_C_DP(10)    I96 @T6G_MB_LIB.T6G(SCH_1):PAGE407
     2 P5E_CPU0_P1_TX_BUF_DP<10> @T6G_MB_LIB.T6G(SCH_1):P5E_CPU0_P1_TX_BUF_DP(10)    I96 @T6G_MB_LIB.T6G(SCH_1):PAGE407

C6554 Q_CAP_DIFFBUS_C0201-DIFF BUS_0.22UF,6.3V,20%,X6S,SA
     1 P5E_CPU0_P1_TX_BUF_C_DN<10> @T6G_MB_LIB.T6G(SCH_1):P5E_CPU0_P1_TX_BUF_C_DN(10)    I97 @T6G_MB_LIB.T6G(SCH_1):PAGE407
     2 P5E_CPU0_P1_TX_BUF_DN<10> @T6G_MB_LIB.T6G(SCH_1):P5E_CPU0_P1_TX_BUF_DN(10)    I97 @T6G_MB_LIB.T6G(SCH_1):PAGE407

C6555 Q_CAP_DIFFBUS_C0201-DIFF BUS_0.22UF,6.3V,20%,X6S,SA
     1 P5E_CPU0_P1_TX_BUF_C_DP<11> @T6G_MB_LIB.T6G(SCH_1):P5E_CPU0_P1_TX_BUF_C_DP(11)    I95 @T6G_MB_LIB.T6G(SCH_1):PAGE407
     2 P5E_CPU0_P1_TX_BUF_DP<11> @T6G_MB_LIB.T6G(SCH_1):P5E_CPU0_P1_TX_BUF_DP(11)    I95 @T6G_MB_LIB.T6G(SCH_1):PAGE407

C6556 Q_CAP_DIFFBUS_C0201-DIFF BUS_0.22UF,6.3V,20%,X6S,SA
     1 P5E_CPU0_P1_TX_BUF_C_DN<11> @T6G_MB_LIB.T6G(SCH_1):P5E_CPU0_P1_TX_BUF_C_DN(11)    I94 @T6G_MB_LIB.T6G(SCH_1):PAGE407
     2 P5E_CPU0_P1_TX_BUF_DN<11> @T6G_MB_LIB.T6G(SCH_1):P5E_CPU0_P1_TX_BUF_DN(11)    I94 @T6G_MB_LIB.T6G(SCH_1):PAGE407

C6557 Q_CAP_DIFFBUS_C0201-DIFF BUS_0.22UF,6.3V,20%,X6S,SA
     1 P5E_CPU0_P1_TX_BUF_C_DP<12> @T6G_MB_LIB.T6G(SCH_1):P5E_CPU0_P1_TX_BUF_C_DP(12)    I93 @T6G_MB_LIB.T6G(SCH_1):PAGE407
     2 P5E_CPU0_P1_TX_BUF_DP<12> @T6G_MB_LIB.T6G(SCH_1):P5E_CPU0_P1_TX_BUF_DP(12)    I93 @T6G_MB_LIB.T6G(SCH_1):PAGE407

C6558 Q_CAP_DIFFBUS_C0201-DIFF BUS_0.22UF,6.3V,20%,X6S,SA
     1 P5E_CPU0_P1_TX_BUF_C_DN<12> @T6G_MB_LIB.T6G(SCH_1):P5E_CPU0_P1_TX_BUF_C_DN(12)    I92 @T6G_MB_LIB.T6G(SCH_1):PAGE407
     2 P5E_CPU0_P1_TX_BUF_DN<12> @T6G_MB_LIB.T6G(SCH_1):P5E_CPU0_P1_TX_BUF_DN(12)    I92 @T6G_MB_LIB.T6G(SCH_1):PAGE407

C6559 Q_CAP_DIFFBUS_C0201-DIFF BUS_0.22UF,6.3V,20%,X6S,SA
     1 P5E_CPU0_P1_TX_BUF_C_DP<13> @T6G_MB_LIB.T6G(SCH_1):P5E_CPU0_P1_TX_BUF_C_DP(13)    I91 @T6G_MB_LIB.T6G(SCH_1):PAGE407
     2 P5E_CPU0_P1_TX_BUF_DP<13> @T6G_MB_LIB.T6G(SCH_1):P5E_CPU0_P1_TX_BUF_DP(13)    I91 @T6G_MB_LIB.T6G(SCH_1):PAGE407

C6560 Q_CAP_DIFFBUS_C0201-DIFF BUS_0.22UF,6.3V,20%,X6S,SA
     1 P5E_CPU0_P1_TX_BUF_C_DN<13> @T6G_MB_LIB.T6G(SCH_1):P5E_CPU0_P1_TX_BUF_C_DN(13)    I90 @T6G_MB_LIB.T6G(SCH_1):PAGE407
     2 P5E_CPU0_P1_TX_BUF_DN<13> @T6G_MB_LIB.T6G(SCH_1):P5E_CPU0_P1_TX_BUF_DN(13)    I90 @T6G_MB_LIB.T6G(SCH_1):PAGE407

C6561 Q_CAP_DIFFBUS_C0201-DIFF BUS_0.22UF,6.3V,20%,X6S,SA
     1 P5E_CPU0_P1_TX_BUF_C_DP<14> @T6G_MB_LIB.T6G(SCH_1):P5E_CPU0_P1_TX_BUF_C_DP(14)    I89 @T6G_MB_LIB.T6G(SCH_1):PAGE407
     2 P5E_CPU0_P1_TX_BUF_DP<14> @T6G_MB_LIB.T6G(SCH_1):P5E_CPU0_P1_TX_BUF_DP(14)    I89 @T6G_MB_LIB.T6G(SCH_1):PAGE407

C6562 Q_CAP_DIFFBUS_C0201-DIFF BUS_0.22UF,6.3V,20%,X6S,SA
     1 P5E_CPU0_P1_TX_BUF_C_DN<14> @T6G_MB_LIB.T6G(SCH_1):P5E_CPU0_P1_TX_BUF_C_DN(14)    I88 @T6G_MB_LIB.T6G(SCH_1):PAGE407
     2 P5E_CPU0_P1_TX_BUF_DN<14> @T6G_MB_LIB.T6G(SCH_1):P5E_CPU0_P1_TX_BUF_DN(14)    I88 @T6G_MB_LIB.T6G(SCH_1):PAGE407

C6563 Q_CAP_DIFFBUS_C0201-DIFF BUS_0.22UF,6.3V,20%,X6S,SA
     1 P5E_CPU0_P1_TX_BUF_C_DP<15> @T6G_MB_LIB.T6G(SCH_1):P5E_CPU0_P1_TX_BUF_C_DP(15)    I87 @T6G_MB_LIB.T6G(SCH_1):PAGE407
     2 P5E_CPU0_P1_TX_BUF_DP<15> @T6G_MB_LIB.T6G(SCH_1):P5E_CPU0_P1_TX_BUF_DP(15)    I87 @T6G_MB_LIB.T6G(SCH_1):PAGE407

C6564 Q_CAP_DIFFBUS_C0201-DIFF BUS_0.22UF,6.3V,20%,X6S,SA
     1 P5E_CPU0_P1_TX_BUF_C_DN<15> @T6G_MB_LIB.T6G(SCH_1):P5E_CPU0_P1_TX_BUF_C_DN(15)    I86 @T6G_MB_LIB.T6G(SCH_1):PAGE407
     2 P5E_CPU0_P1_TX_BUF_DN<15> @T6G_MB_LIB.T6G(SCH_1):P5E_CPU0_P1_TX_BUF_DN(15)    I86 @T6G_MB_LIB.T6G(SCH_1):PAGE407

C6565 Q_CAP_DIFFBUS_C0201-DIFF BUS_0.22UF,6.3V,20%,X6S,SA
     1 P5E_CPU0_P2_TX_BUF_C_DP<0> @T6G_MB_LIB.T6G(SCH_1):P5E_CPU0_P2_TX_BUF_C_DP(0)    I49 @T6G_MB_LIB.T6G(SCH_1):PAGE418
     2 P5E_CPU0_P2_TX_BUF_DP<0> @T6G_MB_LIB.T6G(SCH_1):P5E_CPU0_P2_TX_BUF_DP(0)    I49 @T6G_MB_LIB.T6G(SCH_1):PAGE418

C6566 Q_CAP_DIFFBUS_C0201-DIFF BUS_0.22UF,6.3V,20%,X6S,SA
     1 P5E_CPU0_P2_TX_BUF_C_DN<0> @T6G_MB_LIB.T6G(SCH_1):P5E_CPU0_P2_TX_BUF_C_DN(0)    I48 @T6G_MB_LIB.T6G(SCH_1):PAGE418
     2 P5E_CPU0_P2_TX_BUF_DN<0> @T6G_MB_LIB.T6G(SCH_1):P5E_CPU0_P2_TX_BUF_DN(0)    I48 @T6G_MB_LIB.T6G(SCH_1):PAGE418

C6567 Q_CAP_DIFFBUS_C0201-DIFF BUS_0.22UF,6.3V,20%,X6S,SA
     1 P5E_CPU0_P2_TX_BUF_C_DP<1> @T6G_MB_LIB.T6G(SCH_1):P5E_CPU0_P2_TX_BUF_C_DP(1)    I32 @T6G_MB_LIB.T6G(SCH_1):PAGE418
     2 P5E_CPU0_P2_TX_BUF_DP<1> @T6G_MB_LIB.T6G(SCH_1):P5E_CPU0_P2_TX_BUF_DP(1)    I32 @T6G_MB_LIB.T6G(SCH_1):PAGE418

C6568 Q_CAP_DIFFBUS_C0201-DIFF BUS_0.22UF,6.3V,20%,X6S,SA
     1 P5E_CPU0_P2_TX_BUF_C_DN<1> @T6G_MB_LIB.T6G(SCH_1):P5E_CPU0_P2_TX_BUF_C_DN(1)    I33 @T6G_MB_LIB.T6G(SCH_1):PAGE418
     2 P5E_CPU0_P2_TX_BUF_DN<1> @T6G_MB_LIB.T6G(SCH_1):P5E_CPU0_P2_TX_BUF_DN(1)    I33 @T6G_MB_LIB.T6G(SCH_1):PAGE418

C6569 Q_CAP_DIFFBUS_C0201-DIFF BUS_0.22UF,6.3V,20%,X6S,SA
     1 P5E_CPU0_P2_TX_BUF_C_DP<2> @T6G_MB_LIB.T6G(SCH_1):P5E_CPU0_P2_TX_BUF_C_DP(2)    I34 @T6G_MB_LIB.T6G(SCH_1):PAGE418
     2 P5E_CPU0_P2_TX_BUF_DP<2> @T6G_MB_LIB.T6G(SCH_1):P5E_CPU0_P2_TX_BUF_DP(2)    I34 @T6G_MB_LIB.T6G(SCH_1):PAGE418

C6570 Q_CAP_DIFFBUS_C0201-DIFF BUS_0.22UF,6.3V,20%,X6S,SA
     1 P5E_CPU0_P2_TX_BUF_C_DN<2> @T6G_MB_LIB.T6G(SCH_1):P5E_CPU0_P2_TX_BUF_C_DN(2)    I31 @T6G_MB_LIB.T6G(SCH_1):PAGE418
     2 P5E_CPU0_P2_TX_BUF_DN<2> @T6G_MB_LIB.T6G(SCH_1):P5E_CPU0_P2_TX_BUF_DN(2)    I31 @T6G_MB_LIB.T6G(SCH_1):PAGE418

C6571 Q_CAP_DIFFBUS_C0201-DIFF BUS_0.22UF,6.3V,20%,X6S,SA
     1 P5E_CPU0_P2_TX_BUF_C_DP<3> @T6G_MB_LIB.T6G(SCH_1):P5E_CPU0_P2_TX_BUF_C_DP(3)    I30 @T6G_MB_LIB.T6G(SCH_1):PAGE418
     2 P5E_CPU0_P2_TX_BUF_DP<3> @T6G_MB_LIB.T6G(SCH_1):P5E_CPU0_P2_TX_BUF_DP(3)    I30 @T6G_MB_LIB.T6G(SCH_1):PAGE418

C6572 Q_CAP_DIFFBUS_C0201-DIFF BUS_0.22UF,6.3V,20%,X6S,SA
     1 P5E_CPU0_P2_TX_BUF_C_DN<3> @T6G_MB_LIB.T6G(SCH_1):P5E_CPU0_P2_TX_BUF_C_DN(3)    I29 @T6G_MB_LIB.T6G(SCH_1):PAGE418
     2 P5E_CPU0_P2_TX_BUF_DN<3> @T6G_MB_LIB.T6G(SCH_1):P5E_CPU0_P2_TX_BUF_DN(3)    I29 @T6G_MB_LIB.T6G(SCH_1):PAGE418

C6573 Q_CAP_DIFFBUS_C0201-DIFF BUS_0.22UF,6.3V,20%,X6S,SA
     1 P5E_CPU0_P2_TX_BUF_C_DP<4> @T6G_MB_LIB.T6G(SCH_1):P5E_CPU0_P2_TX_BUF_C_DP(4)    I27 @T6G_MB_LIB.T6G(SCH_1):PAGE418
     2 P5E_CPU0_P2_TX_BUF_DP<4> @T6G_MB_LIB.T6G(SCH_1):P5E_CPU0_P2_TX_BUF_DP(4)    I27 @T6G_MB_LIB.T6G(SCH_1):PAGE418

C6574 Q_CAP_DIFFBUS_C0201-DIFF BUS_0.22UF,6.3V,20%,X6S,SA
     1 P5E_CPU0_P2_TX_BUF_C_DN<4> @T6G_MB_LIB.T6G(SCH_1):P5E_CPU0_P2_TX_BUF_C_DN(4)    I28 @T6G_MB_LIB.T6G(SCH_1):PAGE418
     2 P5E_CPU0_P2_TX_BUF_DN<4> @T6G_MB_LIB.T6G(SCH_1):P5E_CPU0_P2_TX_BUF_DN(4)    I28 @T6G_MB_LIB.T6G(SCH_1):PAGE418

C6575 Q_CAP_DIFFBUS_C0201-DIFF BUS_0.22UF,6.3V,20%,X6S,SA
     1 P5E_CPU0_P2_TX_BUF_C_DP<5> @T6G_MB_LIB.T6G(SCH_1):P5E_CPU0_P2_TX_BUF_C_DP(5)    I25 @T6G_MB_LIB.T6G(SCH_1):PAGE418
     2 P5E_CPU0_P2_TX_BUF_DP<5> @T6G_MB_LIB.T6G(SCH_1):P5E_CPU0_P2_TX_BUF_DP(5)    I25 @T6G_MB_LIB.T6G(SCH_1):PAGE418

C6576 Q_CAP_DIFFBUS_C0201-DIFF BUS_0.22UF,6.3V,20%,X6S,SA
     1 P5E_CPU0_P2_TX_BUF_C_DN<5> @T6G_MB_LIB.T6G(SCH_1):P5E_CPU0_P2_TX_BUF_C_DN(5)    I26 @T6G_MB_LIB.T6G(SCH_1):PAGE418
     2 P5E_CPU0_P2_TX_BUF_DN<5> @T6G_MB_LIB.T6G(SCH_1):P5E_CPU0_P2_TX_BUF_DN(5)    I26 @T6G_MB_LIB.T6G(SCH_1):PAGE418

C6577 Q_CAP_DIFFBUS_C0201-DIFF BUS_0.22UF,6.3V,20%,X6S,SA
     1 P5E_CPU0_P2_TX_BUF_C_DP<6> @T6G_MB_LIB.T6G(SCH_1):P5E_CPU0_P2_TX_BUF_C_DP(6)    I19 @T6G_MB_LIB.T6G(SCH_1):PAGE418
     2 P5E_CPU0_P2_TX_BUF_DP<6> @T6G_MB_LIB.T6G(SCH_1):P5E_CPU0_P2_TX_BUF_DP(6)    I19 @T6G_MB_LIB.T6G(SCH_1):PAGE418

C6578 Q_CAP_DIFFBUS_C0201-DIFF BUS_0.22UF,6.3V,20%,X6S,SA
     1 P5E_CPU0_P2_TX_BUF_C_DN<6> @T6G_MB_LIB.T6G(SCH_1):P5E_CPU0_P2_TX_BUF_C_DN(6)    I20 @T6G_MB_LIB.T6G(SCH_1):PAGE418
     2 P5E_CPU0_P2_TX_BUF_DN<6> @T6G_MB_LIB.T6G(SCH_1):P5E_CPU0_P2_TX_BUF_DN(6)    I20 @T6G_MB_LIB.T6G(SCH_1):PAGE418

C6579 Q_CAP_DIFFBUS_C0201-DIFF BUS_0.22UF,6.3V,20%,X6S,SA
     1 P5E_CPU0_P2_TX_BUF_C_DP<7> @T6G_MB_LIB.T6G(SCH_1):P5E_CPU0_P2_TX_BUF_C_DP(7)    I18 @T6G_MB_LIB.T6G(SCH_1):PAGE418
     2 P5E_CPU0_P2_TX_BUF_DP<7> @T6G_MB_LIB.T6G(SCH_1):P5E_CPU0_P2_TX_BUF_DP(7)    I18 @T6G_MB_LIB.T6G(SCH_1):PAGE418

C6580 Q_CAP_DIFFBUS_C0201-DIFF BUS_0.22UF,6.3V,20%,X6S,SA
     1 P5E_CPU0_P2_TX_BUF_C_DN<7> @T6G_MB_LIB.T6G(SCH_1):P5E_CPU0_P2_TX_BUF_C_DN(7)    I17 @T6G_MB_LIB.T6G(SCH_1):PAGE418
     2 P5E_CPU0_P2_TX_BUF_DN<7> @T6G_MB_LIB.T6G(SCH_1):P5E_CPU0_P2_TX_BUF_DN(7)    I17 @T6G_MB_LIB.T6G(SCH_1):PAGE418

C6581 Q_CAP_DIFFBUS_C0201-DIFF BUS_0.22UF,6.3V,20%,X6S,SA
     1 P5E_CPU0_P2_TX_BUF_C_DP<8> @T6G_MB_LIB.T6G(SCH_1):P5E_CPU0_P2_TX_BUF_C_DP(8)   I104 @T6G_MB_LIB.T6G(SCH_1):PAGE418
     2 P5E_CPU0_P2_TX_BUF_DP<8> @T6G_MB_LIB.T6G(SCH_1):P5E_CPU0_P2_TX_BUF_DP(8)   I104 @T6G_MB_LIB.T6G(SCH_1):PAGE418

C6582 Q_CAP_DIFFBUS_C0201-DIFF BUS_0.22UF,6.3V,20%,X6S,SA
     1 P5E_CPU0_P2_TX_BUF_C_DN<8> @T6G_MB_LIB.T6G(SCH_1):P5E_CPU0_P2_TX_BUF_C_DN(8)   I105 @T6G_MB_LIB.T6G(SCH_1):PAGE418
     2 P5E_CPU0_P2_TX_BUF_DN<8> @T6G_MB_LIB.T6G(SCH_1):P5E_CPU0_P2_TX_BUF_DN(8)   I105 @T6G_MB_LIB.T6G(SCH_1):PAGE418

C6583 Q_CAP_DIFFBUS_C0201-DIFF BUS_0.22UF,6.3V,20%,X6S,SA
     1 P5E_CPU0_P2_TX_BUF_C_DP<9> @T6G_MB_LIB.T6G(SCH_1):P5E_CPU0_P2_TX_BUF_C_DP(9)   I101 @T6G_MB_LIB.T6G(SCH_1):PAGE418
     2 P5E_CPU0_P2_TX_BUF_DP<9> @T6G_MB_LIB.T6G(SCH_1):P5E_CPU0_P2_TX_BUF_DP(9)   I101 @T6G_MB_LIB.T6G(SCH_1):PAGE418

C6584 Q_CAP_DIFFBUS_C0201-DIFF BUS_0.22UF,6.3V,20%,X6S,SA
     1 P5E_CPU0_P2_TX_BUF_C_DN<9> @T6G_MB_LIB.T6G(SCH_1):P5E_CPU0_P2_TX_BUF_C_DN(9)   I100 @T6G_MB_LIB.T6G(SCH_1):PAGE418
     2 P5E_CPU0_P2_TX_BUF_DN<9> @T6G_MB_LIB.T6G(SCH_1):P5E_CPU0_P2_TX_BUF_DN(9)   I100 @T6G_MB_LIB.T6G(SCH_1):PAGE418

C6585 Q_CAP_DIFFBUS_C0201-DIFF BUS_0.22UF,6.3V,20%,X6S,SA
     1 P5E_CPU0_P2_TX_BUF_C_DP<10> @T6G_MB_LIB.T6G(SCH_1):P5E_CPU0_P2_TX_BUF_C_DP(10)    I99 @T6G_MB_LIB.T6G(SCH_1):PAGE418
     2 P5E_CPU0_P2_TX_BUF_DP<10> @T6G_MB_LIB.T6G(SCH_1):P5E_CPU0_P2_TX_BUF_DP(10)    I99 @T6G_MB_LIB.T6G(SCH_1):PAGE418

C6586 Q_CAP_DIFFBUS_C0201-DIFF BUS_0.22UF,6.3V,20%,X6S,SA
     1 P5E_CPU0_P2_TX_BUF_C_DN<10> @T6G_MB_LIB.T6G(SCH_1):P5E_CPU0_P2_TX_BUF_C_DN(10)    I98 @T6G_MB_LIB.T6G(SCH_1):PAGE418
     2 P5E_CPU0_P2_TX_BUF_DN<10> @T6G_MB_LIB.T6G(SCH_1):P5E_CPU0_P2_TX_BUF_DN(10)    I98 @T6G_MB_LIB.T6G(SCH_1):PAGE418

C6587 Q_CAP_DIFFBUS_C0201-DIFF BUS_0.22UF,6.3V,20%,X6S,SA
     1 P5E_CPU0_P2_TX_BUF_C_DP<11> @T6G_MB_LIB.T6G(SCH_1):P5E_CPU0_P2_TX_BUF_C_DP(11)    I97 @T6G_MB_LIB.T6G(SCH_1):PAGE418
     2 P5E_CPU0_P2_TX_BUF_DP<11> @T6G_MB_LIB.T6G(SCH_1):P5E_CPU0_P2_TX_BUF_DP(11)    I97 @T6G_MB_LIB.T6G(SCH_1):PAGE418

C6588 Q_CAP_DIFFBUS_C0201-DIFF BUS_0.22UF,6.3V,20%,X6S,SA
     1 P5E_CPU0_P2_TX_BUF_C_DN<11> @T6G_MB_LIB.T6G(SCH_1):P5E_CPU0_P2_TX_BUF_C_DN(11)    I96 @T6G_MB_LIB.T6G(SCH_1):PAGE418
     2 P5E_CPU0_P2_TX_BUF_DN<11> @T6G_MB_LIB.T6G(SCH_1):P5E_CPU0_P2_TX_BUF_DN(11)    I96 @T6G_MB_LIB.T6G(SCH_1):PAGE418

C6589 Q_CAP_DIFFBUS_C0201-DIFF BUS_0.22UF,6.3V,20%,X6S,SA
     1 P5E_CPU0_P2_TX_BUF_C_DP<12> @T6G_MB_LIB.T6G(SCH_1):P5E_CPU0_P2_TX_BUF_C_DP(12)    I95 @T6G_MB_LIB.T6G(SCH_1):PAGE418
     2 P5E_CPU0_P2_TX_BUF_DP<12> @T6G_MB_LIB.T6G(SCH_1):P5E_CPU0_P2_TX_BUF_DP(12)    I95 @T6G_MB_LIB.T6G(SCH_1):PAGE418

C6590 Q_CAP_DIFFBUS_C0201-DIFF BUS_0.22UF,6.3V,20%,X6S,SA
     1 P5E_CPU0_P2_TX_BUF_C_DN<12> @T6G_MB_LIB.T6G(SCH_1):P5E_CPU0_P2_TX_BUF_C_DN(12)    I94 @T6G_MB_LIB.T6G(SCH_1):PAGE418
     2 P5E_CPU0_P2_TX_BUF_DN<12> @T6G_MB_LIB.T6G(SCH_1):P5E_CPU0_P2_TX_BUF_DN(12)    I94 @T6G_MB_LIB.T6G(SCH_1):PAGE418

C6591 Q_CAP_DIFFBUS_C0201-DIFF BUS_0.22UF,6.3V,20%,X6S,SA
     1 P5E_CPU0_P2_TX_BUF_C_DP<13> @T6G_MB_LIB.T6G(SCH_1):P5E_CPU0_P2_TX_BUF_C_DP(13)    I93 @T6G_MB_LIB.T6G(SCH_1):PAGE418
     2 P5E_CPU0_P2_TX_BUF_DP<13> @T6G_MB_LIB.T6G(SCH_1):P5E_CPU0_P2_TX_BUF_DP(13)    I93 @T6G_MB_LIB.T6G(SCH_1):PAGE418

C6592 Q_CAP_DIFFBUS_C0201-DIFF BUS_0.22UF,6.3V,20%,X6S,SA
     1 P5E_CPU0_P2_TX_BUF_C_DN<13> @T6G_MB_LIB.T6G(SCH_1):P5E_CPU0_P2_TX_BUF_C_DN(13)    I92 @T6G_MB_LIB.T6G(SCH_1):PAGE418
     2 P5E_CPU0_P2_TX_BUF_DN<13> @T6G_MB_LIB.T6G(SCH_1):P5E_CPU0_P2_TX_BUF_DN(13)    I92 @T6G_MB_LIB.T6G(SCH_1):PAGE418

C6593 Q_CAP_DIFFBUS_C0201-DIFF BUS_0.22UF,6.3V,20%,X6S,SA
     1 P5E_CPU0_P2_TX_BUF_C_DP<14> @T6G_MB_LIB.T6G(SCH_1):P5E_CPU0_P2_TX_BUF_C_DP(14)    I91 @T6G_MB_LIB.T6G(SCH_1):PAGE418
     2 P5E_CPU0_P2_TX_BUF_DP<14> @T6G_MB_LIB.T6G(SCH_1):P5E_CPU0_P2_TX_BUF_DP(14)    I91 @T6G_MB_LIB.T6G(SCH_1):PAGE418

C6594 Q_CAP_DIFFBUS_C0201-DIFF BUS_0.22UF,6.3V,20%,X6S,SA
     1 P5E_CPU0_P2_TX_BUF_C_DN<14> @T6G_MB_LIB.T6G(SCH_1):P5E_CPU0_P2_TX_BUF_C_DN(14)    I90 @T6G_MB_LIB.T6G(SCH_1):PAGE418
     2 P5E_CPU0_P2_TX_BUF_DN<14> @T6G_MB_LIB.T6G(SCH_1):P5E_CPU0_P2_TX_BUF_DN(14)    I90 @T6G_MB_LIB.T6G(SCH_1):PAGE418

C6595 Q_CAP_DIFFBUS_C0201-DIFF BUS_0.22UF,6.3V,20%,X6S,SA
     1 P5E_CPU0_P2_TX_BUF_C_DP<15> @T6G_MB_LIB.T6G(SCH_1):P5E_CPU0_P2_TX_BUF_C_DP(15)    I89 @T6G_MB_LIB.T6G(SCH_1):PAGE418
     2 P5E_CPU0_P2_TX_BUF_DP<15> @T6G_MB_LIB.T6G(SCH_1):P5E_CPU0_P2_TX_BUF_DP(15)    I89 @T6G_MB_LIB.T6G(SCH_1):PAGE418

C6596 Q_CAP_DIFFBUS_C0201-DIFF BUS_0.22UF,6.3V,20%,X6S,SA
     1 P5E_CPU0_P2_TX_BUF_C_DN<15> @T6G_MB_LIB.T6G(SCH_1):P5E_CPU0_P2_TX_BUF_C_DN(15)    I88 @T6G_MB_LIB.T6G(SCH_1):PAGE418
     2 P5E_CPU0_P2_TX_BUF_DN<15> @T6G_MB_LIB.T6G(SCH_1):P5E_CPU0_P2_TX_BUF_DN(15)    I88 @T6G_MB_LIB.T6G(SCH_1):PAGE418

C6597 Q_CAP_DIFFBUS_C0201-DIFF BUS_0.22UF,6.3V,20%,X6S,SA
     1 P5E_CPU0_P3_TX_BUF_C_DP<0> @T6G_MB_LIB.T6G(SCH_1):P5E_CPU0_P3_TX_BUF_C_DP(0)    I40 @T6G_MB_LIB.T6G(SCH_1):PAGE429
     2 P5E_CPU0_P3_TX_BUF_DP<0> @T6G_MB_LIB.T6G(SCH_1):P5E_CPU0_P3_TX_BUF_DP(0)    I40 @T6G_MB_LIB.T6G(SCH_1):PAGE429

C6598 Q_CAP_DIFFBUS_C0201-DIFF BUS_0.22UF,6.3V,20%,X6S,SA
     1 P5E_CPU0_P3_TX_BUF_C_DN<0> @T6G_MB_LIB.T6G(SCH_1):P5E_CPU0_P3_TX_BUF_C_DN(0)    I39 @T6G_MB_LIB.T6G(SCH_1):PAGE429
     2 P5E_CPU0_P3_TX_BUF_DN<0> @T6G_MB_LIB.T6G(SCH_1):P5E_CPU0_P3_TX_BUF_DN(0)    I39 @T6G_MB_LIB.T6G(SCH_1):PAGE429

C6599 Q_CAP_DIFFBUS_C0201-DIFF BUS_0.22UF,6.3V,20%,X6S,SA
     1 P5E_CPU0_P3_TX_BUF_C_DP<1> @T6G_MB_LIB.T6G(SCH_1):P5E_CPU0_P3_TX_BUF_C_DP(1)    I38 @T6G_MB_LIB.T6G(SCH_1):PAGE429
     2 P5E_CPU0_P3_TX_BUF_DP<1> @T6G_MB_LIB.T6G(SCH_1):P5E_CPU0_P3_TX_BUF_DP(1)    I38 @T6G_MB_LIB.T6G(SCH_1):PAGE429

C6600 Q_CAP_DIFFBUS_C0201-DIFF BUS_0.22UF,6.3V,20%,X6S,SA
     1 P5E_CPU0_P3_TX_BUF_C_DN<1> @T6G_MB_LIB.T6G(SCH_1):P5E_CPU0_P3_TX_BUF_C_DN(1)    I37 @T6G_MB_LIB.T6G(SCH_1):PAGE429
     2 P5E_CPU0_P3_TX_BUF_DN<1> @T6G_MB_LIB.T6G(SCH_1):P5E_CPU0_P3_TX_BUF_DN(1)    I37 @T6G_MB_LIB.T6G(SCH_1):PAGE429

C6601 Q_CAP_DIFFBUS_C0201-DIFF BUS_0.22UF,6.3V,20%,X6S,SA
     1 P5E_CPU0_P3_TX_BUF_C_DP<2> @T6G_MB_LIB.T6G(SCH_1):P5E_CPU0_P3_TX_BUF_C_DP(2)    I36 @T6G_MB_LIB.T6G(SCH_1):PAGE429
     2 P5E_CPU0_P3_TX_BUF_DP<2> @T6G_MB_LIB.T6G(SCH_1):P5E_CPU0_P3_TX_BUF_DP(2)    I36 @T6G_MB_LIB.T6G(SCH_1):PAGE429

C6602 Q_CAP_DIFFBUS_C0201-DIFF BUS_0.22UF,6.3V,20%,X6S,SA
     1 P5E_CPU0_P3_TX_BUF_C_DN<2> @T6G_MB_LIB.T6G(SCH_1):P5E_CPU0_P3_TX_BUF_C_DN(2)    I35 @T6G_MB_LIB.T6G(SCH_1):PAGE429
     2 P5E_CPU0_P3_TX_BUF_DN<2> @T6G_MB_LIB.T6G(SCH_1):P5E_CPU0_P3_TX_BUF_DN(2)    I35 @T6G_MB_LIB.T6G(SCH_1):PAGE429

C6603 Q_CAP_DIFFBUS_C0201-DIFF BUS_0.22UF,6.3V,20%,X6S,SA
     1 P5E_CPU0_P3_TX_BUF_C_DP<3> @T6G_MB_LIB.T6G(SCH_1):P5E_CPU0_P3_TX_BUF_C_DP(3)    I34 @T6G_MB_LIB.T6G(SCH_1):PAGE429
     2 P5E_CPU0_P3_TX_BUF_DP<3> @T6G_MB_LIB.T6G(SCH_1):P5E_CPU0_P3_TX_BUF_DP(3)    I34 @T6G_MB_LIB.T6G(SCH_1):PAGE429

C6604 Q_CAP_DIFFBUS_C0201-DIFF BUS_0.22UF,6.3V,20%,X6S,SA
     1 P5E_CPU0_P3_TX_BUF_C_DN<3> @T6G_MB_LIB.T6G(SCH_1):P5E_CPU0_P3_TX_BUF_C_DN(3)    I33 @T6G_MB_LIB.T6G(SCH_1):PAGE429
     2 P5E_CPU0_P3_TX_BUF_DN<3> @T6G_MB_LIB.T6G(SCH_1):P5E_CPU0_P3_TX_BUF_DN(3)    I33 @T6G_MB_LIB.T6G(SCH_1):PAGE429

C6605 Q_CAP_DIFFBUS_C0201-DIFF BUS_0.22UF,6.3V,20%,X6S,SA
     1 P5E_CPU0_P3_TX_BUF_C_DP<4> @T6G_MB_LIB.T6G(SCH_1):P5E_CPU0_P3_TX_BUF_C_DP(4)    I32 @T6G_MB_LIB.T6G(SCH_1):PAGE429
     2 P5E_CPU0_P3_TX_BUF_DP<4> @T6G_MB_LIB.T6G(SCH_1):P5E_CPU0_P3_TX_BUF_DP(4)    I32 @T6G_MB_LIB.T6G(SCH_1):PAGE429

C6606 Q_CAP_DIFFBUS_C0201-DIFF BUS_0.22UF,6.3V,20%,X6S,SA
     1 P5E_CPU0_P3_TX_BUF_C_DN<4> @T6G_MB_LIB.T6G(SCH_1):P5E_CPU0_P3_TX_BUF_C_DN(4)    I31 @T6G_MB_LIB.T6G(SCH_1):PAGE429
     2 P5E_CPU0_P3_TX_BUF_DN<4> @T6G_MB_LIB.T6G(SCH_1):P5E_CPU0_P3_TX_BUF_DN(4)    I31 @T6G_MB_LIB.T6G(SCH_1):PAGE429

C6607 Q_CAP_DIFFBUS_C0201-DIFF BUS_0.22UF,6.3V,20%,X6S,SA
     1 P5E_CPU0_P3_TX_BUF_C_DP<5> @T6G_MB_LIB.T6G(SCH_1):P5E_CPU0_P3_TX_BUF_C_DP(5)    I24 @T6G_MB_LIB.T6G(SCH_1):PAGE429
     2 P5E_CPU0_P3_TX_BUF_DP<5> @T6G_MB_LIB.T6G(SCH_1):P5E_CPU0_P3_TX_BUF_DP(5)    I24 @T6G_MB_LIB.T6G(SCH_1):PAGE429

C6608 Q_CAP_DIFFBUS_C0201-DIFF BUS_0.22UF,6.3V,20%,X6S,SA
     1 P5E_CPU0_P3_TX_BUF_C_DN<5> @T6G_MB_LIB.T6G(SCH_1):P5E_CPU0_P3_TX_BUF_C_DN(5)    I23 @T6G_MB_LIB.T6G(SCH_1):PAGE429
     2 P5E_CPU0_P3_TX_BUF_DN<5> @T6G_MB_LIB.T6G(SCH_1):P5E_CPU0_P3_TX_BUF_DN(5)    I23 @T6G_MB_LIB.T6G(SCH_1):PAGE429

C6609 Q_CAP_DIFFBUS_C0201-DIFF BUS_0.22UF,6.3V,20%,X6S,SA
     1 P5E_CPU0_P3_TX_BUF_C_DP<6> @T6G_MB_LIB.T6G(SCH_1):P5E_CPU0_P3_TX_BUF_C_DP(6)    I22 @T6G_MB_LIB.T6G(SCH_1):PAGE429
     2 P5E_CPU0_P3_TX_BUF_DP<6> @T6G_MB_LIB.T6G(SCH_1):P5E_CPU0_P3_TX_BUF_DP(6)    I22 @T6G_MB_LIB.T6G(SCH_1):PAGE429

C6610 Q_CAP_DIFFBUS_C0201-DIFF BUS_0.22UF,6.3V,20%,X6S,SA
     1 P5E_CPU0_P3_TX_BUF_C_DN<6> @T6G_MB_LIB.T6G(SCH_1):P5E_CPU0_P3_TX_BUF_C_DN(6)    I21 @T6G_MB_LIB.T6G(SCH_1):PAGE429
     2 P5E_CPU0_P3_TX_BUF_DN<6> @T6G_MB_LIB.T6G(SCH_1):P5E_CPU0_P3_TX_BUF_DN(6)    I21 @T6G_MB_LIB.T6G(SCH_1):PAGE429

C6611 Q_CAP_DIFFBUS_C0201-DIFF BUS_0.22UF,6.3V,20%,X6S,SA
     1 P5E_CPU0_P3_TX_BUF_C_DP<7> @T6G_MB_LIB.T6G(SCH_1):P5E_CPU0_P3_TX_BUF_C_DP(7)    I19 @T6G_MB_LIB.T6G(SCH_1):PAGE429
     2 P5E_CPU0_P3_TX_BUF_DP<7> @T6G_MB_LIB.T6G(SCH_1):P5E_CPU0_P3_TX_BUF_DP(7)    I19 @T6G_MB_LIB.T6G(SCH_1):PAGE429

C6612 Q_CAP_DIFFBUS_C0201-DIFF BUS_0.22UF,6.3V,20%,X6S,SA
     1 P5E_CPU0_P3_TX_BUF_C_DN<7> @T6G_MB_LIB.T6G(SCH_1):P5E_CPU0_P3_TX_BUF_C_DN(7)    I20 @T6G_MB_LIB.T6G(SCH_1):PAGE429
     2 P5E_CPU0_P3_TX_BUF_DN<7> @T6G_MB_LIB.T6G(SCH_1):P5E_CPU0_P3_TX_BUF_DN(7)    I20 @T6G_MB_LIB.T6G(SCH_1):PAGE429

C6613 Q_CAP_DIFFBUS_C0201-DIFF BUS_0.22UF,6.3V,20%,X6S,SA
     1 P5E_CPU0_P3_TX_BUF_C_DP<8> @T6G_MB_LIB.T6G(SCH_1):P5E_CPU0_P3_TX_BUF_C_DP(8)   I105 @T6G_MB_LIB.T6G(SCH_1):PAGE429
     2 P5E_CPU0_P3_TX_BUF_DP<8> @T6G_MB_LIB.T6G(SCH_1):P5E_CPU0_P3_TX_BUF_DP(8)   I105 @T6G_MB_LIB.T6G(SCH_1):PAGE429

C6614 Q_CAP_DIFFBUS_C0201-DIFF BUS_0.22UF,6.3V,20%,X6S,SA
     1 P5E_CPU0_P3_TX_BUF_C_DN<8> @T6G_MB_LIB.T6G(SCH_1):P5E_CPU0_P3_TX_BUF_C_DN(8)   I104 @T6G_MB_LIB.T6G(SCH_1):PAGE429
     2 P5E_CPU0_P3_TX_BUF_DN<8> @T6G_MB_LIB.T6G(SCH_1):P5E_CPU0_P3_TX_BUF_DN(8)   I104 @T6G_MB_LIB.T6G(SCH_1):PAGE429

C6615 Q_CAP_DIFFBUS_C0201-DIFF BUS_0.22UF,6.3V,20%,X6S,SA
     1 P5E_CPU0_P3_TX_BUF_C_DP<9> @T6G_MB_LIB.T6G(SCH_1):P5E_CPU0_P3_TX_BUF_C_DP(9)   I102 @T6G_MB_LIB.T6G(SCH_1):PAGE429
     2 P5E_CPU0_P3_TX_BUF_DP<9> @T6G_MB_LIB.T6G(SCH_1):P5E_CPU0_P3_TX_BUF_DP(9)   I102 @T6G_MB_LIB.T6G(SCH_1):PAGE429

C6616 Q_CAP_DIFFBUS_C0201-DIFF BUS_0.22UF,6.3V,20%,X6S,SA
     1 P5E_CPU0_P3_TX_BUF_C_DN<9> @T6G_MB_LIB.T6G(SCH_1):P5E_CPU0_P3_TX_BUF_C_DN(9)   I103 @T6G_MB_LIB.T6G(SCH_1):PAGE429
     2 P5E_CPU0_P3_TX_BUF_DN<9> @T6G_MB_LIB.T6G(SCH_1):P5E_CPU0_P3_TX_BUF_DN(9)   I103 @T6G_MB_LIB.T6G(SCH_1):PAGE429

C6617 Q_CAP_DIFFBUS_C0201-DIFF BUS_0.22UF,6.3V,20%,X6S,SA
     1 P5E_CPU0_P3_TX_BUF_C_DP<10> @T6G_MB_LIB.T6G(SCH_1):P5E_CPU0_P3_TX_BUF_C_DP(10)   I101 @T6G_MB_LIB.T6G(SCH_1):PAGE429
     2 P5E_CPU0_P3_TX_BUF_DP<10> @T6G_MB_LIB.T6G(SCH_1):P5E_CPU0_P3_TX_BUF_DP(10)   I101 @T6G_MB_LIB.T6G(SCH_1):PAGE429

C6618 Q_CAP_DIFFBUS_C0201-DIFF BUS_0.22UF,6.3V,20%,X6S,SA
     1 P5E_CPU0_P3_TX_BUF_C_DN<10> @T6G_MB_LIB.T6G(SCH_1):P5E_CPU0_P3_TX_BUF_C_DN(10)    I99 @T6G_MB_LIB.T6G(SCH_1):PAGE429
     2 P5E_CPU0_P3_TX_BUF_DN<10> @T6G_MB_LIB.T6G(SCH_1):P5E_CPU0_P3_TX_BUF_DN(10)    I99 @T6G_MB_LIB.T6G(SCH_1):PAGE429

C6619 Q_CAP_DIFFBUS_C0201-DIFF BUS_0.22UF,6.3V,20%,X6S,SA
     1 P5E_CPU0_P3_TX_BUF_C_DP<11> @T6G_MB_LIB.T6G(SCH_1):P5E_CPU0_P3_TX_BUF_C_DP(11)   I100 @T6G_MB_LIB.T6G(SCH_1):PAGE429
     2 P5E_CPU0_P3_TX_BUF_DP<11> @T6G_MB_LIB.T6G(SCH_1):P5E_CPU0_P3_TX_BUF_DP(11)   I100 @T6G_MB_LIB.T6G(SCH_1):PAGE429

C6620 Q_CAP_DIFFBUS_C0201-DIFF BUS_0.22UF,6.3V,20%,X6S,SA
     1 P5E_CPU0_P3_TX_BUF_C_DN<11> @T6G_MB_LIB.T6G(SCH_1):P5E_CPU0_P3_TX_BUF_C_DN(11)    I98 @T6G_MB_LIB.T6G(SCH_1):PAGE429
     2 P5E_CPU0_P3_TX_BUF_DN<11> @T6G_MB_LIB.T6G(SCH_1):P5E_CPU0_P3_TX_BUF_DN(11)    I98 @T6G_MB_LIB.T6G(SCH_1):PAGE429

C6621 Q_CAP_DIFFBUS_C0201-DIFF BUS_0.22UF,6.3V,20%,X6S,SA
     1 P5E_CPU0_P3_TX_BUF_C_DP<12> @T6G_MB_LIB.T6G(SCH_1):P5E_CPU0_P3_TX_BUF_C_DP(12)    I96 @T6G_MB_LIB.T6G(SCH_1):PAGE429
     2 P5E_CPU0_P3_TX_BUF_DP<12> @T6G_MB_LIB.T6G(SCH_1):P5E_CPU0_P3_TX_BUF_DP(12)    I96 @T6G_MB_LIB.T6G(SCH_1):PAGE429

C6622 Q_CAP_DIFFBUS_C0201-DIFF BUS_0.22UF,6.3V,20%,X6S,SA
     1 P5E_CPU0_P3_TX_BUF_C_DN<12> @T6G_MB_LIB.T6G(SCH_1):P5E_CPU0_P3_TX_BUF_C_DN(12)    I97 @T6G_MB_LIB.T6G(SCH_1):PAGE429
     2 P5E_CPU0_P3_TX_BUF_DN<12> @T6G_MB_LIB.T6G(SCH_1):P5E_CPU0_P3_TX_BUF_DN(12)    I97 @T6G_MB_LIB.T6G(SCH_1):PAGE429

C6623 Q_CAP_DIFFBUS_C0201-DIFF BUS_0.22UF,6.3V,20%,X6S,SA
     1 P5E_CPU0_P3_TX_BUF_C_DP<13> @T6G_MB_LIB.T6G(SCH_1):P5E_CPU0_P3_TX_BUF_C_DP(13)    I94 @T6G_MB_LIB.T6G(SCH_1):PAGE429
     2 P5E_CPU0_P3_TX_BUF_DP<13> @T6G_MB_LIB.T6G(SCH_1):P5E_CPU0_P3_TX_BUF_DP(13)    I94 @T6G_MB_LIB.T6G(SCH_1):PAGE429

C6624 Q_CAP_DIFFBUS_C0201-DIFF BUS_0.22UF,6.3V,20%,X6S,SA
     1 P5E_CPU0_P3_TX_BUF_C_DN<13> @T6G_MB_LIB.T6G(SCH_1):P5E_CPU0_P3_TX_BUF_C_DN(13)    I95 @T6G_MB_LIB.T6G(SCH_1):PAGE429
     2 P5E_CPU0_P3_TX_BUF_DN<13> @T6G_MB_LIB.T6G(SCH_1):P5E_CPU0_P3_TX_BUF_DN(13)    I95 @T6G_MB_LIB.T6G(SCH_1):PAGE429

C6625 Q_CAP_DIFFBUS_C0201-DIFF BUS_0.22UF,6.3V,20%,X6S,SA
     1 P5E_CPU0_P3_TX_BUF_C_DP<14> @T6G_MB_LIB.T6G(SCH_1):P5E_CPU0_P3_TX_BUF_C_DP(14)    I91 @T6G_MB_LIB.T6G(SCH_1):PAGE429
     2 P5E_CPU0_P3_TX_BUF_DP<14> @T6G_MB_LIB.T6G(SCH_1):P5E_CPU0_P3_TX_BUF_DP(14)    I91 @T6G_MB_LIB.T6G(SCH_1):PAGE429

C6626 Q_CAP_DIFFBUS_C0201-DIFF BUS_0.22UF,6.3V,20%,X6S,SA
     1 P5E_CPU0_P3_TX_BUF_C_DN<14> @T6G_MB_LIB.T6G(SCH_1):P5E_CPU0_P3_TX_BUF_C_DN(14)    I92 @T6G_MB_LIB.T6G(SCH_1):PAGE429
     2 P5E_CPU0_P3_TX_BUF_DN<14> @T6G_MB_LIB.T6G(SCH_1):P5E_CPU0_P3_TX_BUF_DN(14)    I92 @T6G_MB_LIB.T6G(SCH_1):PAGE429

C6627 Q_CAP_DIFFBUS_C0201-DIFF BUS_0.22UF,6.3V,20%,X6S,SA
     1 P5E_CPU0_P3_TX_BUF_C_DP<15> @T6G_MB_LIB.T6G(SCH_1):P5E_CPU0_P3_TX_BUF_C_DP(15)    I93 @T6G_MB_LIB.T6G(SCH_1):PAGE429
     2 P5E_CPU0_P3_TX_BUF_DP<15> @T6G_MB_LIB.T6G(SCH_1):P5E_CPU0_P3_TX_BUF_DP(15)    I93 @T6G_MB_LIB.T6G(SCH_1):PAGE429

C6628 Q_CAP_DIFFBUS_C0201-DIFF BUS_0.22UF,6.3V,20%,X6S,SA
     1 P5E_CPU0_P3_TX_BUF_C_DN<15> @T6G_MB_LIB.T6G(SCH_1):P5E_CPU0_P3_TX_BUF_C_DN(15)    I90 @T6G_MB_LIB.T6G(SCH_1):PAGE429
     2 P5E_CPU0_P3_TX_BUF_DN<15> @T6G_MB_LIB.T6G(SCH_1):P5E_CPU0_P3_TX_BUF_DN(15)    I90 @T6G_MB_LIB.T6G(SCH_1):PAGE429

C6629 Q_CAP_DIFFBUS_C0201-DIFF BUS_0.22UF,6.3V,20%,X6S,SA
     1 P5E_CPU1_P0_TX_BUF_C_DP<0> @T6G_MB_LIB.T6G(SCH_1):P5E_CPU1_P0_TX_BUF_C_DP(0)    I46 @T6G_MB_LIB.T6G(SCH_1):PAGE439
     2 P5E_CPU1_P0_TX_BUF_DP<0> @T6G_MB_LIB.T6G(SCH_1):P5E_CPU1_P0_TX_BUF_DP(0)    I46 @T6G_MB_LIB.T6G(SCH_1):PAGE439

C6630 Q_CAP_DIFFBUS_C0201-DIFF BUS_0.22UF,6.3V,20%,X6S,SA
     1 P5E_CPU1_P0_TX_BUF_C_DN<0> @T6G_MB_LIB.T6G(SCH_1):P5E_CPU1_P0_TX_BUF_C_DN(0)    I47 @T6G_MB_LIB.T6G(SCH_1):PAGE439
     2 P5E_CPU1_P0_TX_BUF_DN<0> @T6G_MB_LIB.T6G(SCH_1):P5E_CPU1_P0_TX_BUF_DN(0)    I47 @T6G_MB_LIB.T6G(SCH_1):PAGE439

C6631 Q_CAP_DIFFBUS_C0201-DIFF BUS_0.22UF,6.3V,20%,X6S,SA
     1 P5E_CPU1_P0_TX_BUF_C_DP<1> @T6G_MB_LIB.T6G(SCH_1):P5E_CPU1_P0_TX_BUF_C_DP(1)    I45 @T6G_MB_LIB.T6G(SCH_1):PAGE439
     2 P5E_CPU1_P0_TX_BUF_DP<1> @T6G_MB_LIB.T6G(SCH_1):P5E_CPU1_P0_TX_BUF_DP(1)    I45 @T6G_MB_LIB.T6G(SCH_1):PAGE439

C6632 Q_CAP_DIFFBUS_C0201-DIFF BUS_0.22UF,6.3V,20%,X6S,SA
     1 P5E_CPU1_P0_TX_BUF_C_DN<1> @T6G_MB_LIB.T6G(SCH_1):P5E_CPU1_P0_TX_BUF_C_DN(1)    I44 @T6G_MB_LIB.T6G(SCH_1):PAGE439
     2 P5E_CPU1_P0_TX_BUF_DN<1> @T6G_MB_LIB.T6G(SCH_1):P5E_CPU1_P0_TX_BUF_DN(1)    I44 @T6G_MB_LIB.T6G(SCH_1):PAGE439

C6633 Q_CAP_DIFFBUS_C0201-DIFF BUS_0.22UF,6.3V,20%,X6S,SA
     1 P5E_CPU1_P0_TX_BUF_C_DP<2> @T6G_MB_LIB.T6G(SCH_1):P5E_CPU1_P0_TX_BUF_C_DP(2)    I27 @T6G_MB_LIB.T6G(SCH_1):PAGE439
     2 P5E_CPU1_P0_TX_BUF_DP<2> @T6G_MB_LIB.T6G(SCH_1):P5E_CPU1_P0_TX_BUF_DP(2)    I27 @T6G_MB_LIB.T6G(SCH_1):PAGE439

C6634 Q_CAP_DIFFBUS_C0201-DIFF BUS_0.22UF,6.3V,20%,X6S,SA
     1 P5E_CPU1_P0_TX_BUF_C_DN<2> @T6G_MB_LIB.T6G(SCH_1):P5E_CPU1_P0_TX_BUF_C_DN(2)    I26 @T6G_MB_LIB.T6G(SCH_1):PAGE439
     2 P5E_CPU1_P0_TX_BUF_DN<2> @T6G_MB_LIB.T6G(SCH_1):P5E_CPU1_P0_TX_BUF_DN(2)    I26 @T6G_MB_LIB.T6G(SCH_1):PAGE439

C6635 Q_CAP_DIFFBUS_C0201-DIFF BUS_0.22UF,6.3V,20%,X6S,SA
     1 P5E_CPU1_P0_TX_BUF_C_DP<3> @T6G_MB_LIB.T6G(SCH_1):P5E_CPU1_P0_TX_BUF_C_DP(3)    I25 @T6G_MB_LIB.T6G(SCH_1):PAGE439
     2 P5E_CPU1_P0_TX_BUF_DP<3> @T6G_MB_LIB.T6G(SCH_1):P5E_CPU1_P0_TX_BUF_DP(3)    I25 @T6G_MB_LIB.T6G(SCH_1):PAGE439

C6636 Q_CAP_DIFFBUS_C0201-DIFF BUS_0.22UF,6.3V,20%,X6S,SA
     1 P5E_CPU1_P0_TX_BUF_C_DN<3> @T6G_MB_LIB.T6G(SCH_1):P5E_CPU1_P0_TX_BUF_C_DN(3)    I24 @T6G_MB_LIB.T6G(SCH_1):PAGE439
     2 P5E_CPU1_P0_TX_BUF_DN<3> @T6G_MB_LIB.T6G(SCH_1):P5E_CPU1_P0_TX_BUF_DN(3)    I24 @T6G_MB_LIB.T6G(SCH_1):PAGE439

C6637 Q_CAP_DIFFBUS_C0201-DIFF BUS_0.22UF,6.3V,20%,X6S,SA
     1 P5E_CPU1_P0_TX_BUF_C_DP<4> @T6G_MB_LIB.T6G(SCH_1):P5E_CPU1_P0_TX_BUF_C_DP(4)    I22 @T6G_MB_LIB.T6G(SCH_1):PAGE439
     2 P5E_CPU1_P0_TX_BUF_DP<4> @T6G_MB_LIB.T6G(SCH_1):P5E_CPU1_P0_TX_BUF_DP(4)    I22 @T6G_MB_LIB.T6G(SCH_1):PAGE439

C6638 Q_CAP_DIFFBUS_C0201-DIFF BUS_0.22UF,6.3V,20%,X6S,SA
     1 P5E_CPU1_P0_TX_BUF_C_DN<4> @T6G_MB_LIB.T6G(SCH_1):P5E_CPU1_P0_TX_BUF_C_DN(4)    I23 @T6G_MB_LIB.T6G(SCH_1):PAGE439
     2 P5E_CPU1_P0_TX_BUF_DN<4> @T6G_MB_LIB.T6G(SCH_1):P5E_CPU1_P0_TX_BUF_DN(4)    I23 @T6G_MB_LIB.T6G(SCH_1):PAGE439

C6639 Q_CAP_DIFFBUS_C0201-DIFF BUS_0.22UF,6.3V,20%,X6S,SA
     1 P5E_CPU1_P0_TX_BUF_C_DP<5> @T6G_MB_LIB.T6G(SCH_1):P5E_CPU1_P0_TX_BUF_C_DP(5)    I20 @T6G_MB_LIB.T6G(SCH_1):PAGE439
     2 P5E_CPU1_P0_TX_BUF_DP<5> @T6G_MB_LIB.T6G(SCH_1):P5E_CPU1_P0_TX_BUF_DP(5)    I20 @T6G_MB_LIB.T6G(SCH_1):PAGE439

C6640 Q_CAP_DIFFBUS_C0201-DIFF BUS_0.22UF,6.3V,20%,X6S,SA
     1 P5E_CPU1_P0_TX_BUF_C_DN<5> @T6G_MB_LIB.T6G(SCH_1):P5E_CPU1_P0_TX_BUF_C_DN(5)    I21 @T6G_MB_LIB.T6G(SCH_1):PAGE439
     2 P5E_CPU1_P0_TX_BUF_DN<5> @T6G_MB_LIB.T6G(SCH_1):P5E_CPU1_P0_TX_BUF_DN(5)    I21 @T6G_MB_LIB.T6G(SCH_1):PAGE439

C6641 Q_CAP_DIFFBUS_C0201-DIFF BUS_0.22UF,6.3V,20%,X6S,SA
     1 P5E_CPU1_P0_TX_BUF_C_DP<6> @T6G_MB_LIB.T6G(SCH_1):P5E_CPU1_P0_TX_BUF_C_DP(6)    I18 @T6G_MB_LIB.T6G(SCH_1):PAGE439
     2 P5E_CPU1_P0_TX_BUF_DP<6> @T6G_MB_LIB.T6G(SCH_1):P5E_CPU1_P0_TX_BUF_DP(6)    I18 @T6G_MB_LIB.T6G(SCH_1):PAGE439

C6642 Q_CAP_DIFFBUS_C0201-DIFF BUS_0.22UF,6.3V,20%,X6S,SA
     1 P5E_CPU1_P0_TX_BUF_C_DN<6> @T6G_MB_LIB.T6G(SCH_1):P5E_CPU1_P0_TX_BUF_C_DN(6)    I19 @T6G_MB_LIB.T6G(SCH_1):PAGE439
     2 P5E_CPU1_P0_TX_BUF_DN<6> @T6G_MB_LIB.T6G(SCH_1):P5E_CPU1_P0_TX_BUF_DN(6)    I19 @T6G_MB_LIB.T6G(SCH_1):PAGE439

C6643 Q_CAP_DIFFBUS_C0201-DIFF BUS_0.22UF,6.3V,20%,X6S,SA
     1 P5E_CPU1_P0_TX_BUF_C_DP<7> @T6G_MB_LIB.T6G(SCH_1):P5E_CPU1_P0_TX_BUF_C_DP(7)    I16 @T6G_MB_LIB.T6G(SCH_1):PAGE439
     2 P5E_CPU1_P0_TX_BUF_DP<7> @T6G_MB_LIB.T6G(SCH_1):P5E_CPU1_P0_TX_BUF_DP(7)    I16 @T6G_MB_LIB.T6G(SCH_1):PAGE439

C6644 Q_CAP_DIFFBUS_C0201-DIFF BUS_0.22UF,6.3V,20%,X6S,SA
     1 P5E_CPU1_P0_TX_BUF_C_DN<7> @T6G_MB_LIB.T6G(SCH_1):P5E_CPU1_P0_TX_BUF_C_DN(7)    I15 @T6G_MB_LIB.T6G(SCH_1):PAGE439
     2 P5E_CPU1_P0_TX_BUF_DN<7> @T6G_MB_LIB.T6G(SCH_1):P5E_CPU1_P0_TX_BUF_DN(7)    I15 @T6G_MB_LIB.T6G(SCH_1):PAGE439

C6645 Q_CAP_DIFFBUS_C0201-DIFF BUS_0.22UF,6.3V,20%,X6S,SA
     1 P5E_CPU1_P0_TX_BUF_C_DP<8> @T6G_MB_LIB.T6G(SCH_1):P5E_CPU1_P0_TX_BUF_C_DP(8)   I105 @T6G_MB_LIB.T6G(SCH_1):PAGE439
     2 P5E_CPU1_P0_TX_BUF_DP<8> @T6G_MB_LIB.T6G(SCH_1):P5E_CPU1_P0_TX_BUF_DP(8)   I105 @T6G_MB_LIB.T6G(SCH_1):PAGE439

C6646 Q_CAP_DIFFBUS_C0201-DIFF BUS_0.22UF,6.3V,20%,X6S,SA
     1 P5E_CPU1_P0_TX_BUF_C_DN<8> @T6G_MB_LIB.T6G(SCH_1):P5E_CPU1_P0_TX_BUF_C_DN(8)   I104 @T6G_MB_LIB.T6G(SCH_1):PAGE439
     2 P5E_CPU1_P0_TX_BUF_DN<8> @T6G_MB_LIB.T6G(SCH_1):P5E_CPU1_P0_TX_BUF_DN(8)   I104 @T6G_MB_LIB.T6G(SCH_1):PAGE439

C6647 Q_CAP_DIFFBUS_C0201-DIFF BUS_0.22UF,6.3V,20%,X6S,SA
     1 P5E_CPU1_P0_TX_BUF_C_DP<9> @T6G_MB_LIB.T6G(SCH_1):P5E_CPU1_P0_TX_BUF_C_DP(9)   I102 @T6G_MB_LIB.T6G(SCH_1):PAGE439
     2 P5E_CPU1_P0_TX_BUF_DP<9> @T6G_MB_LIB.T6G(SCH_1):P5E_CPU1_P0_TX_BUF_DP(9)   I102 @T6G_MB_LIB.T6G(SCH_1):PAGE439

C6648 Q_CAP_DIFFBUS_C0201-DIFF BUS_0.22UF,6.3V,20%,X6S,SA
     1 P5E_CPU1_P0_TX_BUF_C_DN<9> @T6G_MB_LIB.T6G(SCH_1):P5E_CPU1_P0_TX_BUF_C_DN(9)   I103 @T6G_MB_LIB.T6G(SCH_1):PAGE439
     2 P5E_CPU1_P0_TX_BUF_DN<9> @T6G_MB_LIB.T6G(SCH_1):P5E_CPU1_P0_TX_BUF_DN(9)   I103 @T6G_MB_LIB.T6G(SCH_1):PAGE439

C6649 Q_CAP_DIFFBUS_C0201-DIFF BUS_0.22UF,6.3V,20%,X6S,SA
     1 P5E_CPU1_P0_TX_BUF_C_DP<10> @T6G_MB_LIB.T6G(SCH_1):P5E_CPU1_P0_TX_BUF_C_DP(10)    I96 @T6G_MB_LIB.T6G(SCH_1):PAGE439
     2 P5E_CPU1_P0_TX_BUF_DP<10> @T6G_MB_LIB.T6G(SCH_1):P5E_CPU1_P0_TX_BUF_DP(10)    I96 @T6G_MB_LIB.T6G(SCH_1):PAGE439

C6650 Q_CAP_DIFFBUS_C0201-DIFF BUS_0.22UF,6.3V,20%,X6S,SA
     1 P5E_CPU1_P0_TX_BUF_C_DN<10> @T6G_MB_LIB.T6G(SCH_1):P5E_CPU1_P0_TX_BUF_C_DN(10)    I97 @T6G_MB_LIB.T6G(SCH_1):PAGE439
     2 P5E_CPU1_P0_TX_BUF_DN<10> @T6G_MB_LIB.T6G(SCH_1):P5E_CPU1_P0_TX_BUF_DN(10)    I97 @T6G_MB_LIB.T6G(SCH_1):PAGE439

C6651 Q_CAP_DIFFBUS_C0201-DIFF BUS_0.22UF,6.3V,20%,X6S,SA
     1 P5E_CPU1_P0_TX_BUF_C_DP<11> @T6G_MB_LIB.T6G(SCH_1):P5E_CPU1_P0_TX_BUF_C_DP(11)    I95 @T6G_MB_LIB.T6G(SCH_1):PAGE439
     2 P5E_CPU1_P0_TX_BUF_DP<11> @T6G_MB_LIB.T6G(SCH_1):P5E_CPU1_P0_TX_BUF_DP(11)    I95 @T6G_MB_LIB.T6G(SCH_1):PAGE439

C6652 Q_CAP_DIFFBUS_C0201-DIFF BUS_0.22UF,6.3V,20%,X6S,SA
     1 P5E_CPU1_P0_TX_BUF_C_DN<11> @T6G_MB_LIB.T6G(SCH_1):P5E_CPU1_P0_TX_BUF_C_DN(11)    I94 @T6G_MB_LIB.T6G(SCH_1):PAGE439
     2 P5E_CPU1_P0_TX_BUF_DN<11> @T6G_MB_LIB.T6G(SCH_1):P5E_CPU1_P0_TX_BUF_DN(11)    I94 @T6G_MB_LIB.T6G(SCH_1):PAGE439

C6653 Q_CAP_DIFFBUS_C0201-DIFF BUS_0.22UF,6.3V,20%,X6S,SA
     1 P5E_CPU1_P0_TX_BUF_C_DP<12> @T6G_MB_LIB.T6G(SCH_1):P5E_CPU1_P0_TX_BUF_C_DP(12)    I93 @T6G_MB_LIB.T6G(SCH_1):PAGE439
     2 P5E_CPU1_P0_TX_BUF_DP<12> @T6G_MB_LIB.T6G(SCH_1):P5E_CPU1_P0_TX_BUF_DP(12)    I93 @T6G_MB_LIB.T6G(SCH_1):PAGE439

C6654 Q_CAP_DIFFBUS_C0201-DIFF BUS_0.22UF,6.3V,20%,X6S,SA
     1 P5E_CPU1_P0_TX_BUF_C_DN<12> @T6G_MB_LIB.T6G(SCH_1):P5E_CPU1_P0_TX_BUF_C_DN(12)    I92 @T6G_MB_LIB.T6G(SCH_1):PAGE439
     2 P5E_CPU1_P0_TX_BUF_DN<12> @T6G_MB_LIB.T6G(SCH_1):P5E_CPU1_P0_TX_BUF_DN(12)    I92 @T6G_MB_LIB.T6G(SCH_1):PAGE439

C6655 Q_CAP_DIFFBUS_C0201-DIFF BUS_0.22UF,6.3V,20%,X6S,SA
     1 P5E_CPU1_P0_TX_BUF_C_DP<13> @T6G_MB_LIB.T6G(SCH_1):P5E_CPU1_P0_TX_BUF_C_DP(13)    I91 @T6G_MB_LIB.T6G(SCH_1):PAGE439
     2 P5E_CPU1_P0_TX_BUF_DP<13> @T6G_MB_LIB.T6G(SCH_1):P5E_CPU1_P0_TX_BUF_DP(13)    I91 @T6G_MB_LIB.T6G(SCH_1):PAGE439

C6656 Q_CAP_DIFFBUS_C0201-DIFF BUS_0.22UF,6.3V,20%,X6S,SA
     1 P5E_CPU1_P0_TX_BUF_C_DN<13> @T6G_MB_LIB.T6G(SCH_1):P5E_CPU1_P0_TX_BUF_C_DN(13)    I90 @T6G_MB_LIB.T6G(SCH_1):PAGE439
     2 P5E_CPU1_P0_TX_BUF_DN<13> @T6G_MB_LIB.T6G(SCH_1):P5E_CPU1_P0_TX_BUF_DN(13)    I90 @T6G_MB_LIB.T6G(SCH_1):PAGE439

C6657 Q_CAP_DIFFBUS_C0201-DIFF BUS_0.22UF,6.3V,20%,X6S,SA
     1 P5E_CPU1_P0_TX_BUF_C_DP<14> @T6G_MB_LIB.T6G(SCH_1):P5E_CPU1_P0_TX_BUF_C_DP(14)    I89 @T6G_MB_LIB.T6G(SCH_1):PAGE439
     2 P5E_CPU1_P0_TX_BUF_DP<14> @T6G_MB_LIB.T6G(SCH_1):P5E_CPU1_P0_TX_BUF_DP(14)    I89 @T6G_MB_LIB.T6G(SCH_1):PAGE439

C6658 Q_CAP_DIFFBUS_C0201-DIFF BUS_0.22UF,6.3V,20%,X6S,SA
     1 P5E_CPU1_P0_TX_BUF_C_DN<14> @T6G_MB_LIB.T6G(SCH_1):P5E_CPU1_P0_TX_BUF_C_DN(14)    I88 @T6G_MB_LIB.T6G(SCH_1):PAGE439
     2 P5E_CPU1_P0_TX_BUF_DN<14> @T6G_MB_LIB.T6G(SCH_1):P5E_CPU1_P0_TX_BUF_DN(14)    I88 @T6G_MB_LIB.T6G(SCH_1):PAGE439

C6659 Q_CAP_DIFFBUS_C0201-DIFF BUS_0.22UF,6.3V,20%,X6S,SA
     1 P5E_CPU1_P0_TX_BUF_C_DP<15> @T6G_MB_LIB.T6G(SCH_1):P5E_CPU1_P0_TX_BUF_C_DP(15)    I87 @T6G_MB_LIB.T6G(SCH_1):PAGE439
     2 P5E_CPU1_P0_TX_BUF_DP<15> @T6G_MB_LIB.T6G(SCH_1):P5E_CPU1_P0_TX_BUF_DP(15)    I87 @T6G_MB_LIB.T6G(SCH_1):PAGE439

C6660 Q_CAP_DIFFBUS_C0201-DIFF BUS_0.22UF,6.3V,20%,X6S,SA
     1 P5E_CPU1_P0_TX_BUF_C_DN<15> @T6G_MB_LIB.T6G(SCH_1):P5E_CPU1_P0_TX_BUF_C_DN(15)    I86 @T6G_MB_LIB.T6G(SCH_1):PAGE439
     2 P5E_CPU1_P0_TX_BUF_DN<15> @T6G_MB_LIB.T6G(SCH_1):P5E_CPU1_P0_TX_BUF_DN(15)    I86 @T6G_MB_LIB.T6G(SCH_1):PAGE439

C6661 Q_CAP_DIFFBUS_C0201-DIFF BUS_0.22UF,6.3V,20%,X6S,SA
     1 P5E_CPU1_P1_TX_BUF_C_DP<0> @T6G_MB_LIB.T6G(SCH_1):P5E_CPU1_P1_TX_BUF_C_DP(0)    I42 @T6G_MB_LIB.T6G(SCH_1):PAGE393
     2 P5E_CPU1_P1_TX_BUF_DP<0> @T6G_MB_LIB.T6G(SCH_1):P5E_CPU1_P1_TX_BUF_DP(0)    I42 @T6G_MB_LIB.T6G(SCH_1):PAGE393

C6662 Q_CAP_DIFFBUS_C0201-DIFF BUS_0.22UF,6.3V,20%,X6S,SA
     1 P5E_CPU1_P1_TX_BUF_C_DN<0> @T6G_MB_LIB.T6G(SCH_1):P5E_CPU1_P1_TX_BUF_C_DN(0)    I33 @T6G_MB_LIB.T6G(SCH_1):PAGE393
     2 P5E_CPU1_P1_TX_BUF_DN<0> @T6G_MB_LIB.T6G(SCH_1):P5E_CPU1_P1_TX_BUF_DN(0)    I33 @T6G_MB_LIB.T6G(SCH_1):PAGE393

C6663 Q_CAP_DIFFBUS_C0201-DIFF BUS_0.22UF,6.3V,20%,X6S,SA
     1 P5E_CPU1_P1_TX_BUF_C_DP<1> @T6G_MB_LIB.T6G(SCH_1):P5E_CPU1_P1_TX_BUF_C_DP(1)    I31 @T6G_MB_LIB.T6G(SCH_1):PAGE393
     2 P5E_CPU1_P1_TX_BUF_DP<1> @T6G_MB_LIB.T6G(SCH_1):P5E_CPU1_P1_TX_BUF_DP(1)    I31 @T6G_MB_LIB.T6G(SCH_1):PAGE393

C6664 Q_CAP_DIFFBUS_C0201-DIFF BUS_0.22UF,6.3V,20%,X6S,SA
     1 P5E_CPU1_P1_TX_BUF_C_DN<1> @T6G_MB_LIB.T6G(SCH_1):P5E_CPU1_P1_TX_BUF_C_DN(1)    I32 @T6G_MB_LIB.T6G(SCH_1):PAGE393
     2 P5E_CPU1_P1_TX_BUF_DN<1> @T6G_MB_LIB.T6G(SCH_1):P5E_CPU1_P1_TX_BUF_DN(1)    I32 @T6G_MB_LIB.T6G(SCH_1):PAGE393

C6665 Q_CAP_DIFFBUS_C0201-DIFF BUS_0.22UF,6.3V,20%,X6S,SA
     1 P5E_CPU1_P1_TX_BUF_C_DP<2> @T6G_MB_LIB.T6G(SCH_1):P5E_CPU1_P1_TX_BUF_C_DP(2)    I30 @T6G_MB_LIB.T6G(SCH_1):PAGE393
     2 P5E_CPU1_P1_TX_BUF_DP<2> @T6G_MB_LIB.T6G(SCH_1):P5E_CPU1_P1_TX_BUF_DP(2)    I30 @T6G_MB_LIB.T6G(SCH_1):PAGE393

C6666 Q_CAP_DIFFBUS_C0201-DIFF BUS_0.22UF,6.3V,20%,X6S,SA
     1 P5E_CPU1_P1_TX_BUF_C_DN<2> @T6G_MB_LIB.T6G(SCH_1):P5E_CPU1_P1_TX_BUF_C_DN(2)    I29 @T6G_MB_LIB.T6G(SCH_1):PAGE393
     2 P5E_CPU1_P1_TX_BUF_DN<2> @T6G_MB_LIB.T6G(SCH_1):P5E_CPU1_P1_TX_BUF_DN(2)    I29 @T6G_MB_LIB.T6G(SCH_1):PAGE393

C6667 Q_CAP_DIFFBUS_C0201-DIFF BUS_0.22UF,6.3V,20%,X6S,SA
     1 P5E_CPU1_P1_TX_BUF_C_DP<3> @T6G_MB_LIB.T6G(SCH_1):P5E_CPU1_P1_TX_BUF_C_DP(3)    I27 @T6G_MB_LIB.T6G(SCH_1):PAGE393
     2 P5E_CPU1_P1_TX_BUF_DP<3> @T6G_MB_LIB.T6G(SCH_1):P5E_CPU1_P1_TX_BUF_DP(3)    I27 @T6G_MB_LIB.T6G(SCH_1):PAGE393

C6668 Q_CAP_DIFFBUS_C0201-DIFF BUS_0.22UF,6.3V,20%,X6S,SA
     1 P5E_CPU1_P1_TX_BUF_C_DN<3> @T6G_MB_LIB.T6G(SCH_1):P5E_CPU1_P1_TX_BUF_C_DN(3)    I28 @T6G_MB_LIB.T6G(SCH_1):PAGE393
     2 P5E_CPU1_P1_TX_BUF_DN<3> @T6G_MB_LIB.T6G(SCH_1):P5E_CPU1_P1_TX_BUF_DN(3)    I28 @T6G_MB_LIB.T6G(SCH_1):PAGE393

C6669 Q_CAP_DIFFBUS_C0201-DIFF BUS_0.22UF,6.3V,20%,X6S,SA
     1 P5E_CPU1_P1_TX_BUF_C_DP<4> @T6G_MB_LIB.T6G(SCH_1):P5E_CPU1_P1_TX_BUF_C_DP(4)    I26 @T6G_MB_LIB.T6G(SCH_1):PAGE393
     2 P5E_CPU1_P1_TX_BUF_DP<4> @T6G_MB_LIB.T6G(SCH_1):P5E_CPU1_P1_TX_BUF_DP(4)    I26 @T6G_MB_LIB.T6G(SCH_1):PAGE393

C6670 Q_CAP_DIFFBUS_C0201-DIFF BUS_0.22UF,6.3V,20%,X6S,SA
     1 P5E_CPU1_P1_TX_BUF_C_DN<4> @T6G_MB_LIB.T6G(SCH_1):P5E_CPU1_P1_TX_BUF_C_DN(4)    I25 @T6G_MB_LIB.T6G(SCH_1):PAGE393
     2 P5E_CPU1_P1_TX_BUF_DN<4> @T6G_MB_LIB.T6G(SCH_1):P5E_CPU1_P1_TX_BUF_DN(4)    I25 @T6G_MB_LIB.T6G(SCH_1):PAGE393

C6671 Q_CAP_DIFFBUS_C0201-DIFF BUS_0.22UF,6.3V,20%,X6S,SA
     1 P5E_CPU1_P1_TX_BUF_C_DP<5> @T6G_MB_LIB.T6G(SCH_1):P5E_CPU1_P1_TX_BUF_C_DP(5)    I24 @T6G_MB_LIB.T6G(SCH_1):PAGE393
     2 P5E_CPU1_P1_TX_BUF_DP<5> @T6G_MB_LIB.T6G(SCH_1):P5E_CPU1_P1_TX_BUF_DP(5)    I24 @T6G_MB_LIB.T6G(SCH_1):PAGE393

C6672 Q_CAP_DIFFBUS_C0201-DIFF BUS_0.22UF,6.3V,20%,X6S,SA
     1 P5E_CPU1_P1_TX_BUF_C_DN<5> @T6G_MB_LIB.T6G(SCH_1):P5E_CPU1_P1_TX_BUF_C_DN(5)    I23 @T6G_MB_LIB.T6G(SCH_1):PAGE393
     2 P5E_CPU1_P1_TX_BUF_DN<5> @T6G_MB_LIB.T6G(SCH_1):P5E_CPU1_P1_TX_BUF_DN(5)    I23 @T6G_MB_LIB.T6G(SCH_1):PAGE393

C6673 Q_CAP_DIFFBUS_C0201-DIFF BUS_0.22UF,6.3V,20%,X6S,SA
     1 P5E_CPU1_P1_TX_BUF_C_DP<6> @T6G_MB_LIB.T6G(SCH_1):P5E_CPU1_P1_TX_BUF_C_DP(6)    I20 @T6G_MB_LIB.T6G(SCH_1):PAGE393
     2 P5E_CPU1_P1_TX_BUF_DP<6> @T6G_MB_LIB.T6G(SCH_1):P5E_CPU1_P1_TX_BUF_DP(6)    I20 @T6G_MB_LIB.T6G(SCH_1):PAGE393

C6674 Q_CAP_DIFFBUS_C0201-DIFF BUS_0.22UF,6.3V,20%,X6S,SA
     1 P5E_CPU1_P1_TX_BUF_C_DN<6> @T6G_MB_LIB.T6G(SCH_1):P5E_CPU1_P1_TX_BUF_C_DN(6)    I19 @T6G_MB_LIB.T6G(SCH_1):PAGE393
     2 P5E_CPU1_P1_TX_BUF_DN<6> @T6G_MB_LIB.T6G(SCH_1):P5E_CPU1_P1_TX_BUF_DN(6)    I19 @T6G_MB_LIB.T6G(SCH_1):PAGE393

C6675 Q_CAP_DIFFBUS_C0201-DIFF BUS_0.22UF,6.3V,20%,X6S,SA
     1 P5E_CPU1_P1_TX_BUF_C_DP<7> @T6G_MB_LIB.T6G(SCH_1):P5E_CPU1_P1_TX_BUF_C_DP(7)    I18 @T6G_MB_LIB.T6G(SCH_1):PAGE393
     2 P5E_CPU1_P1_TX_BUF_DP<7> @T6G_MB_LIB.T6G(SCH_1):P5E_CPU1_P1_TX_BUF_DP(7)    I18 @T6G_MB_LIB.T6G(SCH_1):PAGE393

C6676 Q_CAP_DIFFBUS_C0201-DIFF BUS_0.22UF,6.3V,20%,X6S,SA
     1 P5E_CPU1_P1_TX_BUF_C_DN<7> @T6G_MB_LIB.T6G(SCH_1):P5E_CPU1_P1_TX_BUF_C_DN(7)    I17 @T6G_MB_LIB.T6G(SCH_1):PAGE393
     2 P5E_CPU1_P1_TX_BUF_DN<7> @T6G_MB_LIB.T6G(SCH_1):P5E_CPU1_P1_TX_BUF_DN(7)    I17 @T6G_MB_LIB.T6G(SCH_1):PAGE393

C6677 Q_CAP_DIFFBUS_C0201-DIFF BUS_0.22UF,6.3V,20%,X6S,SA
     1 P5E_CPU1_P1_TX_BUF_C_DP<8> @T6G_MB_LIB.T6G(SCH_1):P5E_CPU1_P1_TX_BUF_C_DP(8)   I104 @T6G_MB_LIB.T6G(SCH_1):PAGE393
     2 P5E_CPU1_P1_TX_BUF_DP<8> @T6G_MB_LIB.T6G(SCH_1):P5E_CPU1_P1_TX_BUF_DP(8)   I104 @T6G_MB_LIB.T6G(SCH_1):PAGE393

C6678 Q_CAP_DIFFBUS_C0201-DIFF BUS_0.22UF,6.3V,20%,X6S,SA
     1 P5E_CPU1_P1_TX_BUF_C_DN<8> @T6G_MB_LIB.T6G(SCH_1):P5E_CPU1_P1_TX_BUF_C_DN(8)   I103 @T6G_MB_LIB.T6G(SCH_1):PAGE393
     2 P5E_CPU1_P1_TX_BUF_DN<8> @T6G_MB_LIB.T6G(SCH_1):P5E_CPU1_P1_TX_BUF_DN(8)   I103 @T6G_MB_LIB.T6G(SCH_1):PAGE393

C6679 Q_CAP_DIFFBUS_C0201-DIFF BUS_0.22UF,6.3V,20%,X6S,SA
     1 P5E_CPU1_P1_TX_BUF_C_DP<9> @T6G_MB_LIB.T6G(SCH_1):P5E_CPU1_P1_TX_BUF_C_DP(9)   I101 @T6G_MB_LIB.T6G(SCH_1):PAGE393
     2 P5E_CPU1_P1_TX_BUF_DP<9> @T6G_MB_LIB.T6G(SCH_1):P5E_CPU1_P1_TX_BUF_DP(9)   I101 @T6G_MB_LIB.T6G(SCH_1):PAGE393

C6680 Q_CAP_DIFFBUS_C0201-DIFF BUS_0.22UF,6.3V,20%,X6S,SA
     1 P5E_CPU1_P1_TX_BUF_C_DN<9> @T6G_MB_LIB.T6G(SCH_1):P5E_CPU1_P1_TX_BUF_C_DN(9)   I102 @T6G_MB_LIB.T6G(SCH_1):PAGE393
     2 P5E_CPU1_P1_TX_BUF_DN<9> @T6G_MB_LIB.T6G(SCH_1):P5E_CPU1_P1_TX_BUF_DN(9)   I102 @T6G_MB_LIB.T6G(SCH_1):PAGE393

C6681 Q_CAP_DIFFBUS_C0201-DIFF BUS_0.22UF,6.3V,20%,X6S,SA
     1 P5E_CPU1_P1_TX_BUF_C_DP<10> @T6G_MB_LIB.T6G(SCH_1):P5E_CPU1_P1_TX_BUF_C_DP(10)    I99 @T6G_MB_LIB.T6G(SCH_1):PAGE393
     2 P5E_CPU1_P1_TX_BUF_DP<10> @T6G_MB_LIB.T6G(SCH_1):P5E_CPU1_P1_TX_BUF_DP(10)    I99 @T6G_MB_LIB.T6G(SCH_1):PAGE393

C6682 Q_CAP_DIFFBUS_C0201-DIFF BUS_0.22UF,6.3V,20%,X6S,SA
     1 P5E_CPU1_P1_TX_BUF_C_DN<10> @T6G_MB_LIB.T6G(SCH_1):P5E_CPU1_P1_TX_BUF_C_DN(10)   I100 @T6G_MB_LIB.T6G(SCH_1):PAGE393
     2 P5E_CPU1_P1_TX_BUF_DN<10> @T6G_MB_LIB.T6G(SCH_1):P5E_CPU1_P1_TX_BUF_DN(10)   I100 @T6G_MB_LIB.T6G(SCH_1):PAGE393

C6683 Q_CAP_DIFFBUS_C0201-DIFF BUS_0.22UF,6.3V,20%,X6S,SA
     1 P5E_CPU1_P1_TX_BUF_C_DP<11> @T6G_MB_LIB.T6G(SCH_1):P5E_CPU1_P1_TX_BUF_C_DP(11)    I98 @T6G_MB_LIB.T6G(SCH_1):PAGE393
     2 P5E_CPU1_P1_TX_BUF_DP<11> @T6G_MB_LIB.T6G(SCH_1):P5E_CPU1_P1_TX_BUF_DP(11)    I98 @T6G_MB_LIB.T6G(SCH_1):PAGE393

C6684 Q_CAP_DIFFBUS_C0201-DIFF BUS_0.22UF,6.3V,20%,X6S,SA
     1 P5E_CPU1_P1_TX_BUF_C_DN<11> @T6G_MB_LIB.T6G(SCH_1):P5E_CPU1_P1_TX_BUF_C_DN(11)    I97 @T6G_MB_LIB.T6G(SCH_1):PAGE393
     2 P5E_CPU1_P1_TX_BUF_DN<11> @T6G_MB_LIB.T6G(SCH_1):P5E_CPU1_P1_TX_BUF_DN(11)    I97 @T6G_MB_LIB.T6G(SCH_1):PAGE393

C6685 Q_CAP_DIFFBUS_C0201-DIFF BUS_0.22UF,6.3V,20%,X6S,SA
     1 P5E_CPU1_P1_TX_BUF_C_DP<12> @T6G_MB_LIB.T6G(SCH_1):P5E_CPU1_P1_TX_BUF_C_DP(12)    I96 @T6G_MB_LIB.T6G(SCH_1):PAGE393
     2 P5E_CPU1_P1_TX_BUF_DP<12> @T6G_MB_LIB.T6G(SCH_1):P5E_CPU1_P1_TX_BUF_DP(12)    I96 @T6G_MB_LIB.T6G(SCH_1):PAGE393

C6686 Q_CAP_DIFFBUS_C0201-DIFF BUS_0.22UF,6.3V,20%,X6S,SA
     1 P5E_CPU1_P1_TX_BUF_C_DN<12> @T6G_MB_LIB.T6G(SCH_1):P5E_CPU1_P1_TX_BUF_C_DN(12)    I95 @T6G_MB_LIB.T6G(SCH_1):PAGE393
     2 P5E_CPU1_P1_TX_BUF_DN<12> @T6G_MB_LIB.T6G(SCH_1):P5E_CPU1_P1_TX_BUF_DN(12)    I95 @T6G_MB_LIB.T6G(SCH_1):PAGE393

C6687 Q_CAP_DIFFBUS_C0201-DIFF BUS_0.22UF,6.3V,20%,X6S,SA
     1 P5E_CPU1_P1_TX_BUF_C_DP<13> @T6G_MB_LIB.T6G(SCH_1):P5E_CPU1_P1_TX_BUF_C_DP(13)    I89 @T6G_MB_LIB.T6G(SCH_1):PAGE393
     2 P5E_CPU1_P1_TX_BUF_DP<13> @T6G_MB_LIB.T6G(SCH_1):P5E_CPU1_P1_TX_BUF_DP(13)    I89 @T6G_MB_LIB.T6G(SCH_1):PAGE393

C6688 Q_CAP_DIFFBUS_C0201-DIFF BUS_0.22UF,6.3V,20%,X6S,SA
     1 P5E_CPU1_P1_TX_BUF_C_DN<13> @T6G_MB_LIB.T6G(SCH_1):P5E_CPU1_P1_TX_BUF_C_DN(13)    I88 @T6G_MB_LIB.T6G(SCH_1):PAGE393
     2 P5E_CPU1_P1_TX_BUF_DN<13> @T6G_MB_LIB.T6G(SCH_1):P5E_CPU1_P1_TX_BUF_DN(13)    I88 @T6G_MB_LIB.T6G(SCH_1):PAGE393

C6689 Q_CAP_DIFFBUS_C0201-DIFF BUS_0.22UF,6.3V,20%,X6S,SA
     1 P5E_CPU1_P1_TX_BUF_C_DP<14> @T6G_MB_LIB.T6G(SCH_1):P5E_CPU1_P1_TX_BUF_C_DP(14)    I87 @T6G_MB_LIB.T6G(SCH_1):PAGE393
     2 P5E_CPU1_P1_TX_BUF_DP<14> @T6G_MB_LIB.T6G(SCH_1):P5E_CPU1_P1_TX_BUF_DP(14)    I87 @T6G_MB_LIB.T6G(SCH_1):PAGE393

C6690 Q_CAP_DIFFBUS_C0201-DIFF BUS_0.22UF,6.3V,20%,X6S,SA
     1 P5E_CPU1_P1_TX_BUF_C_DN<14> @T6G_MB_LIB.T6G(SCH_1):P5E_CPU1_P1_TX_BUF_C_DN(14)    I86 @T6G_MB_LIB.T6G(SCH_1):PAGE393
     2 P5E_CPU1_P1_TX_BUF_DN<14> @T6G_MB_LIB.T6G(SCH_1):P5E_CPU1_P1_TX_BUF_DN(14)    I86 @T6G_MB_LIB.T6G(SCH_1):PAGE393

C6691 Q_CAP_DIFFBUS_C0201-DIFF BUS_0.22UF,6.3V,20%,X6S,SA
     1 P5E_CPU1_P1_TX_BUF_C_DP<15> @T6G_MB_LIB.T6G(SCH_1):P5E_CPU1_P1_TX_BUF_C_DP(15)    I85 @T6G_MB_LIB.T6G(SCH_1):PAGE393
     2 P5E_CPU1_P1_TX_BUF_DP<15> @T6G_MB_LIB.T6G(SCH_1):P5E_CPU1_P1_TX_BUF_DP(15)    I85 @T6G_MB_LIB.T6G(SCH_1):PAGE393

C6692 Q_CAP_DIFFBUS_C0201-DIFF BUS_0.22UF,6.3V,20%,X6S,SA
     1 P5E_CPU1_P1_TX_BUF_C_DN<15> @T6G_MB_LIB.T6G(SCH_1):P5E_CPU1_P1_TX_BUF_C_DN(15)    I84 @T6G_MB_LIB.T6G(SCH_1):PAGE393
     2 P5E_CPU1_P1_TX_BUF_DN<15> @T6G_MB_LIB.T6G(SCH_1):P5E_CPU1_P1_TX_BUF_DN(15)    I84 @T6G_MB_LIB.T6G(SCH_1):PAGE393

C6693 Q_CAP_DIFFBUS_C0201-DIFF BUS_0.22UF,6.3V,20%,X6S,SA
     1 P5E_CPU1_P2_TX_BUF_C_DP<0> @T6G_MB_LIB.T6G(SCH_1):P5E_CPU1_P2_TX_BUF_C_DP(0)    I34 @T6G_MB_LIB.T6G(SCH_1):PAGE450
     2 P5E_CPU1_P2_TX_BUF_DP<0> @T6G_MB_LIB.T6G(SCH_1):P5E_CPU1_P2_TX_BUF_DP(0)    I34 @T6G_MB_LIB.T6G(SCH_1):PAGE450

C6694 Q_CAP_DIFFBUS_C0201-DIFF BUS_0.22UF,6.3V,20%,X6S,SA
     1 P5E_CPU1_P2_TX_BUF_C_DN<0> @T6G_MB_LIB.T6G(SCH_1):P5E_CPU1_P2_TX_BUF_C_DN(0)    I35 @T6G_MB_LIB.T6G(SCH_1):PAGE450
     2 P5E_CPU1_P2_TX_BUF_DN<0> @T6G_MB_LIB.T6G(SCH_1):P5E_CPU1_P2_TX_BUF_DN(0)    I35 @T6G_MB_LIB.T6G(SCH_1):PAGE450

C6695 Q_CAP_DIFFBUS_C0201-DIFF BUS_0.22UF,6.3V,20%,X6S,SA
     1 P5E_CPU1_P2_TX_BUF_C_DP<1> @T6G_MB_LIB.T6G(SCH_1):P5E_CPU1_P2_TX_BUF_C_DP(1)    I29 @T6G_MB_LIB.T6G(SCH_1):PAGE450
     2 P5E_CPU1_P2_TX_BUF_DP<1> @T6G_MB_LIB.T6G(SCH_1):P5E_CPU1_P2_TX_BUF_DP(1)    I29 @T6G_MB_LIB.T6G(SCH_1):PAGE450

C6696 Q_CAP_DIFFBUS_C0201-DIFF BUS_0.22UF,6.3V,20%,X6S,SA
     1 P5E_CPU1_P2_TX_BUF_C_DN<1> @T6G_MB_LIB.T6G(SCH_1):P5E_CPU1_P2_TX_BUF_C_DN(1)    I28 @T6G_MB_LIB.T6G(SCH_1):PAGE450
     2 P5E_CPU1_P2_TX_BUF_DN<1> @T6G_MB_LIB.T6G(SCH_1):P5E_CPU1_P2_TX_BUF_DN(1)    I28 @T6G_MB_LIB.T6G(SCH_1):PAGE450

C6697 Q_CAP_DIFFBUS_C0201-DIFF BUS_0.22UF,6.3V,20%,X6S,SA
     1 P5E_CPU1_P2_TX_BUF_C_DP<2> @T6G_MB_LIB.T6G(SCH_1):P5E_CPU1_P2_TX_BUF_C_DP(2)    I30 @T6G_MB_LIB.T6G(SCH_1):PAGE450
     2 P5E_CPU1_P2_TX_BUF_DP<2> @T6G_MB_LIB.T6G(SCH_1):P5E_CPU1_P2_TX_BUF_DP(2)    I30 @T6G_MB_LIB.T6G(SCH_1):PAGE450

C6698 Q_CAP_DIFFBUS_C0201-DIFF BUS_0.22UF,6.3V,20%,X6S,SA
     1 P5E_CPU1_P2_TX_BUF_C_DN<2> @T6G_MB_LIB.T6G(SCH_1):P5E_CPU1_P2_TX_BUF_C_DN(2)    I27 @T6G_MB_LIB.T6G(SCH_1):PAGE450
     2 P5E_CPU1_P2_TX_BUF_DN<2> @T6G_MB_LIB.T6G(SCH_1):P5E_CPU1_P2_TX_BUF_DN(2)    I27 @T6G_MB_LIB.T6G(SCH_1):PAGE450

C6699 Q_CAP_DIFFBUS_C0201-DIFF BUS_0.22UF,6.3V,20%,X6S,SA
     1 P5E_CPU1_P2_TX_BUF_C_DP<3> @T6G_MB_LIB.T6G(SCH_1):P5E_CPU1_P2_TX_BUF_C_DP(3)    I25 @T6G_MB_LIB.T6G(SCH_1):PAGE450
     2 P5E_CPU1_P2_TX_BUF_DP<3> @T6G_MB_LIB.T6G(SCH_1):P5E_CPU1_P2_TX_BUF_DP(3)    I25 @T6G_MB_LIB.T6G(SCH_1):PAGE450

C6700 Q_CAP_DIFFBUS_C0201-DIFF BUS_0.22UF,6.3V,20%,X6S,SA
     1 P5E_CPU1_P2_TX_BUF_C_DN<3> @T6G_MB_LIB.T6G(SCH_1):P5E_CPU1_P2_TX_BUF_C_DN(3)    I26 @T6G_MB_LIB.T6G(SCH_1):PAGE450
     2 P5E_CPU1_P2_TX_BUF_DN<3> @T6G_MB_LIB.T6G(SCH_1):P5E_CPU1_P2_TX_BUF_DN(3)    I26 @T6G_MB_LIB.T6G(SCH_1):PAGE450

C6701 Q_CAP_DIFFBUS_C0201-DIFF BUS_0.22UF,6.3V,20%,X6S,SA
     1 P5E_CPU1_P2_TX_BUF_C_DP<4> @T6G_MB_LIB.T6G(SCH_1):P5E_CPU1_P2_TX_BUF_C_DP(4)    I24 @T6G_MB_LIB.T6G(SCH_1):PAGE450
     2 P5E_CPU1_P2_TX_BUF_DP<4> @T6G_MB_LIB.T6G(SCH_1):P5E_CPU1_P2_TX_BUF_DP(4)    I24 @T6G_MB_LIB.T6G(SCH_1):PAGE450

C6702 Q_CAP_DIFFBUS_C0201-DIFF BUS_0.22UF,6.3V,20%,X6S,SA
     1 P5E_CPU1_P2_TX_BUF_C_DN<4> @T6G_MB_LIB.T6G(SCH_1):P5E_CPU1_P2_TX_BUF_C_DN(4)    I23 @T6G_MB_LIB.T6G(SCH_1):PAGE450
     2 P5E_CPU1_P2_TX_BUF_DN<4> @T6G_MB_LIB.T6G(SCH_1):P5E_CPU1_P2_TX_BUF_DN(4)    I23 @T6G_MB_LIB.T6G(SCH_1):PAGE450

C6703 Q_CAP_DIFFBUS_C0201-DIFF BUS_0.22UF,6.3V,20%,X6S,SA
     1 P5E_CPU1_P2_TX_BUF_C_DP<5> @T6G_MB_LIB.T6G(SCH_1):P5E_CPU1_P2_TX_BUF_C_DP(5)    I22 @T6G_MB_LIB.T6G(SCH_1):PAGE450
     2 P5E_CPU1_P2_TX_BUF_DP<5> @T6G_MB_LIB.T6G(SCH_1):P5E_CPU1_P2_TX_BUF_DP(5)    I22 @T6G_MB_LIB.T6G(SCH_1):PAGE450

C6704 Q_CAP_DIFFBUS_C0201-DIFF BUS_0.22UF,6.3V,20%,X6S,SA
     1 P5E_CPU1_P2_TX_BUF_C_DN<5> @T6G_MB_LIB.T6G(SCH_1):P5E_CPU1_P2_TX_BUF_C_DN(5)    I21 @T6G_MB_LIB.T6G(SCH_1):PAGE450
     2 P5E_CPU1_P2_TX_BUF_DN<5> @T6G_MB_LIB.T6G(SCH_1):P5E_CPU1_P2_TX_BUF_DN(5)    I21 @T6G_MB_LIB.T6G(SCH_1):PAGE450

C6705 Q_CAP_DIFFBUS_C0201-DIFF BUS_0.22UF,6.3V,20%,X6S,SA
     1 P5E_CPU1_P2_TX_BUF_C_DP<6> @T6G_MB_LIB.T6G(SCH_1):P5E_CPU1_P2_TX_BUF_C_DP(6)    I20 @T6G_MB_LIB.T6G(SCH_1):PAGE450
     2 P5E_CPU1_P2_TX_BUF_DP<6> @T6G_MB_LIB.T6G(SCH_1):P5E_CPU1_P2_TX_BUF_DP(6)    I20 @T6G_MB_LIB.T6G(SCH_1):PAGE450

C6706 Q_CAP_DIFFBUS_C0201-DIFF BUS_0.22UF,6.3V,20%,X6S,SA
     1 P5E_CPU1_P2_TX_BUF_C_DN<6> @T6G_MB_LIB.T6G(SCH_1):P5E_CPU1_P2_TX_BUF_C_DN(6)    I19 @T6G_MB_LIB.T6G(SCH_1):PAGE450
     2 P5E_CPU1_P2_TX_BUF_DN<6> @T6G_MB_LIB.T6G(SCH_1):P5E_CPU1_P2_TX_BUF_DN(6)    I19 @T6G_MB_LIB.T6G(SCH_1):PAGE450

C6707 Q_CAP_DIFFBUS_C0201-DIFF BUS_0.22UF,6.3V,20%,X6S,SA
     1 P5E_CPU1_P2_TX_BUF_C_DP<7> @T6G_MB_LIB.T6G(SCH_1):P5E_CPU1_P2_TX_BUF_C_DP(7)    I18 @T6G_MB_LIB.T6G(SCH_1):PAGE450
     2 P5E_CPU1_P2_TX_BUF_DP<7> @T6G_MB_LIB.T6G(SCH_1):P5E_CPU1_P2_TX_BUF_DP(7)    I18 @T6G_MB_LIB.T6G(SCH_1):PAGE450

C6708 Q_CAP_DIFFBUS_C0201-DIFF BUS_0.22UF,6.3V,20%,X6S,SA
     1 P5E_CPU1_P2_TX_BUF_C_DN<7> @T6G_MB_LIB.T6G(SCH_1):P5E_CPU1_P2_TX_BUF_C_DN(7)    I17 @T6G_MB_LIB.T6G(SCH_1):PAGE450
     2 P5E_CPU1_P2_TX_BUF_DN<7> @T6G_MB_LIB.T6G(SCH_1):P5E_CPU1_P2_TX_BUF_DN(7)    I17 @T6G_MB_LIB.T6G(SCH_1):PAGE450

C6709 Q_CAP_DIFFBUS_C0201-DIFF BUS_0.22UF,6.3V,20%,X6S,SA
     1 P5E_CPU1_P2_TX_BUF_C_DP<8> @T6G_MB_LIB.T6G(SCH_1):P5E_CPU1_P2_TX_BUF_C_DP(8)   I102 @T6G_MB_LIB.T6G(SCH_1):PAGE450
     2 P5E_CPU1_P2_TX_BUF_DP<8> @T6G_MB_LIB.T6G(SCH_1):P5E_CPU1_P2_TX_BUF_DP(8)   I102 @T6G_MB_LIB.T6G(SCH_1):PAGE450

C6710 Q_CAP_DIFFBUS_C0201-DIFF BUS_0.22UF,6.3V,20%,X6S,SA
     1 P5E_CPU1_P2_TX_BUF_C_DN<8> @T6G_MB_LIB.T6G(SCH_1):P5E_CPU1_P2_TX_BUF_C_DN(8)   I103 @T6G_MB_LIB.T6G(SCH_1):PAGE450
     2 P5E_CPU1_P2_TX_BUF_DN<8> @T6G_MB_LIB.T6G(SCH_1):P5E_CPU1_P2_TX_BUF_DN(8)   I103 @T6G_MB_LIB.T6G(SCH_1):PAGE450

C6711 Q_CAP_DIFFBUS_C0201-DIFF BUS_0.22UF,6.3V,20%,X6S,SA
     1 P5E_CPU1_P2_TX_BUF_C_DP<9> @T6G_MB_LIB.T6G(SCH_1):P5E_CPU1_P2_TX_BUF_C_DP(9)    I99 @T6G_MB_LIB.T6G(SCH_1):PAGE450
     2 P5E_CPU1_P2_TX_BUF_DP<9> @T6G_MB_LIB.T6G(SCH_1):P5E_CPU1_P2_TX_BUF_DP(9)    I99 @T6G_MB_LIB.T6G(SCH_1):PAGE450

C6712 Q_CAP_DIFFBUS_C0201-DIFF BUS_0.22UF,6.3V,20%,X6S,SA
     1 P5E_CPU1_P2_TX_BUF_C_DN<9> @T6G_MB_LIB.T6G(SCH_1):P5E_CPU1_P2_TX_BUF_C_DN(9)    I98 @T6G_MB_LIB.T6G(SCH_1):PAGE450
     2 P5E_CPU1_P2_TX_BUF_DN<9> @T6G_MB_LIB.T6G(SCH_1):P5E_CPU1_P2_TX_BUF_DN(9)    I98 @T6G_MB_LIB.T6G(SCH_1):PAGE450

C6713 Q_CAP_DIFFBUS_C0201-DIFF BUS_0.22UF,6.3V,20%,X6S,SA
     1 P5E_CPU1_P2_TX_BUF_C_DP<10> @T6G_MB_LIB.T6G(SCH_1):P5E_CPU1_P2_TX_BUF_C_DP(10)    I97 @T6G_MB_LIB.T6G(SCH_1):PAGE450
     2 P5E_CPU1_P2_TX_BUF_DP<10> @T6G_MB_LIB.T6G(SCH_1):P5E_CPU1_P2_TX_BUF_DP(10)    I97 @T6G_MB_LIB.T6G(SCH_1):PAGE450

C6714 Q_CAP_DIFFBUS_C0201-DIFF BUS_0.22UF,6.3V,20%,X6S,SA
     1 P5E_CPU1_P2_TX_BUF_C_DN<10> @T6G_MB_LIB.T6G(SCH_1):P5E_CPU1_P2_TX_BUF_C_DN(10)    I96 @T6G_MB_LIB.T6G(SCH_1):PAGE450
     2 P5E_CPU1_P2_TX_BUF_DN<10> @T6G_MB_LIB.T6G(SCH_1):P5E_CPU1_P2_TX_BUF_DN(10)    I96 @T6G_MB_LIB.T6G(SCH_1):PAGE450

C6715 Q_CAP_DIFFBUS_C0201-DIFF BUS_0.22UF,6.3V,20%,X6S,SA
     1 P5E_CPU1_P2_TX_BUF_C_DP<11> @T6G_MB_LIB.T6G(SCH_1):P5E_CPU1_P2_TX_BUF_C_DP(11)    I95 @T6G_MB_LIB.T6G(SCH_1):PAGE450
     2 P5E_CPU1_P2_TX_BUF_DP<11> @T6G_MB_LIB.T6G(SCH_1):P5E_CPU1_P2_TX_BUF_DP(11)    I95 @T6G_MB_LIB.T6G(SCH_1):PAGE450

C6716 Q_CAP_DIFFBUS_C0201-DIFF BUS_0.22UF,6.3V,20%,X6S,SA
     1 P5E_CPU1_P2_TX_BUF_C_DN<11> @T6G_MB_LIB.T6G(SCH_1):P5E_CPU1_P2_TX_BUF_C_DN(11)    I94 @T6G_MB_LIB.T6G(SCH_1):PAGE450
     2 P5E_CPU1_P2_TX_BUF_DN<11> @T6G_MB_LIB.T6G(SCH_1):P5E_CPU1_P2_TX_BUF_DN(11)    I94 @T6G_MB_LIB.T6G(SCH_1):PAGE450

C6717 Q_CAP_DIFFBUS_C0201-DIFF BUS_0.22UF,6.3V,20%,X6S,SA
     1 P5E_CPU1_P2_TX_BUF_C_DP<12> @T6G_MB_LIB.T6G(SCH_1):P5E_CPU1_P2_TX_BUF_C_DP(12)    I93 @T6G_MB_LIB.T6G(SCH_1):PAGE450
     2 P5E_CPU1_P2_TX_BUF_DP<12> @T6G_MB_LIB.T6G(SCH_1):P5E_CPU1_P2_TX_BUF_DP(12)    I93 @T6G_MB_LIB.T6G(SCH_1):PAGE450

C6718 Q_CAP_DIFFBUS_C0201-DIFF BUS_0.22UF,6.3V,20%,X6S,SA
     1 P5E_CPU1_P2_TX_BUF_C_DN<12> @T6G_MB_LIB.T6G(SCH_1):P5E_CPU1_P2_TX_BUF_C_DN(12)    I92 @T6G_MB_LIB.T6G(SCH_1):PAGE450
     2 P5E_CPU1_P2_TX_BUF_DN<12> @T6G_MB_LIB.T6G(SCH_1):P5E_CPU1_P2_TX_BUF_DN(12)    I92 @T6G_MB_LIB.T6G(SCH_1):PAGE450

C6719 Q_CAP_DIFFBUS_C0201-DIFF BUS_0.22UF,6.3V,20%,X6S,SA
     1 P5E_CPU1_P2_TX_BUF_C_DP<13> @T6G_MB_LIB.T6G(SCH_1):P5E_CPU1_P2_TX_BUF_C_DP(13)    I91 @T6G_MB_LIB.T6G(SCH_1):PAGE450
     2 P5E_CPU1_P2_TX_BUF_DP<13> @T6G_MB_LIB.T6G(SCH_1):P5E_CPU1_P2_TX_BUF_DP(13)    I91 @T6G_MB_LIB.T6G(SCH_1):PAGE450

C6720 Q_CAP_DIFFBUS_C0201-DIFF BUS_0.22UF,6.3V,20%,X6S,SA
     1 P5E_CPU1_P2_TX_BUF_C_DN<13> @T6G_MB_LIB.T6G(SCH_1):P5E_CPU1_P2_TX_BUF_C_DN(13)    I90 @T6G_MB_LIB.T6G(SCH_1):PAGE450
     2 P5E_CPU1_P2_TX_BUF_DN<13> @T6G_MB_LIB.T6G(SCH_1):P5E_CPU1_P2_TX_BUF_DN(13)    I90 @T6G_MB_LIB.T6G(SCH_1):PAGE450

C6721 Q_CAP_DIFFBUS_C0201-DIFF BUS_0.22UF,6.3V,20%,X6S,SA
     1 P5E_CPU1_P2_TX_BUF_C_DP<14> @T6G_MB_LIB.T6G(SCH_1):P5E_CPU1_P2_TX_BUF_C_DP(14)    I84 @T6G_MB_LIB.T6G(SCH_1):PAGE450
     2 P5E_CPU1_P2_TX_BUF_DP<14> @T6G_MB_LIB.T6G(SCH_1):P5E_CPU1_P2_TX_BUF_DP(14)    I84 @T6G_MB_LIB.T6G(SCH_1):PAGE450

C6722 Q_CAP_DIFFBUS_C0201-DIFF BUS_0.22UF,6.3V,20%,X6S,SA
     1 P5E_CPU1_P2_TX_BUF_C_DN<14> @T6G_MB_LIB.T6G(SCH_1):P5E_CPU1_P2_TX_BUF_C_DN(14)    I83 @T6G_MB_LIB.T6G(SCH_1):PAGE450
     2 P5E_CPU1_P2_TX_BUF_DN<14> @T6G_MB_LIB.T6G(SCH_1):P5E_CPU1_P2_TX_BUF_DN(14)    I83 @T6G_MB_LIB.T6G(SCH_1):PAGE450

C6723 Q_CAP_DIFFBUS_C0201-DIFF BUS_0.22UF,6.3V,20%,X6S,SA
     1 P5E_CPU1_P2_TX_BUF_C_DP<15> @T6G_MB_LIB.T6G(SCH_1):P5E_CPU1_P2_TX_BUF_C_DP(15)    I82 @T6G_MB_LIB.T6G(SCH_1):PAGE450
     2 P5E_CPU1_P2_TX_BUF_DP<15> @T6G_MB_LIB.T6G(SCH_1):P5E_CPU1_P2_TX_BUF_DP(15)    I82 @T6G_MB_LIB.T6G(SCH_1):PAGE450

C6724 Q_CAP_DIFFBUS_C0201-DIFF BUS_0.22UF,6.3V,20%,X6S,SA
     1 P5E_CPU1_P2_TX_BUF_C_DN<15> @T6G_MB_LIB.T6G(SCH_1):P5E_CPU1_P2_TX_BUF_C_DN(15)    I81 @T6G_MB_LIB.T6G(SCH_1):PAGE450
     2 P5E_CPU1_P2_TX_BUF_DN<15> @T6G_MB_LIB.T6G(SCH_1):P5E_CPU1_P2_TX_BUF_DN(15)    I81 @T6G_MB_LIB.T6G(SCH_1):PAGE450

C6725 Q_CAP_DIFFBUS_C0201-DIFF BUS_0.22UF,6.3V,20%,X6S,SA
     1 P5E_CPU1_P3_TX_BUF_C_DP<0> @T6G_MB_LIB.T6G(SCH_1):P5E_CPU1_P3_TX_BUF_C_DP(0)    I48 @T6G_MB_LIB.T6G(SCH_1):PAGE461
     2 P5E_CPU1_P3_TX_BUF_DP<0> @T6G_MB_LIB.T6G(SCH_1):P5E_CPU1_P3_TX_BUF_DP(0)    I48 @T6G_MB_LIB.T6G(SCH_1):PAGE461

C6726 Q_CAP_DIFFBUS_C0201-DIFF BUS_0.22UF,6.3V,20%,X6S,SA
     1 P5E_CPU1_P3_TX_BUF_C_DN<0> @T6G_MB_LIB.T6G(SCH_1):P5E_CPU1_P3_TX_BUF_C_DN(0)    I47 @T6G_MB_LIB.T6G(SCH_1):PAGE461
     2 P5E_CPU1_P3_TX_BUF_DN<0> @T6G_MB_LIB.T6G(SCH_1):P5E_CPU1_P3_TX_BUF_DN(0)    I47 @T6G_MB_LIB.T6G(SCH_1):PAGE461

C6727 Q_CAP_DIFFBUS_C0201-DIFF BUS_0.22UF,6.3V,20%,X6S,SA
     1 P5E_CPU1_P3_TX_BUF_C_DP<1> @T6G_MB_LIB.T6G(SCH_1):P5E_CPU1_P3_TX_BUF_C_DP(1)    I32 @T6G_MB_LIB.T6G(SCH_1):PAGE461
     2 P5E_CPU1_P3_TX_BUF_DP<1> @T6G_MB_LIB.T6G(SCH_1):P5E_CPU1_P3_TX_BUF_DP(1)    I32 @T6G_MB_LIB.T6G(SCH_1):PAGE461

C6728 Q_CAP_DIFFBUS_C0201-DIFF BUS_0.22UF,6.3V,20%,X6S,SA
     1 P5E_CPU1_P3_TX_BUF_C_DN<1> @T6G_MB_LIB.T6G(SCH_1):P5E_CPU1_P3_TX_BUF_C_DN(1)    I30 @T6G_MB_LIB.T6G(SCH_1):PAGE461
     2 P5E_CPU1_P3_TX_BUF_DN<1> @T6G_MB_LIB.T6G(SCH_1):P5E_CPU1_P3_TX_BUF_DN(1)    I30 @T6G_MB_LIB.T6G(SCH_1):PAGE461

C6729 Q_CAP_DIFFBUS_C0201-DIFF BUS_0.22UF,6.3V,20%,X6S,SA
     1 P5E_CPU1_P3_TX_BUF_C_DP<2> @T6G_MB_LIB.T6G(SCH_1):P5E_CPU1_P3_TX_BUF_C_DP(2)    I31 @T6G_MB_LIB.T6G(SCH_1):PAGE461
     2 P5E_CPU1_P3_TX_BUF_DP<2> @T6G_MB_LIB.T6G(SCH_1):P5E_CPU1_P3_TX_BUF_DP(2)    I31 @T6G_MB_LIB.T6G(SCH_1):PAGE461

C6730 Q_CAP_DIFFBUS_C0201-DIFF BUS_0.22UF,6.3V,20%,X6S,SA
     1 P5E_CPU1_P3_TX_BUF_C_DN<2> @T6G_MB_LIB.T6G(SCH_1):P5E_CPU1_P3_TX_BUF_C_DN(2)    I29 @T6G_MB_LIB.T6G(SCH_1):PAGE461
     2 P5E_CPU1_P3_TX_BUF_DN<2> @T6G_MB_LIB.T6G(SCH_1):P5E_CPU1_P3_TX_BUF_DN(2)    I29 @T6G_MB_LIB.T6G(SCH_1):PAGE461

C6731 Q_CAP_DIFFBUS_C0201-DIFF BUS_0.22UF,6.3V,20%,X6S,SA
     1 P5E_CPU1_P3_TX_BUF_C_DP<3> @T6G_MB_LIB.T6G(SCH_1):P5E_CPU1_P3_TX_BUF_C_DP(3)    I27 @T6G_MB_LIB.T6G(SCH_1):PAGE461
     2 P5E_CPU1_P3_TX_BUF_DP<3> @T6G_MB_LIB.T6G(SCH_1):P5E_CPU1_P3_TX_BUF_DP(3)    I27 @T6G_MB_LIB.T6G(SCH_1):PAGE461

C6732 Q_CAP_DIFFBUS_C0201-DIFF BUS_0.22UF,6.3V,20%,X6S,SA
     1 P5E_CPU1_P3_TX_BUF_C_DN<3> @T6G_MB_LIB.T6G(SCH_1):P5E_CPU1_P3_TX_BUF_C_DN(3)    I28 @T6G_MB_LIB.T6G(SCH_1):PAGE461
     2 P5E_CPU1_P3_TX_BUF_DN<3> @T6G_MB_LIB.T6G(SCH_1):P5E_CPU1_P3_TX_BUF_DN(3)    I28 @T6G_MB_LIB.T6G(SCH_1):PAGE461

C6733 Q_CAP_DIFFBUS_C0201-DIFF BUS_0.22UF,6.3V,20%,X6S,SA
     1 P5E_CPU1_P3_TX_BUF_C_DP<4> @T6G_MB_LIB.T6G(SCH_1):P5E_CPU1_P3_TX_BUF_C_DP(4)    I26 @T6G_MB_LIB.T6G(SCH_1):PAGE461
     2 P5E_CPU1_P3_TX_BUF_DP<4> @T6G_MB_LIB.T6G(SCH_1):P5E_CPU1_P3_TX_BUF_DP(4)    I26 @T6G_MB_LIB.T6G(SCH_1):PAGE461

C6734 Q_CAP_DIFFBUS_C0201-DIFF BUS_0.22UF,6.3V,20%,X6S,SA
     1 P5E_CPU1_P3_TX_BUF_C_DN<4> @T6G_MB_LIB.T6G(SCH_1):P5E_CPU1_P3_TX_BUF_C_DN(4)    I25 @T6G_MB_LIB.T6G(SCH_1):PAGE461
     2 P5E_CPU1_P3_TX_BUF_DN<4> @T6G_MB_LIB.T6G(SCH_1):P5E_CPU1_P3_TX_BUF_DN(4)    I25 @T6G_MB_LIB.T6G(SCH_1):PAGE461

C6735 Q_CAP_DIFFBUS_C0201-DIFF BUS_0.22UF,6.3V,20%,X6S,SA
     1 P5E_CPU1_P3_TX_BUF_C_DP<5> @T6G_MB_LIB.T6G(SCH_1):P5E_CPU1_P3_TX_BUF_C_DP(5)    I24 @T6G_MB_LIB.T6G(SCH_1):PAGE461
     2 P5E_CPU1_P3_TX_BUF_DP<5> @T6G_MB_LIB.T6G(SCH_1):P5E_CPU1_P3_TX_BUF_DP(5)    I24 @T6G_MB_LIB.T6G(SCH_1):PAGE461

C6736 Q_CAP_DIFFBUS_C0201-DIFF BUS_0.22UF,6.3V,20%,X6S,SA
     1 P5E_CPU1_P3_TX_BUF_C_DN<5> @T6G_MB_LIB.T6G(SCH_1):P5E_CPU1_P3_TX_BUF_C_DN(5)    I23 @T6G_MB_LIB.T6G(SCH_1):PAGE461
     2 P5E_CPU1_P3_TX_BUF_DN<5> @T6G_MB_LIB.T6G(SCH_1):P5E_CPU1_P3_TX_BUF_DN(5)    I23 @T6G_MB_LIB.T6G(SCH_1):PAGE461

C6737 Q_CAP_DIFFBUS_C0201-DIFF BUS_0.22UF,6.3V,20%,X6S,SA
     1 P5E_CPU1_P3_TX_BUF_C_DP<6> @T6G_MB_LIB.T6G(SCH_1):P5E_CPU1_P3_TX_BUF_C_DP(6)    I22 @T6G_MB_LIB.T6G(SCH_1):PAGE461
     2 P5E_CPU1_P3_TX_BUF_DP<6> @T6G_MB_LIB.T6G(SCH_1):P5E_CPU1_P3_TX_BUF_DP(6)    I22 @T6G_MB_LIB.T6G(SCH_1):PAGE461

C6738 Q_CAP_DIFFBUS_C0201-DIFF BUS_0.22UF,6.3V,20%,X6S,SA
     1 P5E_CPU1_P3_TX_BUF_C_DN<6> @T6G_MB_LIB.T6G(SCH_1):P5E_CPU1_P3_TX_BUF_C_DN(6)    I16 @T6G_MB_LIB.T6G(SCH_1):PAGE461
     2 P5E_CPU1_P3_TX_BUF_DN<6> @T6G_MB_LIB.T6G(SCH_1):P5E_CPU1_P3_TX_BUF_DN(6)    I16 @T6G_MB_LIB.T6G(SCH_1):PAGE461

C6739 Q_CAP_DIFFBUS_C0201-DIFF BUS_0.22UF,6.3V,20%,X6S,SA
     1 P5E_CPU1_P3_TX_BUF_C_DP<7> @T6G_MB_LIB.T6G(SCH_1):P5E_CPU1_P3_TX_BUF_C_DP(7)    I17 @T6G_MB_LIB.T6G(SCH_1):PAGE461
     2 P5E_CPU1_P3_TX_BUF_DP<7> @T6G_MB_LIB.T6G(SCH_1):P5E_CPU1_P3_TX_BUF_DP(7)    I17 @T6G_MB_LIB.T6G(SCH_1):PAGE461

C6740 Q_CAP_DIFFBUS_C0201-DIFF BUS_0.22UF,6.3V,20%,X6S,SA
     1 P5E_CPU1_P3_TX_BUF_C_DN<7> @T6G_MB_LIB.T6G(SCH_1):P5E_CPU1_P3_TX_BUF_C_DN(7)    I18 @T6G_MB_LIB.T6G(SCH_1):PAGE461
     2 P5E_CPU1_P3_TX_BUF_DN<7> @T6G_MB_LIB.T6G(SCH_1):P5E_CPU1_P3_TX_BUF_DN(7)    I18 @T6G_MB_LIB.T6G(SCH_1):PAGE461

C6741 Q_CAP_DIFFBUS_C0201-DIFF BUS_0.22UF,6.3V,20%,X6S,SA
     1 P5E_CPU1_P3_TX_BUF_C_DP<8> @T6G_MB_LIB.T6G(SCH_1):P5E_CPU1_P3_TX_BUF_C_DP(8)   I105 @T6G_MB_LIB.T6G(SCH_1):PAGE461
     2 P5E_CPU1_P3_TX_BUF_DP<8> @T6G_MB_LIB.T6G(SCH_1):P5E_CPU1_P3_TX_BUF_DP(8)   I105 @T6G_MB_LIB.T6G(SCH_1):PAGE461

C6742 Q_CAP_DIFFBUS_C0201-DIFF BUS_0.22UF,6.3V,20%,X6S,SA
     1 P5E_CPU1_P3_TX_BUF_C_DN<8> @T6G_MB_LIB.T6G(SCH_1):P5E_CPU1_P3_TX_BUF_C_DN(8)   I104 @T6G_MB_LIB.T6G(SCH_1):PAGE461
     2 P5E_CPU1_P3_TX_BUF_DN<8> @T6G_MB_LIB.T6G(SCH_1):P5E_CPU1_P3_TX_BUF_DN(8)   I104 @T6G_MB_LIB.T6G(SCH_1):PAGE461

C6743 Q_CAP_DIFFBUS_C0201-DIFF BUS_0.22UF,6.3V,20%,X6S,SA
     1 P5E_CPU1_P3_TX_BUF_C_DP<9> @T6G_MB_LIB.T6G(SCH_1):P5E_CPU1_P3_TX_BUF_C_DP(9)   I101 @T6G_MB_LIB.T6G(SCH_1):PAGE461
     2 P5E_CPU1_P3_TX_BUF_DP<9> @T6G_MB_LIB.T6G(SCH_1):P5E_CPU1_P3_TX_BUF_DP(9)   I101 @T6G_MB_LIB.T6G(SCH_1):PAGE461

C6744 Q_CAP_DIFFBUS_C0201-DIFF BUS_0.22UF,6.3V,20%,X6S,SA
     1 P5E_CPU1_P3_TX_BUF_C_DN<9> @T6G_MB_LIB.T6G(SCH_1):P5E_CPU1_P3_TX_BUF_C_DN(9)   I100 @T6G_MB_LIB.T6G(SCH_1):PAGE461
     2 P5E_CPU1_P3_TX_BUF_DN<9> @T6G_MB_LIB.T6G(SCH_1):P5E_CPU1_P3_TX_BUF_DN(9)   I100 @T6G_MB_LIB.T6G(SCH_1):PAGE461

C6745 Q_CAP_DIFFBUS_C0201-DIFF BUS_0.22UF,6.3V,20%,X6S,SA
     1 P5E_CPU1_P3_TX_BUF_C_DP<10> @T6G_MB_LIB.T6G(SCH_1):P5E_CPU1_P3_TX_BUF_C_DP(10)    I99 @T6G_MB_LIB.T6G(SCH_1):PAGE461
     2 P5E_CPU1_P3_TX_BUF_DP<10> @T6G_MB_LIB.T6G(SCH_1):P5E_CPU1_P3_TX_BUF_DP(10)    I99 @T6G_MB_LIB.T6G(SCH_1):PAGE461

C6746 Q_CAP_DIFFBUS_C0201-DIFF BUS_0.22UF,6.3V,20%,X6S,SA
     1 P5E_CPU1_P3_TX_BUF_C_DN<10> @T6G_MB_LIB.T6G(SCH_1):P5E_CPU1_P3_TX_BUF_C_DN(10)    I98 @T6G_MB_LIB.T6G(SCH_1):PAGE461
     2 P5E_CPU1_P3_TX_BUF_DN<10> @T6G_MB_LIB.T6G(SCH_1):P5E_CPU1_P3_TX_BUF_DN(10)    I98 @T6G_MB_LIB.T6G(SCH_1):PAGE461

C6747 Q_CAP_DIFFBUS_C0201-DIFF BUS_0.22UF,6.3V,20%,X6S,SA
     1 P5E_CPU1_P3_TX_BUF_C_DP<11> @T6G_MB_LIB.T6G(SCH_1):P5E_CPU1_P3_TX_BUF_C_DP(11)    I97 @T6G_MB_LIB.T6G(SCH_1):PAGE461
     2 P5E_CPU1_P3_TX_BUF_DP<11> @T6G_MB_LIB.T6G(SCH_1):P5E_CPU1_P3_TX_BUF_DP(11)    I97 @T6G_MB_LIB.T6G(SCH_1):PAGE461

C6748 Q_CAP_DIFFBUS_C0201-DIFF BUS_0.22UF,6.3V,20%,X6S,SA
     1 P5E_CPU1_P3_TX_BUF_C_DN<11> @T6G_MB_LIB.T6G(SCH_1):P5E_CPU1_P3_TX_BUF_C_DN(11)    I96 @T6G_MB_LIB.T6G(SCH_1):PAGE461
     2 P5E_CPU1_P3_TX_BUF_DN<11> @T6G_MB_LIB.T6G(SCH_1):P5E_CPU1_P3_TX_BUF_DN(11)    I96 @T6G_MB_LIB.T6G(SCH_1):PAGE461

C6749 Q_CAP_DIFFBUS_C0201-DIFF BUS_0.22UF,6.3V,20%,X6S,SA
     1 P5E_CPU1_P3_TX_BUF_C_DP<12> @T6G_MB_LIB.T6G(SCH_1):P5E_CPU1_P3_TX_BUF_C_DP(12)    I95 @T6G_MB_LIB.T6G(SCH_1):PAGE461
     2 P5E_CPU1_P3_TX_BUF_DP<12> @T6G_MB_LIB.T6G(SCH_1):P5E_CPU1_P3_TX_BUF_DP(12)    I95 @T6G_MB_LIB.T6G(SCH_1):PAGE461

C6750 Q_CAP_DIFFBUS_C0201-DIFF BUS_0.22UF,6.3V,20%,X6S,SA
     1 P5E_CPU1_P3_TX_BUF_C_DN<12> @T6G_MB_LIB.T6G(SCH_1):P5E_CPU1_P3_TX_BUF_C_DN(12)    I94 @T6G_MB_LIB.T6G(SCH_1):PAGE461
     2 P5E_CPU1_P3_TX_BUF_DN<12> @T6G_MB_LIB.T6G(SCH_1):P5E_CPU1_P3_TX_BUF_DN(12)    I94 @T6G_MB_LIB.T6G(SCH_1):PAGE461

C6751 Q_CAP_DIFFBUS_C0201-DIFF BUS_0.22UF,6.3V,20%,X6S,SA
     1 P5E_CPU1_P3_TX_BUF_C_DP<13> @T6G_MB_LIB.T6G(SCH_1):P5E_CPU1_P3_TX_BUF_C_DP(13)    I93 @T6G_MB_LIB.T6G(SCH_1):PAGE461
     2 P5E_CPU1_P3_TX_BUF_DP<13> @T6G_MB_LIB.T6G(SCH_1):P5E_CPU1_P3_TX_BUF_DP(13)    I93 @T6G_MB_LIB.T6G(SCH_1):PAGE461

C6752 Q_CAP_DIFFBUS_C0201-DIFF BUS_0.22UF,6.3V,20%,X6S,SA
     1 P5E_CPU1_P3_TX_BUF_C_DN<13> @T6G_MB_LIB.T6G(SCH_1):P5E_CPU1_P3_TX_BUF_C_DN(13)    I92 @T6G_MB_LIB.T6G(SCH_1):PAGE461
     2 P5E_CPU1_P3_TX_BUF_DN<13> @T6G_MB_LIB.T6G(SCH_1):P5E_CPU1_P3_TX_BUF_DN(13)    I92 @T6G_MB_LIB.T6G(SCH_1):PAGE461

C6753 Q_CAP_DIFFBUS_C0201-DIFF BUS_0.22UF,6.3V,20%,X6S,SA
     1 P5E_CPU1_P3_TX_BUF_C_DP<14> @T6G_MB_LIB.T6G(SCH_1):P5E_CPU1_P3_TX_BUF_C_DP(14)    I91 @T6G_MB_LIB.T6G(SCH_1):PAGE461
     2 P5E_CPU1_P3_TX_BUF_DP<14> @T6G_MB_LIB.T6G(SCH_1):P5E_CPU1_P3_TX_BUF_DP(14)    I91 @T6G_MB_LIB.T6G(SCH_1):PAGE461

C6754 Q_CAP_DIFFBUS_C0201-DIFF BUS_0.22UF,6.3V,20%,X6S,SA
     1 P5E_CPU1_P3_TX_BUF_C_DN<14> @T6G_MB_LIB.T6G(SCH_1):P5E_CPU1_P3_TX_BUF_C_DN(14)    I90 @T6G_MB_LIB.T6G(SCH_1):PAGE461
     2 P5E_CPU1_P3_TX_BUF_DN<14> @T6G_MB_LIB.T6G(SCH_1):P5E_CPU1_P3_TX_BUF_DN(14)    I90 @T6G_MB_LIB.T6G(SCH_1):PAGE461

C6755 Q_CAP_DIFFBUS_C0201-DIFF BUS_0.22UF,6.3V,20%,X6S,SA
     1 P5E_CPU1_P3_TX_BUF_C_DP<15> @T6G_MB_LIB.T6G(SCH_1):P5E_CPU1_P3_TX_BUF_C_DP(15)    I89 @T6G_MB_LIB.T6G(SCH_1):PAGE461
     2 P5E_CPU1_P3_TX_BUF_DP<15> @T6G_MB_LIB.T6G(SCH_1):P5E_CPU1_P3_TX_BUF_DP(15)    I89 @T6G_MB_LIB.T6G(SCH_1):PAGE461

C6756 Q_CAP_DIFFBUS_C0201-DIFF BUS_0.22UF,6.3V,20%,X6S,SA
     1 P5E_CPU1_P3_TX_BUF_C_DN<15> @T6G_MB_LIB.T6G(SCH_1):P5E_CPU1_P3_TX_BUF_C_DN(15)    I88 @T6G_MB_LIB.T6G(SCH_1):PAGE461
     2 P5E_CPU1_P3_TX_BUF_DN<15> @T6G_MB_LIB.T6G(SCH_1):P5E_CPU1_P3_TX_BUF_DN(15)    I88 @T6G_MB_LIB.T6G(SCH_1):PAGE461

C6757 Q_CAP_0402-0.1UF,25V,10%,EMPTY,CH4104K1B00
     1 P1V8_RETIMER_CPU0_EN @T6G_MB_LIB.T6G(SCH_1):P1V8_RETIMER_CPU0_EN     I5 @T6G_MB_LIB.T6G(SCH_1):PAGE469
     2    GND @T6G_MB_LIB.T6G(SCH_1):GND     I5 @T6G_MB_LIB.T6G(SCH_1):PAGE469

C6758 Q_CAP_0402-1000PF,50V,5%,X7R,TMP_QCH21006JB10
     1 FM_PWRGD_P1V8_RETIMER_CPU0 @T6G_MB_LIB.T6G(SCH_1):FM_PWRGD_P1V8_RETIMER_CPU0    I42 @T6G_MB_LIB.T6G(SCH_1):PAGE469
     2    GND @T6G_MB_LIB.T6G(SCH_1):GND    I42 @T6G_MB_LIB.T6G(SCH_1):PAGE469

C7000 Q_CAPP_SMLF-470UF,2.5V,20%,SPCAP,CH747LM8818
     1 P0V9_CPU0_RT_2D @T6G_MB_LIB.T6G(SCH_1):P0V9_CPU0_RT_2D    I98 @T6G_MB_LIB.T6G(SCH_1):PAGE388
     2    GND @T6G_MB_LIB.T6G(SCH_1):GND    I98 @T6G_MB_LIB.T6G(SCH_1):PAGE388

C7001 Q_CAPP_SMLF-470UF,2.5V,20%,SPCAP,CH747LM8818
     1 P0V9_CPU0_RT_2D @T6G_MB_LIB.T6G(SCH_1):P0V9_CPU0_RT_2D    I97 @T6G_MB_LIB.T6G(SCH_1):PAGE388
     2    GND @T6G_MB_LIB.T6G(SCH_1):GND    I97 @T6G_MB_LIB.T6G(SCH_1):PAGE388

C7002 Q_CAP_C0805-47UF,4V,20%,X6S,CH647KMEA04
     1 P0V9_CPU0_RT_2D @T6G_MB_LIB.T6G(SCH_1):P0V9_CPU0_RT_2D    I96 @T6G_MB_LIB.T6G(SCH_1):PAGE388
     2    GND @T6G_MB_LIB.T6G(SCH_1):GND    I96 @T6G_MB_LIB.T6G(SCH_1):PAGE388

C7003 Q_CAP_C0805-47UF,4V,20%,X6S,CH647KMEA04
     1 P0V9_CPU0_RT_2D @T6G_MB_LIB.T6G(SCH_1):P0V9_CPU0_RT_2D    I95 @T6G_MB_LIB.T6G(SCH_1):PAGE388
     2    GND @T6G_MB_LIB.T6G(SCH_1):GND    I95 @T6G_MB_LIB.T6G(SCH_1):PAGE388

C7004 Q_CAPP_SMLF-470UF,2.5V,20%,SPCAP,CH747LM8818
     1 P0V9_CPU1_RT_2D @T6G_MB_LIB.T6G(SCH_1):P0V9_CPU1_RT_2D    I94 @T6G_MB_LIB.T6G(SCH_1):PAGE454
     2    GND @T6G_MB_LIB.T6G(SCH_1):GND    I94 @T6G_MB_LIB.T6G(SCH_1):PAGE454

C7005 Q_CAPP_SMLF-470UF,2.5V,20%,SPCAP,CH747LM8818
     1 P0V9_CPU1_RT_2D @T6G_MB_LIB.T6G(SCH_1):P0V9_CPU1_RT_2D    I95 @T6G_MB_LIB.T6G(SCH_1):PAGE454
     2    GND @T6G_MB_LIB.T6G(SCH_1):GND    I95 @T6G_MB_LIB.T6G(SCH_1):PAGE454

C7006 Q_CAP_C0805-47UF,4V,20%,X6S,CH647KMEA04
     1 P0V9_CPU1_RT_2D @T6G_MB_LIB.T6G(SCH_1):P0V9_CPU1_RT_2D    I96 @T6G_MB_LIB.T6G(SCH_1):PAGE454
     2    GND @T6G_MB_LIB.T6G(SCH_1):GND    I96 @T6G_MB_LIB.T6G(SCH_1):PAGE454

C7007 Q_CAP_C0805-47UF,4V,20%,X6S,CH647KMEA04
     1 P0V9_CPU1_RT_2D @T6G_MB_LIB.T6G(SCH_1):P0V9_CPU1_RT_2D    I97 @T6G_MB_LIB.T6G(SCH_1):PAGE454
     2    GND @T6G_MB_LIB.T6G(SCH_1):GND    I97 @T6G_MB_LIB.T6G(SCH_1):PAGE454

C7008 Q_CAPP_SMLF-470UF,2.5V,20%,SPCAP,CH747LM8818
     1 P0V9_CPU0_RT0_2A @T6G_MB_LIB.T6G(SCH_1):P0V9_CPU0_RT0_2A    I99 @T6G_MB_LIB.T6G(SCH_1):PAGE388
     2    GND @T6G_MB_LIB.T6G(SCH_1):GND    I99 @T6G_MB_LIB.T6G(SCH_1):PAGE388

C7009 Q_CAPP_SMLF-470UF,2.5V,20%,SPCAP,CH747LM8818
     1 P0V9_CPU0_RT0_2A @T6G_MB_LIB.T6G(SCH_1):P0V9_CPU0_RT0_2A   I100 @T6G_MB_LIB.T6G(SCH_1):PAGE388
     2    GND @T6G_MB_LIB.T6G(SCH_1):GND   I100 @T6G_MB_LIB.T6G(SCH_1):PAGE388

C7010 Q_CAP_C0805-100UF,4V,20%,X6S,CH710KMEA01
     1 P0V9_CPU0_RT0_2A @T6G_MB_LIB.T6G(SCH_1):P0V9_CPU0_RT0_2A   I101 @T6G_MB_LIB.T6G(SCH_1):PAGE388
     2    GND @T6G_MB_LIB.T6G(SCH_1):GND   I101 @T6G_MB_LIB.T6G(SCH_1):PAGE388

C7011 Q_CAPP_SMLF-470UF,2.5V,20%,SPCAP,CH747LM8818
     1 P0V9_CPU0_RT1_2A @T6G_MB_LIB.T6G(SCH_1):P0V9_CPU0_RT1_2A    I95 @T6G_MB_LIB.T6G(SCH_1):PAGE411
     2    GND @T6G_MB_LIB.T6G(SCH_1):GND    I95 @T6G_MB_LIB.T6G(SCH_1):PAGE411

C7012 Q_CAPP_SMLF-470UF,2.5V,20%,SPCAP,CH747LM8818
     1 P0V9_CPU0_RT1_2A @T6G_MB_LIB.T6G(SCH_1):P0V9_CPU0_RT1_2A    I96 @T6G_MB_LIB.T6G(SCH_1):PAGE411
     2    GND @T6G_MB_LIB.T6G(SCH_1):GND    I96 @T6G_MB_LIB.T6G(SCH_1):PAGE411

C7013 Q_CAP_C0805-100UF,4V,20%,X6S,CH710KMEA01
     1 P0V9_CPU0_RT1_2A @T6G_MB_LIB.T6G(SCH_1):P0V9_CPU0_RT1_2A    I97 @T6G_MB_LIB.T6G(SCH_1):PAGE411
     2    GND @T6G_MB_LIB.T6G(SCH_1):GND    I97 @T6G_MB_LIB.T6G(SCH_1):PAGE411

C7014 Q_CAPP_SMLF-470UF,2.5V,20%,SPCAP,CH747LM8818
     1 P0V9_CPU0_RT2_2A @T6G_MB_LIB.T6G(SCH_1):P0V9_CPU0_RT2_2A    I94 @T6G_MB_LIB.T6G(SCH_1):PAGE422
     2    GND @T6G_MB_LIB.T6G(SCH_1):GND    I94 @T6G_MB_LIB.T6G(SCH_1):PAGE422

C7015 Q_CAPP_SMLF-470UF,2.5V,20%,SPCAP,CH747LM8818
     1 P0V9_CPU0_RT2_2A @T6G_MB_LIB.T6G(SCH_1):P0V9_CPU0_RT2_2A    I95 @T6G_MB_LIB.T6G(SCH_1):PAGE422
     2    GND @T6G_MB_LIB.T6G(SCH_1):GND    I95 @T6G_MB_LIB.T6G(SCH_1):PAGE422

C7016 Q_CAP_C0805-100UF,4V,20%,X6S,CH710KMEA01
     1 P0V9_CPU0_RT2_2A @T6G_MB_LIB.T6G(SCH_1):P0V9_CPU0_RT2_2A    I96 @T6G_MB_LIB.T6G(SCH_1):PAGE422
     2    GND @T6G_MB_LIB.T6G(SCH_1):GND    I96 @T6G_MB_LIB.T6G(SCH_1):PAGE422

C7017 Q_CAPP_SMLF-470UF,2.5V,20%,SPCAP,CH747LM8818
     1 P0V9_CPU0_RT3_2A @T6G_MB_LIB.T6G(SCH_1):P0V9_CPU0_RT3_2A    I94 @T6G_MB_LIB.T6G(SCH_1):PAGE433
     2    GND @T6G_MB_LIB.T6G(SCH_1):GND    I94 @T6G_MB_LIB.T6G(SCH_1):PAGE433

C7018 Q_CAPP_SMLF-470UF,2.5V,20%,SPCAP,CH747LM8818
     1 P0V9_CPU0_RT3_2A @T6G_MB_LIB.T6G(SCH_1):P0V9_CPU0_RT3_2A    I95 @T6G_MB_LIB.T6G(SCH_1):PAGE433
     2    GND @T6G_MB_LIB.T6G(SCH_1):GND    I95 @T6G_MB_LIB.T6G(SCH_1):PAGE433

C7019 Q_CAP_C0805-100UF,4V,20%,X6S,CH710KMEA01
     1 P0V9_CPU0_RT3_2A @T6G_MB_LIB.T6G(SCH_1):P0V9_CPU0_RT3_2A    I96 @T6G_MB_LIB.T6G(SCH_1):PAGE433
     2    GND @T6G_MB_LIB.T6G(SCH_1):GND    I96 @T6G_MB_LIB.T6G(SCH_1):PAGE433

C7020 Q_CAPP_SMLF-470UF,2.5V,20%,SPCAP,CH747LM8818
     1 P0V9_CPU1_RT0_2A @T6G_MB_LIB.T6G(SCH_1):P0V9_CPU1_RT0_2A   I103 @T6G_MB_LIB.T6G(SCH_1):PAGE398
     2    GND @T6G_MB_LIB.T6G(SCH_1):GND   I103 @T6G_MB_LIB.T6G(SCH_1):PAGE398

C7021 Q_CAPP_SMLF-470UF,2.5V,20%,SPCAP,CH747LM8818
     1 P0V9_CPU1_RT0_2A @T6G_MB_LIB.T6G(SCH_1):P0V9_CPU1_RT0_2A   I104 @T6G_MB_LIB.T6G(SCH_1):PAGE398
     2    GND @T6G_MB_LIB.T6G(SCH_1):GND   I104 @T6G_MB_LIB.T6G(SCH_1):PAGE398

C7022 Q_CAP_C0805-100UF,4V,20%,X6S,CH710KMEA01
     1 P0V9_CPU1_RT0_2A @T6G_MB_LIB.T6G(SCH_1):P0V9_CPU1_RT0_2A   I105 @T6G_MB_LIB.T6G(SCH_1):PAGE398
     2    GND @T6G_MB_LIB.T6G(SCH_1):GND   I105 @T6G_MB_LIB.T6G(SCH_1):PAGE398

C7023 Q_CAPP_SMLF-470UF,2.5V,20%,SPCAP,CH747LM8818
     1 P0V9_CPU1_RT1_2A @T6G_MB_LIB.T6G(SCH_1):P0V9_CPU1_RT1_2A    I94 @T6G_MB_LIB.T6G(SCH_1):PAGE443
     2    GND @T6G_MB_LIB.T6G(SCH_1):GND    I94 @T6G_MB_LIB.T6G(SCH_1):PAGE443

C7024 Q_CAPP_SMLF-470UF,2.5V,20%,SPCAP,CH747LM8818
     1 P0V9_CPU1_RT1_2A @T6G_MB_LIB.T6G(SCH_1):P0V9_CPU1_RT1_2A    I95 @T6G_MB_LIB.T6G(SCH_1):PAGE443
     2    GND @T6G_MB_LIB.T6G(SCH_1):GND    I95 @T6G_MB_LIB.T6G(SCH_1):PAGE443

C7025 Q_CAP_C0805-100UF,4V,20%,X6S,CH710KMEA01
     1 P0V9_CPU1_RT1_2A @T6G_MB_LIB.T6G(SCH_1):P0V9_CPU1_RT1_2A    I96 @T6G_MB_LIB.T6G(SCH_1):PAGE443
     2    GND @T6G_MB_LIB.T6G(SCH_1):GND    I96 @T6G_MB_LIB.T6G(SCH_1):PAGE443

C7026 Q_CAPP_SMLF-470UF,2.5V,20%,SPCAP,CH747LM8818
     1 P0V9_CPU1_RT2_2A @T6G_MB_LIB.T6G(SCH_1):P0V9_CPU1_RT2_2A    I98 @T6G_MB_LIB.T6G(SCH_1):PAGE454
     2    GND @T6G_MB_LIB.T6G(SCH_1):GND    I98 @T6G_MB_LIB.T6G(SCH_1):PAGE454

C7027 Q_CAPP_SMLF-470UF,2.5V,20%,SPCAP,CH747LM8818
     1 P0V9_CPU1_RT2_2A @T6G_MB_LIB.T6G(SCH_1):P0V9_CPU1_RT2_2A    I99 @T6G_MB_LIB.T6G(SCH_1):PAGE454
     2    GND @T6G_MB_LIB.T6G(SCH_1):GND    I99 @T6G_MB_LIB.T6G(SCH_1):PAGE454

C7028 Q_CAP_C0805-100UF,4V,20%,X6S,CH710KMEA01
     1 P0V9_CPU1_RT2_2A @T6G_MB_LIB.T6G(SCH_1):P0V9_CPU1_RT2_2A   I100 @T6G_MB_LIB.T6G(SCH_1):PAGE454
     2    GND @T6G_MB_LIB.T6G(SCH_1):GND   I100 @T6G_MB_LIB.T6G(SCH_1):PAGE454

C7029 Q_CAPP_SMLF-470UF,2.5V,20%,SPCAP,CH747LM8818
     1 P0V9_CPU1_RT3_2A @T6G_MB_LIB.T6G(SCH_1):P0V9_CPU1_RT3_2A    I94 @T6G_MB_LIB.T6G(SCH_1):PAGE465
     2    GND @T6G_MB_LIB.T6G(SCH_1):GND    I94 @T6G_MB_LIB.T6G(SCH_1):PAGE465

C7030 Q_CAPP_SMLF-470UF,2.5V,20%,SPCAP,CH747LM8818
     1 P0V9_CPU1_RT3_2A @T6G_MB_LIB.T6G(SCH_1):P0V9_CPU1_RT3_2A    I95 @T6G_MB_LIB.T6G(SCH_1):PAGE465
     2    GND @T6G_MB_LIB.T6G(SCH_1):GND    I95 @T6G_MB_LIB.T6G(SCH_1):PAGE465

C7031 Q_CAP_C0805-100UF,4V,20%,X6S,CH710KMEA01
     1 P0V9_CPU1_RT3_2A @T6G_MB_LIB.T6G(SCH_1):P0V9_CPU1_RT3_2A    I96 @T6G_MB_LIB.T6G(SCH_1):PAGE465
     2    GND @T6G_MB_LIB.T6G(SCH_1):GND    I96 @T6G_MB_LIB.T6G(SCH_1):PAGE465

C7032 Q_CAPP_SMLF-470UF,2.5V,20%,SPCAP,CH747LM8818
     1 P0V9_CPU0_RT_2D @T6G_MB_LIB.T6G(SCH_1):P0V9_CPU0_RT_2D   I102 @T6G_MB_LIB.T6G(SCH_1):PAGE388
     2    GND @T6G_MB_LIB.T6G(SCH_1):GND   I102 @T6G_MB_LIB.T6G(SCH_1):PAGE388

C7033 Q_CAP_C0805-47UF,4V,20%,X6S,CH647KMEA04
     1 P0V9_CPU0_RT_2D @T6G_MB_LIB.T6G(SCH_1):P0V9_CPU0_RT_2D   I103 @T6G_MB_LIB.T6G(SCH_1):PAGE388
     2    GND @T6G_MB_LIB.T6G(SCH_1):GND   I103 @T6G_MB_LIB.T6G(SCH_1):PAGE388

C7034 Q_CAP_C0805-47UF,4V,20%,X6S,CH647KMEA04
     1 P0V9_CPU0_RT_2D @T6G_MB_LIB.T6G(SCH_1):P0V9_CPU0_RT_2D   I104 @T6G_MB_LIB.T6G(SCH_1):PAGE388
     2    GND @T6G_MB_LIB.T6G(SCH_1):GND   I104 @T6G_MB_LIB.T6G(SCH_1):PAGE388

C7035 Q_CAP_C0805-47UF,4V,20%,X6S,CH647KMEA04
     1 P0V9_CPU0_RT_2D @T6G_MB_LIB.T6G(SCH_1):P0V9_CPU0_RT_2D   I105 @T6G_MB_LIB.T6G(SCH_1):PAGE388
     2    GND @T6G_MB_LIB.T6G(SCH_1):GND   I105 @T6G_MB_LIB.T6G(SCH_1):PAGE388

C7036 Q_CAP_C0805-47UF,4V,20%,X6S,CH647KMEA04
     1 P0V9_CPU0_RT_2D @T6G_MB_LIB.T6G(SCH_1):P0V9_CPU0_RT_2D   I106 @T6G_MB_LIB.T6G(SCH_1):PAGE388
     2    GND @T6G_MB_LIB.T6G(SCH_1):GND   I106 @T6G_MB_LIB.T6G(SCH_1):PAGE388

C7037 Q_CAPP_SMLF-470UF,2.5V,20%,SPCAP,CH747LM8818
     1 P0V9_CPU1_RT_2D @T6G_MB_LIB.T6G(SCH_1):P0V9_CPU1_RT_2D   I101 @T6G_MB_LIB.T6G(SCH_1):PAGE454
     2    GND @T6G_MB_LIB.T6G(SCH_1):GND   I101 @T6G_MB_LIB.T6G(SCH_1):PAGE454

C7038 Q_CAP_C0805-47UF,4V,20%,X6S,CH647KMEA04
     1 P0V9_CPU1_RT_2D @T6G_MB_LIB.T6G(SCH_1):P0V9_CPU1_RT_2D   I102 @T6G_MB_LIB.T6G(SCH_1):PAGE454
     2    GND @T6G_MB_LIB.T6G(SCH_1):GND   I102 @T6G_MB_LIB.T6G(SCH_1):PAGE454

C7039 Q_CAP_C0805-47UF,4V,20%,X6S,CH647KMEA04
     1 P0V9_CPU1_RT_2D @T6G_MB_LIB.T6G(SCH_1):P0V9_CPU1_RT_2D   I103 @T6G_MB_LIB.T6G(SCH_1):PAGE454
     2    GND @T6G_MB_LIB.T6G(SCH_1):GND   I103 @T6G_MB_LIB.T6G(SCH_1):PAGE454

C7040 Q_CAP_C0805-47UF,4V,20%,X6S,CH647KMEA04
     1 P0V9_CPU1_RT_2D @T6G_MB_LIB.T6G(SCH_1):P0V9_CPU1_RT_2D   I104 @T6G_MB_LIB.T6G(SCH_1):PAGE454
     2    GND @T6G_MB_LIB.T6G(SCH_1):GND   I104 @T6G_MB_LIB.T6G(SCH_1):PAGE454

C7041 Q_CAP_C0805-47UF,4V,20%,X6S,CH647KMEA04
     1 P0V9_CPU1_RT_2D @T6G_MB_LIB.T6G(SCH_1):P0V9_CPU1_RT_2D   I105 @T6G_MB_LIB.T6G(SCH_1):PAGE454
     2    GND @T6G_MB_LIB.T6G(SCH_1):GND   I105 @T6G_MB_LIB.T6G(SCH_1):PAGE454

C7500 Q_CAP_C0201-0.1UF,10V,10%,X7S,CH4102K6E00
     1 P1V8_AUX @T6G_MB_LIB.T6G(SCH_1):P1V8_AUX    I88 @T6G_MB_LIB.T6G(SCH_1):PAGE378
     2    GND @T6G_MB_LIB.T6G(SCH_1):GND    I88 @T6G_MB_LIB.T6G(SCH_1):PAGE378

C7501 Q_CAP_C0201-0.1UF,10V,10%,X7S,CH4102K6E00
     1 P1V8_CPU1_RT_1D @T6G_MB_LIB.T6G(SCH_1):P1V8_CPU1_RT_1D    I11 @T6G_MB_LIB.T6G(SCH_1):PAGE399
     2    GND @T6G_MB_LIB.T6G(SCH_1):GND    I11 @T6G_MB_LIB.T6G(SCH_1):PAGE399

C7502 Q_CAP_C0201-0.1UF,10V,10%,X7S,CH4102K6E00
     1 P1V8_CPU1_RT_1D @T6G_MB_LIB.T6G(SCH_1):P1V8_CPU1_RT_1D    I22 @T6G_MB_LIB.T6G(SCH_1):PAGE442
     2    GND @T6G_MB_LIB.T6G(SCH_1):GND    I22 @T6G_MB_LIB.T6G(SCH_1):PAGE442

C7503 Q_CAP_C0201-0.1UF,10V,10%,X7S,CH4102K6E00
     1 P1V8_CPU1_RT_1D @T6G_MB_LIB.T6G(SCH_1):P1V8_CPU1_RT_1D    I23 @T6G_MB_LIB.T6G(SCH_1):PAGE453
     2    GND @T6G_MB_LIB.T6G(SCH_1):GND    I23 @T6G_MB_LIB.T6G(SCH_1):PAGE453

C7504 Q_CAP_C0201-0.1UF,10V,10%,X7S,CH4102K6E00
     1 P1V8_CPU1_RT_1D @T6G_MB_LIB.T6G(SCH_1):P1V8_CPU1_RT_1D    I19 @T6G_MB_LIB.T6G(SCH_1):PAGE464
     2    GND @T6G_MB_LIB.T6G(SCH_1):GND    I19 @T6G_MB_LIB.T6G(SCH_1):PAGE464

C7510 Q_CAP_C0201-0.1UF,10V,10%,X7S,CH4102K6E00
     1 P1V8_CPU0_RT_1D @T6G_MB_LIB.T6G(SCH_1):P1V8_CPU0_RT_1D    I21 @T6G_MB_LIB.T6G(SCH_1):PAGE387
     2    GND @T6G_MB_LIB.T6G(SCH_1):GND    I21 @T6G_MB_LIB.T6G(SCH_1):PAGE387

C8000 Q_CAP_0402-1000PF,50V,5%,EMPTY,TMP_QCH21006JB10
     1 PRSNT_SWB_ISO_N @T6G_MB_LIB.T6G(SCH_1):PRSNT_SWB_ISO_N    I36 @T6G_MB_LIB.T6G(SCH_1):PAGE330
     2    GND @T6G_MB_LIB.T6G(SCH_1):GND    I36 @T6G_MB_LIB.T6G(SCH_1):PAGE330

C8001 Q_CAP_0402-0.1UF,25V,10%,EMPTY,CH4104K1B00
     1 OCP_SFF_PRSNT01_R1_N @T6G_MB_LIB.T6G(SCH_1):OCP_SFF_PRSNT01_R1_N    I68 @T6G_MB_LIB.T6G(SCH_1):PAGE258
     2    GND @T6G_MB_LIB.T6G(SCH_1):GND    I68 @T6G_MB_LIB.T6G(SCH_1):PAGE258

C8002 Q_CAP_0402-0.1UF,25V,10%,EMPTY,CH4104K1B00
     1 OCP_SFF_PRSNT23_R1_N @T6G_MB_LIB.T6G(SCH_1):OCP_SFF_PRSNT23_R1_N    I70 @T6G_MB_LIB.T6G(SCH_1):PAGE258
     2    GND @T6G_MB_LIB.T6G(SCH_1):GND    I70 @T6G_MB_LIB.T6G(SCH_1):PAGE258

C8003 Q_CAP_0402-0.1UF,25V,10%,EMPTY,CH4104K1B00
     1 OCP_V3_2_PRSNT01_R1_N @T6G_MB_LIB.T6G(SCH_1):OCP_V3_2_PRSNT01_R1_N    I72 @T6G_MB_LIB.T6G(SCH_1):PAGE258
     2    GND @T6G_MB_LIB.T6G(SCH_1):GND    I72 @T6G_MB_LIB.T6G(SCH_1):PAGE258

C8004 Q_CAP_0402-0.1UF,25V,10%,EMPTY,CH4104K1B00
     1 OCP_V3_2_PRSNT23_R1_N @T6G_MB_LIB.T6G(SCH_1):OCP_V3_2_PRSNT23_R1_N    I74 @T6G_MB_LIB.T6G(SCH_1):PAGE258
     2    GND @T6G_MB_LIB.T6G(SCH_1):GND    I74 @T6G_MB_LIB.T6G(SCH_1):PAGE258

C8005 Q_CAP_0402-0.1UF,25V,10%,X7R,CH4104K1B00
     1 PWRGD_P5V_AUX_R3 @T6G_MB_LIB.T6G(SCH_1):PWRGD_P5V_AUX_R3   I101 @T6G_MB_LIB.T6G(SCH_1):PAGE84
     2    GND @T6G_MB_LIB.T6G(SCH_1):GND   I101 @T6G_MB_LIB.T6G(SCH_1):PAGE84

C8006 Q_CAP_0402-0.1UF,25V,10%,X7R,CH4104K1B00
     1 JTAG_BMC_R_D_OE @T6G_MB_LIB.T6G(SCH_1):JTAG_BMC_R_D_OE   I163 @T6G_MB_LIB.T6G(SCH_1):PAGE149
     2    GND @T6G_MB_LIB.T6G(SCH_1):GND   I163 @T6G_MB_LIB.T6G(SCH_1):PAGE149

C8007 Q_CAP_0402-0.1UF,25V,10%,X7R,CH4104K1B00
     1 P1V8_AUX @T6G_MB_LIB.T6G(SCH_1):P1V8_AUX     I4 @T6G_MB_LIB.T6G(SCH_1):PAGE130
     2    GND @T6G_MB_LIB.T6G(SCH_1):GND     I4 @T6G_MB_LIB.T6G(SCH_1):PAGE130

C8008 Q_CAP_0402-0.1UF,25V,10%,X7R,CH4104K1B00
     1 P3V3_OCP_SFF_R @T6G_MB_LIB.T6G(SCH_1):P3V3_OCP_SFF_R    I79 @T6G_MB_LIB.T6G(SCH_1):PAGE340
     2    GND @T6G_MB_LIB.T6G(SCH_1):GND    I79 @T6G_MB_LIB.T6G(SCH_1):PAGE340

C8009 Q_CAP_0402-0.1UF,25V,10%,X7R,CH4104K1B00
     1 P3V3_OCP_V3_2_R @T6G_MB_LIB.T6G(SCH_1):P3V3_OCP_V3_2_R    I66 @T6G_MB_LIB.T6G(SCH_1):PAGE257
     2    GND @T6G_MB_LIB.T6G(SCH_1):GND    I66 @T6G_MB_LIB.T6G(SCH_1):PAGE257

C8010 Q_CAP_0402-0.1UF,25V,10%,X7R,CH4104K1B00
     1 P3V3_E1S_0_R @T6G_MB_LIB.T6G(SCH_1):P3V3_E1S_0_R    I64 @T6G_MB_LIB.T6G(SCH_1):PAGE323
     2    GND @T6G_MB_LIB.T6G(SCH_1):GND    I64 @T6G_MB_LIB.T6G(SCH_1):PAGE323

C8011 Q_CAP_0402-0.1UF,25V,10%,EMPTY,CH4104K1B00
     1 FM_AC_PWR_BTN_PDB_N @T6G_MB_LIB.T6G(SCH_1):FM_AC_PWR_BTN_PDB_N   I469 @T6G_MB_LIB.T6G(SCH_1):PAGE363
     2    GND @T6G_MB_LIB.T6G(SCH_1):GND   I469 @T6G_MB_LIB.T6G(SCH_1):PAGE363

C8012 Q_CAP_C0402-1UF,25V,10%,EMPTY,CH5104KEB02
     1 FM_AC_PWR_BTN_R_N @T6G_MB_LIB.T6G(SCH_1):FM_AC_PWR_BTN_R_N    I25 @T6G_MB_LIB.T6G(SCH_1):PAGE365
     2    GND @T6G_MB_LIB.T6G(SCH_1):GND    I25 @T6G_MB_LIB.T6G(SCH_1):PAGE365

C8013 Q_CAP_0402-0.1UF,25V,10%,EMPTY,CH4104K1B00
     1 P3V3_AUX @T6G_MB_LIB.T6G(SCH_1):P3V3_AUX    I23 @T6G_MB_LIB.T6G(SCH_1):PAGE365
     2    GND @T6G_MB_LIB.T6G(SCH_1):GND    I23 @T6G_MB_LIB.T6G(SCH_1):PAGE365

C8014 Q_CAP_C0402-100NF,50V,10%,EMPTY,CH4106K1B01
     1 OC_P2V5_COMP @T6G_MB_LIB.T6G(SCH_1):OC_P2V5_COMP    I87 @T6G_MB_LIB.T6G(SCH_1):PAGE371
     2    GND @T6G_MB_LIB.T6G(SCH_1):GND    I87 @T6G_MB_LIB.T6G(SCH_1):PAGE371

C8015 Q_CAP_C0402-100NF,50V,10%,EMPTY,CH4106K1B01
     1 HSC_OC_VOL @T6G_MB_LIB.T6G(SCH_1):HSC_OC_VOL    I89 @T6G_MB_LIB.T6G(SCH_1):PAGE371
     2    GND @T6G_MB_LIB.T6G(SCH_1):GND    I89 @T6G_MB_LIB.T6G(SCH_1):PAGE371

C8016 Q_CAP_C0402-100NF,50V,10%,EMPTY,CH4106K1B01
     1 P12V_AUX @T6G_MB_LIB.T6G(SCH_1):P12V_AUX    I95 @T6G_MB_LIB.T6G(SCH_1):PAGE371
     2    GND @T6G_MB_LIB.T6G(SCH_1):GND    I95 @T6G_MB_LIB.T6G(SCH_1):PAGE371

C8017 Q_CAP_C0402-100NF,50V,10%,EMPTY,CH4106K1B01
     1 UV_ADR_P2V5_COMP @T6G_MB_LIB.T6G(SCH_1):UV_ADR_P2V5_COMP    I59 @T6G_MB_LIB.T6G(SCH_1):PAGE372
     2    GND @T6G_MB_LIB.T6G(SCH_1):GND    I59 @T6G_MB_LIB.T6G(SCH_1):PAGE372

C8018 Q_CAP_C0402-100NF,50V,10%,EMPTY,CH4106K1B01
     1 P12V_AUX_UV_ADR_TRIGGER @T6G_MB_LIB.T6G(SCH_1):P12V_AUX_UV_ADR_TRIGGER    I61 @T6G_MB_LIB.T6G(SCH_1):PAGE372
     2    GND @T6G_MB_LIB.T6G(SCH_1):GND    I61 @T6G_MB_LIB.T6G(SCH_1):PAGE372

C8019 Q_CAP_C0402-100NF,50V,10%,X7R,CH4106K1B01
     1 P12V_AUX @T6G_MB_LIB.T6G(SCH_1):P12V_AUX    I66 @T6G_MB_LIB.T6G(SCH_1):PAGE372
     2    GND @T6G_MB_LIB.T6G(SCH_1):GND    I66 @T6G_MB_LIB.T6G(SCH_1):PAGE372

C8020 Q_CAP_C0402-100NF,50V,10%,EMPTY,CH4106K1B01
     1 UV_P2V5_COMP @T6G_MB_LIB.T6G(SCH_1):UV_P2V5_COMP    I79 @T6G_MB_LIB.T6G(SCH_1):PAGE372
     2    GND @T6G_MB_LIB.T6G(SCH_1):GND    I79 @T6G_MB_LIB.T6G(SCH_1):PAGE372

C8021 Q_CAP_C0402-100NF,50V,10%,EMPTY,CH4106K1B01
     1 P12V_AUX_UV_TRIGGER @T6G_MB_LIB.T6G(SCH_1):P12V_AUX_UV_TRIGGER    I92 @T6G_MB_LIB.T6G(SCH_1):PAGE372
     2    GND @T6G_MB_LIB.T6G(SCH_1):GND    I92 @T6G_MB_LIB.T6G(SCH_1):PAGE372

C8022 Q_CAP_C0402-100NF,50V,10%,X7R,CH4106K1B01
     1 P12V_AUX @T6G_MB_LIB.T6G(SCH_1):P12V_AUX    I84 @T6G_MB_LIB.T6G(SCH_1):PAGE372
     2    GND @T6G_MB_LIB.T6G(SCH_1):GND    I84 @T6G_MB_LIB.T6G(SCH_1):PAGE372

C8066 Q_CAP_0402-1000PF,50V,5%,X7R,TMP_QCH21006JB10
     1 PVDDIO_P0_EN_R @T6G_MB_LIB.T6G(SCH_1):PVDDIO_P0_EN_R     I3 @T6G_MB_LIB.T6G(SCH_1):PAGE175
     2    GND @T6G_MB_LIB.T6G(SCH_1):GND     I3 @T6G_MB_LIB.T6G(SCH_1):PAGE175

C8069 Q_CAP_0402-1000PF,50V,5%,X7R,TMP_QCH21006JB10
     1 PVDDCR_CPU1_P0_EN_R @T6G_MB_LIB.T6G(SCH_1):PVDDCR_CPU1_P0_EN_R    I86 @T6G_MB_LIB.T6G(SCH_1):PAGE175
     2    GND @T6G_MB_LIB.T6G(SCH_1):GND    I86 @T6G_MB_LIB.T6G(SCH_1):PAGE175

C8070 Q_CAP_0402-1000PF,50V,5%,EMPTY,TMP_QCH21006JB10
     1 PWRGD_PVDDCR_CPU1_P0_R @T6G_MB_LIB.T6G(SCH_1):PWRGD_PVDDCR_CPU1_P0_R    I91 @T6G_MB_LIB.T6G(SCH_1):PAGE175
     2    GND @T6G_MB_LIB.T6G(SCH_1):GND    I91 @T6G_MB_LIB.T6G(SCH_1):PAGE175

C8072 Q_CAP_0402-1000PF,50V,5%,EMPTY,TMP_QCH21006JB10
     1 PWRGD_PVDDIO_P0_R @T6G_MB_LIB.T6G(SCH_1):PWRGD_PVDDIO_P0_R    I55 @T6G_MB_LIB.T6G(SCH_1):PAGE175
     2    GND @T6G_MB_LIB.T6G(SCH_1):GND    I55 @T6G_MB_LIB.T6G(SCH_1):PAGE175

C8246 Q_CAP_0402-1000PF,50V,5%,EMPTY,TMP_QCH21006JB10
     1 PWRGD_PVDDCR_SOC_P1_R @T6G_MB_LIB.T6G(SCH_1):PWRGD_PVDDCR_SOC_P1_R    I52 @T6G_MB_LIB.T6G(SCH_1):PAGE185
     2    GND @T6G_MB_LIB.T6G(SCH_1):GND    I52 @T6G_MB_LIB.T6G(SCH_1):PAGE185

C8356 Q_CAP_0402-1000PF,50V,5%,X7R,TMP_QCH21006JB10
     1 PVDDIO_P1_EN_R @T6G_MB_LIB.T6G(SCH_1):PVDDIO_P1_EN_R     I3 @T6G_MB_LIB.T6G(SCH_1):PAGE192
     2    GND @T6G_MB_LIB.T6G(SCH_1):GND     I3 @T6G_MB_LIB.T6G(SCH_1):PAGE192

C8359 Q_CAP_0402-1000PF,50V,5%,X7R,TMP_QCH21006JB10
     1 PVDDCR_CPU1_P1_EN_R @T6G_MB_LIB.T6G(SCH_1):PVDDCR_CPU1_P1_EN_R    I85 @T6G_MB_LIB.T6G(SCH_1):PAGE192
     2    GND @T6G_MB_LIB.T6G(SCH_1):GND    I85 @T6G_MB_LIB.T6G(SCH_1):PAGE192

C8360 Q_CAP_0402-1000PF,50V,5%,EMPTY,TMP_QCH21006JB10
     1 PWRGD_PVDDCR_CPU1_P1_R @T6G_MB_LIB.T6G(SCH_1):PWRGD_PVDDCR_CPU1_P1_R    I90 @T6G_MB_LIB.T6G(SCH_1):PAGE192
     2    GND @T6G_MB_LIB.T6G(SCH_1):GND    I90 @T6G_MB_LIB.T6G(SCH_1):PAGE192

C8362 Q_CAP_0402-1000PF,50V,5%,EMPTY,TMP_QCH21006JB10
     1 PWRGD_PVDDIO_P1_R @T6G_MB_LIB.T6G(SCH_1):PWRGD_PVDDIO_P1_R    I52 @T6G_MB_LIB.T6G(SCH_1):PAGE192
     2    GND @T6G_MB_LIB.T6G(SCH_1):GND    I52 @T6G_MB_LIB.T6G(SCH_1):PAGE192

C8641 Q_CAP_0402-1000PF,50V,5%,EMPTY,TMP_QCH21006JB10
     1 PWRGD_PVDD11_S3_P1_R @T6G_MB_LIB.T6G(SCH_1):PWRGD_PVDD11_S3_P1_R    I46 @T6G_MB_LIB.T6G(SCH_1):PAGE199
     2    GND @T6G_MB_LIB.T6G(SCH_1):GND    I46 @T6G_MB_LIB.T6G(SCH_1):PAGE199

C9000 Q_CAP_0402-1000PF,50V,5%,EMPTY,TMP_QCH21006JB10
     1 PRSNT_CABLE_SWB_B1_ISO_N @T6G_MB_LIB.T6G(SCH_1):PRSNT_CABLE_SWB_B1_ISO_N    I45 @T6G_MB_LIB.T6G(SCH_1):PAGE330
     2    GND @T6G_MB_LIB.T6G(SCH_1):GND    I45 @T6G_MB_LIB.T6G(SCH_1):PAGE330

C9001 Q_CAP_0402-1000PF,50V,5%,EMPTY,TMP_QCH21006JB10
     1 PRSNT_CABLE_SWB_B2_ISO_N @T6G_MB_LIB.T6G(SCH_1):PRSNT_CABLE_SWB_B2_ISO_N    I42 @T6G_MB_LIB.T6G(SCH_1):PAGE330
     2    GND @T6G_MB_LIB.T6G(SCH_1):GND    I42 @T6G_MB_LIB.T6G(SCH_1):PAGE330

C9002 Q_CAP_0402-1000PF,50V,5%,EMPTY,TMP_QCH21006JB10
     1 PRSNT_CABLE_GPU_A3_ISO_N @T6G_MB_LIB.T6G(SCH_1):PRSNT_CABLE_GPU_A3_ISO_N    I71 @T6G_MB_LIB.T6G(SCH_1):PAGE330
     2    GND @T6G_MB_LIB.T6G(SCH_1):GND    I71 @T6G_MB_LIB.T6G(SCH_1):PAGE330

C9003 Q_CAP_C0402-1UF,25V,10%,EMPTY,CH5104KEB02
     1 U142_VS @T6G_MB_LIB.T6G(SCH_1):U142_VS   I110 @T6G_MB_LIB.T6G(SCH_1):PAGE371
     2    GND @T6G_MB_LIB.T6G(SCH_1):GND   I110 @T6G_MB_LIB.T6G(SCH_1):PAGE371

C9004 Q_CAP_C0402-1UF,25V,10%,EMPTY,CH5104KEB02
     1 U206_VS @T6G_MB_LIB.T6G(SCH_1):U206_VS    I99 @T6G_MB_LIB.T6G(SCH_1):PAGE372
     2    GND @T6G_MB_LIB.T6G(SCH_1):GND    I99 @T6G_MB_LIB.T6G(SCH_1):PAGE372

C9005 Q_CAP_0402-0.1UF,25V,10%,X7R,CH4104K1B00
     1 IRQ_HSC_FAULT_BUF_N @T6G_MB_LIB.T6G(SCH_1):IRQ_HSC_FAULT_BUF_N   I116 @T6G_MB_LIB.T6G(SCH_1):PAGE84
     2    GND @T6G_MB_LIB.T6G(SCH_1):GND   I116 @T6G_MB_LIB.T6G(SCH_1):PAGE84

C9007 Q_CAP_0402-0.1UF,25V,10%,X7R,CH4104K1B00
     1 P3V3_AUX @T6G_MB_LIB.T6G(SCH_1):P3V3_AUX    I27 @T6G_MB_LIB.T6G(SCH_1):PAGE340
     2    GND @T6G_MB_LIB.T6G(SCH_1):GND    I27 @T6G_MB_LIB.T6G(SCH_1):PAGE340

C9008 Q_CAP_0402-0.1UF,25V,10%,X7R,CH4104K1B00
     1 P3V3_AUX @T6G_MB_LIB.T6G(SCH_1):P3V3_AUX    I75 @T6G_MB_LIB.T6G(SCH_1):PAGE340
     2    GND @T6G_MB_LIB.T6G(SCH_1):GND    I75 @T6G_MB_LIB.T6G(SCH_1):PAGE340

C9050 Q_CAP_0402-0.1UF,25V,10%,X7R,CH4104K1B00
     1 P3V3_AUX @T6G_MB_LIB.T6G(SCH_1):P3V3_AUX    I94 @T6G_MB_LIB.T6G(SCH_1):PAGE340
     2    GND @T6G_MB_LIB.T6G(SCH_1):GND    I94 @T6G_MB_LIB.T6G(SCH_1):PAGE340

C9051 Q_CAP_0402-0.1UF,25V,10%,X7R,CH4104K1B00
     1 P3V3_AUX @T6G_MB_LIB.T6G(SCH_1):P3V3_AUX    I81 @T6G_MB_LIB.T6G(SCH_1):PAGE257
     2    GND @T6G_MB_LIB.T6G(SCH_1):GND    I81 @T6G_MB_LIB.T6G(SCH_1):PAGE257

C9102 Q_CAP_DIFFBUS_C0201-DIFF BUS_0.22UF,6.3V,20%,X6S,SA
     1 P3E_CPU1_P4_TX_C_DP<1> @T6G_MB_LIB.T6G(SCH_1):P3E_CPU1_P4_TX_C_DP(1)   I138 @T6G_MB_LIB.T6G(SCH_1):PAGE355
     2 P3E_CPU1_P4_TX_DP<1> @T6G_MB_LIB.T6G(SCH_1):P3E_CPU1_P4_TX_DP(1)   I138 @T6G_MB_LIB.T6G(SCH_1):PAGE355

C9103 Q_CAP_DIFFBUS_C0201-DIFF BUS_0.22UF,6.3V,20%,X6S,SA
     1 P3E_CPU1_P4_TX_C_DN<1> @T6G_MB_LIB.T6G(SCH_1):P3E_CPU1_P4_TX_C_DN(1)   I137 @T6G_MB_LIB.T6G(SCH_1):PAGE355
     2 P3E_CPU1_P4_TX_DN<1> @T6G_MB_LIB.T6G(SCH_1):P3E_CPU1_P4_TX_DN(1)   I137 @T6G_MB_LIB.T6G(SCH_1):PAGE355

C9104 Q_CAP_DIFFBUS_C0201-DIFF BUS_0.22UF,6.3V,20%,X6S,SA
     1 P3E_CPU1_P4_TX_C_DP<0> @T6G_MB_LIB.T6G(SCH_1):P3E_CPU1_P4_TX_C_DP(0)   I162 @T6G_MB_LIB.T6G(SCH_1):PAGE355
     2 P3E_CPU1_P4_TX_DP<0> @T6G_MB_LIB.T6G(SCH_1):P3E_CPU1_P4_TX_DP(0)   I162 @T6G_MB_LIB.T6G(SCH_1):PAGE355

C9105 Q_CAP_DIFFBUS_C0201-DIFF BUS_0.22UF,6.3V,20%,X6S,SA
     1 P3E_CPU1_P4_TX_C_DN<0> @T6G_MB_LIB.T6G(SCH_1):P3E_CPU1_P4_TX_C_DN(0)   I161 @T6G_MB_LIB.T6G(SCH_1):PAGE355
     2 P3E_CPU1_P4_TX_DN<0> @T6G_MB_LIB.T6G(SCH_1):P3E_CPU1_P4_TX_DN(0)   I161 @T6G_MB_LIB.T6G(SCH_1):PAGE355

C9226 Q_CAP_C0402-0.22UF,25V,10%,X7R,CH4224K1B01
     1 VR_P5V_EN_D_R @T6G_MB_LIB.T6G(SCH_1):VR_P5V_EN_D_R    I38 @T6G_MB_LIB.T6G(SCH_1):PAGE273
     2    GND @T6G_MB_LIB.T6G(SCH_1):GND    I38 @T6G_MB_LIB.T6G(SCH_1):PAGE273

C9922 Q_CAP_C0603-22UF,6.3V,20%,X6S,CH6221ME900
     1 P3V3_M2_0 @T6G_MB_LIB.T6G(SCH_1):P3V3_M2_0    I79 @T6G_MB_LIB.T6G(SCH_1):PAGE345
     2    GND @T6G_MB_LIB.T6G(SCH_1):GND    I79 @T6G_MB_LIB.T6G(SCH_1):PAGE345

C10179 Q_CAP_C0402-22UF,4V,20%,X6S,CH622KMEB02
     1 PVDDCR_CPU0_P0 @T6G_MB_LIB.T6G(SCH_1):PVDDCR_CPU0_P0    I17 @T6G_MB_LIB.T6G(SCH_1):PAGE68
     2    GND @T6G_MB_LIB.T6G(SCH_1):GND    I17 @T6G_MB_LIB.T6G(SCH_1):PAGE68

  D1 BAT547F-BAT547F,SMLF,IC,BC0BAT54Z53
     1   P3V3 @T6G_MB_LIB.T6G(SCH_1):P3V3    I27 @T6G_MB_LIB.T6G(SCH_1):PAGE273
     3    P5V @T6G_MB_LIB.T6G(SCH_1):P5V    I27 @T6G_MB_LIB.T6G(SCH_1):PAGE273

  D5 Q_LED_SMLF-LED_BLUE,LTST-C281TBKT-5A,IC,BEBL0172Z00
     A PU_BOOT_RDY_LED @T6G_MB_LIB.T6G(SCH_1):PU_BOOT_RDY_LED     I8 @T6G_MB_LIB.T6G(SCH_1):PAGE143
     C BOOT_RDY_LED_N @T6G_MB_LIB.T6G(SCH_1):BOOT_RDY_LED_N     I8 @T6G_MB_LIB.T6G(SCH_1):PAGE143

  D6 Q_LED_SMLF-LED_YELLOW,LTST-C190KSKT-P,IC,BEYL0159ZA
     A PU_SMERR_LED @T6G_MB_LIB.T6G(SCH_1):PU_SMERR_LED     I9 @T6G_MB_LIB.T6G(SCH_1):PAGE143
     C SMERR_LED_N @T6G_MB_LIB.T6G(SCH_1):SMERR_LED_N     I9 @T6G_MB_LIB.T6G(SCH_1):PAGE143

  D7 Q_LED_SMLF-LED_YELLOW,LTST-C190KSKT-P,IC,BEYL0159ZA
     A BMC_FPGA_LED2_R_N @T6G_MB_LIB.T6G(SCH_1):BMC_FPGA_LED2_R_N    I96 @T6G_MB_LIB.T6G(SCH_1):PAGE84
     C BMC_FPGA_LED2_N @T6G_MB_LIB.T6G(SCH_1):BMC_FPGA_LED2_N    I96 @T6G_MB_LIB.T6G(SCH_1):PAGE84

  D8 Q_LED_SMLF-LED_YELLOW,LTST-C190KSKT-P,IC,BEYL0159ZA
     A BMC_FPGA_LED1_R_N @T6G_MB_LIB.T6G(SCH_1):BMC_FPGA_LED1_R_N    I97 @T6G_MB_LIB.T6G(SCH_1):PAGE84
     C BMC_FPGA_LED1_N @T6G_MB_LIB.T6G(SCH_1):BMC_FPGA_LED1_N    I97 @T6G_MB_LIB.T6G(SCH_1):PAGE84

  D9 Q_LED_SMLF-LED_BLUE,LTST-C281TBKT-5A,IC,BEBL0172Z00
     A LED_BIOS_DBG_MODE_R @T6G_MB_LIB.T6G(SCH_1):LED_BIOS_DBG_MODE_R    I79 @T6G_MB_LIB.T6G(SCH_1):PAGE142
     C LED_BIOS_DBG_MODE @T6G_MB_LIB.T6G(SCH_1):LED_BIOS_DBG_MODE    I79 @T6G_MB_LIB.T6G(SCH_1):PAGE142

 D46 Q_LED_SMLF-LED_BLUE,LTST-C281TBKT-5A,IC,BEBL0172Z00
     A PU_P12V_ALL_PWROK_LED @T6G_MB_LIB.T6G(SCH_1):PU_P12V_ALL_PWROK_LED    I43 @T6G_MB_LIB.T6G(SCH_1):PAGE143
     C P12V_ALL_PWROK_N @T6G_MB_LIB.T6G(SCH_1):P12V_ALL_PWROK_N    I43 @T6G_MB_LIB.T6G(SCH_1):PAGE143

 D49 Q_LED_SMLF-LED_BLUE,LTST-C281TBKT-5A,IC,BEBL0172Z00
     A P5V_STBY_PWR_LED @T6G_MB_LIB.T6G(SCH_1):P5V_STBY_PWR_LED    I38 @T6G_MB_LIB.T6G(SCH_1):PAGE143
     C    GND @T6G_MB_LIB.T6G(SCH_1):GND    I38 @T6G_MB_LIB.T6G(SCH_1):PAGE143

 D73 Q_LED_SMLF-LED_BLUE,LTST-C281TBKT-5A,IC,BEBL0172Z00
     A LED_PWRGD_PVDD33_S5_R @T6G_MB_LIB.T6G(SCH_1):LED_PWRGD_PVDD33_S5_R    I19 @T6G_MB_LIB.T6G(SCH_1):PAGE374
     C LED_PWRGD_PVDD33_S5_D @T6G_MB_LIB.T6G(SCH_1):LED_PWRGD_PVDD33_S5_D    I19 @T6G_MB_LIB.T6G(SCH_1):PAGE374

 D74 Q_LED_SMLF-LED_BLUE,LTST-C281TBKT-5A,IC,BEBL0172Z00
     A LED_PWRGD_PVDDCR_CPU0_P0_R @T6G_MB_LIB.T6G(SCH_1):LED_PWRGD_PVDDCR_CPU0_P0_R    I14 @T6G_MB_LIB.T6G(SCH_1):PAGE374
     C LED_PWRGD_PVDDCR_CPU0_P0_D @T6G_MB_LIB.T6G(SCH_1):LED_PWRGD_PVDDCR_CPU0_P0_D    I14 @T6G_MB_LIB.T6G(SCH_1):PAGE374

 D75 Q_LED_SMLF-LED_BLUE,LTST-C281TBKT-5A,IC,BEBL0172Z00
     A LED_PWRGD_PVDDCR_SOC_P0_R @T6G_MB_LIB.T6G(SCH_1):LED_PWRGD_PVDDCR_SOC_P0_R    I13 @T6G_MB_LIB.T6G(SCH_1):PAGE374
     C LED_PWRGD_PVDDCR_SOC_P0_D @T6G_MB_LIB.T6G(SCH_1):LED_PWRGD_PVDDCR_SOC_P0_D    I13 @T6G_MB_LIB.T6G(SCH_1):PAGE374

 D76 Q_LED_SMLF-LED_BLUE,LTST-C281TBKT-5A,IC,BEBL0172Z00
     A LED_PWRGD_PVDDCR_CPU1_P0_R @T6G_MB_LIB.T6G(SCH_1):LED_PWRGD_PVDDCR_CPU1_P0_R    I11 @T6G_MB_LIB.T6G(SCH_1):PAGE374
     C LED_PWRGD_PVDDCR_CPU1_P0_D @T6G_MB_LIB.T6G(SCH_1):LED_PWRGD_PVDDCR_CPU1_P0_D    I11 @T6G_MB_LIB.T6G(SCH_1):PAGE374

 D77 Q_LED_SMLF-LED_BLUE,LTST-C281TBKT-5A,IC,BEBL0172Z00
     A LED_PWRGD_PVDDIO_P0_R @T6G_MB_LIB.T6G(SCH_1):LED_PWRGD_PVDDIO_P0_R    I36 @T6G_MB_LIB.T6G(SCH_1):PAGE374
     C LED_PWRGD_PVDDIO_P0_D @T6G_MB_LIB.T6G(SCH_1):LED_PWRGD_PVDDIO_P0_D    I36 @T6G_MB_LIB.T6G(SCH_1):PAGE374

 D78 Q_LED_SMLF-LED_BLUE,LTST-C281TBKT-5A,IC,BEBL0172Z00
     A LED_PWRGD_PVDD11_S3_P0_R @T6G_MB_LIB.T6G(SCH_1):LED_PWRGD_PVDD11_S3_P0_R    I32 @T6G_MB_LIB.T6G(SCH_1):PAGE374
     C LED_PWRGD_PVDD11_S3_P0_D @T6G_MB_LIB.T6G(SCH_1):LED_PWRGD_PVDD11_S3_P0_D    I32 @T6G_MB_LIB.T6G(SCH_1):PAGE374

 D79 Q_LED_SMLF-LED_BLUE,LTST-C281TBKT-5A,IC,BEBL0172Z00
     A LED_PWRGD_PVDD18_S5_P0_R @T6G_MB_LIB.T6G(SCH_1):LED_PWRGD_PVDD18_S5_P0_R    I30 @T6G_MB_LIB.T6G(SCH_1):PAGE374
     C LED_PWRGD_PVDD18_S5_P0_D @T6G_MB_LIB.T6G(SCH_1):LED_PWRGD_PVDD18_S5_P0_D    I30 @T6G_MB_LIB.T6G(SCH_1):PAGE374

 D80 Q_LED_SMLF-LED_BLUE,LTST-C281TBKT-5A,IC,BEBL0172Z00
     A LED_PWRGD_PVDDCR_CPU0_P1_R @T6G_MB_LIB.T6G(SCH_1):LED_PWRGD_PVDDCR_CPU0_P1_R    I19 @T6G_MB_LIB.T6G(SCH_1):PAGE375
     C LED_PWRGD_PVDDCR_CPU0_P1_D @T6G_MB_LIB.T6G(SCH_1):LED_PWRGD_PVDDCR_CPU0_P1_D    I19 @T6G_MB_LIB.T6G(SCH_1):PAGE375

 D81 Q_LED_SMLF-LED_BLUE,LTST-C281TBKT-5A,IC,BEBL0172Z00
     A LED_PWRGD_PVDDCR_SOC_P1_R @T6G_MB_LIB.T6G(SCH_1):LED_PWRGD_PVDDCR_SOC_P1_R    I17 @T6G_MB_LIB.T6G(SCH_1):PAGE375
     C LED_PWRGD_PVDDCR_SOC_P1_D @T6G_MB_LIB.T6G(SCH_1):LED_PWRGD_PVDDCR_SOC_P1_D    I17 @T6G_MB_LIB.T6G(SCH_1):PAGE375

 D82 Q_LED_SMLF-LED_BLUE,LTST-C281TBKT-5A,IC,BEBL0172Z00
     A LED_PWRGD_PVDDCR_CPU1_P1_R @T6G_MB_LIB.T6G(SCH_1):LED_PWRGD_PVDDCR_CPU1_P1_R    I14 @T6G_MB_LIB.T6G(SCH_1):PAGE375
     C LED_PWRGD_PVDDCR_CPU1_P1_D @T6G_MB_LIB.T6G(SCH_1):LED_PWRGD_PVDDCR_CPU1_P1_D    I14 @T6G_MB_LIB.T6G(SCH_1):PAGE375

 D83 Q_LED_SMLF-LED_BLUE,LTST-C281TBKT-5A,IC,BEBL0172Z00
     A LED_PWRGD_PVDDIO_P1_R @T6G_MB_LIB.T6G(SCH_1):LED_PWRGD_PVDDIO_P1_R    I13 @T6G_MB_LIB.T6G(SCH_1):PAGE375
     C LED_PWRGD_PVDDIO_P1_D @T6G_MB_LIB.T6G(SCH_1):LED_PWRGD_PVDDIO_P1_D    I13 @T6G_MB_LIB.T6G(SCH_1):PAGE375

 D84 Q_LED_SMLF-LED_BLUE,LTST-C281TBKT-5A,IC,BEBL0172Z00
     A LED_PWRGD_PVDD11_S3_P1_R @T6G_MB_LIB.T6G(SCH_1):LED_PWRGD_PVDD11_S3_P1_R    I35 @T6G_MB_LIB.T6G(SCH_1):PAGE375
     C LED_PWRGD_PVDD11_S3_P1_D @T6G_MB_LIB.T6G(SCH_1):LED_PWRGD_PVDD11_S3_P1_D    I35 @T6G_MB_LIB.T6G(SCH_1):PAGE375

 D85 Q_LED_SMLF-LED_BLUE,LTST-C281TBKT-5A,IC,BEBL0172Z00
     A LED_PWRGD_PVDD18_S5_P1_R @T6G_MB_LIB.T6G(SCH_1):LED_PWRGD_PVDD18_S5_P1_R    I33 @T6G_MB_LIB.T6G(SCH_1):PAGE375
     C LED_PWRGD_PVDD18_S5_P1_D @T6G_MB_LIB.T6G(SCH_1):LED_PWRGD_PVDD18_S5_P1_D    I33 @T6G_MB_LIB.T6G(SCH_1):PAGE375

 D88 Q_LED_SMLF-LED_BLUE,LTST-C281TBKT-5A,IC,BEBL0172Z00
     A LED_PWRGD_SYS_PWROK_R @T6G_MB_LIB.T6G(SCH_1):LED_PWRGD_SYS_PWROK_R    I33 @T6G_MB_LIB.T6G(SCH_1):PAGE254
     C LED_PWRGD_SYS_PWROK_R_D @T6G_MB_LIB.T6G(SCH_1):LED_PWRGD_SYS_PWROK_R_D    I33 @T6G_MB_LIB.T6G(SCH_1):PAGE254

 D91 Q_LED_SMLF-LED_BLUE,LTST-C281TBKT-5A,IC,BEBL0172Z00
     A LED_PWRGD_P1V8_AUX @T6G_MB_LIB.T6G(SCH_1):LED_PWRGD_P1V8_AUX    I23 @T6G_MB_LIB.T6G(SCH_1):PAGE254
     C LED_PWRGD_P1V8_AUX_D @T6G_MB_LIB.T6G(SCH_1):LED_PWRGD_P1V8_AUX_D    I23 @T6G_MB_LIB.T6G(SCH_1):PAGE254

 D93 Q_LED_SMLF-LED_BLUE,LTST-C281TBKT-5A,IC,BEBL0172Z00
     A LED_RST_RSMRST_PLD_R_N @T6G_MB_LIB.T6G(SCH_1):LED_RST_RSMRST_PLD_R_N    I40 @T6G_MB_LIB.T6G(SCH_1):PAGE254
     C LED_RST_RSMRST_PLD_R_N_D @T6G_MB_LIB.T6G(SCH_1):LED_RST_RSMRST_PLD_R_N_D    I40 @T6G_MB_LIB.T6G(SCH_1):PAGE254

 D96 Q_LED_SMLF-LED_BLUE,LTST-C281TBKT-5A,IC,BEBL0172Z00
     A LED_PWRGD_PS_PWROK_PLD @T6G_MB_LIB.T6G(SCH_1):LED_PWRGD_PS_PWROK_PLD    I14 @T6G_MB_LIB.T6G(SCH_1):PAGE254
     C LED_PWRGD_PS_PWROK_PLD_D @T6G_MB_LIB.T6G(SCH_1):LED_PWRGD_PS_PWROK_PLD_D    I14 @T6G_MB_LIB.T6G(SCH_1):PAGE254

 D98 Q_LED_SMLF-LED_BLUE,LTST-C281TBKT-5A,IC,BEBL0172Z00
     A LED_P5V @T6G_MB_LIB.T6G(SCH_1):LED_P5V    I17 @T6G_MB_LIB.T6G(SCH_1):PAGE254
     C    GND @T6G_MB_LIB.T6G(SCH_1):GND    I17 @T6G_MB_LIB.T6G(SCH_1):PAGE254

 D99 Q_LED_SMLF-LED_BLUE,LTST-C281TBKT-5A,IC,BEBL0172Z00
     A LED_P3V3 @T6G_MB_LIB.T6G(SCH_1):LED_P3V3     I3 @T6G_MB_LIB.T6G(SCH_1):PAGE254
     C    GND @T6G_MB_LIB.T6G(SCH_1):GND     I3 @T6G_MB_LIB.T6G(SCH_1):PAGE254

D6000 Q_LED_SMLF-LED_BLUE,LTST-C281TBKT-5A,IC,BEBL0172Z00
     A LED_PWRGD_P1V2_AUX @T6G_MB_LIB.T6G(SCH_1):LED_PWRGD_P1V2_AUX    I43 @T6G_MB_LIB.T6G(SCH_1):PAGE254
     C LED_PWRGD_P1V2_AUX_D @T6G_MB_LIB.T6G(SCH_1):LED_PWRGD_P1V2_AUX_D    I43 @T6G_MB_LIB.T6G(SCH_1):PAGE254

D8000 Q_LED_SMLF-LED_BLUE,LTST-C281TBKT-5A,IC,BEBL0172Z00
     A LED_P12V_AUX_R1 @T6G_MB_LIB.T6G(SCH_1):LED_P12V_AUX_R1    I42 @T6G_MB_LIB.T6G(SCH_1):PAGE375
     C    GND @T6G_MB_LIB.T6G(SCH_1):GND    I42 @T6G_MB_LIB.T6G(SCH_1):PAGE375

D8001 Q_LED_SMLF-LED_BLUE,LTST-C281TBKT-5A,IC,BEBL0172Z00
     A LED_P12V_PSU_R1 @T6G_MB_LIB.T6G(SCH_1):LED_P12V_PSU_R1    I52 @T6G_MB_LIB.T6G(SCH_1):PAGE375
     C    GND @T6G_MB_LIB.T6G(SCH_1):GND    I52 @T6G_MB_LIB.T6G(SCH_1):PAGE375

D8002 Q_LED_SMLF-LED_YELLOW,LTST-C190KSKT-P,IC,BEYL0159ZA
     A LED_P12V_SCM_FAULT @T6G_MB_LIB.T6G(SCH_1):LED_P12V_SCM_FAULT    I56 @T6G_MB_LIB.T6G(SCH_1):PAGE375
     C LED_P12V_SCM_FAULT_D2 @T6G_MB_LIB.T6G(SCH_1):LED_P12V_SCM_FAULT_D2    I56 @T6G_MB_LIB.T6G(SCH_1):PAGE375

D8003 SCHOTTKY_12-B0530WS7F,SMLF,EMPTY,BC000530Z41
     1 PWRGD_CHAF_CPU0_R1 @T6G_MB_LIB.T6G(SCH_1):PWRGD_CHAF_CPU0_R1   I549 @T6G_MB_LIB.T6G(SCH_1):PAGE85
     2 P3V3_AUX @T6G_MB_LIB.T6G(SCH_1):P3V3_AUX   I549 @T6G_MB_LIB.T6G(SCH_1):PAGE85

D8004 SCHOTTKY_12-B0530WS7F,SMLF,EMPTY,BC000530Z41
     1 PWRGD_CHGL_CPU0_R1 @T6G_MB_LIB.T6G(SCH_1):PWRGD_CHGL_CPU0_R1   I251 @T6G_MB_LIB.T6G(SCH_1):PAGE91
     2 P3V3_AUX @T6G_MB_LIB.T6G(SCH_1):P3V3_AUX   I251 @T6G_MB_LIB.T6G(SCH_1):PAGE91

D8005 SCHOTTKY_12-B0530WS7F,SMLF,EMPTY,BC000530Z41
     1 PWRGD_CHAF_CPU1_R1 @T6G_MB_LIB.T6G(SCH_1):PWRGD_CHAF_CPU1_R1   I253 @T6G_MB_LIB.T6G(SCH_1):PAGE97
     2 P3V3_AUX @T6G_MB_LIB.T6G(SCH_1):P3V3_AUX   I253 @T6G_MB_LIB.T6G(SCH_1):PAGE97

D8006 SCHOTTKY_12-B0530WS7F,SMLF,EMPTY,BC000530Z41
     1 PWRGD_CHGL_CPU1_R1 @T6G_MB_LIB.T6G(SCH_1):PWRGD_CHGL_CPU1_R1   I253 @T6G_MB_LIB.T6G(SCH_1):PAGE103
     2 P3V3_AUX @T6G_MB_LIB.T6G(SCH_1):P3V3_AUX   I253 @T6G_MB_LIB.T6G(SCH_1):PAGE103

 DB1 TDR_3P_TH2-EMPTY,N_A
     1 T1_GND @T6G_MB_LIB.T6G(SCH_1):T1_GND    I16 @T6G_MB_LIB.T6G(SCH_1):PAGE265
     2 TDR_SE_45_OHM_TOP @T6G_MB_LIB.T6G(SCH_1):TDR_SE_45_OHM_TOP    I16 @T6G_MB_LIB.T6G(SCH_1):PAGE265
     3 TDR_SE_45_OHM_TOP @T6G_MB_LIB.T6G(SCH_1):TDR_SE_45_OHM_TOP    I16 @T6G_MB_LIB.T6G(SCH_1):PAGE265

 DB2 TDR_3P_TH2-EMPTY,N_A
     1 T1_GND @T6G_MB_LIB.T6G(SCH_1):T1_GND    I15 @T6G_MB_LIB.T6G(SCH_1):PAGE265
     2 TDR_SE_45_OHM_IN1 @T6G_MB_LIB.T6G(SCH_1):TDR_SE_45_OHM_IN1    I15 @T6G_MB_LIB.T6G(SCH_1):PAGE265
     3 TDR_SE_45_OHM_IN1 @T6G_MB_LIB.T6G(SCH_1):TDR_SE_45_OHM_IN1    I15 @T6G_MB_LIB.T6G(SCH_1):PAGE265

 DB3 TDR_3P_TH2-EMPTY,N_A
     1 T1_GND @T6G_MB_LIB.T6G(SCH_1):T1_GND    I13 @T6G_MB_LIB.T6G(SCH_1):PAGE265
     2 TDR_SE_45_OHM_IN2 @T6G_MB_LIB.T6G(SCH_1):TDR_SE_45_OHM_IN2    I13 @T6G_MB_LIB.T6G(SCH_1):PAGE265
     3 TDR_SE_45_OHM_IN2 @T6G_MB_LIB.T6G(SCH_1):TDR_SE_45_OHM_IN2    I13 @T6G_MB_LIB.T6G(SCH_1):PAGE265

 DB4 TDR_3P_TH2-EMPTY,N_A
     1 T1_GND @T6G_MB_LIB.T6G(SCH_1):T1_GND    I12 @T6G_MB_LIB.T6G(SCH_1):PAGE265
     2 TDR_SE_45_OHM_IN3 @T6G_MB_LIB.T6G(SCH_1):TDR_SE_45_OHM_IN3    I12 @T6G_MB_LIB.T6G(SCH_1):PAGE265
     3 TDR_SE_45_OHM_IN3 @T6G_MB_LIB.T6G(SCH_1):TDR_SE_45_OHM_IN3    I12 @T6G_MB_LIB.T6G(SCH_1):PAGE265

 DB5 TDR_3P_TH2-EMPTY,N_A
     1 T1_GND @T6G_MB_LIB.T6G(SCH_1):T1_GND     I9 @T6G_MB_LIB.T6G(SCH_1):PAGE265
     2 TDR_SE_45_OHM_IN4 @T6G_MB_LIB.T6G(SCH_1):TDR_SE_45_OHM_IN4     I9 @T6G_MB_LIB.T6G(SCH_1):PAGE265
     3 TDR_SE_45_OHM_IN4 @T6G_MB_LIB.T6G(SCH_1):TDR_SE_45_OHM_IN4     I9 @T6G_MB_LIB.T6G(SCH_1):PAGE265

 DB6 TDR_3P_TH2-EMPTY,N_A
     1 T1_GND @T6G_MB_LIB.T6G(SCH_1):T1_GND     I2 @T6G_MB_LIB.T6G(SCH_1):PAGE265
     2 TDR_SE_45_OHM_BOT @T6G_MB_LIB.T6G(SCH_1):TDR_SE_45_OHM_BOT     I2 @T6G_MB_LIB.T6G(SCH_1):PAGE265
     3 TDR_SE_45_OHM_BOT @T6G_MB_LIB.T6G(SCH_1):TDR_SE_45_OHM_BOT     I2 @T6G_MB_LIB.T6G(SCH_1):PAGE265

 DB7 TDR_3P_TH2-EMPTY,N_A
     1 T1_GND @T6G_MB_LIB.T6G(SCH_1):T1_GND    I44 @T6G_MB_LIB.T6G(SCH_1):PAGE265
     2 TDR_SE_50_OHM_TOP @T6G_MB_LIB.T6G(SCH_1):TDR_SE_50_OHM_TOP    I44 @T6G_MB_LIB.T6G(SCH_1):PAGE265
     3 TDR_SE_50_OHM_TOP @T6G_MB_LIB.T6G(SCH_1):TDR_SE_50_OHM_TOP    I44 @T6G_MB_LIB.T6G(SCH_1):PAGE265

 DB8 TDR_3P_TH2-EMPTY,N_A
     1 T1_GND @T6G_MB_LIB.T6G(SCH_1):T1_GND    I42 @T6G_MB_LIB.T6G(SCH_1):PAGE265
     2 TDR_SE_50_OHM_IN1 @T6G_MB_LIB.T6G(SCH_1):TDR_SE_50_OHM_IN1    I42 @T6G_MB_LIB.T6G(SCH_1):PAGE265
     3 TDR_SE_50_OHM_IN1 @T6G_MB_LIB.T6G(SCH_1):TDR_SE_50_OHM_IN1    I42 @T6G_MB_LIB.T6G(SCH_1):PAGE265

 DB9 TDR_3P_TH2-EMPTY,N_A
     1 T1_GND @T6G_MB_LIB.T6G(SCH_1):T1_GND    I40 @T6G_MB_LIB.T6G(SCH_1):PAGE265
     2 TDR_SE_50_OHM_IN2 @T6G_MB_LIB.T6G(SCH_1):TDR_SE_50_OHM_IN2    I40 @T6G_MB_LIB.T6G(SCH_1):PAGE265
     3 TDR_SE_50_OHM_IN2 @T6G_MB_LIB.T6G(SCH_1):TDR_SE_50_OHM_IN2    I40 @T6G_MB_LIB.T6G(SCH_1):PAGE265

DB10 TDR_3P_TH2-EMPTY,N_A
     1 T1_GND @T6G_MB_LIB.T6G(SCH_1):T1_GND    I38 @T6G_MB_LIB.T6G(SCH_1):PAGE265
     2 TDR_SE_50_OHM_IN3 @T6G_MB_LIB.T6G(SCH_1):TDR_SE_50_OHM_IN3    I38 @T6G_MB_LIB.T6G(SCH_1):PAGE265
     3 TDR_SE_50_OHM_IN3 @T6G_MB_LIB.T6G(SCH_1):TDR_SE_50_OHM_IN3    I38 @T6G_MB_LIB.T6G(SCH_1):PAGE265

DB11 TDR_3P_TH2-EMPTY,N_A
     1 T1_GND @T6G_MB_LIB.T6G(SCH_1):T1_GND    I25 @T6G_MB_LIB.T6G(SCH_1):PAGE265
     2 TDR_SE_50_OHM_IN4 @T6G_MB_LIB.T6G(SCH_1):TDR_SE_50_OHM_IN4    I25 @T6G_MB_LIB.T6G(SCH_1):PAGE265
     3 TDR_SE_50_OHM_IN4 @T6G_MB_LIB.T6G(SCH_1):TDR_SE_50_OHM_IN4    I25 @T6G_MB_LIB.T6G(SCH_1):PAGE265

DB12 TDR_3P_TH2-EMPTY,N_A
     1 T1_GND @T6G_MB_LIB.T6G(SCH_1):T1_GND    I18 @T6G_MB_LIB.T6G(SCH_1):PAGE265
     2 TDR_SE_50_OHM_BOT @T6G_MB_LIB.T6G(SCH_1):TDR_SE_50_OHM_BOT    I18 @T6G_MB_LIB.T6G(SCH_1):PAGE265
     3 TDR_SE_50_OHM_BOT @T6G_MB_LIB.T6G(SCH_1):TDR_SE_50_OHM_BOT    I18 @T6G_MB_LIB.T6G(SCH_1):PAGE265

DB13 TDR_3P_TH2-EMPTY,N_A
     1 T1_GND @T6G_MB_LIB.T6G(SCH_1):T1_GND     I8 @T6G_MB_LIB.T6G(SCH_1):PAGE265
     2 TDR_SE_45_OHM_IN5 @T6G_MB_LIB.T6G(SCH_1):TDR_SE_45_OHM_IN5     I8 @T6G_MB_LIB.T6G(SCH_1):PAGE265
     3 TDR_SE_45_OHM_IN5 @T6G_MB_LIB.T6G(SCH_1):TDR_SE_45_OHM_IN5     I8 @T6G_MB_LIB.T6G(SCH_1):PAGE265

DB14 TDR_3P_TH2-EMPTY,N_A
     1 T1_GND @T6G_MB_LIB.T6G(SCH_1):T1_GND     I5 @T6G_MB_LIB.T6G(SCH_1):PAGE265
     2 TDR_SE_45_OHM_IN6 @T6G_MB_LIB.T6G(SCH_1):TDR_SE_45_OHM_IN6     I5 @T6G_MB_LIB.T6G(SCH_1):PAGE265
     3 TDR_SE_45_OHM_IN6 @T6G_MB_LIB.T6G(SCH_1):TDR_SE_45_OHM_IN6     I5 @T6G_MB_LIB.T6G(SCH_1):PAGE265

DB15 TDR_3P_TH2-EMPTY,N_A
     1 T1_GND @T6G_MB_LIB.T6G(SCH_1):T1_GND    I22 @T6G_MB_LIB.T6G(SCH_1):PAGE265
     2 TDR_SE_50_OHM_IN5 @T6G_MB_LIB.T6G(SCH_1):TDR_SE_50_OHM_IN5    I22 @T6G_MB_LIB.T6G(SCH_1):PAGE265
     3 TDR_SE_50_OHM_IN5 @T6G_MB_LIB.T6G(SCH_1):TDR_SE_50_OHM_IN5    I22 @T6G_MB_LIB.T6G(SCH_1):PAGE265

DB16 TDR_3P_TH2-EMPTY,N_A
     1 T1_GND @T6G_MB_LIB.T6G(SCH_1):T1_GND    I20 @T6G_MB_LIB.T6G(SCH_1):PAGE265
     2 TDR_SE_50_OHM_IN6 @T6G_MB_LIB.T6G(SCH_1):TDR_SE_50_OHM_IN6    I20 @T6G_MB_LIB.T6G(SCH_1):PAGE265
     3 TDR_SE_50_OHM_IN6 @T6G_MB_LIB.T6G(SCH_1):TDR_SE_50_OHM_IN6    I20 @T6G_MB_LIB.T6G(SCH_1):PAGE265

 FS1 Q_FUSE_SMLF-20A/125V,IC,DKK00XFU000
     1 P12V_PSU @T6G_MB_LIB.T6G(SCH_1):P12V_PSU     I6 @T6G_MB_LIB.T6G(SCH_1):PAGE372
     2 P12V_PSU_FUSE @T6G_MB_LIB.T6G(SCH_1):P12V_PSU_FUSE     I6 @T6G_MB_LIB.T6G(SCH_1):PAGE372

  H2 HOLE_TH-EMPTY,HOLE1226
     1    GND @T6G_MB_LIB.T6G(SCH_1):GND   I170 @T6G_MB_LIB.T6G(SCH_1):PAGE212

  H3 HOLE_TH-EMPTY,HOLE1226
     1    GND @T6G_MB_LIB.T6G(SCH_1):GND   I195 @T6G_MB_LIB.T6G(SCH_1):PAGE212

  H5 HOLE_TH-EMPTY,HOLE1226
     1    GND @T6G_MB_LIB.T6G(SCH_1):GND   I193 @T6G_MB_LIB.T6G(SCH_1):PAGE212

  H8 HOLE_TH-EMPTY,HOLE1226
     1    GND @T6G_MB_LIB.T6G(SCH_1):GND   I176 @T6G_MB_LIB.T6G(SCH_1):PAGE212

 H10 HOLE_TH-EMPTY,HOLE1226
     1    GND @T6G_MB_LIB.T6G(SCH_1):GND   I178 @T6G_MB_LIB.T6G(SCH_1):PAGE212

 H11 HOLE_TH-EMPTY,HOLE1226
     1    GND @T6G_MB_LIB.T6G(SCH_1):GND    I87 @T6G_MB_LIB.T6G(SCH_1):PAGE212

 H12 HOLE_TH-EMPTY,HOLE1226
     1    GND @T6G_MB_LIB.T6G(SCH_1):GND   I187 @T6G_MB_LIB.T6G(SCH_1):PAGE212

 H13 HOLE_TH-EMPTY,HOLE1226
     1    GND @T6G_MB_LIB.T6G(SCH_1):GND    I55 @T6G_MB_LIB.T6G(SCH_1):PAGE212

 H21 HOLE_TH-EMPTY,HOLE1226
     1    GND @T6G_MB_LIB.T6G(SCH_1):GND     I5 @T6G_MB_LIB.T6G(SCH_1):PAGE212

 H22 HOLE_TH-EMPTY,HOLE1226
     1    GND @T6G_MB_LIB.T6G(SCH_1):GND    I26 @T6G_MB_LIB.T6G(SCH_1):PAGE212

 H27 HOLE_TH-EMPTY,DUMMY50
     1     NC     NC    I41 @T6G_MB_LIB.T6G(SCH_1):PAGE212

 H28 HOLE_TH-EMPTY,DUMMY50
     1     NC     NC    I50 @T6G_MB_LIB.T6G(SCH_1):PAGE212

 H29 HOLE_TH-EMPTY,DUMMY50
     1     NC     NC    I51 @T6G_MB_LIB.T6G(SCH_1):PAGE212

 H30 HOLE_TH-EMPTY,DUMMY50
     1     NC     NC    I56 @T6G_MB_LIB.T6G(SCH_1):PAGE212

 H31 HOLE_TH-EMPTY,HOLE1248
     1    GND @T6G_MB_LIB.T6G(SCH_1):GND    I91 @T6G_MB_LIB.T6G(SCH_1):PAGE212

 H32 HOLE_TH-EMPTY,HOLE1248
     1    GND @T6G_MB_LIB.T6G(SCH_1):GND    I93 @T6G_MB_LIB.T6G(SCH_1):PAGE212

 H33 HOLE_TH-EMPTY,HOLE1226
     1    GND @T6G_MB_LIB.T6G(SCH_1):GND    I36 @T6G_MB_LIB.T6G(SCH_1):PAGE212

 H34 HOLE_TH-EMPTY,HOLE1226
     1    GND @T6G_MB_LIB.T6G(SCH_1):GND    I31 @T6G_MB_LIB.T6G(SCH_1):PAGE212

 H37 HOLE_TH-EMPTY,HOLE1226
     1    GND @T6G_MB_LIB.T6G(SCH_1):GND    I38 @T6G_MB_LIB.T6G(SCH_1):PAGE212

 H38 HOLE_TH-EMPTY,HOLE1226
     1    GND @T6G_MB_LIB.T6G(SCH_1):GND    I33 @T6G_MB_LIB.T6G(SCH_1):PAGE212

 H43 HOLE_TH-EMPTY,HOLE1226
     1    GND @T6G_MB_LIB.T6G(SCH_1):GND    I40 @T6G_MB_LIB.T6G(SCH_1):PAGE212

 H44 HOLE_TH-EMPTY,HOLE1226
     1    GND @T6G_MB_LIB.T6G(SCH_1):GND    I45 @T6G_MB_LIB.T6G(SCH_1):PAGE212

 H49 HOLE_TH-EMPTY,HOLE1226
     1    GND @T6G_MB_LIB.T6G(SCH_1):GND    I46 @T6G_MB_LIB.T6G(SCH_1):PAGE212

 H50 HOLE_TH-EMPTY,HOLE1226
     1    GND @T6G_MB_LIB.T6G(SCH_1):GND    I49 @T6G_MB_LIB.T6G(SCH_1):PAGE212

 H53 HOLE_TH-EMPTY,HOLE1226
     1    GND @T6G_MB_LIB.T6G(SCH_1):GND     I4 @T6G_MB_LIB.T6G(SCH_1):PAGE212

 H54 HOLE_TH-EMPTY,HOLE1226
     1    GND @T6G_MB_LIB.T6G(SCH_1):GND    I52 @T6G_MB_LIB.T6G(SCH_1):PAGE212

 H74 HOLE_TH-EMPTY,HOLE1247
     1     NC     NC    I88 @T6G_MB_LIB.T6G(SCH_1):PAGE212

 H75 HOLE_TH-EMPTY,HOLE1247
     1     NC     NC    I89 @T6G_MB_LIB.T6G(SCH_1):PAGE212

 H76 HOLE_TH-EMPTY,HOLE1187
     1    GND @T6G_MB_LIB.T6G(SCH_1):GND    I10 @T6G_MB_LIB.T6G(SCH_1):PAGE212

 H77 HOLE_TH-EMPTY,HOLE1187
     1    GND @T6G_MB_LIB.T6G(SCH_1):GND    I12 @T6G_MB_LIB.T6G(SCH_1):PAGE212

 H86 HOLE_TH-EMPTY,HOLE596
     1    GND @T6G_MB_LIB.T6G(SCH_1):GND   I125 @T6G_MB_LIB.T6G(SCH_1):PAGE212

 H87 HOLE_TH-EMPTY,HOLE596
     1    GND @T6G_MB_LIB.T6G(SCH_1):GND   I127 @T6G_MB_LIB.T6G(SCH_1):PAGE212

 H88 HOLE_TH-EMPTY,HOLE596
     1    GND @T6G_MB_LIB.T6G(SCH_1):GND   I129 @T6G_MB_LIB.T6G(SCH_1):PAGE212

 H89 HOLE_TH-EMPTY,HOLE596
     1    GND @T6G_MB_LIB.T6G(SCH_1):GND   I132 @T6G_MB_LIB.T6G(SCH_1):PAGE212

 H90 HOLE_TH-EMPTY,HOLE372
     1     NC     NC   I167 @T6G_MB_LIB.T6G(SCH_1):PAGE212

 H91 HOLE_TH-EMPTY,HOLE596
     1    GND @T6G_MB_LIB.T6G(SCH_1):GND   I133 @T6G_MB_LIB.T6G(SCH_1):PAGE212

 H92 HOLE_TH-EMPTY,HOLE596
     1    GND @T6G_MB_LIB.T6G(SCH_1):GND   I135 @T6G_MB_LIB.T6G(SCH_1):PAGE212

 H93 HOLE_TH-EMPTY,HOLE596
     1    GND @T6G_MB_LIB.T6G(SCH_1):GND   I138 @T6G_MB_LIB.T6G(SCH_1):PAGE212

 H94 HOLE_TH-EMPTY,HOLE596
     1    GND @T6G_MB_LIB.T6G(SCH_1):GND   I140 @T6G_MB_LIB.T6G(SCH_1):PAGE212

 H95 HOLE_TH-EMPTY,HOLE596
     1    GND @T6G_MB_LIB.T6G(SCH_1):GND   I141 @T6G_MB_LIB.T6G(SCH_1):PAGE212

 H96 HOLE_TH-EMPTY,HOLE596
     1    GND @T6G_MB_LIB.T6G(SCH_1):GND   I142 @T6G_MB_LIB.T6G(SCH_1):PAGE212

 H97 HOLE_TH-EMPTY,HOLE596
     1    GND @T6G_MB_LIB.T6G(SCH_1):GND   I145 @T6G_MB_LIB.T6G(SCH_1):PAGE212

 H98 HOLE_TH-EMPTY,HOLE596
     1    GND @T6G_MB_LIB.T6G(SCH_1):GND   I147 @T6G_MB_LIB.T6G(SCH_1):PAGE212

 H99 HOLE_TH-EMPTY,HOLE596
     1    GND @T6G_MB_LIB.T6G(SCH_1):GND   I149 @T6G_MB_LIB.T6G(SCH_1):PAGE212

H100 HOLE_TH-EMPTY,HOLE596
     1    GND @T6G_MB_LIB.T6G(SCH_1):GND   I152 @T6G_MB_LIB.T6G(SCH_1):PAGE212

H101 HOLE_TH-EMPTY,HOLE596
     1    GND @T6G_MB_LIB.T6G(SCH_1):GND   I153 @T6G_MB_LIB.T6G(SCH_1):PAGE212

H102 HOLE_TH-EMPTY,HOLE596
     1    GND @T6G_MB_LIB.T6G(SCH_1):GND   I156 @T6G_MB_LIB.T6G(SCH_1):PAGE212

H103 HOLE_TH-EMPTY,HOLE596
     1    GND @T6G_MB_LIB.T6G(SCH_1):GND   I157 @T6G_MB_LIB.T6G(SCH_1):PAGE212

H104 HOLE_TH-EMPTY,HOLE596
     1    GND @T6G_MB_LIB.T6G(SCH_1):GND   I159 @T6G_MB_LIB.T6G(SCH_1):PAGE212

H105 HOLE_TH-EMPTY,HOLE596
     1    GND @T6G_MB_LIB.T6G(SCH_1):GND   I161 @T6G_MB_LIB.T6G(SCH_1):PAGE212

H106 HOLE_TH-EMPTY,HOLE596
     1    GND @T6G_MB_LIB.T6G(SCH_1):GND   I163 @T6G_MB_LIB.T6G(SCH_1):PAGE212

H111 GND_HOLE_TH-EMPTY,TMP-QGND_HOLE12
     3    GND @T6G_MB_LIB.T6G(SCH_1):GND   I120 @T6G_MB_LIB.T6G(SCH_1):PAGE212
     2    GND @T6G_MB_LIB.T6G(SCH_1):GND   I120 @T6G_MB_LIB.T6G(SCH_1):PAGE212
     9    GND @T6G_MB_LIB.T6G(SCH_1):GND   I120 @T6G_MB_LIB.T6G(SCH_1):PAGE212
     8    GND @T6G_MB_LIB.T6G(SCH_1):GND   I120 @T6G_MB_LIB.T6G(SCH_1):PAGE212
     7    GND @T6G_MB_LIB.T6G(SCH_1):GND   I120 @T6G_MB_LIB.T6G(SCH_1):PAGE212
     6    GND @T6G_MB_LIB.T6G(SCH_1):GND   I120 @T6G_MB_LIB.T6G(SCH_1):PAGE212
     5    GND @T6G_MB_LIB.T6G(SCH_1):GND   I120 @T6G_MB_LIB.T6G(SCH_1):PAGE212
     4    GND @T6G_MB_LIB.T6G(SCH_1):GND   I120 @T6G_MB_LIB.T6G(SCH_1):PAGE212

H112 GND_HOLE_TH-EMPTY,TMP-QGND_HOLE12
     3    GND @T6G_MB_LIB.T6G(SCH_1):GND   I123 @T6G_MB_LIB.T6G(SCH_1):PAGE212
     2    GND @T6G_MB_LIB.T6G(SCH_1):GND   I123 @T6G_MB_LIB.T6G(SCH_1):PAGE212
     9    GND @T6G_MB_LIB.T6G(SCH_1):GND   I123 @T6G_MB_LIB.T6G(SCH_1):PAGE212
     8    GND @T6G_MB_LIB.T6G(SCH_1):GND   I123 @T6G_MB_LIB.T6G(SCH_1):PAGE212
     7    GND @T6G_MB_LIB.T6G(SCH_1):GND   I123 @T6G_MB_LIB.T6G(SCH_1):PAGE212
     6    GND @T6G_MB_LIB.T6G(SCH_1):GND   I123 @T6G_MB_LIB.T6G(SCH_1):PAGE212
     5    GND @T6G_MB_LIB.T6G(SCH_1):GND   I123 @T6G_MB_LIB.T6G(SCH_1):PAGE212
     4    GND @T6G_MB_LIB.T6G(SCH_1):GND   I123 @T6G_MB_LIB.T6G(SCH_1):PAGE212

H113 GND_HOLE_TH-EMPTY,GND_HOLE140
     3    GND @T6G_MB_LIB.T6G(SCH_1):GND    I25 @T6G_MB_LIB.T6G(SCH_1):PAGE212
     2    GND @T6G_MB_LIB.T6G(SCH_1):GND    I25 @T6G_MB_LIB.T6G(SCH_1):PAGE212
     9    GND @T6G_MB_LIB.T6G(SCH_1):GND    I25 @T6G_MB_LIB.T6G(SCH_1):PAGE212
     8    GND @T6G_MB_LIB.T6G(SCH_1):GND    I25 @T6G_MB_LIB.T6G(SCH_1):PAGE212
     7    GND @T6G_MB_LIB.T6G(SCH_1):GND    I25 @T6G_MB_LIB.T6G(SCH_1):PAGE212
     6    GND @T6G_MB_LIB.T6G(SCH_1):GND    I25 @T6G_MB_LIB.T6G(SCH_1):PAGE212
     5    GND @T6G_MB_LIB.T6G(SCH_1):GND    I25 @T6G_MB_LIB.T6G(SCH_1):PAGE212
     4    GND @T6G_MB_LIB.T6G(SCH_1):GND    I25 @T6G_MB_LIB.T6G(SCH_1):PAGE212

H114 GND_HOLE_TH-EMPTY,GND_HOLE140
     3    GND @T6G_MB_LIB.T6G(SCH_1):GND    I30 @T6G_MB_LIB.T6G(SCH_1):PAGE212
     2    GND @T6G_MB_LIB.T6G(SCH_1):GND    I30 @T6G_MB_LIB.T6G(SCH_1):PAGE212
     9    GND @T6G_MB_LIB.T6G(SCH_1):GND    I30 @T6G_MB_LIB.T6G(SCH_1):PAGE212
     8    GND @T6G_MB_LIB.T6G(SCH_1):GND    I30 @T6G_MB_LIB.T6G(SCH_1):PAGE212
     7    GND @T6G_MB_LIB.T6G(SCH_1):GND    I30 @T6G_MB_LIB.T6G(SCH_1):PAGE212
     6    GND @T6G_MB_LIB.T6G(SCH_1):GND    I30 @T6G_MB_LIB.T6G(SCH_1):PAGE212
     5    GND @T6G_MB_LIB.T6G(SCH_1):GND    I30 @T6G_MB_LIB.T6G(SCH_1):PAGE212
     4    GND @T6G_MB_LIB.T6G(SCH_1):GND    I30 @T6G_MB_LIB.T6G(SCH_1):PAGE212

H115 GND_HOLE_TH-EMPTY,GND_HOLE514
     3    GND @T6G_MB_LIB.T6G(SCH_1):GND    I43 @T6G_MB_LIB.T6G(SCH_1):PAGE212
     2    GND @T6G_MB_LIB.T6G(SCH_1):GND    I43 @T6G_MB_LIB.T6G(SCH_1):PAGE212
     9    GND @T6G_MB_LIB.T6G(SCH_1):GND    I43 @T6G_MB_LIB.T6G(SCH_1):PAGE212
     8    GND @T6G_MB_LIB.T6G(SCH_1):GND    I43 @T6G_MB_LIB.T6G(SCH_1):PAGE212
     7    GND @T6G_MB_LIB.T6G(SCH_1):GND    I43 @T6G_MB_LIB.T6G(SCH_1):PAGE212
     6    GND @T6G_MB_LIB.T6G(SCH_1):GND    I43 @T6G_MB_LIB.T6G(SCH_1):PAGE212
     5    GND @T6G_MB_LIB.T6G(SCH_1):GND    I43 @T6G_MB_LIB.T6G(SCH_1):PAGE212
     4    GND @T6G_MB_LIB.T6G(SCH_1):GND    I43 @T6G_MB_LIB.T6G(SCH_1):PAGE212

H124 HOLE_TH-EMPTY,TMP-C_T2I_ALEX_1121_1
     1     NC     NC    I84 @T6G_MB_LIB.T6G(SCH_1):PAGE212

H125 HOLE_TH-EMPTY,TMP-C_T2I_ALEX_1121_1
     1     NC     NC    I85 @T6G_MB_LIB.T6G(SCH_1):PAGE212

H126 HOLE_TH-EMPTY,TMP-C_T2I_ALEX_1121_1
     1     NC     NC   I111 @T6G_MB_LIB.T6G(SCH_1):PAGE212

H127 HOLE_TH-EMPTY,TMP-C_T2I_ALEX_1121_1
     1     NC     NC    I94 @T6G_MB_LIB.T6G(SCH_1):PAGE212

H128 HOLE_TH-EMPTY,HOLE596
     1    GND @T6G_MB_LIB.T6G(SCH_1):GND   I166 @T6G_MB_LIB.T6G(SCH_1):PAGE212

H6000 HOLE_TH-EMPTY,HOLE1226
     1    GND @T6G_MB_LIB.T6G(SCH_1):GND   I113 @T6G_MB_LIB.T6G(SCH_1):PAGE212

H6001 HOLE_TH-EMPTY,HOLE1226
     1    GND @T6G_MB_LIB.T6G(SCH_1):GND   I116 @T6G_MB_LIB.T6G(SCH_1):PAGE212

H6002 HOLE_TH-EMPTY,HOLE1195
     1    GND @T6G_MB_LIB.T6G(SCH_1):GND   I168 @T6G_MB_LIB.T6G(SCH_1):PAGE212

H8027 HOLE_TH-EMPTY,HOLE1226
     1    GND @T6G_MB_LIB.T6G(SCH_1):GND     I7 @T6G_MB_LIB.T6G(SCH_1):PAGE212

H8028 HOLE_TH-EMPTY,HOLE1226
     1    GND @T6G_MB_LIB.T6G(SCH_1):GND    I27 @T6G_MB_LIB.T6G(SCH_1):PAGE212

  J1 SCONN288_DDR506112002KQ-SCONN288_DDR506112002KQ,SMA
     3 P3V3_AUX @T6G_MB_LIB.T6G(SCH_1):P3V3_AUX   I536 @T6G_MB_LIB.T6G(SCH_1):PAGE85
     2     NC     NC   I536 @T6G_MB_LIB.T6G(SCH_1):PAGE85
   144     NC     NC   I536 @T6G_MB_LIB.T6G(SCH_1):PAGE85
   149     NC     NC   I536 @T6G_MB_LIB.T6G(SCH_1):PAGE85
   150     NC     NC   I536 @T6G_MB_LIB.T6G(SCH_1):PAGE85
   220     NC     NC   I536 @T6G_MB_LIB.T6G(SCH_1):PAGE85
   231     NC     NC   I536 @T6G_MB_LIB.T6G(SCH_1):PAGE85
   232     NC     NC   I536 @T6G_MB_LIB.T6G(SCH_1):PAGE85
   207 M_A_CPU0_RESET_N @T6G_MB_LIB.T6G(SCH_1):M_A_CPU0_RESET_N   I536 @T6G_MB_LIB.T6G(SCH_1):PAGE85
   147 PWRGD_CHA_CPU0_DIMM0 @T6G_MB_LIB.T6G(SCH_1):PWRGD_CHA_CPU0_DIMM0   I536 @T6G_MB_LIB.T6G(SCH_1):PAGE85
   227 M_A_CPU0_SB_PAR @T6G_MB_LIB.T6G(SCH_1):M_A_CPU0_SB_PAR   I536 @T6G_MB_LIB.T6G(SCH_1):PAGE85
    74 M_A_CPU0_SA_PAR @T6G_MB_LIB.T6G(SCH_1):M_A_CPU0_SA_PAR   I536 @T6G_MB_LIB.T6G(SCH_1):PAGE85
    87 M_A_CPU0_SB_RSP<0> @T6G_MB_LIB.T6G(SCH_1):M_A_CPU0_SB_RSP(0)   I536 @T6G_MB_LIB.T6G(SCH_1):PAGE85
    86 M_A_CPU0_SA_RSP<0> @T6G_MB_LIB.T6G(SCH_1):M_A_CPU0_SA_RSP(0)   I536 @T6G_MB_LIB.T6G(SCH_1):PAGE85
     5 I3C_SPD_DDRA_CPU0_SDA @T6G_MB_LIB.T6G(SCH_1):I3C_SPD_DDRA_CPU0_SDA   I536 @T6G_MB_LIB.T6G(SCH_1):PAGE85
     4 I3C_SPD_DDRA_CPU0_SCL @T6G_MB_LIB.T6G(SCH_1):I3C_SPD_DDRA_CPU0_SCL   I536 @T6G_MB_LIB.T6G(SCH_1):PAGE85
   148 PD_CHA_CPU0_DIMM0_SAA @T6G_MB_LIB.T6G(SCH_1):PD_CHA_CPU0_DIMM0_SAA   I536 @T6G_MB_LIB.T6G(SCH_1):PAGE85
   100 M_A_CPU0_SB_DQ<0> @T6G_MB_LIB.T6G(SCH_1):M_A_CPU0_SB_DQ(0)   I536 @T6G_MB_LIB.T6G(SCH_1):PAGE85
   102 M_A_CPU0_SB_DQ<1> @T6G_MB_LIB.T6G(SCH_1):M_A_CPU0_SB_DQ(1)   I536 @T6G_MB_LIB.T6G(SCH_1):PAGE85
   245 M_A_CPU0_SB_DQ<2> @T6G_MB_LIB.T6G(SCH_1):M_A_CPU0_SB_DQ(2)   I536 @T6G_MB_LIB.T6G(SCH_1):PAGE85
   247 M_A_CPU0_SB_DQ<3> @T6G_MB_LIB.T6G(SCH_1):M_A_CPU0_SB_DQ(3)   I536 @T6G_MB_LIB.T6G(SCH_1):PAGE85
   107 M_A_CPU0_SB_DQ<4> @T6G_MB_LIB.T6G(SCH_1):M_A_CPU0_SB_DQ(4)   I536 @T6G_MB_LIB.T6G(SCH_1):PAGE85
   109 M_A_CPU0_SB_DQ<5> @T6G_MB_LIB.T6G(SCH_1):M_A_CPU0_SB_DQ(5)   I536 @T6G_MB_LIB.T6G(SCH_1):PAGE85
   252 M_A_CPU0_SB_DQ<6> @T6G_MB_LIB.T6G(SCH_1):M_A_CPU0_SB_DQ(6)   I536 @T6G_MB_LIB.T6G(SCH_1):PAGE85
   254 M_A_CPU0_SB_DQ<7> @T6G_MB_LIB.T6G(SCH_1):M_A_CPU0_SB_DQ(7)   I536 @T6G_MB_LIB.T6G(SCH_1):PAGE85
   111 M_A_CPU0_SB_DQ<8> @T6G_MB_LIB.T6G(SCH_1):M_A_CPU0_SB_DQ(8)   I536 @T6G_MB_LIB.T6G(SCH_1):PAGE85
   113 M_A_CPU0_SB_DQ<9> @T6G_MB_LIB.T6G(SCH_1):M_A_CPU0_SB_DQ(9)   I536 @T6G_MB_LIB.T6G(SCH_1):PAGE85
   256 M_A_CPU0_SB_DQ<10> @T6G_MB_LIB.T6G(SCH_1):M_A_CPU0_SB_DQ(10)   I536 @T6G_MB_LIB.T6G(SCH_1):PAGE85
   258 M_A_CPU0_SB_DQ<11> @T6G_MB_LIB.T6G(SCH_1):M_A_CPU0_SB_DQ(11)   I536 @T6G_MB_LIB.T6G(SCH_1):PAGE85
   118 M_A_CPU0_SB_DQ<12> @T6G_MB_LIB.T6G(SCH_1):M_A_CPU0_SB_DQ(12)   I536 @T6G_MB_LIB.T6G(SCH_1):PAGE85
   120 M_A_CPU0_SB_DQ<13> @T6G_MB_LIB.T6G(SCH_1):M_A_CPU0_SB_DQ(13)   I536 @T6G_MB_LIB.T6G(SCH_1):PAGE85
   263 M_A_CPU0_SB_DQ<14> @T6G_MB_LIB.T6G(SCH_1):M_A_CPU0_SB_DQ(14)   I536 @T6G_MB_LIB.T6G(SCH_1):PAGE85
   265 M_A_CPU0_SB_DQ<15> @T6G_MB_LIB.T6G(SCH_1):M_A_CPU0_SB_DQ(15)   I536 @T6G_MB_LIB.T6G(SCH_1):PAGE85
   122 M_A_CPU0_SB_DQ<16> @T6G_MB_LIB.T6G(SCH_1):M_A_CPU0_SB_DQ(16)   I536 @T6G_MB_LIB.T6G(SCH_1):PAGE85
   124 M_A_CPU0_SB_DQ<17> @T6G_MB_LIB.T6G(SCH_1):M_A_CPU0_SB_DQ(17)   I536 @T6G_MB_LIB.T6G(SCH_1):PAGE85
   267 M_A_CPU0_SB_DQ<18> @T6G_MB_LIB.T6G(SCH_1):M_A_CPU0_SB_DQ(18)   I536 @T6G_MB_LIB.T6G(SCH_1):PAGE85
   269 M_A_CPU0_SB_DQ<19> @T6G_MB_LIB.T6G(SCH_1):M_A_CPU0_SB_DQ(19)   I536 @T6G_MB_LIB.T6G(SCH_1):PAGE85
   129 M_A_CPU0_SB_DQ<20> @T6G_MB_LIB.T6G(SCH_1):M_A_CPU0_SB_DQ(20)   I536 @T6G_MB_LIB.T6G(SCH_1):PAGE85
   131 M_A_CPU0_SB_DQ<21> @T6G_MB_LIB.T6G(SCH_1):M_A_CPU0_SB_DQ(21)   I536 @T6G_MB_LIB.T6G(SCH_1):PAGE85
   274 M_A_CPU0_SB_DQ<22> @T6G_MB_LIB.T6G(SCH_1):M_A_CPU0_SB_DQ(22)   I536 @T6G_MB_LIB.T6G(SCH_1):PAGE85
   276 M_A_CPU0_SB_DQ<23> @T6G_MB_LIB.T6G(SCH_1):M_A_CPU0_SB_DQ(23)   I536 @T6G_MB_LIB.T6G(SCH_1):PAGE85
   133 M_A_CPU0_SB_DQ<24> @T6G_MB_LIB.T6G(SCH_1):M_A_CPU0_SB_DQ(24)   I536 @T6G_MB_LIB.T6G(SCH_1):PAGE85
   135 M_A_CPU0_SB_DQ<25> @T6G_MB_LIB.T6G(SCH_1):M_A_CPU0_SB_DQ(25)   I536 @T6G_MB_LIB.T6G(SCH_1):PAGE85
   278 M_A_CPU0_SB_DQ<26> @T6G_MB_LIB.T6G(SCH_1):M_A_CPU0_SB_DQ(26)   I536 @T6G_MB_LIB.T6G(SCH_1):PAGE85
   280 M_A_CPU0_SB_DQ<27> @T6G_MB_LIB.T6G(SCH_1):M_A_CPU0_SB_DQ(27)   I536 @T6G_MB_LIB.T6G(SCH_1):PAGE85
   140 M_A_CPU0_SB_DQ<28> @T6G_MB_LIB.T6G(SCH_1):M_A_CPU0_SB_DQ(28)   I536 @T6G_MB_LIB.T6G(SCH_1):PAGE85
   142 M_A_CPU0_SB_DQ<29> @T6G_MB_LIB.T6G(SCH_1):M_A_CPU0_SB_DQ(29)   I536 @T6G_MB_LIB.T6G(SCH_1):PAGE85
   285 M_A_CPU0_SB_DQ<30> @T6G_MB_LIB.T6G(SCH_1):M_A_CPU0_SB_DQ(30)   I536 @T6G_MB_LIB.T6G(SCH_1):PAGE85
   287 M_A_CPU0_SB_DQ<31> @T6G_MB_LIB.T6G(SCH_1):M_A_CPU0_SB_DQ(31)   I536 @T6G_MB_LIB.T6G(SCH_1):PAGE85
     7 M_A_CPU0_SA_DQ<0> @T6G_MB_LIB.T6G(SCH_1):M_A_CPU0_SA_DQ(0)   I536 @T6G_MB_LIB.T6G(SCH_1):PAGE85
     9 M_A_CPU0_SA_DQ<1> @T6G_MB_LIB.T6G(SCH_1):M_A_CPU0_SA_DQ(1)   I536 @T6G_MB_LIB.T6G(SCH_1):PAGE85
   152 M_A_CPU0_SA_DQ<2> @T6G_MB_LIB.T6G(SCH_1):M_A_CPU0_SA_DQ(2)   I536 @T6G_MB_LIB.T6G(SCH_1):PAGE85
   154 M_A_CPU0_SA_DQ<3> @T6G_MB_LIB.T6G(SCH_1):M_A_CPU0_SA_DQ(3)   I536 @T6G_MB_LIB.T6G(SCH_1):PAGE85
    14 M_A_CPU0_SA_DQ<4> @T6G_MB_LIB.T6G(SCH_1):M_A_CPU0_SA_DQ(4)   I536 @T6G_MB_LIB.T6G(SCH_1):PAGE85
    16 M_A_CPU0_SA_DQ<5> @T6G_MB_LIB.T6G(SCH_1):M_A_CPU0_SA_DQ(5)   I536 @T6G_MB_LIB.T6G(SCH_1):PAGE85
   159 M_A_CPU0_SA_DQ<6> @T6G_MB_LIB.T6G(SCH_1):M_A_CPU0_SA_DQ(6)   I536 @T6G_MB_LIB.T6G(SCH_1):PAGE85
   161 M_A_CPU0_SA_DQ<7> @T6G_MB_LIB.T6G(SCH_1):M_A_CPU0_SA_DQ(7)   I536 @T6G_MB_LIB.T6G(SCH_1):PAGE85
    18 M_A_CPU0_SA_DQ<8> @T6G_MB_LIB.T6G(SCH_1):M_A_CPU0_SA_DQ(8)   I536 @T6G_MB_LIB.T6G(SCH_1):PAGE85
    20 M_A_CPU0_SA_DQ<9> @T6G_MB_LIB.T6G(SCH_1):M_A_CPU0_SA_DQ(9)   I536 @T6G_MB_LIB.T6G(SCH_1):PAGE85
   163 M_A_CPU0_SA_DQ<10> @T6G_MB_LIB.T6G(SCH_1):M_A_CPU0_SA_DQ(10)   I536 @T6G_MB_LIB.T6G(SCH_1):PAGE85
   165 M_A_CPU0_SA_DQ<11> @T6G_MB_LIB.T6G(SCH_1):M_A_CPU0_SA_DQ(11)   I536 @T6G_MB_LIB.T6G(SCH_1):PAGE85
    25 M_A_CPU0_SA_DQ<12> @T6G_MB_LIB.T6G(SCH_1):M_A_CPU0_SA_DQ(12)   I536 @T6G_MB_LIB.T6G(SCH_1):PAGE85
    27 M_A_CPU0_SA_DQ<13> @T6G_MB_LIB.T6G(SCH_1):M_A_CPU0_SA_DQ(13)   I536 @T6G_MB_LIB.T6G(SCH_1):PAGE85
   170 M_A_CPU0_SA_DQ<14> @T6G_MB_LIB.T6G(SCH_1):M_A_CPU0_SA_DQ(14)   I536 @T6G_MB_LIB.T6G(SCH_1):PAGE85
   172 M_A_CPU0_SA_DQ<15> @T6G_MB_LIB.T6G(SCH_1):M_A_CPU0_SA_DQ(15)   I536 @T6G_MB_LIB.T6G(SCH_1):PAGE85
    29 M_A_CPU0_SA_DQ<16> @T6G_MB_LIB.T6G(SCH_1):M_A_CPU0_SA_DQ(16)   I536 @T6G_MB_LIB.T6G(SCH_1):PAGE85
    31 M_A_CPU0_SA_DQ<17> @T6G_MB_LIB.T6G(SCH_1):M_A_CPU0_SA_DQ(17)   I536 @T6G_MB_LIB.T6G(SCH_1):PAGE85
   174 M_A_CPU0_SA_DQ<18> @T6G_MB_LIB.T6G(SCH_1):M_A_CPU0_SA_DQ(18)   I536 @T6G_MB_LIB.T6G(SCH_1):PAGE85
   176 M_A_CPU0_SA_DQ<19> @T6G_MB_LIB.T6G(SCH_1):M_A_CPU0_SA_DQ(19)   I536 @T6G_MB_LIB.T6G(SCH_1):PAGE85
    36 M_A_CPU0_SA_DQ<20> @T6G_MB_LIB.T6G(SCH_1):M_A_CPU0_SA_DQ(20)   I536 @T6G_MB_LIB.T6G(SCH_1):PAGE85
    38 M_A_CPU0_SA_DQ<21> @T6G_MB_LIB.T6G(SCH_1):M_A_CPU0_SA_DQ(21)   I536 @T6G_MB_LIB.T6G(SCH_1):PAGE85
   181 M_A_CPU0_SA_DQ<22> @T6G_MB_LIB.T6G(SCH_1):M_A_CPU0_SA_DQ(22)   I536 @T6G_MB_LIB.T6G(SCH_1):PAGE85
   183 M_A_CPU0_SA_DQ<23> @T6G_MB_LIB.T6G(SCH_1):M_A_CPU0_SA_DQ(23)   I536 @T6G_MB_LIB.T6G(SCH_1):PAGE85
    40 M_A_CPU0_SA_DQ<24> @T6G_MB_LIB.T6G(SCH_1):M_A_CPU0_SA_DQ(24)   I536 @T6G_MB_LIB.T6G(SCH_1):PAGE85
    42 M_A_CPU0_SA_DQ<25> @T6G_MB_LIB.T6G(SCH_1):M_A_CPU0_SA_DQ(25)   I536 @T6G_MB_LIB.T6G(SCH_1):PAGE85
   185 M_A_CPU0_SA_DQ<26> @T6G_MB_LIB.T6G(SCH_1):M_A_CPU0_SA_DQ(26)   I536 @T6G_MB_LIB.T6G(SCH_1):PAGE85
   187 M_A_CPU0_SA_DQ<27> @T6G_MB_LIB.T6G(SCH_1):M_A_CPU0_SA_DQ(27)   I536 @T6G_MB_LIB.T6G(SCH_1):PAGE85
    47 M_A_CPU0_SA_DQ<28> @T6G_MB_LIB.T6G(SCH_1):M_A_CPU0_SA_DQ(28)   I536 @T6G_MB_LIB.T6G(SCH_1):PAGE85
    49 M_A_CPU0_SA_DQ<29> @T6G_MB_LIB.T6G(SCH_1):M_A_CPU0_SA_DQ(29)   I536 @T6G_MB_LIB.T6G(SCH_1):PAGE85
   192 M_A_CPU0_SA_DQ<30> @T6G_MB_LIB.T6G(SCH_1):M_A_CPU0_SA_DQ(30)   I536 @T6G_MB_LIB.T6G(SCH_1):PAGE85
   229 M_A_CPU0_SB_CS_N<1> @T6G_MB_LIB.T6G(SCH_1):M_A_CPU0_SB_CS_N(1)   I536 @T6G_MB_LIB.T6G(SCH_1):PAGE85
   209 M_A_CPU0_SA_CS_N<1> @T6G_MB_LIB.T6G(SCH_1):M_A_CPU0_SA_CS_N(1)   I536 @T6G_MB_LIB.T6G(SCH_1):PAGE85
    84 M_A_CPU0_SB_CS_N<0> @T6G_MB_LIB.T6G(SCH_1):M_A_CPU0_SB_CS_N(0)   I536 @T6G_MB_LIB.T6G(SCH_1):PAGE85
    64 M_A_CPU0_SA_CS_N<0> @T6G_MB_LIB.T6G(SCH_1):M_A_CPU0_SA_CS_N(0)   I536 @T6G_MB_LIB.T6G(SCH_1):PAGE85
   217 M_A_CPU0_CLK_DP<0> @T6G_MB_LIB.T6G(SCH_1):M_A_CPU0_CLK_DP(0)   I536 @T6G_MB_LIB.T6G(SCH_1):PAGE85
   218 M_A_CPU0_CLK_DN<0> @T6G_MB_LIB.T6G(SCH_1):M_A_CPU0_CLK_DN(0)   I536 @T6G_MB_LIB.T6G(SCH_1):PAGE85
    96 M_A_CPU0_SB_CB<0> @T6G_MB_LIB.T6G(SCH_1):M_A_CPU0_SB_CB(0)   I536 @T6G_MB_LIB.T6G(SCH_1):PAGE85
    98 M_A_CPU0_SB_CB<1> @T6G_MB_LIB.T6G(SCH_1):M_A_CPU0_SB_CB(1)   I536 @T6G_MB_LIB.T6G(SCH_1):PAGE85
   241 M_A_CPU0_SB_CB<2> @T6G_MB_LIB.T6G(SCH_1):M_A_CPU0_SB_CB(2)   I536 @T6G_MB_LIB.T6G(SCH_1):PAGE85
   243 M_A_CPU0_SB_CB<3> @T6G_MB_LIB.T6G(SCH_1):M_A_CPU0_SB_CB(3)   I536 @T6G_MB_LIB.T6G(SCH_1):PAGE85
    89 M_A_CPU0_SB_CB<4> @T6G_MB_LIB.T6G(SCH_1):M_A_CPU0_SB_CB(4)   I536 @T6G_MB_LIB.T6G(SCH_1):PAGE85
    91 M_A_CPU0_SB_CB<5> @T6G_MB_LIB.T6G(SCH_1):M_A_CPU0_SB_CB(5)   I536 @T6G_MB_LIB.T6G(SCH_1):PAGE85
   234 M_A_CPU0_SB_CB<6> @T6G_MB_LIB.T6G(SCH_1):M_A_CPU0_SB_CB(6)   I536 @T6G_MB_LIB.T6G(SCH_1):PAGE85
    51 M_A_CPU0_SA_CB<0> @T6G_MB_LIB.T6G(SCH_1):M_A_CPU0_SA_CB(0)   I536 @T6G_MB_LIB.T6G(SCH_1):PAGE85
   196 M_A_CPU0_SA_CB<2> @T6G_MB_LIB.T6G(SCH_1):M_A_CPU0_SA_CB(2)   I536 @T6G_MB_LIB.T6G(SCH_1):PAGE85
   198 M_A_CPU0_SA_CB<3> @T6G_MB_LIB.T6G(SCH_1):M_A_CPU0_SA_CB(3)   I536 @T6G_MB_LIB.T6G(SCH_1):PAGE85
    60 M_A_CPU0_SA_CB<5> @T6G_MB_LIB.T6G(SCH_1):M_A_CPU0_SA_CB(5)   I536 @T6G_MB_LIB.T6G(SCH_1):PAGE85
   203 M_A_CPU0_SA_CB<6> @T6G_MB_LIB.T6G(SCH_1):M_A_CPU0_SA_CB(6)   I536 @T6G_MB_LIB.T6G(SCH_1):PAGE85
    82 M_A_CPU0_SB_CA<6> @T6G_MB_LIB.T6G(SCH_1):M_A_CPU0_SB_CA(6)   I536 @T6G_MB_LIB.T6G(SCH_1):PAGE85
    72 M_A_CPU0_SA_CA<6> @T6G_MB_LIB.T6G(SCH_1):M_A_CPU0_SA_CA(6)   I536 @T6G_MB_LIB.T6G(SCH_1):PAGE85
   225 M_A_CPU0_SB_CA<5> @T6G_MB_LIB.T6G(SCH_1):M_A_CPU0_SB_CA(5)   I536 @T6G_MB_LIB.T6G(SCH_1):PAGE85
   215 M_A_CPU0_SA_CA<5> @T6G_MB_LIB.T6G(SCH_1):M_A_CPU0_SA_CA(5)   I536 @T6G_MB_LIB.T6G(SCH_1):PAGE85
    80 M_A_CPU0_SB_CA<4> @T6G_MB_LIB.T6G(SCH_1):M_A_CPU0_SB_CA(4)   I536 @T6G_MB_LIB.T6G(SCH_1):PAGE85
    70 M_A_CPU0_SA_CA<4> @T6G_MB_LIB.T6G(SCH_1):M_A_CPU0_SA_CA(4)   I536 @T6G_MB_LIB.T6G(SCH_1):PAGE85
   223 M_A_CPU0_SB_CA<3> @T6G_MB_LIB.T6G(SCH_1):M_A_CPU0_SB_CA(3)   I536 @T6G_MB_LIB.T6G(SCH_1):PAGE85
   213 M_A_CPU0_SA_CA<3> @T6G_MB_LIB.T6G(SCH_1):M_A_CPU0_SA_CA(3)   I536 @T6G_MB_LIB.T6G(SCH_1):PAGE85
    78 M_A_CPU0_SB_CA<2> @T6G_MB_LIB.T6G(SCH_1):M_A_CPU0_SB_CA(2)   I536 @T6G_MB_LIB.T6G(SCH_1):PAGE85
    68 M_A_CPU0_SA_CA<2> @T6G_MB_LIB.T6G(SCH_1):M_A_CPU0_SA_CA(2)   I536 @T6G_MB_LIB.T6G(SCH_1):PAGE85
   221 M_A_CPU0_SB_CA<1> @T6G_MB_LIB.T6G(SCH_1):M_A_CPU0_SB_CA(1)   I536 @T6G_MB_LIB.T6G(SCH_1):PAGE85
   211 M_A_CPU0_SA_CA<1> @T6G_MB_LIB.T6G(SCH_1):M_A_CPU0_SA_CA(1)   I536 @T6G_MB_LIB.T6G(SCH_1):PAGE85
    76 M_A_CPU0_SB_CA<0> @T6G_MB_LIB.T6G(SCH_1):M_A_CPU0_SB_CA(0)   I536 @T6G_MB_LIB.T6G(SCH_1):PAGE85
    66 M_A_CPU0_SA_CA<0> @T6G_MB_LIB.T6G(SCH_1):M_A_CPU0_SA_CA(0)   I536 @T6G_MB_LIB.T6G(SCH_1):PAGE85
    62 M_A_CPU0_ALERT_N @T6G_MB_LIB.T6G(SCH_1):M_A_CPU0_ALERT_N   I536 @T6G_MB_LIB.T6G(SCH_1):PAGE85
   236 M_A_CPU0_SB_CB<7> @T6G_MB_LIB.T6G(SCH_1):M_A_CPU0_SB_CB(7)   I536 @T6G_MB_LIB.T6G(SCH_1):PAGE85
    53 M_A_CPU0_SA_CB<1> @T6G_MB_LIB.T6G(SCH_1):M_A_CPU0_SA_CB(1)   I536 @T6G_MB_LIB.T6G(SCH_1):PAGE85
    58 M_A_CPU0_SA_CB<4> @T6G_MB_LIB.T6G(SCH_1):M_A_CPU0_SA_CB(4)   I536 @T6G_MB_LIB.T6G(SCH_1):PAGE85
   205 M_A_CPU0_SA_CB<7> @T6G_MB_LIB.T6G(SCH_1):M_A_CPU0_SA_CB(7)   I536 @T6G_MB_LIB.T6G(SCH_1):PAGE85
   194 M_A_CPU0_SA_DQ<31> @T6G_MB_LIB.T6G(SCH_1):M_A_CPU0_SA_DQ(31)   I536 @T6G_MB_LIB.T6G(SCH_1):PAGE85
    93 M_A_CPU0_SB_DQS_DP<9> @T6G_MB_LIB.T6G(SCH_1):M_A_CPU0_SB_DQS_DP(9)   I537 @T6G_MB_LIB.T6G(SCH_1):PAGE85
    94 M_A_CPU0_SB_DQS_DN<9> @T6G_MB_LIB.T6G(SCH_1):M_A_CPU0_SB_DQS_DN(9)   I537 @T6G_MB_LIB.T6G(SCH_1):PAGE85
   201 M_A_CPU0_SA_DQS_DP<9> @T6G_MB_LIB.T6G(SCH_1):M_A_CPU0_SA_DQS_DP(9)   I537 @T6G_MB_LIB.T6G(SCH_1):PAGE85
   200 M_A_CPU0_SA_DQS_DN<9> @T6G_MB_LIB.T6G(SCH_1):M_A_CPU0_SA_DQS_DN(9)   I537 @T6G_MB_LIB.T6G(SCH_1):PAGE85
   190 M_A_CPU0_SA_DQS_DP<8> @T6G_MB_LIB.T6G(SCH_1):M_A_CPU0_SA_DQS_DP(8)   I537 @T6G_MB_LIB.T6G(SCH_1):PAGE85
   189 M_A_CPU0_SA_DQS_DN<8> @T6G_MB_LIB.T6G(SCH_1):M_A_CPU0_SA_DQS_DN(8)   I537 @T6G_MB_LIB.T6G(SCH_1):PAGE85
   271 M_A_CPU0_SB_DQS_DN<7> @T6G_MB_LIB.T6G(SCH_1):M_A_CPU0_SB_DQS_DN(7)   I537 @T6G_MB_LIB.T6G(SCH_1):PAGE85
   179 M_A_CPU0_SA_DQS_DP<7> @T6G_MB_LIB.T6G(SCH_1):M_A_CPU0_SA_DQS_DP(7)   I537 @T6G_MB_LIB.T6G(SCH_1):PAGE85
   261 M_A_CPU0_SB_DQS_DP<6> @T6G_MB_LIB.T6G(SCH_1):M_A_CPU0_SB_DQS_DP(6)   I537 @T6G_MB_LIB.T6G(SCH_1):PAGE85
   260 M_A_CPU0_SB_DQS_DN<6> @T6G_MB_LIB.T6G(SCH_1):M_A_CPU0_SB_DQS_DN(6)   I537 @T6G_MB_LIB.T6G(SCH_1):PAGE85
   167 M_A_CPU0_SA_DQS_DN<6> @T6G_MB_LIB.T6G(SCH_1):M_A_CPU0_SA_DQS_DN(6)   I537 @T6G_MB_LIB.T6G(SCH_1):PAGE85
   250 M_A_CPU0_SB_DQS_DP<5> @T6G_MB_LIB.T6G(SCH_1):M_A_CPU0_SB_DQS_DP(5)   I537 @T6G_MB_LIB.T6G(SCH_1):PAGE85
   249 M_A_CPU0_SB_DQS_DN<5> @T6G_MB_LIB.T6G(SCH_1):M_A_CPU0_SB_DQS_DN(5)   I537 @T6G_MB_LIB.T6G(SCH_1):PAGE85
   157 M_A_CPU0_SA_DQS_DP<5> @T6G_MB_LIB.T6G(SCH_1):M_A_CPU0_SA_DQS_DP(5)   I537 @T6G_MB_LIB.T6G(SCH_1):PAGE85
   156 M_A_CPU0_SA_DQS_DN<5> @T6G_MB_LIB.T6G(SCH_1):M_A_CPU0_SA_DQS_DN(5)   I537 @T6G_MB_LIB.T6G(SCH_1):PAGE85
   239 M_A_CPU0_SB_DQS_DP<4> @T6G_MB_LIB.T6G(SCH_1):M_A_CPU0_SB_DQS_DP(4)   I537 @T6G_MB_LIB.T6G(SCH_1):PAGE85
   238 M_A_CPU0_SB_DQS_DN<4> @T6G_MB_LIB.T6G(SCH_1):M_A_CPU0_SB_DQS_DN(4)   I537 @T6G_MB_LIB.T6G(SCH_1):PAGE85
    55 M_A_CPU0_SA_DQS_DP<4> @T6G_MB_LIB.T6G(SCH_1):M_A_CPU0_SA_DQS_DP(4)   I537 @T6G_MB_LIB.T6G(SCH_1):PAGE85
    56 M_A_CPU0_SA_DQS_DN<4> @T6G_MB_LIB.T6G(SCH_1):M_A_CPU0_SA_DQS_DN(4)   I537 @T6G_MB_LIB.T6G(SCH_1):PAGE85
   137 M_A_CPU0_SB_DQS_DP<3> @T6G_MB_LIB.T6G(SCH_1):M_A_CPU0_SB_DQS_DP(3)   I537 @T6G_MB_LIB.T6G(SCH_1):PAGE85
   138 M_A_CPU0_SB_DQS_DN<3> @T6G_MB_LIB.T6G(SCH_1):M_A_CPU0_SB_DQS_DN(3)   I537 @T6G_MB_LIB.T6G(SCH_1):PAGE85
    44 M_A_CPU0_SA_DQS_DP<3> @T6G_MB_LIB.T6G(SCH_1):M_A_CPU0_SA_DQS_DP(3)   I537 @T6G_MB_LIB.T6G(SCH_1):PAGE85
    45 M_A_CPU0_SA_DQS_DN<3> @T6G_MB_LIB.T6G(SCH_1):M_A_CPU0_SA_DQS_DN(3)   I537 @T6G_MB_LIB.T6G(SCH_1):PAGE85
   126 M_A_CPU0_SB_DQS_DP<2> @T6G_MB_LIB.T6G(SCH_1):M_A_CPU0_SB_DQS_DP(2)   I537 @T6G_MB_LIB.T6G(SCH_1):PAGE85
   127 M_A_CPU0_SB_DQS_DN<2> @T6G_MB_LIB.T6G(SCH_1):M_A_CPU0_SB_DQS_DN(2)   I537 @T6G_MB_LIB.T6G(SCH_1):PAGE85
    33 M_A_CPU0_SA_DQS_DP<2> @T6G_MB_LIB.T6G(SCH_1):M_A_CPU0_SA_DQS_DP(2)   I537 @T6G_MB_LIB.T6G(SCH_1):PAGE85
    34 M_A_CPU0_SA_DQS_DN<2> @T6G_MB_LIB.T6G(SCH_1):M_A_CPU0_SA_DQS_DN(2)   I537 @T6G_MB_LIB.T6G(SCH_1):PAGE85
   115 M_A_CPU0_SB_DQS_DP<1> @T6G_MB_LIB.T6G(SCH_1):M_A_CPU0_SB_DQS_DP(1)   I537 @T6G_MB_LIB.T6G(SCH_1):PAGE85
   116 M_A_CPU0_SB_DQS_DN<1> @T6G_MB_LIB.T6G(SCH_1):M_A_CPU0_SB_DQS_DN(1)   I537 @T6G_MB_LIB.T6G(SCH_1):PAGE85
    22 M_A_CPU0_SA_DQS_DP<1> @T6G_MB_LIB.T6G(SCH_1):M_A_CPU0_SA_DQS_DP(1)   I537 @T6G_MB_LIB.T6G(SCH_1):PAGE85
    23 M_A_CPU0_SA_DQS_DN<1> @T6G_MB_LIB.T6G(SCH_1):M_A_CPU0_SA_DQS_DN(1)   I537 @T6G_MB_LIB.T6G(SCH_1):PAGE85
   104 M_A_CPU0_SB_DQS_DP<0> @T6G_MB_LIB.T6G(SCH_1):M_A_CPU0_SB_DQS_DP(0)   I537 @T6G_MB_LIB.T6G(SCH_1):PAGE85
   105 M_A_CPU0_SB_DQS_DN<0> @T6G_MB_LIB.T6G(SCH_1):M_A_CPU0_SB_DQS_DN(0)   I537 @T6G_MB_LIB.T6G(SCH_1):PAGE85
    11 M_A_CPU0_SA_DQS_DP<0> @T6G_MB_LIB.T6G(SCH_1):M_A_CPU0_SA_DQS_DP(0)   I537 @T6G_MB_LIB.T6G(SCH_1):PAGE85
    12 M_A_CPU0_SA_DQS_DN<0> @T6G_MB_LIB.T6G(SCH_1):M_A_CPU0_SA_DQS_DN(0)   I537 @T6G_MB_LIB.T6G(SCH_1):PAGE85
   272 M_A_CPU0_SB_DQS_DP<7> @T6G_MB_LIB.T6G(SCH_1):M_A_CPU0_SB_DQS_DP(7)   I537 @T6G_MB_LIB.T6G(SCH_1):PAGE85
   282 M_A_CPU0_SB_DQS_DN<8> @T6G_MB_LIB.T6G(SCH_1):M_A_CPU0_SB_DQS_DN(8)   I537 @T6G_MB_LIB.T6G(SCH_1):PAGE85
   283 M_A_CPU0_SB_DQS_DP<8> @T6G_MB_LIB.T6G(SCH_1):M_A_CPU0_SB_DQS_DP(8)   I537 @T6G_MB_LIB.T6G(SCH_1):PAGE85
   168 M_A_CPU0_SA_DQS_DP<6> @T6G_MB_LIB.T6G(SCH_1):M_A_CPU0_SA_DQS_DP(6)   I537 @T6G_MB_LIB.T6G(SCH_1):PAGE85
   178 M_A_CPU0_SA_DQS_DN<7> @T6G_MB_LIB.T6G(SCH_1):M_A_CPU0_SA_DQS_DN(7)   I537 @T6G_MB_LIB.T6G(SCH_1):PAGE85
     6    GND @T6G_MB_LIB.T6G(SCH_1):GND   I538 @T6G_MB_LIB.T6G(SCH_1):PAGE85
     8    GND @T6G_MB_LIB.T6G(SCH_1):GND   I538 @T6G_MB_LIB.T6G(SCH_1):PAGE85
    10    GND @T6G_MB_LIB.T6G(SCH_1):GND   I538 @T6G_MB_LIB.T6G(SCH_1):PAGE85
    13    GND @T6G_MB_LIB.T6G(SCH_1):GND   I538 @T6G_MB_LIB.T6G(SCH_1):PAGE85
    15    GND @T6G_MB_LIB.T6G(SCH_1):GND   I538 @T6G_MB_LIB.T6G(SCH_1):PAGE85
    17    GND @T6G_MB_LIB.T6G(SCH_1):GND   I538 @T6G_MB_LIB.T6G(SCH_1):PAGE85
    19    GND @T6G_MB_LIB.T6G(SCH_1):GND   I538 @T6G_MB_LIB.T6G(SCH_1):PAGE85
    21    GND @T6G_MB_LIB.T6G(SCH_1):GND   I538 @T6G_MB_LIB.T6G(SCH_1):PAGE85
    24    GND @T6G_MB_LIB.T6G(SCH_1):GND   I538 @T6G_MB_LIB.T6G(SCH_1):PAGE85
    26    GND @T6G_MB_LIB.T6G(SCH_1):GND   I538 @T6G_MB_LIB.T6G(SCH_1):PAGE85
    28    GND @T6G_MB_LIB.T6G(SCH_1):GND   I538 @T6G_MB_LIB.T6G(SCH_1):PAGE85
    30    GND @T6G_MB_LIB.T6G(SCH_1):GND   I538 @T6G_MB_LIB.T6G(SCH_1):PAGE85
    32    GND @T6G_MB_LIB.T6G(SCH_1):GND   I538 @T6G_MB_LIB.T6G(SCH_1):PAGE85
    35    GND @T6G_MB_LIB.T6G(SCH_1):GND   I538 @T6G_MB_LIB.T6G(SCH_1):PAGE85
    37    GND @T6G_MB_LIB.T6G(SCH_1):GND   I538 @T6G_MB_LIB.T6G(SCH_1):PAGE85
    39    GND @T6G_MB_LIB.T6G(SCH_1):GND   I538 @T6G_MB_LIB.T6G(SCH_1):PAGE85
    41    GND @T6G_MB_LIB.T6G(SCH_1):GND   I538 @T6G_MB_LIB.T6G(SCH_1):PAGE85
    43    GND @T6G_MB_LIB.T6G(SCH_1):GND   I538 @T6G_MB_LIB.T6G(SCH_1):PAGE85
    46    GND @T6G_MB_LIB.T6G(SCH_1):GND   I538 @T6G_MB_LIB.T6G(SCH_1):PAGE85
    48    GND @T6G_MB_LIB.T6G(SCH_1):GND   I538 @T6G_MB_LIB.T6G(SCH_1):PAGE85
    50    GND @T6G_MB_LIB.T6G(SCH_1):GND   I538 @T6G_MB_LIB.T6G(SCH_1):PAGE85
    52    GND @T6G_MB_LIB.T6G(SCH_1):GND   I538 @T6G_MB_LIB.T6G(SCH_1):PAGE85
    54    GND @T6G_MB_LIB.T6G(SCH_1):GND   I538 @T6G_MB_LIB.T6G(SCH_1):PAGE85
    57    GND @T6G_MB_LIB.T6G(SCH_1):GND   I538 @T6G_MB_LIB.T6G(SCH_1):PAGE85
    59    GND @T6G_MB_LIB.T6G(SCH_1):GND   I538 @T6G_MB_LIB.T6G(SCH_1):PAGE85
    61    GND @T6G_MB_LIB.T6G(SCH_1):GND   I538 @T6G_MB_LIB.T6G(SCH_1):PAGE85
    63    GND @T6G_MB_LIB.T6G(SCH_1):GND   I538 @T6G_MB_LIB.T6G(SCH_1):PAGE85
    65    GND @T6G_MB_LIB.T6G(SCH_1):GND   I538 @T6G_MB_LIB.T6G(SCH_1):PAGE85
    67    GND @T6G_MB_LIB.T6G(SCH_1):GND   I538 @T6G_MB_LIB.T6G(SCH_1):PAGE85
    69    GND @T6G_MB_LIB.T6G(SCH_1):GND   I538 @T6G_MB_LIB.T6G(SCH_1):PAGE85
    71    GND @T6G_MB_LIB.T6G(SCH_1):GND   I538 @T6G_MB_LIB.T6G(SCH_1):PAGE85
    73    GND @T6G_MB_LIB.T6G(SCH_1):GND   I538 @T6G_MB_LIB.T6G(SCH_1):PAGE85
    75    GND @T6G_MB_LIB.T6G(SCH_1):GND   I538 @T6G_MB_LIB.T6G(SCH_1):PAGE85
    77    GND @T6G_MB_LIB.T6G(SCH_1):GND   I538 @T6G_MB_LIB.T6G(SCH_1):PAGE85
    79    GND @T6G_MB_LIB.T6G(SCH_1):GND   I538 @T6G_MB_LIB.T6G(SCH_1):PAGE85
    81    GND @T6G_MB_LIB.T6G(SCH_1):GND   I538 @T6G_MB_LIB.T6G(SCH_1):PAGE85
    83    GND @T6G_MB_LIB.T6G(SCH_1):GND   I538 @T6G_MB_LIB.T6G(SCH_1):PAGE85
    85    GND @T6G_MB_LIB.T6G(SCH_1):GND   I538 @T6G_MB_LIB.T6G(SCH_1):PAGE85
    88    GND @T6G_MB_LIB.T6G(SCH_1):GND   I538 @T6G_MB_LIB.T6G(SCH_1):PAGE85
    90    GND @T6G_MB_LIB.T6G(SCH_1):GND   I538 @T6G_MB_LIB.T6G(SCH_1):PAGE85
    92    GND @T6G_MB_LIB.T6G(SCH_1):GND   I538 @T6G_MB_LIB.T6G(SCH_1):PAGE85
    95    GND @T6G_MB_LIB.T6G(SCH_1):GND   I538 @T6G_MB_LIB.T6G(SCH_1):PAGE85
    97    GND @T6G_MB_LIB.T6G(SCH_1):GND   I538 @T6G_MB_LIB.T6G(SCH_1):PAGE85
    99    GND @T6G_MB_LIB.T6G(SCH_1):GND   I538 @T6G_MB_LIB.T6G(SCH_1):PAGE85
   101    GND @T6G_MB_LIB.T6G(SCH_1):GND   I538 @T6G_MB_LIB.T6G(SCH_1):PAGE85
   103    GND @T6G_MB_LIB.T6G(SCH_1):GND   I538 @T6G_MB_LIB.T6G(SCH_1):PAGE85
   106    GND @T6G_MB_LIB.T6G(SCH_1):GND   I538 @T6G_MB_LIB.T6G(SCH_1):PAGE85
   108    GND @T6G_MB_LIB.T6G(SCH_1):GND   I538 @T6G_MB_LIB.T6G(SCH_1):PAGE85
   110    GND @T6G_MB_LIB.T6G(SCH_1):GND   I538 @T6G_MB_LIB.T6G(SCH_1):PAGE85
   112    GND @T6G_MB_LIB.T6G(SCH_1):GND   I538 @T6G_MB_LIB.T6G(SCH_1):PAGE85
   114    GND @T6G_MB_LIB.T6G(SCH_1):GND   I538 @T6G_MB_LIB.T6G(SCH_1):PAGE85
   117    GND @T6G_MB_LIB.T6G(SCH_1):GND   I538 @T6G_MB_LIB.T6G(SCH_1):PAGE85
   119    GND @T6G_MB_LIB.T6G(SCH_1):GND   I538 @T6G_MB_LIB.T6G(SCH_1):PAGE85
   121    GND @T6G_MB_LIB.T6G(SCH_1):GND   I538 @T6G_MB_LIB.T6G(SCH_1):PAGE85
   123    GND @T6G_MB_LIB.T6G(SCH_1):GND   I538 @T6G_MB_LIB.T6G(SCH_1):PAGE85
   125    GND @T6G_MB_LIB.T6G(SCH_1):GND   I538 @T6G_MB_LIB.T6G(SCH_1):PAGE85
   128    GND @T6G_MB_LIB.T6G(SCH_1):GND   I538 @T6G_MB_LIB.T6G(SCH_1):PAGE85
   130    GND @T6G_MB_LIB.T6G(SCH_1):GND   I538 @T6G_MB_LIB.T6G(SCH_1):PAGE85
   134    GND @T6G_MB_LIB.T6G(SCH_1):GND   I538 @T6G_MB_LIB.T6G(SCH_1):PAGE85
   143    GND @T6G_MB_LIB.T6G(SCH_1):GND   I538 @T6G_MB_LIB.T6G(SCH_1):PAGE85
   151    GND @T6G_MB_LIB.T6G(SCH_1):GND   I538 @T6G_MB_LIB.T6G(SCH_1):PAGE85
   153    GND @T6G_MB_LIB.T6G(SCH_1):GND   I538 @T6G_MB_LIB.T6G(SCH_1):PAGE85
   155    GND @T6G_MB_LIB.T6G(SCH_1):GND   I538 @T6G_MB_LIB.T6G(SCH_1):PAGE85
   158    GND @T6G_MB_LIB.T6G(SCH_1):GND   I538 @T6G_MB_LIB.T6G(SCH_1):PAGE85
   160    GND @T6G_MB_LIB.T6G(SCH_1):GND   I538 @T6G_MB_LIB.T6G(SCH_1):PAGE85
   162    GND @T6G_MB_LIB.T6G(SCH_1):GND   I538 @T6G_MB_LIB.T6G(SCH_1):PAGE85
   164    GND @T6G_MB_LIB.T6G(SCH_1):GND   I538 @T6G_MB_LIB.T6G(SCH_1):PAGE85
   166    GND @T6G_MB_LIB.T6G(SCH_1):GND   I538 @T6G_MB_LIB.T6G(SCH_1):PAGE85
   169    GND @T6G_MB_LIB.T6G(SCH_1):GND   I538 @T6G_MB_LIB.T6G(SCH_1):PAGE85
   171    GND @T6G_MB_LIB.T6G(SCH_1):GND   I538 @T6G_MB_LIB.T6G(SCH_1):PAGE85
   173    GND @T6G_MB_LIB.T6G(SCH_1):GND   I538 @T6G_MB_LIB.T6G(SCH_1):PAGE85
   175    GND @T6G_MB_LIB.T6G(SCH_1):GND   I538 @T6G_MB_LIB.T6G(SCH_1):PAGE85
   177    GND @T6G_MB_LIB.T6G(SCH_1):GND   I538 @T6G_MB_LIB.T6G(SCH_1):PAGE85
   180    GND @T6G_MB_LIB.T6G(SCH_1):GND   I538 @T6G_MB_LIB.T6G(SCH_1):PAGE85
   182    GND @T6G_MB_LIB.T6G(SCH_1):GND   I538 @T6G_MB_LIB.T6G(SCH_1):PAGE85
   184    GND @T6G_MB_LIB.T6G(SCH_1):GND   I538 @T6G_MB_LIB.T6G(SCH_1):PAGE85
   186    GND @T6G_MB_LIB.T6G(SCH_1):GND   I538 @T6G_MB_LIB.T6G(SCH_1):PAGE85
   188    GND @T6G_MB_LIB.T6G(SCH_1):GND   I538 @T6G_MB_LIB.T6G(SCH_1):PAGE85
   191    GND @T6G_MB_LIB.T6G(SCH_1):GND   I538 @T6G_MB_LIB.T6G(SCH_1):PAGE85
   193    GND @T6G_MB_LIB.T6G(SCH_1):GND   I538 @T6G_MB_LIB.T6G(SCH_1):PAGE85
   195    GND @T6G_MB_LIB.T6G(SCH_1):GND   I538 @T6G_MB_LIB.T6G(SCH_1):PAGE85
   197    GND @T6G_MB_LIB.T6G(SCH_1):GND   I538 @T6G_MB_LIB.T6G(SCH_1):PAGE85
   199    GND @T6G_MB_LIB.T6G(SCH_1):GND   I538 @T6G_MB_LIB.T6G(SCH_1):PAGE85
   202    GND @T6G_MB_LIB.T6G(SCH_1):GND   I538 @T6G_MB_LIB.T6G(SCH_1):PAGE85
   204    GND @T6G_MB_LIB.T6G(SCH_1):GND   I538 @T6G_MB_LIB.T6G(SCH_1):PAGE85
   206    GND @T6G_MB_LIB.T6G(SCH_1):GND   I538 @T6G_MB_LIB.T6G(SCH_1):PAGE85
   208    GND @T6G_MB_LIB.T6G(SCH_1):GND   I538 @T6G_MB_LIB.T6G(SCH_1):PAGE85
   210    GND @T6G_MB_LIB.T6G(SCH_1):GND   I538 @T6G_MB_LIB.T6G(SCH_1):PAGE85
   212    GND @T6G_MB_LIB.T6G(SCH_1):GND   I538 @T6G_MB_LIB.T6G(SCH_1):PAGE85
   214    GND @T6G_MB_LIB.T6G(SCH_1):GND   I538 @T6G_MB_LIB.T6G(SCH_1):PAGE85
   216    GND @T6G_MB_LIB.T6G(SCH_1):GND   I538 @T6G_MB_LIB.T6G(SCH_1):PAGE85
   219    GND @T6G_MB_LIB.T6G(SCH_1):GND   I538 @T6G_MB_LIB.T6G(SCH_1):PAGE85
   222    GND @T6G_MB_LIB.T6G(SCH_1):GND   I538 @T6G_MB_LIB.T6G(SCH_1):PAGE85
   224    GND @T6G_MB_LIB.T6G(SCH_1):GND   I538 @T6G_MB_LIB.T6G(SCH_1):PAGE85
   226    GND @T6G_MB_LIB.T6G(SCH_1):GND   I538 @T6G_MB_LIB.T6G(SCH_1):PAGE85
   228    GND @T6G_MB_LIB.T6G(SCH_1):GND   I538 @T6G_MB_LIB.T6G(SCH_1):PAGE85
   233    GND @T6G_MB_LIB.T6G(SCH_1):GND   I538 @T6G_MB_LIB.T6G(SCH_1):PAGE85
   237    GND @T6G_MB_LIB.T6G(SCH_1):GND   I538 @T6G_MB_LIB.T6G(SCH_1):PAGE85
   242    GND @T6G_MB_LIB.T6G(SCH_1):GND   I538 @T6G_MB_LIB.T6G(SCH_1):PAGE85
   244    GND @T6G_MB_LIB.T6G(SCH_1):GND   I538 @T6G_MB_LIB.T6G(SCH_1):PAGE85
   246    GND @T6G_MB_LIB.T6G(SCH_1):GND   I538 @T6G_MB_LIB.T6G(SCH_1):PAGE85
   248    GND @T6G_MB_LIB.T6G(SCH_1):GND   I538 @T6G_MB_LIB.T6G(SCH_1):PAGE85
   251    GND @T6G_MB_LIB.T6G(SCH_1):GND   I538 @T6G_MB_LIB.T6G(SCH_1):PAGE85
   253    GND @T6G_MB_LIB.T6G(SCH_1):GND   I538 @T6G_MB_LIB.T6G(SCH_1):PAGE85
   255    GND @T6G_MB_LIB.T6G(SCH_1):GND   I538 @T6G_MB_LIB.T6G(SCH_1):PAGE85
   257    GND @T6G_MB_LIB.T6G(SCH_1):GND   I538 @T6G_MB_LIB.T6G(SCH_1):PAGE85
   259    GND @T6G_MB_LIB.T6G(SCH_1):GND   I538 @T6G_MB_LIB.T6G(SCH_1):PAGE85
   262    GND @T6G_MB_LIB.T6G(SCH_1):GND   I538 @T6G_MB_LIB.T6G(SCH_1):PAGE85
   264    GND @T6G_MB_LIB.T6G(SCH_1):GND   I538 @T6G_MB_LIB.T6G(SCH_1):PAGE85
   266    GND @T6G_MB_LIB.T6G(SCH_1):GND   I538 @T6G_MB_LIB.T6G(SCH_1):PAGE85
   268    GND @T6G_MB_LIB.T6G(SCH_1):GND   I538 @T6G_MB_LIB.T6G(SCH_1):PAGE85
   270    GND @T6G_MB_LIB.T6G(SCH_1):GND   I538 @T6G_MB_LIB.T6G(SCH_1):PAGE85
   273    GND @T6G_MB_LIB.T6G(SCH_1):GND   I538 @T6G_MB_LIB.T6G(SCH_1):PAGE85
   275    GND @T6G_MB_LIB.T6G(SCH_1):GND   I538 @T6G_MB_LIB.T6G(SCH_1):PAGE85
   277    GND @T6G_MB_LIB.T6G(SCH_1):GND   I538 @T6G_MB_LIB.T6G(SCH_1):PAGE85
   279    GND @T6G_MB_LIB.T6G(SCH_1):GND   I538 @T6G_MB_LIB.T6G(SCH_1):PAGE85
   281    GND @T6G_MB_LIB.T6G(SCH_1):GND   I538 @T6G_MB_LIB.T6G(SCH_1):PAGE85
   284    GND @T6G_MB_LIB.T6G(SCH_1):GND   I538 @T6G_MB_LIB.T6G(SCH_1):PAGE85
   286    GND @T6G_MB_LIB.T6G(SCH_1):GND   I538 @T6G_MB_LIB.T6G(SCH_1):PAGE85
   288    GND @T6G_MB_LIB.T6G(SCH_1):GND   I538 @T6G_MB_LIB.T6G(SCH_1):PAGE85
     1 P12V_MEM_CPU0 @T6G_MB_LIB.T6G(SCH_1):P12V_MEM_CPU0   I538 @T6G_MB_LIB.T6G(SCH_1):PAGE85
   145 P12V_MEM_CPU0 @T6G_MB_LIB.T6G(SCH_1):P12V_MEM_CPU0   I538 @T6G_MB_LIB.T6G(SCH_1):PAGE85
   146 P12V_MEM_CPU0 @T6G_MB_LIB.T6G(SCH_1):P12V_MEM_CPU0   I538 @T6G_MB_LIB.T6G(SCH_1):PAGE85
   230    GND @T6G_MB_LIB.T6G(SCH_1):GND   I538 @T6G_MB_LIB.T6G(SCH_1):PAGE85
   235    GND @T6G_MB_LIB.T6G(SCH_1):GND   I538 @T6G_MB_LIB.T6G(SCH_1):PAGE85
   240    GND @T6G_MB_LIB.T6G(SCH_1):GND   I538 @T6G_MB_LIB.T6G(SCH_1):PAGE85
   132    GND @T6G_MB_LIB.T6G(SCH_1):GND   I538 @T6G_MB_LIB.T6G(SCH_1):PAGE85
   136    GND @T6G_MB_LIB.T6G(SCH_1):GND   I538 @T6G_MB_LIB.T6G(SCH_1):PAGE85
   139    GND @T6G_MB_LIB.T6G(SCH_1):GND   I538 @T6G_MB_LIB.T6G(SCH_1):PAGE85
   141    GND @T6G_MB_LIB.T6G(SCH_1):GND   I538 @T6G_MB_LIB.T6G(SCH_1):PAGE85
    G1    GND @T6G_MB_LIB.T6G(SCH_1):GND   I538 @T6G_MB_LIB.T6G(SCH_1):PAGE85
    G2    GND @T6G_MB_LIB.T6G(SCH_1):GND   I538 @T6G_MB_LIB.T6G(SCH_1):PAGE85
    G3    GND @T6G_MB_LIB.T6G(SCH_1):GND   I538 @T6G_MB_LIB.T6G(SCH_1):PAGE85

  J5 SCONN8_G802M0083150RD3HR-SCONN8_G802M0083150RD3HR,A
     1 CPU0_XTRIG_R1_L4 @T6G_MB_LIB.T6G(SCH_1):CPU0_XTRIG_R1_L4   I425 @T6G_MB_LIB.T6G(SCH_1):PAGE27
     2    GND @T6G_MB_LIB.T6G(SCH_1):GND   I425 @T6G_MB_LIB.T6G(SCH_1):PAGE27
     3 CPU0_XTRIG_R1_L5 @T6G_MB_LIB.T6G(SCH_1):CPU0_XTRIG_R1_L5   I425 @T6G_MB_LIB.T6G(SCH_1):PAGE27
     4    GND @T6G_MB_LIB.T6G(SCH_1):GND   I425 @T6G_MB_LIB.T6G(SCH_1):PAGE27
     5 CPU0_XTRIG_R1_L6 @T6G_MB_LIB.T6G(SCH_1):CPU0_XTRIG_R1_L6   I425 @T6G_MB_LIB.T6G(SCH_1):PAGE27
     6    GND @T6G_MB_LIB.T6G(SCH_1):GND   I425 @T6G_MB_LIB.T6G(SCH_1):PAGE27
     7 CPU0_XTRIG_R1_L7 @T6G_MB_LIB.T6G(SCH_1):CPU0_XTRIG_R1_L7   I425 @T6G_MB_LIB.T6G(SCH_1):PAGE27
     8    GND @T6G_MB_LIB.T6G(SCH_1):GND   I425 @T6G_MB_LIB.T6G(SCH_1):PAGE27

  J6 CONN6_HBC1031L200D8H-CONN6_HBC1031-L200D-8H,THLF,IA
     1 CPU0_PWR_BTN_N @T6G_MB_LIB.T6G(SCH_1):CPU0_PWR_BTN_N    I28 @T6G_MB_LIB.T6G(SCH_1):PAGE28
     2    GND @T6G_MB_LIB.T6G(SCH_1):GND    I28 @T6G_MB_LIB.T6G(SCH_1):PAGE28
     3 RST_CPU0_SYS_N @T6G_MB_LIB.T6G(SCH_1):RST_CPU0_SYS_N    I28 @T6G_MB_LIB.T6G(SCH_1):PAGE28
     4    GND @T6G_MB_LIB.T6G(SCH_1):GND    I28 @T6G_MB_LIB.T6G(SCH_1):PAGE28
     5     NC     NC    I28 @T6G_MB_LIB.T6G(SCH_1):PAGE28
     6    GND @T6G_MB_LIB.T6G(SCH_1):GND    I28 @T6G_MB_LIB.T6G(SCH_1):PAGE28

  J7 SCONN8_G802M0083150RD3HR-SCONN8_G802M0083150RD3HR,A
     1 CPU1_XTRIG_R1_L4 @T6G_MB_LIB.T6G(SCH_1):CPU1_XTRIG_R1_L4   I418 @T6G_MB_LIB.T6G(SCH_1):PAGE54
     2    GND @T6G_MB_LIB.T6G(SCH_1):GND   I418 @T6G_MB_LIB.T6G(SCH_1):PAGE54
     3 CPU1_XTRIG_R1_L5 @T6G_MB_LIB.T6G(SCH_1):CPU1_XTRIG_R1_L5   I418 @T6G_MB_LIB.T6G(SCH_1):PAGE54
     4    GND @T6G_MB_LIB.T6G(SCH_1):GND   I418 @T6G_MB_LIB.T6G(SCH_1):PAGE54
     5 CPU1_XTRIG_R1_L6 @T6G_MB_LIB.T6G(SCH_1):CPU1_XTRIG_R1_L6   I418 @T6G_MB_LIB.T6G(SCH_1):PAGE54
     6    GND @T6G_MB_LIB.T6G(SCH_1):GND   I418 @T6G_MB_LIB.T6G(SCH_1):PAGE54
     7 CPU1_XTRIG_R1_L7 @T6G_MB_LIB.T6G(SCH_1):CPU1_XTRIG_R1_L7   I418 @T6G_MB_LIB.T6G(SCH_1):PAGE54
     8    GND @T6G_MB_LIB.T6G(SCH_1):GND   I418 @T6G_MB_LIB.T6G(SCH_1):PAGE54

  J8 CONN4_HFK1040L0P1L7H-CONN4_HFK1040-L0P1L-7H,THLF,IA
     4    GND @T6G_MB_LIB.T6G(SCH_1):GND   I148 @T6G_MB_LIB.T6G(SCH_1):PAGE349
     3 UART_CPU0_SCM_LVC3_UART1_TX @T6G_MB_LIB.T6G(SCH_1):UART_CPU0_SCM_LVC3_UART1_TX   I148 @T6G_MB_LIB.T6G(SCH_1):PAGE349
     2 UART_CPU0_SCM_LVC3_UART1_R_RX @T6G_MB_LIB.T6G(SCH_1):UART_CPU0_SCM_LVC3_UART1_R_RX   I148 @T6G_MB_LIB.T6G(SCH_1):PAGE349
     1 UART_VCC_J8 @T6G_MB_LIB.T6G(SCH_1):UART_VCC_J8   I148 @T6G_MB_LIB.T6G(SCH_1):PAGE349

 J13 CONN4_HFK1040L0P1L7H-CONN4_HFK1040-L0P1L-7H,THLF,IA
     4    GND @T6G_MB_LIB.T6G(SCH_1):GND   I195 @T6G_MB_LIB.T6G(SCH_1):PAGE141
     3 UART_CPU0_LVC3_UART0_TX @T6G_MB_LIB.T6G(SCH_1):UART_CPU0_LVC3_UART0_TX   I195 @T6G_MB_LIB.T6G(SCH_1):PAGE141
     2 UART_CPU0_LVC3_UART0_RX @T6G_MB_LIB.T6G(SCH_1):UART_CPU0_LVC3_UART0_RX   I195 @T6G_MB_LIB.T6G(SCH_1):PAGE141
     1 UART_VCC_J13 @T6G_MB_LIB.T6G(SCH_1):UART_VCC_J13   I195 @T6G_MB_LIB.T6G(SCH_1):PAGE141

 J15 SCONN288_DDR506112002KQ-SCONN288_DDR506112002KQ,SMA
     3 P3V3_AUX @T6G_MB_LIB.T6G(SCH_1):P3V3_AUX   I350 @T6G_MB_LIB.T6G(SCH_1):PAGE86
     2     NC     NC   I350 @T6G_MB_LIB.T6G(SCH_1):PAGE86
   144     NC     NC   I350 @T6G_MB_LIB.T6G(SCH_1):PAGE86
   149     NC     NC   I350 @T6G_MB_LIB.T6G(SCH_1):PAGE86
   150     NC     NC   I350 @T6G_MB_LIB.T6G(SCH_1):PAGE86
   220     NC     NC   I350 @T6G_MB_LIB.T6G(SCH_1):PAGE86
   231     NC     NC   I350 @T6G_MB_LIB.T6G(SCH_1):PAGE86
   232     NC     NC   I350 @T6G_MB_LIB.T6G(SCH_1):PAGE86
   207 M_B_CPU0_RESET_N @T6G_MB_LIB.T6G(SCH_1):M_B_CPU0_RESET_N   I350 @T6G_MB_LIB.T6G(SCH_1):PAGE86
   147 PWRGD_CHB_CPU0_DIMM @T6G_MB_LIB.T6G(SCH_1):PWRGD_CHB_CPU0_DIMM   I350 @T6G_MB_LIB.T6G(SCH_1):PAGE86
   227 M_B_CPU0_SB_PAR @T6G_MB_LIB.T6G(SCH_1):M_B_CPU0_SB_PAR   I350 @T6G_MB_LIB.T6G(SCH_1):PAGE86
    74 M_B_CPU0_SA_PAR @T6G_MB_LIB.T6G(SCH_1):M_B_CPU0_SA_PAR   I350 @T6G_MB_LIB.T6G(SCH_1):PAGE86
    87 M_B_CPU0_SB_RSP<0> @T6G_MB_LIB.T6G(SCH_1):M_B_CPU0_SB_RSP(0)   I350 @T6G_MB_LIB.T6G(SCH_1):PAGE86
    86 M_B_CPU0_SA_RSP<0> @T6G_MB_LIB.T6G(SCH_1):M_B_CPU0_SA_RSP(0)   I350 @T6G_MB_LIB.T6G(SCH_1):PAGE86
     5 I3C_SPD_DDRB_CPU0_SDA @T6G_MB_LIB.T6G(SCH_1):I3C_SPD_DDRB_CPU0_SDA   I350 @T6G_MB_LIB.T6G(SCH_1):PAGE86
     4 I3C_SPD_DDRB_CPU0_SCL @T6G_MB_LIB.T6G(SCH_1):I3C_SPD_DDRB_CPU0_SCL   I350 @T6G_MB_LIB.T6G(SCH_1):PAGE86
   148 PD_CHB_CPU0_DIMM_SAA @T6G_MB_LIB.T6G(SCH_1):PD_CHB_CPU0_DIMM_SAA   I350 @T6G_MB_LIB.T6G(SCH_1):PAGE86
   100 M_B_CPU0_SB_DQ<0> @T6G_MB_LIB.T6G(SCH_1):M_B_CPU0_SB_DQ(0)   I350 @T6G_MB_LIB.T6G(SCH_1):PAGE86
   102 M_B_CPU0_SB_DQ<1> @T6G_MB_LIB.T6G(SCH_1):M_B_CPU0_SB_DQ(1)   I350 @T6G_MB_LIB.T6G(SCH_1):PAGE86
   245 M_B_CPU0_SB_DQ<2> @T6G_MB_LIB.T6G(SCH_1):M_B_CPU0_SB_DQ(2)   I350 @T6G_MB_LIB.T6G(SCH_1):PAGE86
   247 M_B_CPU0_SB_DQ<3> @T6G_MB_LIB.T6G(SCH_1):M_B_CPU0_SB_DQ(3)   I350 @T6G_MB_LIB.T6G(SCH_1):PAGE86
   107 M_B_CPU0_SB_DQ<4> @T6G_MB_LIB.T6G(SCH_1):M_B_CPU0_SB_DQ(4)   I350 @T6G_MB_LIB.T6G(SCH_1):PAGE86
   109 M_B_CPU0_SB_DQ<5> @T6G_MB_LIB.T6G(SCH_1):M_B_CPU0_SB_DQ(5)   I350 @T6G_MB_LIB.T6G(SCH_1):PAGE86
   252 M_B_CPU0_SB_DQ<6> @T6G_MB_LIB.T6G(SCH_1):M_B_CPU0_SB_DQ(6)   I350 @T6G_MB_LIB.T6G(SCH_1):PAGE86
   254 M_B_CPU0_SB_DQ<7> @T6G_MB_LIB.T6G(SCH_1):M_B_CPU0_SB_DQ(7)   I350 @T6G_MB_LIB.T6G(SCH_1):PAGE86
   111 M_B_CPU0_SB_DQ<8> @T6G_MB_LIB.T6G(SCH_1):M_B_CPU0_SB_DQ(8)   I350 @T6G_MB_LIB.T6G(SCH_1):PAGE86
   113 M_B_CPU0_SB_DQ<9> @T6G_MB_LIB.T6G(SCH_1):M_B_CPU0_SB_DQ(9)   I350 @T6G_MB_LIB.T6G(SCH_1):PAGE86
   256 M_B_CPU0_SB_DQ<10> @T6G_MB_LIB.T6G(SCH_1):M_B_CPU0_SB_DQ(10)   I350 @T6G_MB_LIB.T6G(SCH_1):PAGE86
   258 M_B_CPU0_SB_DQ<11> @T6G_MB_LIB.T6G(SCH_1):M_B_CPU0_SB_DQ(11)   I350 @T6G_MB_LIB.T6G(SCH_1):PAGE86
   118 M_B_CPU0_SB_DQ<12> @T6G_MB_LIB.T6G(SCH_1):M_B_CPU0_SB_DQ(12)   I350 @T6G_MB_LIB.T6G(SCH_1):PAGE86
   120 M_B_CPU0_SB_DQ<13> @T6G_MB_LIB.T6G(SCH_1):M_B_CPU0_SB_DQ(13)   I350 @T6G_MB_LIB.T6G(SCH_1):PAGE86
   263 M_B_CPU0_SB_DQ<14> @T6G_MB_LIB.T6G(SCH_1):M_B_CPU0_SB_DQ(14)   I350 @T6G_MB_LIB.T6G(SCH_1):PAGE86
   265 M_B_CPU0_SB_DQ<15> @T6G_MB_LIB.T6G(SCH_1):M_B_CPU0_SB_DQ(15)   I350 @T6G_MB_LIB.T6G(SCH_1):PAGE86
   122 M_B_CPU0_SB_DQ<16> @T6G_MB_LIB.T6G(SCH_1):M_B_CPU0_SB_DQ(16)   I350 @T6G_MB_LIB.T6G(SCH_1):PAGE86
   124 M_B_CPU0_SB_DQ<17> @T6G_MB_LIB.T6G(SCH_1):M_B_CPU0_SB_DQ(17)   I350 @T6G_MB_LIB.T6G(SCH_1):PAGE86
   267 M_B_CPU0_SB_DQ<18> @T6G_MB_LIB.T6G(SCH_1):M_B_CPU0_SB_DQ(18)   I350 @T6G_MB_LIB.T6G(SCH_1):PAGE86
   269 M_B_CPU0_SB_DQ<19> @T6G_MB_LIB.T6G(SCH_1):M_B_CPU0_SB_DQ(19)   I350 @T6G_MB_LIB.T6G(SCH_1):PAGE86
   129 M_B_CPU0_SB_DQ<20> @T6G_MB_LIB.T6G(SCH_1):M_B_CPU0_SB_DQ(20)   I350 @T6G_MB_LIB.T6G(SCH_1):PAGE86
   131 M_B_CPU0_SB_DQ<21> @T6G_MB_LIB.T6G(SCH_1):M_B_CPU0_SB_DQ(21)   I350 @T6G_MB_LIB.T6G(SCH_1):PAGE86
   274 M_B_CPU0_SB_DQ<22> @T6G_MB_LIB.T6G(SCH_1):M_B_CPU0_SB_DQ(22)   I350 @T6G_MB_LIB.T6G(SCH_1):PAGE86
   276 M_B_CPU0_SB_DQ<23> @T6G_MB_LIB.T6G(SCH_1):M_B_CPU0_SB_DQ(23)   I350 @T6G_MB_LIB.T6G(SCH_1):PAGE86
   133 M_B_CPU0_SB_DQ<24> @T6G_MB_LIB.T6G(SCH_1):M_B_CPU0_SB_DQ(24)   I350 @T6G_MB_LIB.T6G(SCH_1):PAGE86
   135 M_B_CPU0_SB_DQ<25> @T6G_MB_LIB.T6G(SCH_1):M_B_CPU0_SB_DQ(25)   I350 @T6G_MB_LIB.T6G(SCH_1):PAGE86
   278 M_B_CPU0_SB_DQ<26> @T6G_MB_LIB.T6G(SCH_1):M_B_CPU0_SB_DQ(26)   I350 @T6G_MB_LIB.T6G(SCH_1):PAGE86
   280 M_B_CPU0_SB_DQ<27> @T6G_MB_LIB.T6G(SCH_1):M_B_CPU0_SB_DQ(27)   I350 @T6G_MB_LIB.T6G(SCH_1):PAGE86
   140 M_B_CPU0_SB_DQ<28> @T6G_MB_LIB.T6G(SCH_1):M_B_CPU0_SB_DQ(28)   I350 @T6G_MB_LIB.T6G(SCH_1):PAGE86
   142 M_B_CPU0_SB_DQ<29> @T6G_MB_LIB.T6G(SCH_1):M_B_CPU0_SB_DQ(29)   I350 @T6G_MB_LIB.T6G(SCH_1):PAGE86
   285 M_B_CPU0_SB_DQ<30> @T6G_MB_LIB.T6G(SCH_1):M_B_CPU0_SB_DQ(30)   I350 @T6G_MB_LIB.T6G(SCH_1):PAGE86
   287 M_B_CPU0_SB_DQ<31> @T6G_MB_LIB.T6G(SCH_1):M_B_CPU0_SB_DQ(31)   I350 @T6G_MB_LIB.T6G(SCH_1):PAGE86
     7 M_B_CPU0_SA_DQ<0> @T6G_MB_LIB.T6G(SCH_1):M_B_CPU0_SA_DQ(0)   I350 @T6G_MB_LIB.T6G(SCH_1):PAGE86
     9 M_B_CPU0_SA_DQ<1> @T6G_MB_LIB.T6G(SCH_1):M_B_CPU0_SA_DQ(1)   I350 @T6G_MB_LIB.T6G(SCH_1):PAGE86
   152 M_B_CPU0_SA_DQ<2> @T6G_MB_LIB.T6G(SCH_1):M_B_CPU0_SA_DQ(2)   I350 @T6G_MB_LIB.T6G(SCH_1):PAGE86
   154 M_B_CPU0_SA_DQ<3> @T6G_MB_LIB.T6G(SCH_1):M_B_CPU0_SA_DQ(3)   I350 @T6G_MB_LIB.T6G(SCH_1):PAGE86
    14 M_B_CPU0_SA_DQ<4> @T6G_MB_LIB.T6G(SCH_1):M_B_CPU0_SA_DQ(4)   I350 @T6G_MB_LIB.T6G(SCH_1):PAGE86
    16 M_B_CPU0_SA_DQ<5> @T6G_MB_LIB.T6G(SCH_1):M_B_CPU0_SA_DQ(5)   I350 @T6G_MB_LIB.T6G(SCH_1):PAGE86
   159 M_B_CPU0_SA_DQ<6> @T6G_MB_LIB.T6G(SCH_1):M_B_CPU0_SA_DQ(6)   I350 @T6G_MB_LIB.T6G(SCH_1):PAGE86
   161 M_B_CPU0_SA_DQ<7> @T6G_MB_LIB.T6G(SCH_1):M_B_CPU0_SA_DQ(7)   I350 @T6G_MB_LIB.T6G(SCH_1):PAGE86
    18 M_B_CPU0_SA_DQ<8> @T6G_MB_LIB.T6G(SCH_1):M_B_CPU0_SA_DQ(8)   I350 @T6G_MB_LIB.T6G(SCH_1):PAGE86
    20 M_B_CPU0_SA_DQ<9> @T6G_MB_LIB.T6G(SCH_1):M_B_CPU0_SA_DQ(9)   I350 @T6G_MB_LIB.T6G(SCH_1):PAGE86
   163 M_B_CPU0_SA_DQ<10> @T6G_MB_LIB.T6G(SCH_1):M_B_CPU0_SA_DQ(10)   I350 @T6G_MB_LIB.T6G(SCH_1):PAGE86
   165 M_B_CPU0_SA_DQ<11> @T6G_MB_LIB.T6G(SCH_1):M_B_CPU0_SA_DQ(11)   I350 @T6G_MB_LIB.T6G(SCH_1):PAGE86
    25 M_B_CPU0_SA_DQ<12> @T6G_MB_LIB.T6G(SCH_1):M_B_CPU0_SA_DQ(12)   I350 @T6G_MB_LIB.T6G(SCH_1):PAGE86
    27 M_B_CPU0_SA_DQ<13> @T6G_MB_LIB.T6G(SCH_1):M_B_CPU0_SA_DQ(13)   I350 @T6G_MB_LIB.T6G(SCH_1):PAGE86
   170 M_B_CPU0_SA_DQ<14> @T6G_MB_LIB.T6G(SCH_1):M_B_CPU0_SA_DQ(14)   I350 @T6G_MB_LIB.T6G(SCH_1):PAGE86
   172 M_B_CPU0_SA_DQ<15> @T6G_MB_LIB.T6G(SCH_1):M_B_CPU0_SA_DQ(15)   I350 @T6G_MB_LIB.T6G(SCH_1):PAGE86
    29 M_B_CPU0_SA_DQ<16> @T6G_MB_LIB.T6G(SCH_1):M_B_CPU0_SA_DQ(16)   I350 @T6G_MB_LIB.T6G(SCH_1):PAGE86
    31 M_B_CPU0_SA_DQ<17> @T6G_MB_LIB.T6G(SCH_1):M_B_CPU0_SA_DQ(17)   I350 @T6G_MB_LIB.T6G(SCH_1):PAGE86
   174 M_B_CPU0_SA_DQ<18> @T6G_MB_LIB.T6G(SCH_1):M_B_CPU0_SA_DQ(18)   I350 @T6G_MB_LIB.T6G(SCH_1):PAGE86
   176 M_B_CPU0_SA_DQ<19> @T6G_MB_LIB.T6G(SCH_1):M_B_CPU0_SA_DQ(19)   I350 @T6G_MB_LIB.T6G(SCH_1):PAGE86
    36 M_B_CPU0_SA_DQ<20> @T6G_MB_LIB.T6G(SCH_1):M_B_CPU0_SA_DQ(20)   I350 @T6G_MB_LIB.T6G(SCH_1):PAGE86
    38 M_B_CPU0_SA_DQ<21> @T6G_MB_LIB.T6G(SCH_1):M_B_CPU0_SA_DQ(21)   I350 @T6G_MB_LIB.T6G(SCH_1):PAGE86
   181 M_B_CPU0_SA_DQ<22> @T6G_MB_LIB.T6G(SCH_1):M_B_CPU0_SA_DQ(22)   I350 @T6G_MB_LIB.T6G(SCH_1):PAGE86
   183 M_B_CPU0_SA_DQ<23> @T6G_MB_LIB.T6G(SCH_1):M_B_CPU0_SA_DQ(23)   I350 @T6G_MB_LIB.T6G(SCH_1):PAGE86
    40 M_B_CPU0_SA_DQ<24> @T6G_MB_LIB.T6G(SCH_1):M_B_CPU0_SA_DQ(24)   I350 @T6G_MB_LIB.T6G(SCH_1):PAGE86
    42 M_B_CPU0_SA_DQ<25> @T6G_MB_LIB.T6G(SCH_1):M_B_CPU0_SA_DQ(25)   I350 @T6G_MB_LIB.T6G(SCH_1):PAGE86
   185 M_B_CPU0_SA_DQ<26> @T6G_MB_LIB.T6G(SCH_1):M_B_CPU0_SA_DQ(26)   I350 @T6G_MB_LIB.T6G(SCH_1):PAGE86
   187 M_B_CPU0_SA_DQ<27> @T6G_MB_LIB.T6G(SCH_1):M_B_CPU0_SA_DQ(27)   I350 @T6G_MB_LIB.T6G(SCH_1):PAGE86
    47 M_B_CPU0_SA_DQ<28> @T6G_MB_LIB.T6G(SCH_1):M_B_CPU0_SA_DQ(28)   I350 @T6G_MB_LIB.T6G(SCH_1):PAGE86
    49 M_B_CPU0_SA_DQ<29> @T6G_MB_LIB.T6G(SCH_1):M_B_CPU0_SA_DQ(29)   I350 @T6G_MB_LIB.T6G(SCH_1):PAGE86
   192 M_B_CPU0_SA_DQ<30> @T6G_MB_LIB.T6G(SCH_1):M_B_CPU0_SA_DQ(30)   I350 @T6G_MB_LIB.T6G(SCH_1):PAGE86
   229 M_B_CPU0_SB_CS_N<1> @T6G_MB_LIB.T6G(SCH_1):M_B_CPU0_SB_CS_N(1)   I350 @T6G_MB_LIB.T6G(SCH_1):PAGE86
   209 M_B_CPU0_SA_CS_N<1> @T6G_MB_LIB.T6G(SCH_1):M_B_CPU0_SA_CS_N(1)   I350 @T6G_MB_LIB.T6G(SCH_1):PAGE86
    84 M_B_CPU0_SB_CS_N<0> @T6G_MB_LIB.T6G(SCH_1):M_B_CPU0_SB_CS_N(0)   I350 @T6G_MB_LIB.T6G(SCH_1):PAGE86
    64 M_B_CPU0_SA_CS_N<0> @T6G_MB_LIB.T6G(SCH_1):M_B_CPU0_SA_CS_N(0)   I350 @T6G_MB_LIB.T6G(SCH_1):PAGE86
   217 M_B_CPU0_CLK_DP<0> @T6G_MB_LIB.T6G(SCH_1):M_B_CPU0_CLK_DP(0)   I350 @T6G_MB_LIB.T6G(SCH_1):PAGE86
   218 M_B_CPU0_CLK_DN<0> @T6G_MB_LIB.T6G(SCH_1):M_B_CPU0_CLK_DN(0)   I350 @T6G_MB_LIB.T6G(SCH_1):PAGE86
    96 M_B_CPU0_SB_CB<0> @T6G_MB_LIB.T6G(SCH_1):M_B_CPU0_SB_CB(0)   I350 @T6G_MB_LIB.T6G(SCH_1):PAGE86
    98 M_B_CPU0_SB_CB<1> @T6G_MB_LIB.T6G(SCH_1):M_B_CPU0_SB_CB(1)   I350 @T6G_MB_LIB.T6G(SCH_1):PAGE86
   241 M_B_CPU0_SB_CB<2> @T6G_MB_LIB.T6G(SCH_1):M_B_CPU0_SB_CB(2)   I350 @T6G_MB_LIB.T6G(SCH_1):PAGE86
   243 M_B_CPU0_SB_CB<3> @T6G_MB_LIB.T6G(SCH_1):M_B_CPU0_SB_CB(3)   I350 @T6G_MB_LIB.T6G(SCH_1):PAGE86
    89 M_B_CPU0_SB_CB<4> @T6G_MB_LIB.T6G(SCH_1):M_B_CPU0_SB_CB(4)   I350 @T6G_MB_LIB.T6G(SCH_1):PAGE86
    91 M_B_CPU0_SB_CB<5> @T6G_MB_LIB.T6G(SCH_1):M_B_CPU0_SB_CB(5)   I350 @T6G_MB_LIB.T6G(SCH_1):PAGE86
   234 M_B_CPU0_SB_CB<6> @T6G_MB_LIB.T6G(SCH_1):M_B_CPU0_SB_CB(6)   I350 @T6G_MB_LIB.T6G(SCH_1):PAGE86
    51 M_B_CPU0_SA_CB<0> @T6G_MB_LIB.T6G(SCH_1):M_B_CPU0_SA_CB(0)   I350 @T6G_MB_LIB.T6G(SCH_1):PAGE86
   196 M_B_CPU0_SA_CB<2> @T6G_MB_LIB.T6G(SCH_1):M_B_CPU0_SA_CB(2)   I350 @T6G_MB_LIB.T6G(SCH_1):PAGE86
   198 M_B_CPU0_SA_CB<3> @T6G_MB_LIB.T6G(SCH_1):M_B_CPU0_SA_CB(3)   I350 @T6G_MB_LIB.T6G(SCH_1):PAGE86
    60 M_B_CPU0_SA_CB<5> @T6G_MB_LIB.T6G(SCH_1):M_B_CPU0_SA_CB(5)   I350 @T6G_MB_LIB.T6G(SCH_1):PAGE86
   203 M_B_CPU0_SA_CB<6> @T6G_MB_LIB.T6G(SCH_1):M_B_CPU0_SA_CB(6)   I350 @T6G_MB_LIB.T6G(SCH_1):PAGE86
    82 M_B_CPU0_SB_CA<6> @T6G_MB_LIB.T6G(SCH_1):M_B_CPU0_SB_CA(6)   I350 @T6G_MB_LIB.T6G(SCH_1):PAGE86
    72 M_B_CPU0_SA_CA<6> @T6G_MB_LIB.T6G(SCH_1):M_B_CPU0_SA_CA(6)   I350 @T6G_MB_LIB.T6G(SCH_1):PAGE86
   225 M_B_CPU0_SB_CA<5> @T6G_MB_LIB.T6G(SCH_1):M_B_CPU0_SB_CA(5)   I350 @T6G_MB_LIB.T6G(SCH_1):PAGE86
   215 M_B_CPU0_SA_CA<5> @T6G_MB_LIB.T6G(SCH_1):M_B_CPU0_SA_CA(5)   I350 @T6G_MB_LIB.T6G(SCH_1):PAGE86
    80 M_B_CPU0_SB_CA<4> @T6G_MB_LIB.T6G(SCH_1):M_B_CPU0_SB_CA(4)   I350 @T6G_MB_LIB.T6G(SCH_1):PAGE86
    70 M_B_CPU0_SA_CA<4> @T6G_MB_LIB.T6G(SCH_1):M_B_CPU0_SA_CA(4)   I350 @T6G_MB_LIB.T6G(SCH_1):PAGE86
   223 M_B_CPU0_SB_CA<3> @T6G_MB_LIB.T6G(SCH_1):M_B_CPU0_SB_CA(3)   I350 @T6G_MB_LIB.T6G(SCH_1):PAGE86
   213 M_B_CPU0_SA_CA<3> @T6G_MB_LIB.T6G(SCH_1):M_B_CPU0_SA_CA(3)   I350 @T6G_MB_LIB.T6G(SCH_1):PAGE86
    78 M_B_CPU0_SB_CA<2> @T6G_MB_LIB.T6G(SCH_1):M_B_CPU0_SB_CA(2)   I350 @T6G_MB_LIB.T6G(SCH_1):PAGE86
    68 M_B_CPU0_SA_CA<2> @T6G_MB_LIB.T6G(SCH_1):M_B_CPU0_SA_CA(2)   I350 @T6G_MB_LIB.T6G(SCH_1):PAGE86
   221 M_B_CPU0_SB_CA<1> @T6G_MB_LIB.T6G(SCH_1):M_B_CPU0_SB_CA(1)   I350 @T6G_MB_LIB.T6G(SCH_1):PAGE86
   211 M_B_CPU0_SA_CA<1> @T6G_MB_LIB.T6G(SCH_1):M_B_CPU0_SA_CA(1)   I350 @T6G_MB_LIB.T6G(SCH_1):PAGE86
    76 M_B_CPU0_SB_CA<0> @T6G_MB_LIB.T6G(SCH_1):M_B_CPU0_SB_CA(0)   I350 @T6G_MB_LIB.T6G(SCH_1):PAGE86
    66 M_B_CPU0_SA_CA<0> @T6G_MB_LIB.T6G(SCH_1):M_B_CPU0_SA_CA(0)   I350 @T6G_MB_LIB.T6G(SCH_1):PAGE86
    62 M_B_CPU0_ALERT_N @T6G_MB_LIB.T6G(SCH_1):M_B_CPU0_ALERT_N   I350 @T6G_MB_LIB.T6G(SCH_1):PAGE86
   236 M_B_CPU0_SB_CB<7> @T6G_MB_LIB.T6G(SCH_1):M_B_CPU0_SB_CB(7)   I350 @T6G_MB_LIB.T6G(SCH_1):PAGE86
    53 M_B_CPU0_SA_CB<1> @T6G_MB_LIB.T6G(SCH_1):M_B_CPU0_SA_CB(1)   I350 @T6G_MB_LIB.T6G(SCH_1):PAGE86
    58 M_B_CPU0_SA_CB<4> @T6G_MB_LIB.T6G(SCH_1):M_B_CPU0_SA_CB(4)   I350 @T6G_MB_LIB.T6G(SCH_1):PAGE86
   205 M_B_CPU0_SA_CB<7> @T6G_MB_LIB.T6G(SCH_1):M_B_CPU0_SA_CB(7)   I350 @T6G_MB_LIB.T6G(SCH_1):PAGE86
   194 M_B_CPU0_SA_DQ<31> @T6G_MB_LIB.T6G(SCH_1):M_B_CPU0_SA_DQ(31)   I350 @T6G_MB_LIB.T6G(SCH_1):PAGE86
    93 M_B_CPU0_SB_DQS_DP<9> @T6G_MB_LIB.T6G(SCH_1):M_B_CPU0_SB_DQS_DP(9)   I367 @T6G_MB_LIB.T6G(SCH_1):PAGE86
    94 M_B_CPU0_SB_DQS_DN<9> @T6G_MB_LIB.T6G(SCH_1):M_B_CPU0_SB_DQS_DN(9)   I367 @T6G_MB_LIB.T6G(SCH_1):PAGE86
   201 M_B_CPU0_SA_DQS_DP<9> @T6G_MB_LIB.T6G(SCH_1):M_B_CPU0_SA_DQS_DP(9)   I367 @T6G_MB_LIB.T6G(SCH_1):PAGE86
   200 M_B_CPU0_SA_DQS_DN<9> @T6G_MB_LIB.T6G(SCH_1):M_B_CPU0_SA_DQS_DN(9)   I367 @T6G_MB_LIB.T6G(SCH_1):PAGE86
   190 M_B_CPU0_SA_DQS_DP<8> @T6G_MB_LIB.T6G(SCH_1):M_B_CPU0_SA_DQS_DP(8)   I367 @T6G_MB_LIB.T6G(SCH_1):PAGE86
   189 M_B_CPU0_SA_DQS_DN<8> @T6G_MB_LIB.T6G(SCH_1):M_B_CPU0_SA_DQS_DN(8)   I367 @T6G_MB_LIB.T6G(SCH_1):PAGE86
   271 M_B_CPU0_SB_DQS_DN<7> @T6G_MB_LIB.T6G(SCH_1):M_B_CPU0_SB_DQS_DN(7)   I367 @T6G_MB_LIB.T6G(SCH_1):PAGE86
   179 M_B_CPU0_SA_DQS_DP<7> @T6G_MB_LIB.T6G(SCH_1):M_B_CPU0_SA_DQS_DP(7)   I367 @T6G_MB_LIB.T6G(SCH_1):PAGE86
   261 M_B_CPU0_SB_DQS_DP<6> @T6G_MB_LIB.T6G(SCH_1):M_B_CPU0_SB_DQS_DP(6)   I367 @T6G_MB_LIB.T6G(SCH_1):PAGE86
   260 M_B_CPU0_SB_DQS_DN<6> @T6G_MB_LIB.T6G(SCH_1):M_B_CPU0_SB_DQS_DN(6)   I367 @T6G_MB_LIB.T6G(SCH_1):PAGE86
   167 M_B_CPU0_SA_DQS_DN<6> @T6G_MB_LIB.T6G(SCH_1):M_B_CPU0_SA_DQS_DN(6)   I367 @T6G_MB_LIB.T6G(SCH_1):PAGE86
   250 M_B_CPU0_SB_DQS_DP<5> @T6G_MB_LIB.T6G(SCH_1):M_B_CPU0_SB_DQS_DP(5)   I367 @T6G_MB_LIB.T6G(SCH_1):PAGE86
   249 M_B_CPU0_SB_DQS_DN<5> @T6G_MB_LIB.T6G(SCH_1):M_B_CPU0_SB_DQS_DN(5)   I367 @T6G_MB_LIB.T6G(SCH_1):PAGE86
   157 M_B_CPU0_SA_DQS_DP<5> @T6G_MB_LIB.T6G(SCH_1):M_B_CPU0_SA_DQS_DP(5)   I367 @T6G_MB_LIB.T6G(SCH_1):PAGE86
   156 M_B_CPU0_SA_DQS_DN<5> @T6G_MB_LIB.T6G(SCH_1):M_B_CPU0_SA_DQS_DN(5)   I367 @T6G_MB_LIB.T6G(SCH_1):PAGE86
   239 M_B_CPU0_SB_DQS_DP<4> @T6G_MB_LIB.T6G(SCH_1):M_B_CPU0_SB_DQS_DP(4)   I367 @T6G_MB_LIB.T6G(SCH_1):PAGE86
   238 M_B_CPU0_SB_DQS_DN<4> @T6G_MB_LIB.T6G(SCH_1):M_B_CPU0_SB_DQS_DN(4)   I367 @T6G_MB_LIB.T6G(SCH_1):PAGE86
    55 M_B_CPU0_SA_DQS_DP<4> @T6G_MB_LIB.T6G(SCH_1):M_B_CPU0_SA_DQS_DP(4)   I367 @T6G_MB_LIB.T6G(SCH_1):PAGE86
    56 M_B_CPU0_SA_DQS_DN<4> @T6G_MB_LIB.T6G(SCH_1):M_B_CPU0_SA_DQS_DN(4)   I367 @T6G_MB_LIB.T6G(SCH_1):PAGE86
   137 M_B_CPU0_SB_DQS_DP<3> @T6G_MB_LIB.T6G(SCH_1):M_B_CPU0_SB_DQS_DP(3)   I367 @T6G_MB_LIB.T6G(SCH_1):PAGE86
   138 M_B_CPU0_SB_DQS_DN<3> @T6G_MB_LIB.T6G(SCH_1):M_B_CPU0_SB_DQS_DN(3)   I367 @T6G_MB_LIB.T6G(SCH_1):PAGE86
    44 M_B_CPU0_SA_DQS_DP<3> @T6G_MB_LIB.T6G(SCH_1):M_B_CPU0_SA_DQS_DP(3)   I367 @T6G_MB_LIB.T6G(SCH_1):PAGE86
    45 M_B_CPU0_SA_DQS_DN<3> @T6G_MB_LIB.T6G(SCH_1):M_B_CPU0_SA_DQS_DN(3)   I367 @T6G_MB_LIB.T6G(SCH_1):PAGE86
   126 M_B_CPU0_SB_DQS_DP<2> @T6G_MB_LIB.T6G(SCH_1):M_B_CPU0_SB_DQS_DP(2)   I367 @T6G_MB_LIB.T6G(SCH_1):PAGE86
   127 M_B_CPU0_SB_DQS_DN<2> @T6G_MB_LIB.T6G(SCH_1):M_B_CPU0_SB_DQS_DN(2)   I367 @T6G_MB_LIB.T6G(SCH_1):PAGE86
    33 M_B_CPU0_SA_DQS_DP<2> @T6G_MB_LIB.T6G(SCH_1):M_B_CPU0_SA_DQS_DP(2)   I367 @T6G_MB_LIB.T6G(SCH_1):PAGE86
    34 M_B_CPU0_SA_DQS_DN<2> @T6G_MB_LIB.T6G(SCH_1):M_B_CPU0_SA_DQS_DN(2)   I367 @T6G_MB_LIB.T6G(SCH_1):PAGE86
   115 M_B_CPU0_SB_DQS_DP<1> @T6G_MB_LIB.T6G(SCH_1):M_B_CPU0_SB_DQS_DP(1)   I367 @T6G_MB_LIB.T6G(SCH_1):PAGE86
   116 M_B_CPU0_SB_DQS_DN<1> @T6G_MB_LIB.T6G(SCH_1):M_B_CPU0_SB_DQS_DN(1)   I367 @T6G_MB_LIB.T6G(SCH_1):PAGE86
    22 M_B_CPU0_SA_DQS_DP<1> @T6G_MB_LIB.T6G(SCH_1):M_B_CPU0_SA_DQS_DP(1)   I367 @T6G_MB_LIB.T6G(SCH_1):PAGE86
    23 M_B_CPU0_SA_DQS_DN<1> @T6G_MB_LIB.T6G(SCH_1):M_B_CPU0_SA_DQS_DN(1)   I367 @T6G_MB_LIB.T6G(SCH_1):PAGE86
   104 M_B_CPU0_SB_DQS_DP<0> @T6G_MB_LIB.T6G(SCH_1):M_B_CPU0_SB_DQS_DP(0)   I367 @T6G_MB_LIB.T6G(SCH_1):PAGE86
   105 M_B_CPU0_SB_DQS_DN<0> @T6G_MB_LIB.T6G(SCH_1):M_B_CPU0_SB_DQS_DN(0)   I367 @T6G_MB_LIB.T6G(SCH_1):PAGE86
    11 M_B_CPU0_SA_DQS_DP<0> @T6G_MB_LIB.T6G(SCH_1):M_B_CPU0_SA_DQS_DP(0)   I367 @T6G_MB_LIB.T6G(SCH_1):PAGE86
    12 M_B_CPU0_SA_DQS_DN<0> @T6G_MB_LIB.T6G(SCH_1):M_B_CPU0_SA_DQS_DN(0)   I367 @T6G_MB_LIB.T6G(SCH_1):PAGE86
   272 M_B_CPU0_SB_DQS_DP<7> @T6G_MB_LIB.T6G(SCH_1):M_B_CPU0_SB_DQS_DP(7)   I367 @T6G_MB_LIB.T6G(SCH_1):PAGE86
   282 M_B_CPU0_SB_DQS_DN<8> @T6G_MB_LIB.T6G(SCH_1):M_B_CPU0_SB_DQS_DN(8)   I367 @T6G_MB_LIB.T6G(SCH_1):PAGE86
   283 M_B_CPU0_SB_DQS_DP<8> @T6G_MB_LIB.T6G(SCH_1):M_B_CPU0_SB_DQS_DP(8)   I367 @T6G_MB_LIB.T6G(SCH_1):PAGE86
   168 M_B_CPU0_SA_DQS_DP<6> @T6G_MB_LIB.T6G(SCH_1):M_B_CPU0_SA_DQS_DP(6)   I367 @T6G_MB_LIB.T6G(SCH_1):PAGE86
   178 M_B_CPU0_SA_DQS_DN<7> @T6G_MB_LIB.T6G(SCH_1):M_B_CPU0_SA_DQS_DN(7)   I367 @T6G_MB_LIB.T6G(SCH_1):PAGE86
     6    GND @T6G_MB_LIB.T6G(SCH_1):GND   I352 @T6G_MB_LIB.T6G(SCH_1):PAGE86
     8    GND @T6G_MB_LIB.T6G(SCH_1):GND   I352 @T6G_MB_LIB.T6G(SCH_1):PAGE86
    10    GND @T6G_MB_LIB.T6G(SCH_1):GND   I352 @T6G_MB_LIB.T6G(SCH_1):PAGE86
    13    GND @T6G_MB_LIB.T6G(SCH_1):GND   I352 @T6G_MB_LIB.T6G(SCH_1):PAGE86
    15    GND @T6G_MB_LIB.T6G(SCH_1):GND   I352 @T6G_MB_LIB.T6G(SCH_1):PAGE86
    17    GND @T6G_MB_LIB.T6G(SCH_1):GND   I352 @T6G_MB_LIB.T6G(SCH_1):PAGE86
    19    GND @T6G_MB_LIB.T6G(SCH_1):GND   I352 @T6G_MB_LIB.T6G(SCH_1):PAGE86
    21    GND @T6G_MB_LIB.T6G(SCH_1):GND   I352 @T6G_MB_LIB.T6G(SCH_1):PAGE86
    24    GND @T6G_MB_LIB.T6G(SCH_1):GND   I352 @T6G_MB_LIB.T6G(SCH_1):PAGE86
    26    GND @T6G_MB_LIB.T6G(SCH_1):GND   I352 @T6G_MB_LIB.T6G(SCH_1):PAGE86
    28    GND @T6G_MB_LIB.T6G(SCH_1):GND   I352 @T6G_MB_LIB.T6G(SCH_1):PAGE86
    30    GND @T6G_MB_LIB.T6G(SCH_1):GND   I352 @T6G_MB_LIB.T6G(SCH_1):PAGE86
    32    GND @T6G_MB_LIB.T6G(SCH_1):GND   I352 @T6G_MB_LIB.T6G(SCH_1):PAGE86
    35    GND @T6G_MB_LIB.T6G(SCH_1):GND   I352 @T6G_MB_LIB.T6G(SCH_1):PAGE86
    37    GND @T6G_MB_LIB.T6G(SCH_1):GND   I352 @T6G_MB_LIB.T6G(SCH_1):PAGE86
    39    GND @T6G_MB_LIB.T6G(SCH_1):GND   I352 @T6G_MB_LIB.T6G(SCH_1):PAGE86
    41    GND @T6G_MB_LIB.T6G(SCH_1):GND   I352 @T6G_MB_LIB.T6G(SCH_1):PAGE86
    43    GND @T6G_MB_LIB.T6G(SCH_1):GND   I352 @T6G_MB_LIB.T6G(SCH_1):PAGE86
    46    GND @T6G_MB_LIB.T6G(SCH_1):GND   I352 @T6G_MB_LIB.T6G(SCH_1):PAGE86
    48    GND @T6G_MB_LIB.T6G(SCH_1):GND   I352 @T6G_MB_LIB.T6G(SCH_1):PAGE86
    50    GND @T6G_MB_LIB.T6G(SCH_1):GND   I352 @T6G_MB_LIB.T6G(SCH_1):PAGE86
    52    GND @T6G_MB_LIB.T6G(SCH_1):GND   I352 @T6G_MB_LIB.T6G(SCH_1):PAGE86
    54    GND @T6G_MB_LIB.T6G(SCH_1):GND   I352 @T6G_MB_LIB.T6G(SCH_1):PAGE86
    57    GND @T6G_MB_LIB.T6G(SCH_1):GND   I352 @T6G_MB_LIB.T6G(SCH_1):PAGE86
    59    GND @T6G_MB_LIB.T6G(SCH_1):GND   I352 @T6G_MB_LIB.T6G(SCH_1):PAGE86
    61    GND @T6G_MB_LIB.T6G(SCH_1):GND   I352 @T6G_MB_LIB.T6G(SCH_1):PAGE86
    63    GND @T6G_MB_LIB.T6G(SCH_1):GND   I352 @T6G_MB_LIB.T6G(SCH_1):PAGE86
    65    GND @T6G_MB_LIB.T6G(SCH_1):GND   I352 @T6G_MB_LIB.T6G(SCH_1):PAGE86
    67    GND @T6G_MB_LIB.T6G(SCH_1):GND   I352 @T6G_MB_LIB.T6G(SCH_1):PAGE86
    69    GND @T6G_MB_LIB.T6G(SCH_1):GND   I352 @T6G_MB_LIB.T6G(SCH_1):PAGE86
    71    GND @T6G_MB_LIB.T6G(SCH_1):GND   I352 @T6G_MB_LIB.T6G(SCH_1):PAGE86
    73    GND @T6G_MB_LIB.T6G(SCH_1):GND   I352 @T6G_MB_LIB.T6G(SCH_1):PAGE86
    75    GND @T6G_MB_LIB.T6G(SCH_1):GND   I352 @T6G_MB_LIB.T6G(SCH_1):PAGE86
    77    GND @T6G_MB_LIB.T6G(SCH_1):GND   I352 @T6G_MB_LIB.T6G(SCH_1):PAGE86
    79    GND @T6G_MB_LIB.T6G(SCH_1):GND   I352 @T6G_MB_LIB.T6G(SCH_1):PAGE86
    81    GND @T6G_MB_LIB.T6G(SCH_1):GND   I352 @T6G_MB_LIB.T6G(SCH_1):PAGE86
    83    GND @T6G_MB_LIB.T6G(SCH_1):GND   I352 @T6G_MB_LIB.T6G(SCH_1):PAGE86
    85    GND @T6G_MB_LIB.T6G(SCH_1):GND   I352 @T6G_MB_LIB.T6G(SCH_1):PAGE86
    88    GND @T6G_MB_LIB.T6G(SCH_1):GND   I352 @T6G_MB_LIB.T6G(SCH_1):PAGE86
    90    GND @T6G_MB_LIB.T6G(SCH_1):GND   I352 @T6G_MB_LIB.T6G(SCH_1):PAGE86
    92    GND @T6G_MB_LIB.T6G(SCH_1):GND   I352 @T6G_MB_LIB.T6G(SCH_1):PAGE86
    95    GND @T6G_MB_LIB.T6G(SCH_1):GND   I352 @T6G_MB_LIB.T6G(SCH_1):PAGE86
    97    GND @T6G_MB_LIB.T6G(SCH_1):GND   I352 @T6G_MB_LIB.T6G(SCH_1):PAGE86
    99    GND @T6G_MB_LIB.T6G(SCH_1):GND   I352 @T6G_MB_LIB.T6G(SCH_1):PAGE86
   101    GND @T6G_MB_LIB.T6G(SCH_1):GND   I352 @T6G_MB_LIB.T6G(SCH_1):PAGE86
   103    GND @T6G_MB_LIB.T6G(SCH_1):GND   I352 @T6G_MB_LIB.T6G(SCH_1):PAGE86
   106    GND @T6G_MB_LIB.T6G(SCH_1):GND   I352 @T6G_MB_LIB.T6G(SCH_1):PAGE86
   108    GND @T6G_MB_LIB.T6G(SCH_1):GND   I352 @T6G_MB_LIB.T6G(SCH_1):PAGE86
   110    GND @T6G_MB_LIB.T6G(SCH_1):GND   I352 @T6G_MB_LIB.T6G(SCH_1):PAGE86
   112    GND @T6G_MB_LIB.T6G(SCH_1):GND   I352 @T6G_MB_LIB.T6G(SCH_1):PAGE86
   114    GND @T6G_MB_LIB.T6G(SCH_1):GND   I352 @T6G_MB_LIB.T6G(SCH_1):PAGE86
   117    GND @T6G_MB_LIB.T6G(SCH_1):GND   I352 @T6G_MB_LIB.T6G(SCH_1):PAGE86
   119    GND @T6G_MB_LIB.T6G(SCH_1):GND   I352 @T6G_MB_LIB.T6G(SCH_1):PAGE86
   121    GND @T6G_MB_LIB.T6G(SCH_1):GND   I352 @T6G_MB_LIB.T6G(SCH_1):PAGE86
   123    GND @T6G_MB_LIB.T6G(SCH_1):GND   I352 @T6G_MB_LIB.T6G(SCH_1):PAGE86
   125    GND @T6G_MB_LIB.T6G(SCH_1):GND   I352 @T6G_MB_LIB.T6G(SCH_1):PAGE86
   128    GND @T6G_MB_LIB.T6G(SCH_1):GND   I352 @T6G_MB_LIB.T6G(SCH_1):PAGE86
   130    GND @T6G_MB_LIB.T6G(SCH_1):GND   I352 @T6G_MB_LIB.T6G(SCH_1):PAGE86
   134    GND @T6G_MB_LIB.T6G(SCH_1):GND   I352 @T6G_MB_LIB.T6G(SCH_1):PAGE86
   143    GND @T6G_MB_LIB.T6G(SCH_1):GND   I352 @T6G_MB_LIB.T6G(SCH_1):PAGE86
   151    GND @T6G_MB_LIB.T6G(SCH_1):GND   I352 @T6G_MB_LIB.T6G(SCH_1):PAGE86
   153    GND @T6G_MB_LIB.T6G(SCH_1):GND   I352 @T6G_MB_LIB.T6G(SCH_1):PAGE86
   155    GND @T6G_MB_LIB.T6G(SCH_1):GND   I352 @T6G_MB_LIB.T6G(SCH_1):PAGE86
   158    GND @T6G_MB_LIB.T6G(SCH_1):GND   I352 @T6G_MB_LIB.T6G(SCH_1):PAGE86
   160    GND @T6G_MB_LIB.T6G(SCH_1):GND   I352 @T6G_MB_LIB.T6G(SCH_1):PAGE86
   162    GND @T6G_MB_LIB.T6G(SCH_1):GND   I352 @T6G_MB_LIB.T6G(SCH_1):PAGE86
   164    GND @T6G_MB_LIB.T6G(SCH_1):GND   I352 @T6G_MB_LIB.T6G(SCH_1):PAGE86
   166    GND @T6G_MB_LIB.T6G(SCH_1):GND   I352 @T6G_MB_LIB.T6G(SCH_1):PAGE86
   169    GND @T6G_MB_LIB.T6G(SCH_1):GND   I352 @T6G_MB_LIB.T6G(SCH_1):PAGE86
   171    GND @T6G_MB_LIB.T6G(SCH_1):GND   I352 @T6G_MB_LIB.T6G(SCH_1):PAGE86
   173    GND @T6G_MB_LIB.T6G(SCH_1):GND   I352 @T6G_MB_LIB.T6G(SCH_1):PAGE86
   175    GND @T6G_MB_LIB.T6G(SCH_1):GND   I352 @T6G_MB_LIB.T6G(SCH_1):PAGE86
   177    GND @T6G_MB_LIB.T6G(SCH_1):GND   I352 @T6G_MB_LIB.T6G(SCH_1):PAGE86
   180    GND @T6G_MB_LIB.T6G(SCH_1):GND   I352 @T6G_MB_LIB.T6G(SCH_1):PAGE86
   182    GND @T6G_MB_LIB.T6G(SCH_1):GND   I352 @T6G_MB_LIB.T6G(SCH_1):PAGE86
   184    GND @T6G_MB_LIB.T6G(SCH_1):GND   I352 @T6G_MB_LIB.T6G(SCH_1):PAGE86
   186    GND @T6G_MB_LIB.T6G(SCH_1):GND   I352 @T6G_MB_LIB.T6G(SCH_1):PAGE86
   188    GND @T6G_MB_LIB.T6G(SCH_1):GND   I352 @T6G_MB_LIB.T6G(SCH_1):PAGE86
   191    GND @T6G_MB_LIB.T6G(SCH_1):GND   I352 @T6G_MB_LIB.T6G(SCH_1):PAGE86
   193    GND @T6G_MB_LIB.T6G(SCH_1):GND   I352 @T6G_MB_LIB.T6G(SCH_1):PAGE86
   195    GND @T6G_MB_LIB.T6G(SCH_1):GND   I352 @T6G_MB_LIB.T6G(SCH_1):PAGE86
   197    GND @T6G_MB_LIB.T6G(SCH_1):GND   I352 @T6G_MB_LIB.T6G(SCH_1):PAGE86
   199    GND @T6G_MB_LIB.T6G(SCH_1):GND   I352 @T6G_MB_LIB.T6G(SCH_1):PAGE86
   202    GND @T6G_MB_LIB.T6G(SCH_1):GND   I352 @T6G_MB_LIB.T6G(SCH_1):PAGE86
   204    GND @T6G_MB_LIB.T6G(SCH_1):GND   I352 @T6G_MB_LIB.T6G(SCH_1):PAGE86
   206    GND @T6G_MB_LIB.T6G(SCH_1):GND   I352 @T6G_MB_LIB.T6G(SCH_1):PAGE86
   208    GND @T6G_MB_LIB.T6G(SCH_1):GND   I352 @T6G_MB_LIB.T6G(SCH_1):PAGE86
   210    GND @T6G_MB_LIB.T6G(SCH_1):GND   I352 @T6G_MB_LIB.T6G(SCH_1):PAGE86
   212    GND @T6G_MB_LIB.T6G(SCH_1):GND   I352 @T6G_MB_LIB.T6G(SCH_1):PAGE86
   214    GND @T6G_MB_LIB.T6G(SCH_1):GND   I352 @T6G_MB_LIB.T6G(SCH_1):PAGE86
   216    GND @T6G_MB_LIB.T6G(SCH_1):GND   I352 @T6G_MB_LIB.T6G(SCH_1):PAGE86
   219    GND @T6G_MB_LIB.T6G(SCH_1):GND   I352 @T6G_MB_LIB.T6G(SCH_1):PAGE86
   222    GND @T6G_MB_LIB.T6G(SCH_1):GND   I352 @T6G_MB_LIB.T6G(SCH_1):PAGE86
   224    GND @T6G_MB_LIB.T6G(SCH_1):GND   I352 @T6G_MB_LIB.T6G(SCH_1):PAGE86
   226    GND @T6G_MB_LIB.T6G(SCH_1):GND   I352 @T6G_MB_LIB.T6G(SCH_1):PAGE86
   228    GND @T6G_MB_LIB.T6G(SCH_1):GND   I352 @T6G_MB_LIB.T6G(SCH_1):PAGE86
   233    GND @T6G_MB_LIB.T6G(SCH_1):GND   I352 @T6G_MB_LIB.T6G(SCH_1):PAGE86
   237    GND @T6G_MB_LIB.T6G(SCH_1):GND   I352 @T6G_MB_LIB.T6G(SCH_1):PAGE86
   242    GND @T6G_MB_LIB.T6G(SCH_1):GND   I352 @T6G_MB_LIB.T6G(SCH_1):PAGE86
   244    GND @T6G_MB_LIB.T6G(SCH_1):GND   I352 @T6G_MB_LIB.T6G(SCH_1):PAGE86
   246    GND @T6G_MB_LIB.T6G(SCH_1):GND   I352 @T6G_MB_LIB.T6G(SCH_1):PAGE86
   248    GND @T6G_MB_LIB.T6G(SCH_1):GND   I352 @T6G_MB_LIB.T6G(SCH_1):PAGE86
   251    GND @T6G_MB_LIB.T6G(SCH_1):GND   I352 @T6G_MB_LIB.T6G(SCH_1):PAGE86
   253    GND @T6G_MB_LIB.T6G(SCH_1):GND   I352 @T6G_MB_LIB.T6G(SCH_1):PAGE86
   255    GND @T6G_MB_LIB.T6G(SCH_1):GND   I352 @T6G_MB_LIB.T6G(SCH_1):PAGE86
   257    GND @T6G_MB_LIB.T6G(SCH_1):GND   I352 @T6G_MB_LIB.T6G(SCH_1):PAGE86
   259    GND @T6G_MB_LIB.T6G(SCH_1):GND   I352 @T6G_MB_LIB.T6G(SCH_1):PAGE86
   262    GND @T6G_MB_LIB.T6G(SCH_1):GND   I352 @T6G_MB_LIB.T6G(SCH_1):PAGE86
   264    GND @T6G_MB_LIB.T6G(SCH_1):GND   I352 @T6G_MB_LIB.T6G(SCH_1):PAGE86
   266    GND @T6G_MB_LIB.T6G(SCH_1):GND   I352 @T6G_MB_LIB.T6G(SCH_1):PAGE86
   268    GND @T6G_MB_LIB.T6G(SCH_1):GND   I352 @T6G_MB_LIB.T6G(SCH_1):PAGE86
   270    GND @T6G_MB_LIB.T6G(SCH_1):GND   I352 @T6G_MB_LIB.T6G(SCH_1):PAGE86
   273    GND @T6G_MB_LIB.T6G(SCH_1):GND   I352 @T6G_MB_LIB.T6G(SCH_1):PAGE86
   275    GND @T6G_MB_LIB.T6G(SCH_1):GND   I352 @T6G_MB_LIB.T6G(SCH_1):PAGE86
   277    GND @T6G_MB_LIB.T6G(SCH_1):GND   I352 @T6G_MB_LIB.T6G(SCH_1):PAGE86
   279    GND @T6G_MB_LIB.T6G(SCH_1):GND   I352 @T6G_MB_LIB.T6G(SCH_1):PAGE86
   281    GND @T6G_MB_LIB.T6G(SCH_1):GND   I352 @T6G_MB_LIB.T6G(SCH_1):PAGE86
   284    GND @T6G_MB_LIB.T6G(SCH_1):GND   I352 @T6G_MB_LIB.T6G(SCH_1):PAGE86
   286    GND @T6G_MB_LIB.T6G(SCH_1):GND   I352 @T6G_MB_LIB.T6G(SCH_1):PAGE86
   288    GND @T6G_MB_LIB.T6G(SCH_1):GND   I352 @T6G_MB_LIB.T6G(SCH_1):PAGE86
     1 P12V_MEM_CPU0 @T6G_MB_LIB.T6G(SCH_1):P12V_MEM_CPU0   I352 @T6G_MB_LIB.T6G(SCH_1):PAGE86
   145 P12V_MEM_CPU0 @T6G_MB_LIB.T6G(SCH_1):P12V_MEM_CPU0   I352 @T6G_MB_LIB.T6G(SCH_1):PAGE86
   146 P12V_MEM_CPU0 @T6G_MB_LIB.T6G(SCH_1):P12V_MEM_CPU0   I352 @T6G_MB_LIB.T6G(SCH_1):PAGE86
   230    GND @T6G_MB_LIB.T6G(SCH_1):GND   I352 @T6G_MB_LIB.T6G(SCH_1):PAGE86
   235    GND @T6G_MB_LIB.T6G(SCH_1):GND   I352 @T6G_MB_LIB.T6G(SCH_1):PAGE86
   240    GND @T6G_MB_LIB.T6G(SCH_1):GND   I352 @T6G_MB_LIB.T6G(SCH_1):PAGE86
   132    GND @T6G_MB_LIB.T6G(SCH_1):GND   I352 @T6G_MB_LIB.T6G(SCH_1):PAGE86
   136    GND @T6G_MB_LIB.T6G(SCH_1):GND   I352 @T6G_MB_LIB.T6G(SCH_1):PAGE86
   139    GND @T6G_MB_LIB.T6G(SCH_1):GND   I352 @T6G_MB_LIB.T6G(SCH_1):PAGE86
   141    GND @T6G_MB_LIB.T6G(SCH_1):GND   I352 @T6G_MB_LIB.T6G(SCH_1):PAGE86
    G1    GND @T6G_MB_LIB.T6G(SCH_1):GND   I352 @T6G_MB_LIB.T6G(SCH_1):PAGE86
    G2    GND @T6G_MB_LIB.T6G(SCH_1):GND   I352 @T6G_MB_LIB.T6G(SCH_1):PAGE86
    G3    GND @T6G_MB_LIB.T6G(SCH_1):GND   I352 @T6G_MB_LIB.T6G(SCH_1):PAGE86

 J16 SCONN288_DDR506112002KQ-SCONN288_DDR506112002KQ,SMA
     3 P3V3_AUX @T6G_MB_LIB.T6G(SCH_1):P3V3_AUX    I22 @T6G_MB_LIB.T6G(SCH_1):PAGE91
     2     NC     NC    I22 @T6G_MB_LIB.T6G(SCH_1):PAGE91
   144     NC     NC    I22 @T6G_MB_LIB.T6G(SCH_1):PAGE91
   149     NC     NC    I22 @T6G_MB_LIB.T6G(SCH_1):PAGE91
   150     NC     NC    I22 @T6G_MB_LIB.T6G(SCH_1):PAGE91
   220     NC     NC    I22 @T6G_MB_LIB.T6G(SCH_1):PAGE91
   231     NC     NC    I22 @T6G_MB_LIB.T6G(SCH_1):PAGE91
   232     NC     NC    I22 @T6G_MB_LIB.T6G(SCH_1):PAGE91
   207 M_G_CPU0_RESET_N @T6G_MB_LIB.T6G(SCH_1):M_G_CPU0_RESET_N    I22 @T6G_MB_LIB.T6G(SCH_1):PAGE91
   147 PWRGD_CHG_CPU0_DIMM0 @T6G_MB_LIB.T6G(SCH_1):PWRGD_CHG_CPU0_DIMM0    I22 @T6G_MB_LIB.T6G(SCH_1):PAGE91
   227 M_G_CPU0_SB_PAR @T6G_MB_LIB.T6G(SCH_1):M_G_CPU0_SB_PAR    I22 @T6G_MB_LIB.T6G(SCH_1):PAGE91
    74 M_G_CPU0_SA_PAR @T6G_MB_LIB.T6G(SCH_1):M_G_CPU0_SA_PAR    I22 @T6G_MB_LIB.T6G(SCH_1):PAGE91
    87 M_G_CPU0_SB_RSP<0> @T6G_MB_LIB.T6G(SCH_1):M_G_CPU0_SB_RSP(0)    I22 @T6G_MB_LIB.T6G(SCH_1):PAGE91
    86 M_G_CPU0_SA_RSP<0> @T6G_MB_LIB.T6G(SCH_1):M_G_CPU0_SA_RSP(0)    I22 @T6G_MB_LIB.T6G(SCH_1):PAGE91
     5 I3C_SPD_DDRG_CPU0_SDA @T6G_MB_LIB.T6G(SCH_1):I3C_SPD_DDRG_CPU0_SDA    I22 @T6G_MB_LIB.T6G(SCH_1):PAGE91
     4 I3C_SPD_DDRG_CPU0_SCL @T6G_MB_LIB.T6G(SCH_1):I3C_SPD_DDRG_CPU0_SCL    I22 @T6G_MB_LIB.T6G(SCH_1):PAGE91
   148 PD_CHG_CPU0_DIMM0_SAA @T6G_MB_LIB.T6G(SCH_1):PD_CHG_CPU0_DIMM0_SAA    I22 @T6G_MB_LIB.T6G(SCH_1):PAGE91
   100 M_G_CPU0_SB_DQ<0> @T6G_MB_LIB.T6G(SCH_1):M_G_CPU0_SB_DQ(0)    I22 @T6G_MB_LIB.T6G(SCH_1):PAGE91
   102 M_G_CPU0_SB_DQ<1> @T6G_MB_LIB.T6G(SCH_1):M_G_CPU0_SB_DQ(1)    I22 @T6G_MB_LIB.T6G(SCH_1):PAGE91
   245 M_G_CPU0_SB_DQ<2> @T6G_MB_LIB.T6G(SCH_1):M_G_CPU0_SB_DQ(2)    I22 @T6G_MB_LIB.T6G(SCH_1):PAGE91
   247 M_G_CPU0_SB_DQ<3> @T6G_MB_LIB.T6G(SCH_1):M_G_CPU0_SB_DQ(3)    I22 @T6G_MB_LIB.T6G(SCH_1):PAGE91
   107 M_G_CPU0_SB_DQ<4> @T6G_MB_LIB.T6G(SCH_1):M_G_CPU0_SB_DQ(4)    I22 @T6G_MB_LIB.T6G(SCH_1):PAGE91
   109 M_G_CPU0_SB_DQ<5> @T6G_MB_LIB.T6G(SCH_1):M_G_CPU0_SB_DQ(5)    I22 @T6G_MB_LIB.T6G(SCH_1):PAGE91
   252 M_G_CPU0_SB_DQ<6> @T6G_MB_LIB.T6G(SCH_1):M_G_CPU0_SB_DQ(6)    I22 @T6G_MB_LIB.T6G(SCH_1):PAGE91
   254 M_G_CPU0_SB_DQ<7> @T6G_MB_LIB.T6G(SCH_1):M_G_CPU0_SB_DQ(7)    I22 @T6G_MB_LIB.T6G(SCH_1):PAGE91
   111 M_G_CPU0_SB_DQ<8> @T6G_MB_LIB.T6G(SCH_1):M_G_CPU0_SB_DQ(8)    I22 @T6G_MB_LIB.T6G(SCH_1):PAGE91
   113 M_G_CPU0_SB_DQ<9> @T6G_MB_LIB.T6G(SCH_1):M_G_CPU0_SB_DQ(9)    I22 @T6G_MB_LIB.T6G(SCH_1):PAGE91
   256 M_G_CPU0_SB_DQ<10> @T6G_MB_LIB.T6G(SCH_1):M_G_CPU0_SB_DQ(10)    I22 @T6G_MB_LIB.T6G(SCH_1):PAGE91
   258 M_G_CPU0_SB_DQ<11> @T6G_MB_LIB.T6G(SCH_1):M_G_CPU0_SB_DQ(11)    I22 @T6G_MB_LIB.T6G(SCH_1):PAGE91
   118 M_G_CPU0_SB_DQ<12> @T6G_MB_LIB.T6G(SCH_1):M_G_CPU0_SB_DQ(12)    I22 @T6G_MB_LIB.T6G(SCH_1):PAGE91
   120 M_G_CPU0_SB_DQ<13> @T6G_MB_LIB.T6G(SCH_1):M_G_CPU0_SB_DQ(13)    I22 @T6G_MB_LIB.T6G(SCH_1):PAGE91
   263 M_G_CPU0_SB_DQ<14> @T6G_MB_LIB.T6G(SCH_1):M_G_CPU0_SB_DQ(14)    I22 @T6G_MB_LIB.T6G(SCH_1):PAGE91
   265 M_G_CPU0_SB_DQ<15> @T6G_MB_LIB.T6G(SCH_1):M_G_CPU0_SB_DQ(15)    I22 @T6G_MB_LIB.T6G(SCH_1):PAGE91
   122 M_G_CPU0_SB_DQ<16> @T6G_MB_LIB.T6G(SCH_1):M_G_CPU0_SB_DQ(16)    I22 @T6G_MB_LIB.T6G(SCH_1):PAGE91
   124 M_G_CPU0_SB_DQ<17> @T6G_MB_LIB.T6G(SCH_1):M_G_CPU0_SB_DQ(17)    I22 @T6G_MB_LIB.T6G(SCH_1):PAGE91
   267 M_G_CPU0_SB_DQ<18> @T6G_MB_LIB.T6G(SCH_1):M_G_CPU0_SB_DQ(18)    I22 @T6G_MB_LIB.T6G(SCH_1):PAGE91
   269 M_G_CPU0_SB_DQ<19> @T6G_MB_LIB.T6G(SCH_1):M_G_CPU0_SB_DQ(19)    I22 @T6G_MB_LIB.T6G(SCH_1):PAGE91
   129 M_G_CPU0_SB_DQ<20> @T6G_MB_LIB.T6G(SCH_1):M_G_CPU0_SB_DQ(20)    I22 @T6G_MB_LIB.T6G(SCH_1):PAGE91
   131 M_G_CPU0_SB_DQ<21> @T6G_MB_LIB.T6G(SCH_1):M_G_CPU0_SB_DQ(21)    I22 @T6G_MB_LIB.T6G(SCH_1):PAGE91
   274 M_G_CPU0_SB_DQ<22> @T6G_MB_LIB.T6G(SCH_1):M_G_CPU0_SB_DQ(22)    I22 @T6G_MB_LIB.T6G(SCH_1):PAGE91
   276 M_G_CPU0_SB_DQ<23> @T6G_MB_LIB.T6G(SCH_1):M_G_CPU0_SB_DQ(23)    I22 @T6G_MB_LIB.T6G(SCH_1):PAGE91
   133 M_G_CPU0_SB_DQ<24> @T6G_MB_LIB.T6G(SCH_1):M_G_CPU0_SB_DQ(24)    I22 @T6G_MB_LIB.T6G(SCH_1):PAGE91
   135 M_G_CPU0_SB_DQ<25> @T6G_MB_LIB.T6G(SCH_1):M_G_CPU0_SB_DQ(25)    I22 @T6G_MB_LIB.T6G(SCH_1):PAGE91
   278 M_G_CPU0_SB_DQ<26> @T6G_MB_LIB.T6G(SCH_1):M_G_CPU0_SB_DQ(26)    I22 @T6G_MB_LIB.T6G(SCH_1):PAGE91
   280 M_G_CPU0_SB_DQ<27> @T6G_MB_LIB.T6G(SCH_1):M_G_CPU0_SB_DQ(27)    I22 @T6G_MB_LIB.T6G(SCH_1):PAGE91
   140 M_G_CPU0_SB_DQ<28> @T6G_MB_LIB.T6G(SCH_1):M_G_CPU0_SB_DQ(28)    I22 @T6G_MB_LIB.T6G(SCH_1):PAGE91
   142 M_G_CPU0_SB_DQ<29> @T6G_MB_LIB.T6G(SCH_1):M_G_CPU0_SB_DQ(29)    I22 @T6G_MB_LIB.T6G(SCH_1):PAGE91
   285 M_G_CPU0_SB_DQ<30> @T6G_MB_LIB.T6G(SCH_1):M_G_CPU0_SB_DQ(30)    I22 @T6G_MB_LIB.T6G(SCH_1):PAGE91
   287 M_G_CPU0_SB_DQ<31> @T6G_MB_LIB.T6G(SCH_1):M_G_CPU0_SB_DQ(31)    I22 @T6G_MB_LIB.T6G(SCH_1):PAGE91
     7 M_G_CPU0_SA_DQ<0> @T6G_MB_LIB.T6G(SCH_1):M_G_CPU0_SA_DQ(0)    I22 @T6G_MB_LIB.T6G(SCH_1):PAGE91
     9 M_G_CPU0_SA_DQ<1> @T6G_MB_LIB.T6G(SCH_1):M_G_CPU0_SA_DQ(1)    I22 @T6G_MB_LIB.T6G(SCH_1):PAGE91
   152 M_G_CPU0_SA_DQ<2> @T6G_MB_LIB.T6G(SCH_1):M_G_CPU0_SA_DQ(2)    I22 @T6G_MB_LIB.T6G(SCH_1):PAGE91
   154 M_G_CPU0_SA_DQ<3> @T6G_MB_LIB.T6G(SCH_1):M_G_CPU0_SA_DQ(3)    I22 @T6G_MB_LIB.T6G(SCH_1):PAGE91
    14 M_G_CPU0_SA_DQ<4> @T6G_MB_LIB.T6G(SCH_1):M_G_CPU0_SA_DQ(4)    I22 @T6G_MB_LIB.T6G(SCH_1):PAGE91
    16 M_G_CPU0_SA_DQ<5> @T6G_MB_LIB.T6G(SCH_1):M_G_CPU0_SA_DQ(5)    I22 @T6G_MB_LIB.T6G(SCH_1):PAGE91
   159 M_G_CPU0_SA_DQ<6> @T6G_MB_LIB.T6G(SCH_1):M_G_CPU0_SA_DQ(6)    I22 @T6G_MB_LIB.T6G(SCH_1):PAGE91
   161 M_G_CPU0_SA_DQ<7> @T6G_MB_LIB.T6G(SCH_1):M_G_CPU0_SA_DQ(7)    I22 @T6G_MB_LIB.T6G(SCH_1):PAGE91
    18 M_G_CPU0_SA_DQ<8> @T6G_MB_LIB.T6G(SCH_1):M_G_CPU0_SA_DQ(8)    I22 @T6G_MB_LIB.T6G(SCH_1):PAGE91
    20 M_G_CPU0_SA_DQ<9> @T6G_MB_LIB.T6G(SCH_1):M_G_CPU0_SA_DQ(9)    I22 @T6G_MB_LIB.T6G(SCH_1):PAGE91
   163 M_G_CPU0_SA_DQ<10> @T6G_MB_LIB.T6G(SCH_1):M_G_CPU0_SA_DQ(10)    I22 @T6G_MB_LIB.T6G(SCH_1):PAGE91
   165 M_G_CPU0_SA_DQ<11> @T6G_MB_LIB.T6G(SCH_1):M_G_CPU0_SA_DQ(11)    I22 @T6G_MB_LIB.T6G(SCH_1):PAGE91
    25 M_G_CPU0_SA_DQ<12> @T6G_MB_LIB.T6G(SCH_1):M_G_CPU0_SA_DQ(12)    I22 @T6G_MB_LIB.T6G(SCH_1):PAGE91
    27 M_G_CPU0_SA_DQ<13> @T6G_MB_LIB.T6G(SCH_1):M_G_CPU0_SA_DQ(13)    I22 @T6G_MB_LIB.T6G(SCH_1):PAGE91
   170 M_G_CPU0_SA_DQ<14> @T6G_MB_LIB.T6G(SCH_1):M_G_CPU0_SA_DQ(14)    I22 @T6G_MB_LIB.T6G(SCH_1):PAGE91
   172 M_G_CPU0_SA_DQ<15> @T6G_MB_LIB.T6G(SCH_1):M_G_CPU0_SA_DQ(15)    I22 @T6G_MB_LIB.T6G(SCH_1):PAGE91
    29 M_G_CPU0_SA_DQ<16> @T6G_MB_LIB.T6G(SCH_1):M_G_CPU0_SA_DQ(16)    I22 @T6G_MB_LIB.T6G(SCH_1):PAGE91
    31 M_G_CPU0_SA_DQ<17> @T6G_MB_LIB.T6G(SCH_1):M_G_CPU0_SA_DQ(17)    I22 @T6G_MB_LIB.T6G(SCH_1):PAGE91
   174 M_G_CPU0_SA_DQ<18> @T6G_MB_LIB.T6G(SCH_1):M_G_CPU0_SA_DQ(18)    I22 @T6G_MB_LIB.T6G(SCH_1):PAGE91
   176 M_G_CPU0_SA_DQ<19> @T6G_MB_LIB.T6G(SCH_1):M_G_CPU0_SA_DQ(19)    I22 @T6G_MB_LIB.T6G(SCH_1):PAGE91
    36 M_G_CPU0_SA_DQ<20> @T6G_MB_LIB.T6G(SCH_1):M_G_CPU0_SA_DQ(20)    I22 @T6G_MB_LIB.T6G(SCH_1):PAGE91
    38 M_G_CPU0_SA_DQ<21> @T6G_MB_LIB.T6G(SCH_1):M_G_CPU0_SA_DQ(21)    I22 @T6G_MB_LIB.T6G(SCH_1):PAGE91
   181 M_G_CPU0_SA_DQ<22> @T6G_MB_LIB.T6G(SCH_1):M_G_CPU0_SA_DQ(22)    I22 @T6G_MB_LIB.T6G(SCH_1):PAGE91
   183 M_G_CPU0_SA_DQ<23> @T6G_MB_LIB.T6G(SCH_1):M_G_CPU0_SA_DQ(23)    I22 @T6G_MB_LIB.T6G(SCH_1):PAGE91
    40 M_G_CPU0_SA_DQ<24> @T6G_MB_LIB.T6G(SCH_1):M_G_CPU0_SA_DQ(24)    I22 @T6G_MB_LIB.T6G(SCH_1):PAGE91
    42 M_G_CPU0_SA_DQ<25> @T6G_MB_LIB.T6G(SCH_1):M_G_CPU0_SA_DQ(25)    I22 @T6G_MB_LIB.T6G(SCH_1):PAGE91
   185 M_G_CPU0_SA_DQ<26> @T6G_MB_LIB.T6G(SCH_1):M_G_CPU0_SA_DQ(26)    I22 @T6G_MB_LIB.T6G(SCH_1):PAGE91
   187 M_G_CPU0_SA_DQ<27> @T6G_MB_LIB.T6G(SCH_1):M_G_CPU0_SA_DQ(27)    I22 @T6G_MB_LIB.T6G(SCH_1):PAGE91
    47 M_G_CPU0_SA_DQ<28> @T6G_MB_LIB.T6G(SCH_1):M_G_CPU0_SA_DQ(28)    I22 @T6G_MB_LIB.T6G(SCH_1):PAGE91
    49 M_G_CPU0_SA_DQ<29> @T6G_MB_LIB.T6G(SCH_1):M_G_CPU0_SA_DQ(29)    I22 @T6G_MB_LIB.T6G(SCH_1):PAGE91
   192 M_G_CPU0_SA_DQ<30> @T6G_MB_LIB.T6G(SCH_1):M_G_CPU0_SA_DQ(30)    I22 @T6G_MB_LIB.T6G(SCH_1):PAGE91
   229 M_G_CPU0_SB_CS_N<1> @T6G_MB_LIB.T6G(SCH_1):M_G_CPU0_SB_CS_N(1)    I22 @T6G_MB_LIB.T6G(SCH_1):PAGE91
   209 M_G_CPU0_SA_CS_N<1> @T6G_MB_LIB.T6G(SCH_1):M_G_CPU0_SA_CS_N(1)    I22 @T6G_MB_LIB.T6G(SCH_1):PAGE91
    84 M_G_CPU0_SB_CS_N<0> @T6G_MB_LIB.T6G(SCH_1):M_G_CPU0_SB_CS_N(0)    I22 @T6G_MB_LIB.T6G(SCH_1):PAGE91
    64 M_G_CPU0_SA_CS_N<0> @T6G_MB_LIB.T6G(SCH_1):M_G_CPU0_SA_CS_N(0)    I22 @T6G_MB_LIB.T6G(SCH_1):PAGE91
   217 M_G_CPU0_CLK_DP<0> @T6G_MB_LIB.T6G(SCH_1):M_G_CPU0_CLK_DP(0)    I22 @T6G_MB_LIB.T6G(SCH_1):PAGE91
   218 M_G_CPU0_CLK_DN<0> @T6G_MB_LIB.T6G(SCH_1):M_G_CPU0_CLK_DN(0)    I22 @T6G_MB_LIB.T6G(SCH_1):PAGE91
    96 M_G_CPU0_SB_CB<0> @T6G_MB_LIB.T6G(SCH_1):M_G_CPU0_SB_CB(0)    I22 @T6G_MB_LIB.T6G(SCH_1):PAGE91
    98 M_G_CPU0_SB_CB<1> @T6G_MB_LIB.T6G(SCH_1):M_G_CPU0_SB_CB(1)    I22 @T6G_MB_LIB.T6G(SCH_1):PAGE91
   241 M_G_CPU0_SB_CB<2> @T6G_MB_LIB.T6G(SCH_1):M_G_CPU0_SB_CB(2)    I22 @T6G_MB_LIB.T6G(SCH_1):PAGE91
   243 M_G_CPU0_SB_CB<3> @T6G_MB_LIB.T6G(SCH_1):M_G_CPU0_SB_CB(3)    I22 @T6G_MB_LIB.T6G(SCH_1):PAGE91
    89 M_G_CPU0_SB_CB<4> @T6G_MB_LIB.T6G(SCH_1):M_G_CPU0_SB_CB(4)    I22 @T6G_MB_LIB.T6G(SCH_1):PAGE91
    91 M_G_CPU0_SB_CB<5> @T6G_MB_LIB.T6G(SCH_1):M_G_CPU0_SB_CB(5)    I22 @T6G_MB_LIB.T6G(SCH_1):PAGE91
   234 M_G_CPU0_SB_CB<6> @T6G_MB_LIB.T6G(SCH_1):M_G_CPU0_SB_CB(6)    I22 @T6G_MB_LIB.T6G(SCH_1):PAGE91
    51 M_G_CPU0_SA_CB<0> @T6G_MB_LIB.T6G(SCH_1):M_G_CPU0_SA_CB(0)    I22 @T6G_MB_LIB.T6G(SCH_1):PAGE91
   196 M_G_CPU0_SA_CB<2> @T6G_MB_LIB.T6G(SCH_1):M_G_CPU0_SA_CB(2)    I22 @T6G_MB_LIB.T6G(SCH_1):PAGE91
   198 M_G_CPU0_SA_CB<3> @T6G_MB_LIB.T6G(SCH_1):M_G_CPU0_SA_CB(3)    I22 @T6G_MB_LIB.T6G(SCH_1):PAGE91
    60 M_G_CPU0_SA_CB<5> @T6G_MB_LIB.T6G(SCH_1):M_G_CPU0_SA_CB(5)    I22 @T6G_MB_LIB.T6G(SCH_1):PAGE91
   203 M_G_CPU0_SA_CB<6> @T6G_MB_LIB.T6G(SCH_1):M_G_CPU0_SA_CB(6)    I22 @T6G_MB_LIB.T6G(SCH_1):PAGE91
    82 M_G_CPU0_SB_CA<6> @T6G_MB_LIB.T6G(SCH_1):M_G_CPU0_SB_CA(6)    I22 @T6G_MB_LIB.T6G(SCH_1):PAGE91
    72 M_G_CPU0_SA_CA<6> @T6G_MB_LIB.T6G(SCH_1):M_G_CPU0_SA_CA(6)    I22 @T6G_MB_LIB.T6G(SCH_1):PAGE91
   225 M_G_CPU0_SB_CA<5> @T6G_MB_LIB.T6G(SCH_1):M_G_CPU0_SB_CA(5)    I22 @T6G_MB_LIB.T6G(SCH_1):PAGE91
   215 M_G_CPU0_SA_CA<5> @T6G_MB_LIB.T6G(SCH_1):M_G_CPU0_SA_CA(5)    I22 @T6G_MB_LIB.T6G(SCH_1):PAGE91
    80 M_G_CPU0_SB_CA<4> @T6G_MB_LIB.T6G(SCH_1):M_G_CPU0_SB_CA(4)    I22 @T6G_MB_LIB.T6G(SCH_1):PAGE91
    70 M_G_CPU0_SA_CA<4> @T6G_MB_LIB.T6G(SCH_1):M_G_CPU0_SA_CA(4)    I22 @T6G_MB_LIB.T6G(SCH_1):PAGE91
   223 M_G_CPU0_SB_CA<3> @T6G_MB_LIB.T6G(SCH_1):M_G_CPU0_SB_CA(3)    I22 @T6G_MB_LIB.T6G(SCH_1):PAGE91
   213 M_G_CPU0_SA_CA<3> @T6G_MB_LIB.T6G(SCH_1):M_G_CPU0_SA_CA(3)    I22 @T6G_MB_LIB.T6G(SCH_1):PAGE91
    78 M_G_CPU0_SB_CA<2> @T6G_MB_LIB.T6G(SCH_1):M_G_CPU0_SB_CA(2)    I22 @T6G_MB_LIB.T6G(SCH_1):PAGE91
    68 M_G_CPU0_SA_CA<2> @T6G_MB_LIB.T6G(SCH_1):M_G_CPU0_SA_CA(2)    I22 @T6G_MB_LIB.T6G(SCH_1):PAGE91
   221 M_G_CPU0_SB_CA<1> @T6G_MB_LIB.T6G(SCH_1):M_G_CPU0_SB_CA(1)    I22 @T6G_MB_LIB.T6G(SCH_1):PAGE91
   211 M_G_CPU0_SA_CA<1> @T6G_MB_LIB.T6G(SCH_1):M_G_CPU0_SA_CA(1)    I22 @T6G_MB_LIB.T6G(SCH_1):PAGE91
    76 M_G_CPU0_SB_CA<0> @T6G_MB_LIB.T6G(SCH_1):M_G_CPU0_SB_CA(0)    I22 @T6G_MB_LIB.T6G(SCH_1):PAGE91
    66 M_G_CPU0_SA_CA<0> @T6G_MB_LIB.T6G(SCH_1):M_G_CPU0_SA_CA(0)    I22 @T6G_MB_LIB.T6G(SCH_1):PAGE91
    62 M_G_CPU0_ALERT_N @T6G_MB_LIB.T6G(SCH_1):M_G_CPU0_ALERT_N    I22 @T6G_MB_LIB.T6G(SCH_1):PAGE91
   236 M_G_CPU0_SB_CB<7> @T6G_MB_LIB.T6G(SCH_1):M_G_CPU0_SB_CB(7)    I22 @T6G_MB_LIB.T6G(SCH_1):PAGE91
    53 M_G_CPU0_SA_CB<1> @T6G_MB_LIB.T6G(SCH_1):M_G_CPU0_SA_CB(1)    I22 @T6G_MB_LIB.T6G(SCH_1):PAGE91
    58 M_G_CPU0_SA_CB<4> @T6G_MB_LIB.T6G(SCH_1):M_G_CPU0_SA_CB(4)    I22 @T6G_MB_LIB.T6G(SCH_1):PAGE91
   205 M_G_CPU0_SA_CB<7> @T6G_MB_LIB.T6G(SCH_1):M_G_CPU0_SA_CB(7)    I22 @T6G_MB_LIB.T6G(SCH_1):PAGE91
   194 M_G_CPU0_SA_DQ<31> @T6G_MB_LIB.T6G(SCH_1):M_G_CPU0_SA_DQ(31)    I22 @T6G_MB_LIB.T6G(SCH_1):PAGE91
    93 M_G_CPU0_SB_DQS_DP<9> @T6G_MB_LIB.T6G(SCH_1):M_G_CPU0_SB_DQS_DP(9)   I236 @T6G_MB_LIB.T6G(SCH_1):PAGE91
    94 M_G_CPU0_SB_DQS_DN<9> @T6G_MB_LIB.T6G(SCH_1):M_G_CPU0_SB_DQS_DN(9)   I236 @T6G_MB_LIB.T6G(SCH_1):PAGE91
   201 M_G_CPU0_SA_DQS_DP<9> @T6G_MB_LIB.T6G(SCH_1):M_G_CPU0_SA_DQS_DP(9)   I236 @T6G_MB_LIB.T6G(SCH_1):PAGE91
   200 M_G_CPU0_SA_DQS_DN<9> @T6G_MB_LIB.T6G(SCH_1):M_G_CPU0_SA_DQS_DN(9)   I236 @T6G_MB_LIB.T6G(SCH_1):PAGE91
   190 M_G_CPU0_SA_DQS_DP<8> @T6G_MB_LIB.T6G(SCH_1):M_G_CPU0_SA_DQS_DP(8)   I236 @T6G_MB_LIB.T6G(SCH_1):PAGE91
   189 M_G_CPU0_SA_DQS_DN<8> @T6G_MB_LIB.T6G(SCH_1):M_G_CPU0_SA_DQS_DN(8)   I236 @T6G_MB_LIB.T6G(SCH_1):PAGE91
   271 M_G_CPU0_SB_DQS_DN<7> @T6G_MB_LIB.T6G(SCH_1):M_G_CPU0_SB_DQS_DN(7)   I236 @T6G_MB_LIB.T6G(SCH_1):PAGE91
   179 M_G_CPU0_SA_DQS_DP<7> @T6G_MB_LIB.T6G(SCH_1):M_G_CPU0_SA_DQS_DP(7)   I236 @T6G_MB_LIB.T6G(SCH_1):PAGE91
   261 M_G_CPU0_SB_DQS_DP<6> @T6G_MB_LIB.T6G(SCH_1):M_G_CPU0_SB_DQS_DP(6)   I236 @T6G_MB_LIB.T6G(SCH_1):PAGE91
   260 M_G_CPU0_SB_DQS_DN<6> @T6G_MB_LIB.T6G(SCH_1):M_G_CPU0_SB_DQS_DN(6)   I236 @T6G_MB_LIB.T6G(SCH_1):PAGE91
   167 M_G_CPU0_SA_DQS_DN<6> @T6G_MB_LIB.T6G(SCH_1):M_G_CPU0_SA_DQS_DN(6)   I236 @T6G_MB_LIB.T6G(SCH_1):PAGE91
   250 M_G_CPU0_SB_DQS_DP<5> @T6G_MB_LIB.T6G(SCH_1):M_G_CPU0_SB_DQS_DP(5)   I236 @T6G_MB_LIB.T6G(SCH_1):PAGE91
   249 M_G_CPU0_SB_DQS_DN<5> @T6G_MB_LIB.T6G(SCH_1):M_G_CPU0_SB_DQS_DN(5)   I236 @T6G_MB_LIB.T6G(SCH_1):PAGE91
   157 M_G_CPU0_SA_DQS_DP<5> @T6G_MB_LIB.T6G(SCH_1):M_G_CPU0_SA_DQS_DP(5)   I236 @T6G_MB_LIB.T6G(SCH_1):PAGE91
   156 M_G_CPU0_SA_DQS_DN<5> @T6G_MB_LIB.T6G(SCH_1):M_G_CPU0_SA_DQS_DN(5)   I236 @T6G_MB_LIB.T6G(SCH_1):PAGE91
   239 M_G_CPU0_SB_DQS_DP<4> @T6G_MB_LIB.T6G(SCH_1):M_G_CPU0_SB_DQS_DP(4)   I236 @T6G_MB_LIB.T6G(SCH_1):PAGE91
   238 M_G_CPU0_SB_DQS_DN<4> @T6G_MB_LIB.T6G(SCH_1):M_G_CPU0_SB_DQS_DN(4)   I236 @T6G_MB_LIB.T6G(SCH_1):PAGE91
    55 M_G_CPU0_SA_DQS_DP<4> @T6G_MB_LIB.T6G(SCH_1):M_G_CPU0_SA_DQS_DP(4)   I236 @T6G_MB_LIB.T6G(SCH_1):PAGE91
    56 M_G_CPU0_SA_DQS_DN<4> @T6G_MB_LIB.T6G(SCH_1):M_G_CPU0_SA_DQS_DN(4)   I236 @T6G_MB_LIB.T6G(SCH_1):PAGE91
   137 M_G_CPU0_SB_DQS_DP<3> @T6G_MB_LIB.T6G(SCH_1):M_G_CPU0_SB_DQS_DP(3)   I236 @T6G_MB_LIB.T6G(SCH_1):PAGE91
   138 M_G_CPU0_SB_DQS_DN<3> @T6G_MB_LIB.T6G(SCH_1):M_G_CPU0_SB_DQS_DN(3)   I236 @T6G_MB_LIB.T6G(SCH_1):PAGE91
    44 M_G_CPU0_SA_DQS_DP<3> @T6G_MB_LIB.T6G(SCH_1):M_G_CPU0_SA_DQS_DP(3)   I236 @T6G_MB_LIB.T6G(SCH_1):PAGE91
    45 M_G_CPU0_SA_DQS_DN<3> @T6G_MB_LIB.T6G(SCH_1):M_G_CPU0_SA_DQS_DN(3)   I236 @T6G_MB_LIB.T6G(SCH_1):PAGE91
   126 M_G_CPU0_SB_DQS_DP<2> @T6G_MB_LIB.T6G(SCH_1):M_G_CPU0_SB_DQS_DP(2)   I236 @T6G_MB_LIB.T6G(SCH_1):PAGE91
   127 M_G_CPU0_SB_DQS_DN<2> @T6G_MB_LIB.T6G(SCH_1):M_G_CPU0_SB_DQS_DN(2)   I236 @T6G_MB_LIB.T6G(SCH_1):PAGE91
    33 M_G_CPU0_SA_DQS_DP<2> @T6G_MB_LIB.T6G(SCH_1):M_G_CPU0_SA_DQS_DP(2)   I236 @T6G_MB_LIB.T6G(SCH_1):PAGE91
    34 M_G_CPU0_SA_DQS_DN<2> @T6G_MB_LIB.T6G(SCH_1):M_G_CPU0_SA_DQS_DN(2)   I236 @T6G_MB_LIB.T6G(SCH_1):PAGE91
   115 M_G_CPU0_SB_DQS_DP<1> @T6G_MB_LIB.T6G(SCH_1):M_G_CPU0_SB_DQS_DP(1)   I236 @T6G_MB_LIB.T6G(SCH_1):PAGE91
   116 M_G_CPU0_SB_DQS_DN<1> @T6G_MB_LIB.T6G(SCH_1):M_G_CPU0_SB_DQS_DN(1)   I236 @T6G_MB_LIB.T6G(SCH_1):PAGE91
    22 M_G_CPU0_SA_DQS_DP<1> @T6G_MB_LIB.T6G(SCH_1):M_G_CPU0_SA_DQS_DP(1)   I236 @T6G_MB_LIB.T6G(SCH_1):PAGE91
    23 M_G_CPU0_SA_DQS_DN<1> @T6G_MB_LIB.T6G(SCH_1):M_G_CPU0_SA_DQS_DN(1)   I236 @T6G_MB_LIB.T6G(SCH_1):PAGE91
   104 M_G_CPU0_SB_DQS_DP<0> @T6G_MB_LIB.T6G(SCH_1):M_G_CPU0_SB_DQS_DP(0)   I236 @T6G_MB_LIB.T6G(SCH_1):PAGE91
   105 M_G_CPU0_SB_DQS_DN<0> @T6G_MB_LIB.T6G(SCH_1):M_G_CPU0_SB_DQS_DN(0)   I236 @T6G_MB_LIB.T6G(SCH_1):PAGE91
    11 M_G_CPU0_SA_DQS_DP<0> @T6G_MB_LIB.T6G(SCH_1):M_G_CPU0_SA_DQS_DP(0)   I236 @T6G_MB_LIB.T6G(SCH_1):PAGE91
    12 M_G_CPU0_SA_DQS_DN<0> @T6G_MB_LIB.T6G(SCH_1):M_G_CPU0_SA_DQS_DN(0)   I236 @T6G_MB_LIB.T6G(SCH_1):PAGE91
   272 M_G_CPU0_SB_DQS_DP<7> @T6G_MB_LIB.T6G(SCH_1):M_G_CPU0_SB_DQS_DP(7)   I236 @T6G_MB_LIB.T6G(SCH_1):PAGE91
   282 M_G_CPU0_SB_DQS_DN<8> @T6G_MB_LIB.T6G(SCH_1):M_G_CPU0_SB_DQS_DN(8)   I236 @T6G_MB_LIB.T6G(SCH_1):PAGE91
   283 M_G_CPU0_SB_DQS_DP<8> @T6G_MB_LIB.T6G(SCH_1):M_G_CPU0_SB_DQS_DP(8)   I236 @T6G_MB_LIB.T6G(SCH_1):PAGE91
   168 M_G_CPU0_SA_DQS_DP<6> @T6G_MB_LIB.T6G(SCH_1):M_G_CPU0_SA_DQS_DP(6)   I236 @T6G_MB_LIB.T6G(SCH_1):PAGE91
   178 M_G_CPU0_SA_DQS_DN<7> @T6G_MB_LIB.T6G(SCH_1):M_G_CPU0_SA_DQS_DN(7)   I236 @T6G_MB_LIB.T6G(SCH_1):PAGE91
     6    GND @T6G_MB_LIB.T6G(SCH_1):GND   I177 @T6G_MB_LIB.T6G(SCH_1):PAGE91
     8    GND @T6G_MB_LIB.T6G(SCH_1):GND   I177 @T6G_MB_LIB.T6G(SCH_1):PAGE91
    10    GND @T6G_MB_LIB.T6G(SCH_1):GND   I177 @T6G_MB_LIB.T6G(SCH_1):PAGE91
    13    GND @T6G_MB_LIB.T6G(SCH_1):GND   I177 @T6G_MB_LIB.T6G(SCH_1):PAGE91
    15    GND @T6G_MB_LIB.T6G(SCH_1):GND   I177 @T6G_MB_LIB.T6G(SCH_1):PAGE91
    17    GND @T6G_MB_LIB.T6G(SCH_1):GND   I177 @T6G_MB_LIB.T6G(SCH_1):PAGE91
    19    GND @T6G_MB_LIB.T6G(SCH_1):GND   I177 @T6G_MB_LIB.T6G(SCH_1):PAGE91
    21    GND @T6G_MB_LIB.T6G(SCH_1):GND   I177 @T6G_MB_LIB.T6G(SCH_1):PAGE91
    24    GND @T6G_MB_LIB.T6G(SCH_1):GND   I177 @T6G_MB_LIB.T6G(SCH_1):PAGE91
    26    GND @T6G_MB_LIB.T6G(SCH_1):GND   I177 @T6G_MB_LIB.T6G(SCH_1):PAGE91
    28    GND @T6G_MB_LIB.T6G(SCH_1):GND   I177 @T6G_MB_LIB.T6G(SCH_1):PAGE91
    30    GND @T6G_MB_LIB.T6G(SCH_1):GND   I177 @T6G_MB_LIB.T6G(SCH_1):PAGE91
    32    GND @T6G_MB_LIB.T6G(SCH_1):GND   I177 @T6G_MB_LIB.T6G(SCH_1):PAGE91
    35    GND @T6G_MB_LIB.T6G(SCH_1):GND   I177 @T6G_MB_LIB.T6G(SCH_1):PAGE91
    37    GND @T6G_MB_LIB.T6G(SCH_1):GND   I177 @T6G_MB_LIB.T6G(SCH_1):PAGE91
    39    GND @T6G_MB_LIB.T6G(SCH_1):GND   I177 @T6G_MB_LIB.T6G(SCH_1):PAGE91
    41    GND @T6G_MB_LIB.T6G(SCH_1):GND   I177 @T6G_MB_LIB.T6G(SCH_1):PAGE91
    43    GND @T6G_MB_LIB.T6G(SCH_1):GND   I177 @T6G_MB_LIB.T6G(SCH_1):PAGE91
    46    GND @T6G_MB_LIB.T6G(SCH_1):GND   I177 @T6G_MB_LIB.T6G(SCH_1):PAGE91
    48    GND @T6G_MB_LIB.T6G(SCH_1):GND   I177 @T6G_MB_LIB.T6G(SCH_1):PAGE91
    50    GND @T6G_MB_LIB.T6G(SCH_1):GND   I177 @T6G_MB_LIB.T6G(SCH_1):PAGE91
    52    GND @T6G_MB_LIB.T6G(SCH_1):GND   I177 @T6G_MB_LIB.T6G(SCH_1):PAGE91
    54    GND @T6G_MB_LIB.T6G(SCH_1):GND   I177 @T6G_MB_LIB.T6G(SCH_1):PAGE91
    57    GND @T6G_MB_LIB.T6G(SCH_1):GND   I177 @T6G_MB_LIB.T6G(SCH_1):PAGE91
    59    GND @T6G_MB_LIB.T6G(SCH_1):GND   I177 @T6G_MB_LIB.T6G(SCH_1):PAGE91
    61    GND @T6G_MB_LIB.T6G(SCH_1):GND   I177 @T6G_MB_LIB.T6G(SCH_1):PAGE91
    63    GND @T6G_MB_LIB.T6G(SCH_1):GND   I177 @T6G_MB_LIB.T6G(SCH_1):PAGE91
    65    GND @T6G_MB_LIB.T6G(SCH_1):GND   I177 @T6G_MB_LIB.T6G(SCH_1):PAGE91
    67    GND @T6G_MB_LIB.T6G(SCH_1):GND   I177 @T6G_MB_LIB.T6G(SCH_1):PAGE91
    69    GND @T6G_MB_LIB.T6G(SCH_1):GND   I177 @T6G_MB_LIB.T6G(SCH_1):PAGE91
    71    GND @T6G_MB_LIB.T6G(SCH_1):GND   I177 @T6G_MB_LIB.T6G(SCH_1):PAGE91
    73    GND @T6G_MB_LIB.T6G(SCH_1):GND   I177 @T6G_MB_LIB.T6G(SCH_1):PAGE91
    75    GND @T6G_MB_LIB.T6G(SCH_1):GND   I177 @T6G_MB_LIB.T6G(SCH_1):PAGE91
    77    GND @T6G_MB_LIB.T6G(SCH_1):GND   I177 @T6G_MB_LIB.T6G(SCH_1):PAGE91
    79    GND @T6G_MB_LIB.T6G(SCH_1):GND   I177 @T6G_MB_LIB.T6G(SCH_1):PAGE91
    81    GND @T6G_MB_LIB.T6G(SCH_1):GND   I177 @T6G_MB_LIB.T6G(SCH_1):PAGE91
    83    GND @T6G_MB_LIB.T6G(SCH_1):GND   I177 @T6G_MB_LIB.T6G(SCH_1):PAGE91
    85    GND @T6G_MB_LIB.T6G(SCH_1):GND   I177 @T6G_MB_LIB.T6G(SCH_1):PAGE91
    88    GND @T6G_MB_LIB.T6G(SCH_1):GND   I177 @T6G_MB_LIB.T6G(SCH_1):PAGE91
    90    GND @T6G_MB_LIB.T6G(SCH_1):GND   I177 @T6G_MB_LIB.T6G(SCH_1):PAGE91
    92    GND @T6G_MB_LIB.T6G(SCH_1):GND   I177 @T6G_MB_LIB.T6G(SCH_1):PAGE91
    95    GND @T6G_MB_LIB.T6G(SCH_1):GND   I177 @T6G_MB_LIB.T6G(SCH_1):PAGE91
    97    GND @T6G_MB_LIB.T6G(SCH_1):GND   I177 @T6G_MB_LIB.T6G(SCH_1):PAGE91
    99    GND @T6G_MB_LIB.T6G(SCH_1):GND   I177 @T6G_MB_LIB.T6G(SCH_1):PAGE91
   101    GND @T6G_MB_LIB.T6G(SCH_1):GND   I177 @T6G_MB_LIB.T6G(SCH_1):PAGE91
   103    GND @T6G_MB_LIB.T6G(SCH_1):GND   I177 @T6G_MB_LIB.T6G(SCH_1):PAGE91
   106    GND @T6G_MB_LIB.T6G(SCH_1):GND   I177 @T6G_MB_LIB.T6G(SCH_1):PAGE91
   108    GND @T6G_MB_LIB.T6G(SCH_1):GND   I177 @T6G_MB_LIB.T6G(SCH_1):PAGE91
   110    GND @T6G_MB_LIB.T6G(SCH_1):GND   I177 @T6G_MB_LIB.T6G(SCH_1):PAGE91
   112    GND @T6G_MB_LIB.T6G(SCH_1):GND   I177 @T6G_MB_LIB.T6G(SCH_1):PAGE91
   114    GND @T6G_MB_LIB.T6G(SCH_1):GND   I177 @T6G_MB_LIB.T6G(SCH_1):PAGE91
   117    GND @T6G_MB_LIB.T6G(SCH_1):GND   I177 @T6G_MB_LIB.T6G(SCH_1):PAGE91
   119    GND @T6G_MB_LIB.T6G(SCH_1):GND   I177 @T6G_MB_LIB.T6G(SCH_1):PAGE91
   121    GND @T6G_MB_LIB.T6G(SCH_1):GND   I177 @T6G_MB_LIB.T6G(SCH_1):PAGE91
   123    GND @T6G_MB_LIB.T6G(SCH_1):GND   I177 @T6G_MB_LIB.T6G(SCH_1):PAGE91
   125    GND @T6G_MB_LIB.T6G(SCH_1):GND   I177 @T6G_MB_LIB.T6G(SCH_1):PAGE91
   128    GND @T6G_MB_LIB.T6G(SCH_1):GND   I177 @T6G_MB_LIB.T6G(SCH_1):PAGE91
   130    GND @T6G_MB_LIB.T6G(SCH_1):GND   I177 @T6G_MB_LIB.T6G(SCH_1):PAGE91
   134    GND @T6G_MB_LIB.T6G(SCH_1):GND   I177 @T6G_MB_LIB.T6G(SCH_1):PAGE91
   143    GND @T6G_MB_LIB.T6G(SCH_1):GND   I177 @T6G_MB_LIB.T6G(SCH_1):PAGE91
   151    GND @T6G_MB_LIB.T6G(SCH_1):GND   I177 @T6G_MB_LIB.T6G(SCH_1):PAGE91
   153    GND @T6G_MB_LIB.T6G(SCH_1):GND   I177 @T6G_MB_LIB.T6G(SCH_1):PAGE91
   155    GND @T6G_MB_LIB.T6G(SCH_1):GND   I177 @T6G_MB_LIB.T6G(SCH_1):PAGE91
   158    GND @T6G_MB_LIB.T6G(SCH_1):GND   I177 @T6G_MB_LIB.T6G(SCH_1):PAGE91
   160    GND @T6G_MB_LIB.T6G(SCH_1):GND   I177 @T6G_MB_LIB.T6G(SCH_1):PAGE91
   162    GND @T6G_MB_LIB.T6G(SCH_1):GND   I177 @T6G_MB_LIB.T6G(SCH_1):PAGE91
   164    GND @T6G_MB_LIB.T6G(SCH_1):GND   I177 @T6G_MB_LIB.T6G(SCH_1):PAGE91
   166    GND @T6G_MB_LIB.T6G(SCH_1):GND   I177 @T6G_MB_LIB.T6G(SCH_1):PAGE91
   169    GND @T6G_MB_LIB.T6G(SCH_1):GND   I177 @T6G_MB_LIB.T6G(SCH_1):PAGE91
   171    GND @T6G_MB_LIB.T6G(SCH_1):GND   I177 @T6G_MB_LIB.T6G(SCH_1):PAGE91
   173    GND @T6G_MB_LIB.T6G(SCH_1):GND   I177 @T6G_MB_LIB.T6G(SCH_1):PAGE91
   175    GND @T6G_MB_LIB.T6G(SCH_1):GND   I177 @T6G_MB_LIB.T6G(SCH_1):PAGE91
   177    GND @T6G_MB_LIB.T6G(SCH_1):GND   I177 @T6G_MB_LIB.T6G(SCH_1):PAGE91
   180    GND @T6G_MB_LIB.T6G(SCH_1):GND   I177 @T6G_MB_LIB.T6G(SCH_1):PAGE91
   182    GND @T6G_MB_LIB.T6G(SCH_1):GND   I177 @T6G_MB_LIB.T6G(SCH_1):PAGE91
   184    GND @T6G_MB_LIB.T6G(SCH_1):GND   I177 @T6G_MB_LIB.T6G(SCH_1):PAGE91
   186    GND @T6G_MB_LIB.T6G(SCH_1):GND   I177 @T6G_MB_LIB.T6G(SCH_1):PAGE91
   188    GND @T6G_MB_LIB.T6G(SCH_1):GND   I177 @T6G_MB_LIB.T6G(SCH_1):PAGE91
   191    GND @T6G_MB_LIB.T6G(SCH_1):GND   I177 @T6G_MB_LIB.T6G(SCH_1):PAGE91
   193    GND @T6G_MB_LIB.T6G(SCH_1):GND   I177 @T6G_MB_LIB.T6G(SCH_1):PAGE91
   195    GND @T6G_MB_LIB.T6G(SCH_1):GND   I177 @T6G_MB_LIB.T6G(SCH_1):PAGE91
   197    GND @T6G_MB_LIB.T6G(SCH_1):GND   I177 @T6G_MB_LIB.T6G(SCH_1):PAGE91
   199    GND @T6G_MB_LIB.T6G(SCH_1):GND   I177 @T6G_MB_LIB.T6G(SCH_1):PAGE91
   202    GND @T6G_MB_LIB.T6G(SCH_1):GND   I177 @T6G_MB_LIB.T6G(SCH_1):PAGE91
   204    GND @T6G_MB_LIB.T6G(SCH_1):GND   I177 @T6G_MB_LIB.T6G(SCH_1):PAGE91
   206    GND @T6G_MB_LIB.T6G(SCH_1):GND   I177 @T6G_MB_LIB.T6G(SCH_1):PAGE91
   208    GND @T6G_MB_LIB.T6G(SCH_1):GND   I177 @T6G_MB_LIB.T6G(SCH_1):PAGE91
   210    GND @T6G_MB_LIB.T6G(SCH_1):GND   I177 @T6G_MB_LIB.T6G(SCH_1):PAGE91
   212    GND @T6G_MB_LIB.T6G(SCH_1):GND   I177 @T6G_MB_LIB.T6G(SCH_1):PAGE91
   214    GND @T6G_MB_LIB.T6G(SCH_1):GND   I177 @T6G_MB_LIB.T6G(SCH_1):PAGE91
   216    GND @T6G_MB_LIB.T6G(SCH_1):GND   I177 @T6G_MB_LIB.T6G(SCH_1):PAGE91
   219    GND @T6G_MB_LIB.T6G(SCH_1):GND   I177 @T6G_MB_LIB.T6G(SCH_1):PAGE91
   222    GND @T6G_MB_LIB.T6G(SCH_1):GND   I177 @T6G_MB_LIB.T6G(SCH_1):PAGE91
   224    GND @T6G_MB_LIB.T6G(SCH_1):GND   I177 @T6G_MB_LIB.T6G(SCH_1):PAGE91
   226    GND @T6G_MB_LIB.T6G(SCH_1):GND   I177 @T6G_MB_LIB.T6G(SCH_1):PAGE91
   228    GND @T6G_MB_LIB.T6G(SCH_1):GND   I177 @T6G_MB_LIB.T6G(SCH_1):PAGE91
   233    GND @T6G_MB_LIB.T6G(SCH_1):GND   I177 @T6G_MB_LIB.T6G(SCH_1):PAGE91
   237    GND @T6G_MB_LIB.T6G(SCH_1):GND   I177 @T6G_MB_LIB.T6G(SCH_1):PAGE91
   242    GND @T6G_MB_LIB.T6G(SCH_1):GND   I177 @T6G_MB_LIB.T6G(SCH_1):PAGE91
   244    GND @T6G_MB_LIB.T6G(SCH_1):GND   I177 @T6G_MB_LIB.T6G(SCH_1):PAGE91
   246    GND @T6G_MB_LIB.T6G(SCH_1):GND   I177 @T6G_MB_LIB.T6G(SCH_1):PAGE91
   248    GND @T6G_MB_LIB.T6G(SCH_1):GND   I177 @T6G_MB_LIB.T6G(SCH_1):PAGE91
   251    GND @T6G_MB_LIB.T6G(SCH_1):GND   I177 @T6G_MB_LIB.T6G(SCH_1):PAGE91
   253    GND @T6G_MB_LIB.T6G(SCH_1):GND   I177 @T6G_MB_LIB.T6G(SCH_1):PAGE91
   255    GND @T6G_MB_LIB.T6G(SCH_1):GND   I177 @T6G_MB_LIB.T6G(SCH_1):PAGE91
   257    GND @T6G_MB_LIB.T6G(SCH_1):GND   I177 @T6G_MB_LIB.T6G(SCH_1):PAGE91
   259    GND @T6G_MB_LIB.T6G(SCH_1):GND   I177 @T6G_MB_LIB.T6G(SCH_1):PAGE91
   262    GND @T6G_MB_LIB.T6G(SCH_1):GND   I177 @T6G_MB_LIB.T6G(SCH_1):PAGE91
   264    GND @T6G_MB_LIB.T6G(SCH_1):GND   I177 @T6G_MB_LIB.T6G(SCH_1):PAGE91
   266    GND @T6G_MB_LIB.T6G(SCH_1):GND   I177 @T6G_MB_LIB.T6G(SCH_1):PAGE91
   268    GND @T6G_MB_LIB.T6G(SCH_1):GND   I177 @T6G_MB_LIB.T6G(SCH_1):PAGE91
   270    GND @T6G_MB_LIB.T6G(SCH_1):GND   I177 @T6G_MB_LIB.T6G(SCH_1):PAGE91
   273    GND @T6G_MB_LIB.T6G(SCH_1):GND   I177 @T6G_MB_LIB.T6G(SCH_1):PAGE91
   275    GND @T6G_MB_LIB.T6G(SCH_1):GND   I177 @T6G_MB_LIB.T6G(SCH_1):PAGE91
   277    GND @T6G_MB_LIB.T6G(SCH_1):GND   I177 @T6G_MB_LIB.T6G(SCH_1):PAGE91
   279    GND @T6G_MB_LIB.T6G(SCH_1):GND   I177 @T6G_MB_LIB.T6G(SCH_1):PAGE91
   281    GND @T6G_MB_LIB.T6G(SCH_1):GND   I177 @T6G_MB_LIB.T6G(SCH_1):PAGE91
   284    GND @T6G_MB_LIB.T6G(SCH_1):GND   I177 @T6G_MB_LIB.T6G(SCH_1):PAGE91
   286    GND @T6G_MB_LIB.T6G(SCH_1):GND   I177 @T6G_MB_LIB.T6G(SCH_1):PAGE91
   288    GND @T6G_MB_LIB.T6G(SCH_1):GND   I177 @T6G_MB_LIB.T6G(SCH_1):PAGE91
     1 P12V_MEM_CPU0 @T6G_MB_LIB.T6G(SCH_1):P12V_MEM_CPU0   I177 @T6G_MB_LIB.T6G(SCH_1):PAGE91
   145 P12V_MEM_CPU0 @T6G_MB_LIB.T6G(SCH_1):P12V_MEM_CPU0   I177 @T6G_MB_LIB.T6G(SCH_1):PAGE91
   146 P12V_MEM_CPU0 @T6G_MB_LIB.T6G(SCH_1):P12V_MEM_CPU0   I177 @T6G_MB_LIB.T6G(SCH_1):PAGE91
   230    GND @T6G_MB_LIB.T6G(SCH_1):GND   I177 @T6G_MB_LIB.T6G(SCH_1):PAGE91
   235    GND @T6G_MB_LIB.T6G(SCH_1):GND   I177 @T6G_MB_LIB.T6G(SCH_1):PAGE91
   240    GND @T6G_MB_LIB.T6G(SCH_1):GND   I177 @T6G_MB_LIB.T6G(SCH_1):PAGE91
   132    GND @T6G_MB_LIB.T6G(SCH_1):GND   I177 @T6G_MB_LIB.T6G(SCH_1):PAGE91
   136    GND @T6G_MB_LIB.T6G(SCH_1):GND   I177 @T6G_MB_LIB.T6G(SCH_1):PAGE91
   139    GND @T6G_MB_LIB.T6G(SCH_1):GND   I177 @T6G_MB_LIB.T6G(SCH_1):PAGE91
   141    GND @T6G_MB_LIB.T6G(SCH_1):GND   I177 @T6G_MB_LIB.T6G(SCH_1):PAGE91
    G1    GND @T6G_MB_LIB.T6G(SCH_1):GND   I177 @T6G_MB_LIB.T6G(SCH_1):PAGE91
    G2    GND @T6G_MB_LIB.T6G(SCH_1):GND   I177 @T6G_MB_LIB.T6G(SCH_1):PAGE91
    G3    GND @T6G_MB_LIB.T6G(SCH_1):GND   I177 @T6G_MB_LIB.T6G(SCH_1):PAGE91

 J17 SCONN288_DDR506112002KQ-SCONN288_DDR506112002KQ,SMA
     3 P3V3_AUX @T6G_MB_LIB.T6G(SCH_1):P3V3_AUX   I350 @T6G_MB_LIB.T6G(SCH_1):PAGE87
     2     NC     NC   I350 @T6G_MB_LIB.T6G(SCH_1):PAGE87
   144     NC     NC   I350 @T6G_MB_LIB.T6G(SCH_1):PAGE87
   149     NC     NC   I350 @T6G_MB_LIB.T6G(SCH_1):PAGE87
   150     NC     NC   I350 @T6G_MB_LIB.T6G(SCH_1):PAGE87
   220     NC     NC   I350 @T6G_MB_LIB.T6G(SCH_1):PAGE87
   231     NC     NC   I350 @T6G_MB_LIB.T6G(SCH_1):PAGE87
   232     NC     NC   I350 @T6G_MB_LIB.T6G(SCH_1):PAGE87
   207 M_C_CPU0_RESET_N @T6G_MB_LIB.T6G(SCH_1):M_C_CPU0_RESET_N   I350 @T6G_MB_LIB.T6G(SCH_1):PAGE87
   147 PWRGD_CHC_CPU0_DIMM @T6G_MB_LIB.T6G(SCH_1):PWRGD_CHC_CPU0_DIMM   I350 @T6G_MB_LIB.T6G(SCH_1):PAGE87
   227 M_C_CPU0_SB_PAR @T6G_MB_LIB.T6G(SCH_1):M_C_CPU0_SB_PAR   I350 @T6G_MB_LIB.T6G(SCH_1):PAGE87
    74 M_C_CPU0_SA_PAR @T6G_MB_LIB.T6G(SCH_1):M_C_CPU0_SA_PAR   I350 @T6G_MB_LIB.T6G(SCH_1):PAGE87
    87 M_C_CPU0_SB_RSP<0> @T6G_MB_LIB.T6G(SCH_1):M_C_CPU0_SB_RSP(0)   I350 @T6G_MB_LIB.T6G(SCH_1):PAGE87
    86 M_C_CPU0_SA_RSP<0> @T6G_MB_LIB.T6G(SCH_1):M_C_CPU0_SA_RSP(0)   I350 @T6G_MB_LIB.T6G(SCH_1):PAGE87
     5 I3C_SPD_DDRC_CPU0_SDA @T6G_MB_LIB.T6G(SCH_1):I3C_SPD_DDRC_CPU0_SDA   I350 @T6G_MB_LIB.T6G(SCH_1):PAGE87
     4 I3C_SPD_DDRC_CPU0_SCL @T6G_MB_LIB.T6G(SCH_1):I3C_SPD_DDRC_CPU0_SCL   I350 @T6G_MB_LIB.T6G(SCH_1):PAGE87
   148 PD_CHC_CPU0_DIMM_SAA @T6G_MB_LIB.T6G(SCH_1):PD_CHC_CPU0_DIMM_SAA   I350 @T6G_MB_LIB.T6G(SCH_1):PAGE87
   100 M_C_CPU0_SB_DQ<0> @T6G_MB_LIB.T6G(SCH_1):M_C_CPU0_SB_DQ(0)   I350 @T6G_MB_LIB.T6G(SCH_1):PAGE87
   102 M_C_CPU0_SB_DQ<1> @T6G_MB_LIB.T6G(SCH_1):M_C_CPU0_SB_DQ(1)   I350 @T6G_MB_LIB.T6G(SCH_1):PAGE87
   245 M_C_CPU0_SB_DQ<2> @T6G_MB_LIB.T6G(SCH_1):M_C_CPU0_SB_DQ(2)   I350 @T6G_MB_LIB.T6G(SCH_1):PAGE87
   247 M_C_CPU0_SB_DQ<3> @T6G_MB_LIB.T6G(SCH_1):M_C_CPU0_SB_DQ(3)   I350 @T6G_MB_LIB.T6G(SCH_1):PAGE87
   107 M_C_CPU0_SB_DQ<4> @T6G_MB_LIB.T6G(SCH_1):M_C_CPU0_SB_DQ(4)   I350 @T6G_MB_LIB.T6G(SCH_1):PAGE87
   109 M_C_CPU0_SB_DQ<5> @T6G_MB_LIB.T6G(SCH_1):M_C_CPU0_SB_DQ(5)   I350 @T6G_MB_LIB.T6G(SCH_1):PAGE87
   252 M_C_CPU0_SB_DQ<6> @T6G_MB_LIB.T6G(SCH_1):M_C_CPU0_SB_DQ(6)   I350 @T6G_MB_LIB.T6G(SCH_1):PAGE87
   254 M_C_CPU0_SB_DQ<7> @T6G_MB_LIB.T6G(SCH_1):M_C_CPU0_SB_DQ(7)   I350 @T6G_MB_LIB.T6G(SCH_1):PAGE87
   111 M_C_CPU0_SB_DQ<8> @T6G_MB_LIB.T6G(SCH_1):M_C_CPU0_SB_DQ(8)   I350 @T6G_MB_LIB.T6G(SCH_1):PAGE87
   113 M_C_CPU0_SB_DQ<9> @T6G_MB_LIB.T6G(SCH_1):M_C_CPU0_SB_DQ(9)   I350 @T6G_MB_LIB.T6G(SCH_1):PAGE87
   256 M_C_CPU0_SB_DQ<10> @T6G_MB_LIB.T6G(SCH_1):M_C_CPU0_SB_DQ(10)   I350 @T6G_MB_LIB.T6G(SCH_1):PAGE87
   258 M_C_CPU0_SB_DQ<11> @T6G_MB_LIB.T6G(SCH_1):M_C_CPU0_SB_DQ(11)   I350 @T6G_MB_LIB.T6G(SCH_1):PAGE87
   118 M_C_CPU0_SB_DQ<12> @T6G_MB_LIB.T6G(SCH_1):M_C_CPU0_SB_DQ(12)   I350 @T6G_MB_LIB.T6G(SCH_1):PAGE87
   120 M_C_CPU0_SB_DQ<13> @T6G_MB_LIB.T6G(SCH_1):M_C_CPU0_SB_DQ(13)   I350 @T6G_MB_LIB.T6G(SCH_1):PAGE87
   263 M_C_CPU0_SB_DQ<14> @T6G_MB_LIB.T6G(SCH_1):M_C_CPU0_SB_DQ(14)   I350 @T6G_MB_LIB.T6G(SCH_1):PAGE87
   265 M_C_CPU0_SB_DQ<15> @T6G_MB_LIB.T6G(SCH_1):M_C_CPU0_SB_DQ(15)   I350 @T6G_MB_LIB.T6G(SCH_1):PAGE87
   122 M_C_CPU0_SB_DQ<16> @T6G_MB_LIB.T6G(SCH_1):M_C_CPU0_SB_DQ(16)   I350 @T6G_MB_LIB.T6G(SCH_1):PAGE87
   124 M_C_CPU0_SB_DQ<17> @T6G_MB_LIB.T6G(SCH_1):M_C_CPU0_SB_DQ(17)   I350 @T6G_MB_LIB.T6G(SCH_1):PAGE87
   267 M_C_CPU0_SB_DQ<18> @T6G_MB_LIB.T6G(SCH_1):M_C_CPU0_SB_DQ(18)   I350 @T6G_MB_LIB.T6G(SCH_1):PAGE87
   269 M_C_CPU0_SB_DQ<19> @T6G_MB_LIB.T6G(SCH_1):M_C_CPU0_SB_DQ(19)   I350 @T6G_MB_LIB.T6G(SCH_1):PAGE87
   129 M_C_CPU0_SB_DQ<20> @T6G_MB_LIB.T6G(SCH_1):M_C_CPU0_SB_DQ(20)   I350 @T6G_MB_LIB.T6G(SCH_1):PAGE87
   131 M_C_CPU0_SB_DQ<21> @T6G_MB_LIB.T6G(SCH_1):M_C_CPU0_SB_DQ(21)   I350 @T6G_MB_LIB.T6G(SCH_1):PAGE87
   274 M_C_CPU0_SB_DQ<22> @T6G_MB_LIB.T6G(SCH_1):M_C_CPU0_SB_DQ(22)   I350 @T6G_MB_LIB.T6G(SCH_1):PAGE87
   276 M_C_CPU0_SB_DQ<23> @T6G_MB_LIB.T6G(SCH_1):M_C_CPU0_SB_DQ(23)   I350 @T6G_MB_LIB.T6G(SCH_1):PAGE87
   133 M_C_CPU0_SB_DQ<24> @T6G_MB_LIB.T6G(SCH_1):M_C_CPU0_SB_DQ(24)   I350 @T6G_MB_LIB.T6G(SCH_1):PAGE87
   135 M_C_CPU0_SB_DQ<25> @T6G_MB_LIB.T6G(SCH_1):M_C_CPU0_SB_DQ(25)   I350 @T6G_MB_LIB.T6G(SCH_1):PAGE87
   278 M_C_CPU0_SB_DQ<26> @T6G_MB_LIB.T6G(SCH_1):M_C_CPU0_SB_DQ(26)   I350 @T6G_MB_LIB.T6G(SCH_1):PAGE87
   280 M_C_CPU0_SB_DQ<27> @T6G_MB_LIB.T6G(SCH_1):M_C_CPU0_SB_DQ(27)   I350 @T6G_MB_LIB.T6G(SCH_1):PAGE87
   140 M_C_CPU0_SB_DQ<28> @T6G_MB_LIB.T6G(SCH_1):M_C_CPU0_SB_DQ(28)   I350 @T6G_MB_LIB.T6G(SCH_1):PAGE87
   142 M_C_CPU0_SB_DQ<29> @T6G_MB_LIB.T6G(SCH_1):M_C_CPU0_SB_DQ(29)   I350 @T6G_MB_LIB.T6G(SCH_1):PAGE87
   285 M_C_CPU0_SB_DQ<30> @T6G_MB_LIB.T6G(SCH_1):M_C_CPU0_SB_DQ(30)   I350 @T6G_MB_LIB.T6G(SCH_1):PAGE87
   287 M_C_CPU0_SB_DQ<31> @T6G_MB_LIB.T6G(SCH_1):M_C_CPU0_SB_DQ(31)   I350 @T6G_MB_LIB.T6G(SCH_1):PAGE87
     7 M_C_CPU0_SA_DQ<0> @T6G_MB_LIB.T6G(SCH_1):M_C_CPU0_SA_DQ(0)   I350 @T6G_MB_LIB.T6G(SCH_1):PAGE87
     9 M_C_CPU0_SA_DQ<1> @T6G_MB_LIB.T6G(SCH_1):M_C_CPU0_SA_DQ(1)   I350 @T6G_MB_LIB.T6G(SCH_1):PAGE87
   152 M_C_CPU0_SA_DQ<2> @T6G_MB_LIB.T6G(SCH_1):M_C_CPU0_SA_DQ(2)   I350 @T6G_MB_LIB.T6G(SCH_1):PAGE87
   154 M_C_CPU0_SA_DQ<3> @T6G_MB_LIB.T6G(SCH_1):M_C_CPU0_SA_DQ(3)   I350 @T6G_MB_LIB.T6G(SCH_1):PAGE87
    14 M_C_CPU0_SA_DQ<4> @T6G_MB_LIB.T6G(SCH_1):M_C_CPU0_SA_DQ(4)   I350 @T6G_MB_LIB.T6G(SCH_1):PAGE87
    16 M_C_CPU0_SA_DQ<5> @T6G_MB_LIB.T6G(SCH_1):M_C_CPU0_SA_DQ(5)   I350 @T6G_MB_LIB.T6G(SCH_1):PAGE87
   159 M_C_CPU0_SA_DQ<6> @T6G_MB_LIB.T6G(SCH_1):M_C_CPU0_SA_DQ(6)   I350 @T6G_MB_LIB.T6G(SCH_1):PAGE87
   161 M_C_CPU0_SA_DQ<7> @T6G_MB_LIB.T6G(SCH_1):M_C_CPU0_SA_DQ(7)   I350 @T6G_MB_LIB.T6G(SCH_1):PAGE87
    18 M_C_CPU0_SA_DQ<8> @T6G_MB_LIB.T6G(SCH_1):M_C_CPU0_SA_DQ(8)   I350 @T6G_MB_LIB.T6G(SCH_1):PAGE87
    20 M_C_CPU0_SA_DQ<9> @T6G_MB_LIB.T6G(SCH_1):M_C_CPU0_SA_DQ(9)   I350 @T6G_MB_LIB.T6G(SCH_1):PAGE87
   163 M_C_CPU0_SA_DQ<10> @T6G_MB_LIB.T6G(SCH_1):M_C_CPU0_SA_DQ(10)   I350 @T6G_MB_LIB.T6G(SCH_1):PAGE87
   165 M_C_CPU0_SA_DQ<11> @T6G_MB_LIB.T6G(SCH_1):M_C_CPU0_SA_DQ(11)   I350 @T6G_MB_LIB.T6G(SCH_1):PAGE87
    25 M_C_CPU0_SA_DQ<12> @T6G_MB_LIB.T6G(SCH_1):M_C_CPU0_SA_DQ(12)   I350 @T6G_MB_LIB.T6G(SCH_1):PAGE87
    27 M_C_CPU0_SA_DQ<13> @T6G_MB_LIB.T6G(SCH_1):M_C_CPU0_SA_DQ(13)   I350 @T6G_MB_LIB.T6G(SCH_1):PAGE87
   170 M_C_CPU0_SA_DQ<14> @T6G_MB_LIB.T6G(SCH_1):M_C_CPU0_SA_DQ(14)   I350 @T6G_MB_LIB.T6G(SCH_1):PAGE87
   172 M_C_CPU0_SA_DQ<15> @T6G_MB_LIB.T6G(SCH_1):M_C_CPU0_SA_DQ(15)   I350 @T6G_MB_LIB.T6G(SCH_1):PAGE87
    29 M_C_CPU0_SA_DQ<16> @T6G_MB_LIB.T6G(SCH_1):M_C_CPU0_SA_DQ(16)   I350 @T6G_MB_LIB.T6G(SCH_1):PAGE87
    31 M_C_CPU0_SA_DQ<17> @T6G_MB_LIB.T6G(SCH_1):M_C_CPU0_SA_DQ(17)   I350 @T6G_MB_LIB.T6G(SCH_1):PAGE87
   174 M_C_CPU0_SA_DQ<18> @T6G_MB_LIB.T6G(SCH_1):M_C_CPU0_SA_DQ(18)   I350 @T6G_MB_LIB.T6G(SCH_1):PAGE87
   176 M_C_CPU0_SA_DQ<19> @T6G_MB_LIB.T6G(SCH_1):M_C_CPU0_SA_DQ(19)   I350 @T6G_MB_LIB.T6G(SCH_1):PAGE87
    36 M_C_CPU0_SA_DQ<20> @T6G_MB_LIB.T6G(SCH_1):M_C_CPU0_SA_DQ(20)   I350 @T6G_MB_LIB.T6G(SCH_1):PAGE87
    38 M_C_CPU0_SA_DQ<21> @T6G_MB_LIB.T6G(SCH_1):M_C_CPU0_SA_DQ(21)   I350 @T6G_MB_LIB.T6G(SCH_1):PAGE87
   181 M_C_CPU0_SA_DQ<22> @T6G_MB_LIB.T6G(SCH_1):M_C_CPU0_SA_DQ(22)   I350 @T6G_MB_LIB.T6G(SCH_1):PAGE87
   183 M_C_CPU0_SA_DQ<23> @T6G_MB_LIB.T6G(SCH_1):M_C_CPU0_SA_DQ(23)   I350 @T6G_MB_LIB.T6G(SCH_1):PAGE87
    40 M_C_CPU0_SA_DQ<24> @T6G_MB_LIB.T6G(SCH_1):M_C_CPU0_SA_DQ(24)   I350 @T6G_MB_LIB.T6G(SCH_1):PAGE87
    42 M_C_CPU0_SA_DQ<25> @T6G_MB_LIB.T6G(SCH_1):M_C_CPU0_SA_DQ(25)   I350 @T6G_MB_LIB.T6G(SCH_1):PAGE87
   185 M_C_CPU0_SA_DQ<26> @T6G_MB_LIB.T6G(SCH_1):M_C_CPU0_SA_DQ(26)   I350 @T6G_MB_LIB.T6G(SCH_1):PAGE87
   187 M_C_CPU0_SA_DQ<27> @T6G_MB_LIB.T6G(SCH_1):M_C_CPU0_SA_DQ(27)   I350 @T6G_MB_LIB.T6G(SCH_1):PAGE87
    47 M_C_CPU0_SA_DQ<28> @T6G_MB_LIB.T6G(SCH_1):M_C_CPU0_SA_DQ(28)   I350 @T6G_MB_LIB.T6G(SCH_1):PAGE87
    49 M_C_CPU0_SA_DQ<29> @T6G_MB_LIB.T6G(SCH_1):M_C_CPU0_SA_DQ(29)   I350 @T6G_MB_LIB.T6G(SCH_1):PAGE87
   192 M_C_CPU0_SA_DQ<30> @T6G_MB_LIB.T6G(SCH_1):M_C_CPU0_SA_DQ(30)   I350 @T6G_MB_LIB.T6G(SCH_1):PAGE87
   229 M_C_CPU0_SB_CS_N<1> @T6G_MB_LIB.T6G(SCH_1):M_C_CPU0_SB_CS_N(1)   I350 @T6G_MB_LIB.T6G(SCH_1):PAGE87
   209 M_C_CPU0_SA_CS_N<1> @T6G_MB_LIB.T6G(SCH_1):M_C_CPU0_SA_CS_N(1)   I350 @T6G_MB_LIB.T6G(SCH_1):PAGE87
    84 M_C_CPU0_SB_CS_N<0> @T6G_MB_LIB.T6G(SCH_1):M_C_CPU0_SB_CS_N(0)   I350 @T6G_MB_LIB.T6G(SCH_1):PAGE87
    64 M_C_CPU0_SA_CS_N<0> @T6G_MB_LIB.T6G(SCH_1):M_C_CPU0_SA_CS_N(0)   I350 @T6G_MB_LIB.T6G(SCH_1):PAGE87
   217 M_C_CPU0_CLK_DP<0> @T6G_MB_LIB.T6G(SCH_1):M_C_CPU0_CLK_DP(0)   I350 @T6G_MB_LIB.T6G(SCH_1):PAGE87
   218 M_C_CPU0_CLK_DN<0> @T6G_MB_LIB.T6G(SCH_1):M_C_CPU0_CLK_DN(0)   I350 @T6G_MB_LIB.T6G(SCH_1):PAGE87
    96 M_C_CPU0_SB_CB<0> @T6G_MB_LIB.T6G(SCH_1):M_C_CPU0_SB_CB(0)   I350 @T6G_MB_LIB.T6G(SCH_1):PAGE87
    98 M_C_CPU0_SB_CB<1> @T6G_MB_LIB.T6G(SCH_1):M_C_CPU0_SB_CB(1)   I350 @T6G_MB_LIB.T6G(SCH_1):PAGE87
   241 M_C_CPU0_SB_CB<2> @T6G_MB_LIB.T6G(SCH_1):M_C_CPU0_SB_CB(2)   I350 @T6G_MB_LIB.T6G(SCH_1):PAGE87
   243 M_C_CPU0_SB_CB<3> @T6G_MB_LIB.T6G(SCH_1):M_C_CPU0_SB_CB(3)   I350 @T6G_MB_LIB.T6G(SCH_1):PAGE87
    89 M_C_CPU0_SB_CB<4> @T6G_MB_LIB.T6G(SCH_1):M_C_CPU0_SB_CB(4)   I350 @T6G_MB_LIB.T6G(SCH_1):PAGE87
    91 M_C_CPU0_SB_CB<5> @T6G_MB_LIB.T6G(SCH_1):M_C_CPU0_SB_CB(5)   I350 @T6G_MB_LIB.T6G(SCH_1):PAGE87
   234 M_C_CPU0_SB_CB<6> @T6G_MB_LIB.T6G(SCH_1):M_C_CPU0_SB_CB(6)   I350 @T6G_MB_LIB.T6G(SCH_1):PAGE87
    51 M_C_CPU0_SA_CB<0> @T6G_MB_LIB.T6G(SCH_1):M_C_CPU0_SA_CB(0)   I350 @T6G_MB_LIB.T6G(SCH_1):PAGE87
   196 M_C_CPU0_SA_CB<2> @T6G_MB_LIB.T6G(SCH_1):M_C_CPU0_SA_CB(2)   I350 @T6G_MB_LIB.T6G(SCH_1):PAGE87
   198 M_C_CPU0_SA_CB<3> @T6G_MB_LIB.T6G(SCH_1):M_C_CPU0_SA_CB(3)   I350 @T6G_MB_LIB.T6G(SCH_1):PAGE87
    60 M_C_CPU0_SA_CB<5> @T6G_MB_LIB.T6G(SCH_1):M_C_CPU0_SA_CB(5)   I350 @T6G_MB_LIB.T6G(SCH_1):PAGE87
   203 M_C_CPU0_SA_CB<6> @T6G_MB_LIB.T6G(SCH_1):M_C_CPU0_SA_CB(6)   I350 @T6G_MB_LIB.T6G(SCH_1):PAGE87
    82 M_C_CPU0_SB_CA<6> @T6G_MB_LIB.T6G(SCH_1):M_C_CPU0_SB_CA(6)   I350 @T6G_MB_LIB.T6G(SCH_1):PAGE87
    72 M_C_CPU0_SA_CA<6> @T6G_MB_LIB.T6G(SCH_1):M_C_CPU0_SA_CA(6)   I350 @T6G_MB_LIB.T6G(SCH_1):PAGE87
   225 M_C_CPU0_SB_CA<5> @T6G_MB_LIB.T6G(SCH_1):M_C_CPU0_SB_CA(5)   I350 @T6G_MB_LIB.T6G(SCH_1):PAGE87
   215 M_C_CPU0_SA_CA<5> @T6G_MB_LIB.T6G(SCH_1):M_C_CPU0_SA_CA(5)   I350 @T6G_MB_LIB.T6G(SCH_1):PAGE87
    80 M_C_CPU0_SB_CA<4> @T6G_MB_LIB.T6G(SCH_1):M_C_CPU0_SB_CA(4)   I350 @T6G_MB_LIB.T6G(SCH_1):PAGE87
    70 M_C_CPU0_SA_CA<4> @T6G_MB_LIB.T6G(SCH_1):M_C_CPU0_SA_CA(4)   I350 @T6G_MB_LIB.T6G(SCH_1):PAGE87
   223 M_C_CPU0_SB_CA<3> @T6G_MB_LIB.T6G(SCH_1):M_C_CPU0_SB_CA(3)   I350 @T6G_MB_LIB.T6G(SCH_1):PAGE87
   213 M_C_CPU0_SA_CA<3> @T6G_MB_LIB.T6G(SCH_1):M_C_CPU0_SA_CA(3)   I350 @T6G_MB_LIB.T6G(SCH_1):PAGE87
    78 M_C_CPU0_SB_CA<2> @T6G_MB_LIB.T6G(SCH_1):M_C_CPU0_SB_CA(2)   I350 @T6G_MB_LIB.T6G(SCH_1):PAGE87
    68 M_C_CPU0_SA_CA<2> @T6G_MB_LIB.T6G(SCH_1):M_C_CPU0_SA_CA(2)   I350 @T6G_MB_LIB.T6G(SCH_1):PAGE87
   221 M_C_CPU0_SB_CA<1> @T6G_MB_LIB.T6G(SCH_1):M_C_CPU0_SB_CA(1)   I350 @T6G_MB_LIB.T6G(SCH_1):PAGE87
   211 M_C_CPU0_SA_CA<1> @T6G_MB_LIB.T6G(SCH_1):M_C_CPU0_SA_CA(1)   I350 @T6G_MB_LIB.T6G(SCH_1):PAGE87
    76 M_C_CPU0_SB_CA<0> @T6G_MB_LIB.T6G(SCH_1):M_C_CPU0_SB_CA(0)   I350 @T6G_MB_LIB.T6G(SCH_1):PAGE87
    66 M_C_CPU0_SA_CA<0> @T6G_MB_LIB.T6G(SCH_1):M_C_CPU0_SA_CA(0)   I350 @T6G_MB_LIB.T6G(SCH_1):PAGE87
    62 M_C_CPU0_ALERT_N @T6G_MB_LIB.T6G(SCH_1):M_C_CPU0_ALERT_N   I350 @T6G_MB_LIB.T6G(SCH_1):PAGE87
   236 M_C_CPU0_SB_CB<7> @T6G_MB_LIB.T6G(SCH_1):M_C_CPU0_SB_CB(7)   I350 @T6G_MB_LIB.T6G(SCH_1):PAGE87
    53 M_C_CPU0_SA_CB<1> @T6G_MB_LIB.T6G(SCH_1):M_C_CPU0_SA_CB(1)   I350 @T6G_MB_LIB.T6G(SCH_1):PAGE87
    58 M_C_CPU0_SA_CB<4> @T6G_MB_LIB.T6G(SCH_1):M_C_CPU0_SA_CB(4)   I350 @T6G_MB_LIB.T6G(SCH_1):PAGE87
   205 M_C_CPU0_SA_CB<7> @T6G_MB_LIB.T6G(SCH_1):M_C_CPU0_SA_CB(7)   I350 @T6G_MB_LIB.T6G(SCH_1):PAGE87
   194 M_C_CPU0_SA_DQ<31> @T6G_MB_LIB.T6G(SCH_1):M_C_CPU0_SA_DQ(31)   I350 @T6G_MB_LIB.T6G(SCH_1):PAGE87
    93 M_C_CPU0_SB_DQS_DP<9> @T6G_MB_LIB.T6G(SCH_1):M_C_CPU0_SB_DQS_DP(9)   I411 @T6G_MB_LIB.T6G(SCH_1):PAGE87
    94 M_C_CPU0_SB_DQS_DN<9> @T6G_MB_LIB.T6G(SCH_1):M_C_CPU0_SB_DQS_DN(9)   I411 @T6G_MB_LIB.T6G(SCH_1):PAGE87
   201 M_C_CPU0_SA_DQS_DP<9> @T6G_MB_LIB.T6G(SCH_1):M_C_CPU0_SA_DQS_DP(9)   I411 @T6G_MB_LIB.T6G(SCH_1):PAGE87
   200 M_C_CPU0_SA_DQS_DN<9> @T6G_MB_LIB.T6G(SCH_1):M_C_CPU0_SA_DQS_DN(9)   I411 @T6G_MB_LIB.T6G(SCH_1):PAGE87
   190 M_C_CPU0_SA_DQS_DP<8> @T6G_MB_LIB.T6G(SCH_1):M_C_CPU0_SA_DQS_DP(8)   I411 @T6G_MB_LIB.T6G(SCH_1):PAGE87
   189 M_C_CPU0_SA_DQS_DN<8> @T6G_MB_LIB.T6G(SCH_1):M_C_CPU0_SA_DQS_DN(8)   I411 @T6G_MB_LIB.T6G(SCH_1):PAGE87
   271 M_C_CPU0_SB_DQS_DN<7> @T6G_MB_LIB.T6G(SCH_1):M_C_CPU0_SB_DQS_DN(7)   I411 @T6G_MB_LIB.T6G(SCH_1):PAGE87
   179 M_C_CPU0_SA_DQS_DP<7> @T6G_MB_LIB.T6G(SCH_1):M_C_CPU0_SA_DQS_DP(7)   I411 @T6G_MB_LIB.T6G(SCH_1):PAGE87
   261 M_C_CPU0_SB_DQS_DP<6> @T6G_MB_LIB.T6G(SCH_1):M_C_CPU0_SB_DQS_DP(6)   I411 @T6G_MB_LIB.T6G(SCH_1):PAGE87
   260 M_C_CPU0_SB_DQS_DN<6> @T6G_MB_LIB.T6G(SCH_1):M_C_CPU0_SB_DQS_DN(6)   I411 @T6G_MB_LIB.T6G(SCH_1):PAGE87
   167 M_C_CPU0_SA_DQS_DN<6> @T6G_MB_LIB.T6G(SCH_1):M_C_CPU0_SA_DQS_DN(6)   I411 @T6G_MB_LIB.T6G(SCH_1):PAGE87
   250 M_C_CPU0_SB_DQS_DP<5> @T6G_MB_LIB.T6G(SCH_1):M_C_CPU0_SB_DQS_DP(5)   I411 @T6G_MB_LIB.T6G(SCH_1):PAGE87
   249 M_C_CPU0_SB_DQS_DN<5> @T6G_MB_LIB.T6G(SCH_1):M_C_CPU0_SB_DQS_DN(5)   I411 @T6G_MB_LIB.T6G(SCH_1):PAGE87
   157 M_C_CPU0_SA_DQS_DP<5> @T6G_MB_LIB.T6G(SCH_1):M_C_CPU0_SA_DQS_DP(5)   I411 @T6G_MB_LIB.T6G(SCH_1):PAGE87
   156 M_C_CPU0_SA_DQS_DN<5> @T6G_MB_LIB.T6G(SCH_1):M_C_CPU0_SA_DQS_DN(5)   I411 @T6G_MB_LIB.T6G(SCH_1):PAGE87
   239 M_C_CPU0_SB_DQS_DP<4> @T6G_MB_LIB.T6G(SCH_1):M_C_CPU0_SB_DQS_DP(4)   I411 @T6G_MB_LIB.T6G(SCH_1):PAGE87
   238 M_C_CPU0_SB_DQS_DN<4> @T6G_MB_LIB.T6G(SCH_1):M_C_CPU0_SB_DQS_DN(4)   I411 @T6G_MB_LIB.T6G(SCH_1):PAGE87
    55 M_C_CPU0_SA_DQS_DP<4> @T6G_MB_LIB.T6G(SCH_1):M_C_CPU0_SA_DQS_DP(4)   I411 @T6G_MB_LIB.T6G(SCH_1):PAGE87
    56 M_C_CPU0_SA_DQS_DN<4> @T6G_MB_LIB.T6G(SCH_1):M_C_CPU0_SA_DQS_DN(4)   I411 @T6G_MB_LIB.T6G(SCH_1):PAGE87
   137 M_C_CPU0_SB_DQS_DP<3> @T6G_MB_LIB.T6G(SCH_1):M_C_CPU0_SB_DQS_DP(3)   I411 @T6G_MB_LIB.T6G(SCH_1):PAGE87
   138 M_C_CPU0_SB_DQS_DN<3> @T6G_MB_LIB.T6G(SCH_1):M_C_CPU0_SB_DQS_DN(3)   I411 @T6G_MB_LIB.T6G(SCH_1):PAGE87
    44 M_C_CPU0_SA_DQS_DP<3> @T6G_MB_LIB.T6G(SCH_1):M_C_CPU0_SA_DQS_DP(3)   I411 @T6G_MB_LIB.T6G(SCH_1):PAGE87
    45 M_C_CPU0_SA_DQS_DN<3> @T6G_MB_LIB.T6G(SCH_1):M_C_CPU0_SA_DQS_DN(3)   I411 @T6G_MB_LIB.T6G(SCH_1):PAGE87
   126 M_C_CPU0_SB_DQS_DP<2> @T6G_MB_LIB.T6G(SCH_1):M_C_CPU0_SB_DQS_DP(2)   I411 @T6G_MB_LIB.T6G(SCH_1):PAGE87
   127 M_C_CPU0_SB_DQS_DN<2> @T6G_MB_LIB.T6G(SCH_1):M_C_CPU0_SB_DQS_DN(2)   I411 @T6G_MB_LIB.T6G(SCH_1):PAGE87
    33 M_C_CPU0_SA_DQS_DP<2> @T6G_MB_LIB.T6G(SCH_1):M_C_CPU0_SA_DQS_DP(2)   I411 @T6G_MB_LIB.T6G(SCH_1):PAGE87
    34 M_C_CPU0_SA_DQS_DN<2> @T6G_MB_LIB.T6G(SCH_1):M_C_CPU0_SA_DQS_DN(2)   I411 @T6G_MB_LIB.T6G(SCH_1):PAGE87
   115 M_C_CPU0_SB_DQS_DP<1> @T6G_MB_LIB.T6G(SCH_1):M_C_CPU0_SB_DQS_DP(1)   I411 @T6G_MB_LIB.T6G(SCH_1):PAGE87
   116 M_C_CPU0_SB_DQS_DN<1> @T6G_MB_LIB.T6G(SCH_1):M_C_CPU0_SB_DQS_DN(1)   I411 @T6G_MB_LIB.T6G(SCH_1):PAGE87
    22 M_C_CPU0_SA_DQS_DP<1> @T6G_MB_LIB.T6G(SCH_1):M_C_CPU0_SA_DQS_DP(1)   I411 @T6G_MB_LIB.T6G(SCH_1):PAGE87
    23 M_C_CPU0_SA_DQS_DN<1> @T6G_MB_LIB.T6G(SCH_1):M_C_CPU0_SA_DQS_DN(1)   I411 @T6G_MB_LIB.T6G(SCH_1):PAGE87
   104 M_C_CPU0_SB_DQS_DP<0> @T6G_MB_LIB.T6G(SCH_1):M_C_CPU0_SB_DQS_DP(0)   I411 @T6G_MB_LIB.T6G(SCH_1):PAGE87
   105 M_C_CPU0_SB_DQS_DN<0> @T6G_MB_LIB.T6G(SCH_1):M_C_CPU0_SB_DQS_DN(0)   I411 @T6G_MB_LIB.T6G(SCH_1):PAGE87
    11 M_C_CPU0_SA_DQS_DP<0> @T6G_MB_LIB.T6G(SCH_1):M_C_CPU0_SA_DQS_DP(0)   I411 @T6G_MB_LIB.T6G(SCH_1):PAGE87
    12 M_C_CPU0_SA_DQS_DN<0> @T6G_MB_LIB.T6G(SCH_1):M_C_CPU0_SA_DQS_DN(0)   I411 @T6G_MB_LIB.T6G(SCH_1):PAGE87
   272 M_C_CPU0_SB_DQS_DP<7> @T6G_MB_LIB.T6G(SCH_1):M_C_CPU0_SB_DQS_DP(7)   I411 @T6G_MB_LIB.T6G(SCH_1):PAGE87
   282 M_C_CPU0_SB_DQS_DN<8> @T6G_MB_LIB.T6G(SCH_1):M_C_CPU0_SB_DQS_DN(8)   I411 @T6G_MB_LIB.T6G(SCH_1):PAGE87
   283 M_C_CPU0_SB_DQS_DP<8> @T6G_MB_LIB.T6G(SCH_1):M_C_CPU0_SB_DQS_DP(8)   I411 @T6G_MB_LIB.T6G(SCH_1):PAGE87
   168 M_C_CPU0_SA_DQS_DP<6> @T6G_MB_LIB.T6G(SCH_1):M_C_CPU0_SA_DQS_DP(6)   I411 @T6G_MB_LIB.T6G(SCH_1):PAGE87
   178 M_C_CPU0_SA_DQS_DN<7> @T6G_MB_LIB.T6G(SCH_1):M_C_CPU0_SA_DQS_DN(7)   I411 @T6G_MB_LIB.T6G(SCH_1):PAGE87
     6    GND @T6G_MB_LIB.T6G(SCH_1):GND   I352 @T6G_MB_LIB.T6G(SCH_1):PAGE87
     8    GND @T6G_MB_LIB.T6G(SCH_1):GND   I352 @T6G_MB_LIB.T6G(SCH_1):PAGE87
    10    GND @T6G_MB_LIB.T6G(SCH_1):GND   I352 @T6G_MB_LIB.T6G(SCH_1):PAGE87
    13    GND @T6G_MB_LIB.T6G(SCH_1):GND   I352 @T6G_MB_LIB.T6G(SCH_1):PAGE87
    15    GND @T6G_MB_LIB.T6G(SCH_1):GND   I352 @T6G_MB_LIB.T6G(SCH_1):PAGE87
    17    GND @T6G_MB_LIB.T6G(SCH_1):GND   I352 @T6G_MB_LIB.T6G(SCH_1):PAGE87
    19    GND @T6G_MB_LIB.T6G(SCH_1):GND   I352 @T6G_MB_LIB.T6G(SCH_1):PAGE87
    21    GND @T6G_MB_LIB.T6G(SCH_1):GND   I352 @T6G_MB_LIB.T6G(SCH_1):PAGE87
    24    GND @T6G_MB_LIB.T6G(SCH_1):GND   I352 @T6G_MB_LIB.T6G(SCH_1):PAGE87
    26    GND @T6G_MB_LIB.T6G(SCH_1):GND   I352 @T6G_MB_LIB.T6G(SCH_1):PAGE87
    28    GND @T6G_MB_LIB.T6G(SCH_1):GND   I352 @T6G_MB_LIB.T6G(SCH_1):PAGE87
    30    GND @T6G_MB_LIB.T6G(SCH_1):GND   I352 @T6G_MB_LIB.T6G(SCH_1):PAGE87
    32    GND @T6G_MB_LIB.T6G(SCH_1):GND   I352 @T6G_MB_LIB.T6G(SCH_1):PAGE87
    35    GND @T6G_MB_LIB.T6G(SCH_1):GND   I352 @T6G_MB_LIB.T6G(SCH_1):PAGE87
    37    GND @T6G_MB_LIB.T6G(SCH_1):GND   I352 @T6G_MB_LIB.T6G(SCH_1):PAGE87
    39    GND @T6G_MB_LIB.T6G(SCH_1):GND   I352 @T6G_MB_LIB.T6G(SCH_1):PAGE87
    41    GND @T6G_MB_LIB.T6G(SCH_1):GND   I352 @T6G_MB_LIB.T6G(SCH_1):PAGE87
    43    GND @T6G_MB_LIB.T6G(SCH_1):GND   I352 @T6G_MB_LIB.T6G(SCH_1):PAGE87
    46    GND @T6G_MB_LIB.T6G(SCH_1):GND   I352 @T6G_MB_LIB.T6G(SCH_1):PAGE87
    48    GND @T6G_MB_LIB.T6G(SCH_1):GND   I352 @T6G_MB_LIB.T6G(SCH_1):PAGE87
    50    GND @T6G_MB_LIB.T6G(SCH_1):GND   I352 @T6G_MB_LIB.T6G(SCH_1):PAGE87
    52    GND @T6G_MB_LIB.T6G(SCH_1):GND   I352 @T6G_MB_LIB.T6G(SCH_1):PAGE87
    54    GND @T6G_MB_LIB.T6G(SCH_1):GND   I352 @T6G_MB_LIB.T6G(SCH_1):PAGE87
    57    GND @T6G_MB_LIB.T6G(SCH_1):GND   I352 @T6G_MB_LIB.T6G(SCH_1):PAGE87
    59    GND @T6G_MB_LIB.T6G(SCH_1):GND   I352 @T6G_MB_LIB.T6G(SCH_1):PAGE87
    61    GND @T6G_MB_LIB.T6G(SCH_1):GND   I352 @T6G_MB_LIB.T6G(SCH_1):PAGE87
    63    GND @T6G_MB_LIB.T6G(SCH_1):GND   I352 @T6G_MB_LIB.T6G(SCH_1):PAGE87
    65    GND @T6G_MB_LIB.T6G(SCH_1):GND   I352 @T6G_MB_LIB.T6G(SCH_1):PAGE87
    67    GND @T6G_MB_LIB.T6G(SCH_1):GND   I352 @T6G_MB_LIB.T6G(SCH_1):PAGE87
    69    GND @T6G_MB_LIB.T6G(SCH_1):GND   I352 @T6G_MB_LIB.T6G(SCH_1):PAGE87
    71    GND @T6G_MB_LIB.T6G(SCH_1):GND   I352 @T6G_MB_LIB.T6G(SCH_1):PAGE87
    73    GND @T6G_MB_LIB.T6G(SCH_1):GND   I352 @T6G_MB_LIB.T6G(SCH_1):PAGE87
    75    GND @T6G_MB_LIB.T6G(SCH_1):GND   I352 @T6G_MB_LIB.T6G(SCH_1):PAGE87
    77    GND @T6G_MB_LIB.T6G(SCH_1):GND   I352 @T6G_MB_LIB.T6G(SCH_1):PAGE87
    79    GND @T6G_MB_LIB.T6G(SCH_1):GND   I352 @T6G_MB_LIB.T6G(SCH_1):PAGE87
    81    GND @T6G_MB_LIB.T6G(SCH_1):GND   I352 @T6G_MB_LIB.T6G(SCH_1):PAGE87
    83    GND @T6G_MB_LIB.T6G(SCH_1):GND   I352 @T6G_MB_LIB.T6G(SCH_1):PAGE87
    85    GND @T6G_MB_LIB.T6G(SCH_1):GND   I352 @T6G_MB_LIB.T6G(SCH_1):PAGE87
    88    GND @T6G_MB_LIB.T6G(SCH_1):GND   I352 @T6G_MB_LIB.T6G(SCH_1):PAGE87
    90    GND @T6G_MB_LIB.T6G(SCH_1):GND   I352 @T6G_MB_LIB.T6G(SCH_1):PAGE87
    92    GND @T6G_MB_LIB.T6G(SCH_1):GND   I352 @T6G_MB_LIB.T6G(SCH_1):PAGE87
    95    GND @T6G_MB_LIB.T6G(SCH_1):GND   I352 @T6G_MB_LIB.T6G(SCH_1):PAGE87
    97    GND @T6G_MB_LIB.T6G(SCH_1):GND   I352 @T6G_MB_LIB.T6G(SCH_1):PAGE87
    99    GND @T6G_MB_LIB.T6G(SCH_1):GND   I352 @T6G_MB_LIB.T6G(SCH_1):PAGE87
   101    GND @T6G_MB_LIB.T6G(SCH_1):GND   I352 @T6G_MB_LIB.T6G(SCH_1):PAGE87
   103    GND @T6G_MB_LIB.T6G(SCH_1):GND   I352 @T6G_MB_LIB.T6G(SCH_1):PAGE87
   106    GND @T6G_MB_LIB.T6G(SCH_1):GND   I352 @T6G_MB_LIB.T6G(SCH_1):PAGE87
   108    GND @T6G_MB_LIB.T6G(SCH_1):GND   I352 @T6G_MB_LIB.T6G(SCH_1):PAGE87
   110    GND @T6G_MB_LIB.T6G(SCH_1):GND   I352 @T6G_MB_LIB.T6G(SCH_1):PAGE87
   112    GND @T6G_MB_LIB.T6G(SCH_1):GND   I352 @T6G_MB_LIB.T6G(SCH_1):PAGE87
   114    GND @T6G_MB_LIB.T6G(SCH_1):GND   I352 @T6G_MB_LIB.T6G(SCH_1):PAGE87
   117    GND @T6G_MB_LIB.T6G(SCH_1):GND   I352 @T6G_MB_LIB.T6G(SCH_1):PAGE87
   119    GND @T6G_MB_LIB.T6G(SCH_1):GND   I352 @T6G_MB_LIB.T6G(SCH_1):PAGE87
   121    GND @T6G_MB_LIB.T6G(SCH_1):GND   I352 @T6G_MB_LIB.T6G(SCH_1):PAGE87
   123    GND @T6G_MB_LIB.T6G(SCH_1):GND   I352 @T6G_MB_LIB.T6G(SCH_1):PAGE87
   125    GND @T6G_MB_LIB.T6G(SCH_1):GND   I352 @T6G_MB_LIB.T6G(SCH_1):PAGE87
   128    GND @T6G_MB_LIB.T6G(SCH_1):GND   I352 @T6G_MB_LIB.T6G(SCH_1):PAGE87
   130    GND @T6G_MB_LIB.T6G(SCH_1):GND   I352 @T6G_MB_LIB.T6G(SCH_1):PAGE87
   134    GND @T6G_MB_LIB.T6G(SCH_1):GND   I352 @T6G_MB_LIB.T6G(SCH_1):PAGE87
   143    GND @T6G_MB_LIB.T6G(SCH_1):GND   I352 @T6G_MB_LIB.T6G(SCH_1):PAGE87
   151    GND @T6G_MB_LIB.T6G(SCH_1):GND   I352 @T6G_MB_LIB.T6G(SCH_1):PAGE87
   153    GND @T6G_MB_LIB.T6G(SCH_1):GND   I352 @T6G_MB_LIB.T6G(SCH_1):PAGE87
   155    GND @T6G_MB_LIB.T6G(SCH_1):GND   I352 @T6G_MB_LIB.T6G(SCH_1):PAGE87
   158    GND @T6G_MB_LIB.T6G(SCH_1):GND   I352 @T6G_MB_LIB.T6G(SCH_1):PAGE87
   160    GND @T6G_MB_LIB.T6G(SCH_1):GND   I352 @T6G_MB_LIB.T6G(SCH_1):PAGE87
   162    GND @T6G_MB_LIB.T6G(SCH_1):GND   I352 @T6G_MB_LIB.T6G(SCH_1):PAGE87
   164    GND @T6G_MB_LIB.T6G(SCH_1):GND   I352 @T6G_MB_LIB.T6G(SCH_1):PAGE87
   166    GND @T6G_MB_LIB.T6G(SCH_1):GND   I352 @T6G_MB_LIB.T6G(SCH_1):PAGE87
   169    GND @T6G_MB_LIB.T6G(SCH_1):GND   I352 @T6G_MB_LIB.T6G(SCH_1):PAGE87
   171    GND @T6G_MB_LIB.T6G(SCH_1):GND   I352 @T6G_MB_LIB.T6G(SCH_1):PAGE87
   173    GND @T6G_MB_LIB.T6G(SCH_1):GND   I352 @T6G_MB_LIB.T6G(SCH_1):PAGE87
   175    GND @T6G_MB_LIB.T6G(SCH_1):GND   I352 @T6G_MB_LIB.T6G(SCH_1):PAGE87
   177    GND @T6G_MB_LIB.T6G(SCH_1):GND   I352 @T6G_MB_LIB.T6G(SCH_1):PAGE87
   180    GND @T6G_MB_LIB.T6G(SCH_1):GND   I352 @T6G_MB_LIB.T6G(SCH_1):PAGE87
   182    GND @T6G_MB_LIB.T6G(SCH_1):GND   I352 @T6G_MB_LIB.T6G(SCH_1):PAGE87
   184    GND @T6G_MB_LIB.T6G(SCH_1):GND   I352 @T6G_MB_LIB.T6G(SCH_1):PAGE87
   186    GND @T6G_MB_LIB.T6G(SCH_1):GND   I352 @T6G_MB_LIB.T6G(SCH_1):PAGE87
   188    GND @T6G_MB_LIB.T6G(SCH_1):GND   I352 @T6G_MB_LIB.T6G(SCH_1):PAGE87
   191    GND @T6G_MB_LIB.T6G(SCH_1):GND   I352 @T6G_MB_LIB.T6G(SCH_1):PAGE87
   193    GND @T6G_MB_LIB.T6G(SCH_1):GND   I352 @T6G_MB_LIB.T6G(SCH_1):PAGE87
   195    GND @T6G_MB_LIB.T6G(SCH_1):GND   I352 @T6G_MB_LIB.T6G(SCH_1):PAGE87
   197    GND @T6G_MB_LIB.T6G(SCH_1):GND   I352 @T6G_MB_LIB.T6G(SCH_1):PAGE87
   199    GND @T6G_MB_LIB.T6G(SCH_1):GND   I352 @T6G_MB_LIB.T6G(SCH_1):PAGE87
   202    GND @T6G_MB_LIB.T6G(SCH_1):GND   I352 @T6G_MB_LIB.T6G(SCH_1):PAGE87
   204    GND @T6G_MB_LIB.T6G(SCH_1):GND   I352 @T6G_MB_LIB.T6G(SCH_1):PAGE87
   206    GND @T6G_MB_LIB.T6G(SCH_1):GND   I352 @T6G_MB_LIB.T6G(SCH_1):PAGE87
   208    GND @T6G_MB_LIB.T6G(SCH_1):GND   I352 @T6G_MB_LIB.T6G(SCH_1):PAGE87
   210    GND @T6G_MB_LIB.T6G(SCH_1):GND   I352 @T6G_MB_LIB.T6G(SCH_1):PAGE87
   212    GND @T6G_MB_LIB.T6G(SCH_1):GND   I352 @T6G_MB_LIB.T6G(SCH_1):PAGE87
   214    GND @T6G_MB_LIB.T6G(SCH_1):GND   I352 @T6G_MB_LIB.T6G(SCH_1):PAGE87
   216    GND @T6G_MB_LIB.T6G(SCH_1):GND   I352 @T6G_MB_LIB.T6G(SCH_1):PAGE87
   219    GND @T6G_MB_LIB.T6G(SCH_1):GND   I352 @T6G_MB_LIB.T6G(SCH_1):PAGE87
   222    GND @T6G_MB_LIB.T6G(SCH_1):GND   I352 @T6G_MB_LIB.T6G(SCH_1):PAGE87
   224    GND @T6G_MB_LIB.T6G(SCH_1):GND   I352 @T6G_MB_LIB.T6G(SCH_1):PAGE87
   226    GND @T6G_MB_LIB.T6G(SCH_1):GND   I352 @T6G_MB_LIB.T6G(SCH_1):PAGE87
   228    GND @T6G_MB_LIB.T6G(SCH_1):GND   I352 @T6G_MB_LIB.T6G(SCH_1):PAGE87
   233    GND @T6G_MB_LIB.T6G(SCH_1):GND   I352 @T6G_MB_LIB.T6G(SCH_1):PAGE87
   237    GND @T6G_MB_LIB.T6G(SCH_1):GND   I352 @T6G_MB_LIB.T6G(SCH_1):PAGE87
   242    GND @T6G_MB_LIB.T6G(SCH_1):GND   I352 @T6G_MB_LIB.T6G(SCH_1):PAGE87
   244    GND @T6G_MB_LIB.T6G(SCH_1):GND   I352 @T6G_MB_LIB.T6G(SCH_1):PAGE87
   246    GND @T6G_MB_LIB.T6G(SCH_1):GND   I352 @T6G_MB_LIB.T6G(SCH_1):PAGE87
   248    GND @T6G_MB_LIB.T6G(SCH_1):GND   I352 @T6G_MB_LIB.T6G(SCH_1):PAGE87
   251    GND @T6G_MB_LIB.T6G(SCH_1):GND   I352 @T6G_MB_LIB.T6G(SCH_1):PAGE87
   253    GND @T6G_MB_LIB.T6G(SCH_1):GND   I352 @T6G_MB_LIB.T6G(SCH_1):PAGE87
   255    GND @T6G_MB_LIB.T6G(SCH_1):GND   I352 @T6G_MB_LIB.T6G(SCH_1):PAGE87
   257    GND @T6G_MB_LIB.T6G(SCH_1):GND   I352 @T6G_MB_LIB.T6G(SCH_1):PAGE87
   259    GND @T6G_MB_LIB.T6G(SCH_1):GND   I352 @T6G_MB_LIB.T6G(SCH_1):PAGE87
   262    GND @T6G_MB_LIB.T6G(SCH_1):GND   I352 @T6G_MB_LIB.T6G(SCH_1):PAGE87
   264    GND @T6G_MB_LIB.T6G(SCH_1):GND   I352 @T6G_MB_LIB.T6G(SCH_1):PAGE87
   266    GND @T6G_MB_LIB.T6G(SCH_1):GND   I352 @T6G_MB_LIB.T6G(SCH_1):PAGE87
   268    GND @T6G_MB_LIB.T6G(SCH_1):GND   I352 @T6G_MB_LIB.T6G(SCH_1):PAGE87
   270    GND @T6G_MB_LIB.T6G(SCH_1):GND   I352 @T6G_MB_LIB.T6G(SCH_1):PAGE87
   273    GND @T6G_MB_LIB.T6G(SCH_1):GND   I352 @T6G_MB_LIB.T6G(SCH_1):PAGE87
   275    GND @T6G_MB_LIB.T6G(SCH_1):GND   I352 @T6G_MB_LIB.T6G(SCH_1):PAGE87
   277    GND @T6G_MB_LIB.T6G(SCH_1):GND   I352 @T6G_MB_LIB.T6G(SCH_1):PAGE87
   279    GND @T6G_MB_LIB.T6G(SCH_1):GND   I352 @T6G_MB_LIB.T6G(SCH_1):PAGE87
   281    GND @T6G_MB_LIB.T6G(SCH_1):GND   I352 @T6G_MB_LIB.T6G(SCH_1):PAGE87
   284    GND @T6G_MB_LIB.T6G(SCH_1):GND   I352 @T6G_MB_LIB.T6G(SCH_1):PAGE87
   286    GND @T6G_MB_LIB.T6G(SCH_1):GND   I352 @T6G_MB_LIB.T6G(SCH_1):PAGE87
   288    GND @T6G_MB_LIB.T6G(SCH_1):GND   I352 @T6G_MB_LIB.T6G(SCH_1):PAGE87
     1 P12V_MEM_CPU0 @T6G_MB_LIB.T6G(SCH_1):P12V_MEM_CPU0   I352 @T6G_MB_LIB.T6G(SCH_1):PAGE87
   145 P12V_MEM_CPU0 @T6G_MB_LIB.T6G(SCH_1):P12V_MEM_CPU0   I352 @T6G_MB_LIB.T6G(SCH_1):PAGE87
   146 P12V_MEM_CPU0 @T6G_MB_LIB.T6G(SCH_1):P12V_MEM_CPU0   I352 @T6G_MB_LIB.T6G(SCH_1):PAGE87
   230    GND @T6G_MB_LIB.T6G(SCH_1):GND   I352 @T6G_MB_LIB.T6G(SCH_1):PAGE87
   235    GND @T6G_MB_LIB.T6G(SCH_1):GND   I352 @T6G_MB_LIB.T6G(SCH_1):PAGE87
   240    GND @T6G_MB_LIB.T6G(SCH_1):GND   I352 @T6G_MB_LIB.T6G(SCH_1):PAGE87
   132    GND @T6G_MB_LIB.T6G(SCH_1):GND   I352 @T6G_MB_LIB.T6G(SCH_1):PAGE87
   136    GND @T6G_MB_LIB.T6G(SCH_1):GND   I352 @T6G_MB_LIB.T6G(SCH_1):PAGE87
   139    GND @T6G_MB_LIB.T6G(SCH_1):GND   I352 @T6G_MB_LIB.T6G(SCH_1):PAGE87
   141    GND @T6G_MB_LIB.T6G(SCH_1):GND   I352 @T6G_MB_LIB.T6G(SCH_1):PAGE87
    G1    GND @T6G_MB_LIB.T6G(SCH_1):GND   I352 @T6G_MB_LIB.T6G(SCH_1):PAGE87
    G2    GND @T6G_MB_LIB.T6G(SCH_1):GND   I352 @T6G_MB_LIB.T6G(SCH_1):PAGE87
    G3    GND @T6G_MB_LIB.T6G(SCH_1):GND   I352 @T6G_MB_LIB.T6G(SCH_1):PAGE87

 J18 SCONN288_DDR506112002KQ-SCONN288_DDR506112002KQ,SMA
     3 P3V3_AUX @T6G_MB_LIB.T6G(SCH_1):P3V3_AUX    I22 @T6G_MB_LIB.T6G(SCH_1):PAGE93
     2     NC     NC    I22 @T6G_MB_LIB.T6G(SCH_1):PAGE93
   144     NC     NC    I22 @T6G_MB_LIB.T6G(SCH_1):PAGE93
   149     NC     NC    I22 @T6G_MB_LIB.T6G(SCH_1):PAGE93
   150     NC     NC    I22 @T6G_MB_LIB.T6G(SCH_1):PAGE93
   220     NC     NC    I22 @T6G_MB_LIB.T6G(SCH_1):PAGE93
   231     NC     NC    I22 @T6G_MB_LIB.T6G(SCH_1):PAGE93
   232     NC     NC    I22 @T6G_MB_LIB.T6G(SCH_1):PAGE93
   207 M_I_CPU0_RESET_N @T6G_MB_LIB.T6G(SCH_1):M_I_CPU0_RESET_N    I22 @T6G_MB_LIB.T6G(SCH_1):PAGE93
   147 PWRGD_CHI_CPU0_DIMM @T6G_MB_LIB.T6G(SCH_1):PWRGD_CHI_CPU0_DIMM    I22 @T6G_MB_LIB.T6G(SCH_1):PAGE93
   227 M_I_CPU0_SB_PAR @T6G_MB_LIB.T6G(SCH_1):M_I_CPU0_SB_PAR    I22 @T6G_MB_LIB.T6G(SCH_1):PAGE93
    74 M_I_CPU0_SA_PAR @T6G_MB_LIB.T6G(SCH_1):M_I_CPU0_SA_PAR    I22 @T6G_MB_LIB.T6G(SCH_1):PAGE93
    87 M_I_CPU0_SB_RSP<0> @T6G_MB_LIB.T6G(SCH_1):M_I_CPU0_SB_RSP(0)    I22 @T6G_MB_LIB.T6G(SCH_1):PAGE93
    86 M_I_CPU0_SA_RSP<0> @T6G_MB_LIB.T6G(SCH_1):M_I_CPU0_SA_RSP(0)    I22 @T6G_MB_LIB.T6G(SCH_1):PAGE93
     5 I3C_SPD_DDRI_CPU0_SDA @T6G_MB_LIB.T6G(SCH_1):I3C_SPD_DDRI_CPU0_SDA    I22 @T6G_MB_LIB.T6G(SCH_1):PAGE93
     4 I3C_SPD_DDRI_CPU0_SCL @T6G_MB_LIB.T6G(SCH_1):I3C_SPD_DDRI_CPU0_SCL    I22 @T6G_MB_LIB.T6G(SCH_1):PAGE93
   148 PD_CHI_CPU0_DIMM_SAA @T6G_MB_LIB.T6G(SCH_1):PD_CHI_CPU0_DIMM_SAA    I22 @T6G_MB_LIB.T6G(SCH_1):PAGE93
   100 M_I_CPU0_SB_DQ<0> @T6G_MB_LIB.T6G(SCH_1):M_I_CPU0_SB_DQ(0)    I22 @T6G_MB_LIB.T6G(SCH_1):PAGE93
   102 M_I_CPU0_SB_DQ<1> @T6G_MB_LIB.T6G(SCH_1):M_I_CPU0_SB_DQ(1)    I22 @T6G_MB_LIB.T6G(SCH_1):PAGE93
   245 M_I_CPU0_SB_DQ<2> @T6G_MB_LIB.T6G(SCH_1):M_I_CPU0_SB_DQ(2)    I22 @T6G_MB_LIB.T6G(SCH_1):PAGE93
   247 M_I_CPU0_SB_DQ<3> @T6G_MB_LIB.T6G(SCH_1):M_I_CPU0_SB_DQ(3)    I22 @T6G_MB_LIB.T6G(SCH_1):PAGE93
   107 M_I_CPU0_SB_DQ<4> @T6G_MB_LIB.T6G(SCH_1):M_I_CPU0_SB_DQ(4)    I22 @T6G_MB_LIB.T6G(SCH_1):PAGE93
   109 M_I_CPU0_SB_DQ<5> @T6G_MB_LIB.T6G(SCH_1):M_I_CPU0_SB_DQ(5)    I22 @T6G_MB_LIB.T6G(SCH_1):PAGE93
   252 M_I_CPU0_SB_DQ<6> @T6G_MB_LIB.T6G(SCH_1):M_I_CPU0_SB_DQ(6)    I22 @T6G_MB_LIB.T6G(SCH_1):PAGE93
   254 M_I_CPU0_SB_DQ<7> @T6G_MB_LIB.T6G(SCH_1):M_I_CPU0_SB_DQ(7)    I22 @T6G_MB_LIB.T6G(SCH_1):PAGE93
   111 M_I_CPU0_SB_DQ<8> @T6G_MB_LIB.T6G(SCH_1):M_I_CPU0_SB_DQ(8)    I22 @T6G_MB_LIB.T6G(SCH_1):PAGE93
   113 M_I_CPU0_SB_DQ<9> @T6G_MB_LIB.T6G(SCH_1):M_I_CPU0_SB_DQ(9)    I22 @T6G_MB_LIB.T6G(SCH_1):PAGE93
   256 M_I_CPU0_SB_DQ<10> @T6G_MB_LIB.T6G(SCH_1):M_I_CPU0_SB_DQ(10)    I22 @T6G_MB_LIB.T6G(SCH_1):PAGE93
   258 M_I_CPU0_SB_DQ<11> @T6G_MB_LIB.T6G(SCH_1):M_I_CPU0_SB_DQ(11)    I22 @T6G_MB_LIB.T6G(SCH_1):PAGE93
   118 M_I_CPU0_SB_DQ<12> @T6G_MB_LIB.T6G(SCH_1):M_I_CPU0_SB_DQ(12)    I22 @T6G_MB_LIB.T6G(SCH_1):PAGE93
   120 M_I_CPU0_SB_DQ<13> @T6G_MB_LIB.T6G(SCH_1):M_I_CPU0_SB_DQ(13)    I22 @T6G_MB_LIB.T6G(SCH_1):PAGE93
   263 M_I_CPU0_SB_DQ<14> @T6G_MB_LIB.T6G(SCH_1):M_I_CPU0_SB_DQ(14)    I22 @T6G_MB_LIB.T6G(SCH_1):PAGE93
   265 M_I_CPU0_SB_DQ<15> @T6G_MB_LIB.T6G(SCH_1):M_I_CPU0_SB_DQ(15)    I22 @T6G_MB_LIB.T6G(SCH_1):PAGE93
   122 M_I_CPU0_SB_DQ<16> @T6G_MB_LIB.T6G(SCH_1):M_I_CPU0_SB_DQ(16)    I22 @T6G_MB_LIB.T6G(SCH_1):PAGE93
   124 M_I_CPU0_SB_DQ<17> @T6G_MB_LIB.T6G(SCH_1):M_I_CPU0_SB_DQ(17)    I22 @T6G_MB_LIB.T6G(SCH_1):PAGE93
   267 M_I_CPU0_SB_DQ<18> @T6G_MB_LIB.T6G(SCH_1):M_I_CPU0_SB_DQ(18)    I22 @T6G_MB_LIB.T6G(SCH_1):PAGE93
   269 M_I_CPU0_SB_DQ<19> @T6G_MB_LIB.T6G(SCH_1):M_I_CPU0_SB_DQ(19)    I22 @T6G_MB_LIB.T6G(SCH_1):PAGE93
   129 M_I_CPU0_SB_DQ<20> @T6G_MB_LIB.T6G(SCH_1):M_I_CPU0_SB_DQ(20)    I22 @T6G_MB_LIB.T6G(SCH_1):PAGE93
   131 M_I_CPU0_SB_DQ<21> @T6G_MB_LIB.T6G(SCH_1):M_I_CPU0_SB_DQ(21)    I22 @T6G_MB_LIB.T6G(SCH_1):PAGE93
   274 M_I_CPU0_SB_DQ<22> @T6G_MB_LIB.T6G(SCH_1):M_I_CPU0_SB_DQ(22)    I22 @T6G_MB_LIB.T6G(SCH_1):PAGE93
   276 M_I_CPU0_SB_DQ<23> @T6G_MB_LIB.T6G(SCH_1):M_I_CPU0_SB_DQ(23)    I22 @T6G_MB_LIB.T6G(SCH_1):PAGE93
   133 M_I_CPU0_SB_DQ<24> @T6G_MB_LIB.T6G(SCH_1):M_I_CPU0_SB_DQ(24)    I22 @T6G_MB_LIB.T6G(SCH_1):PAGE93
   135 M_I_CPU0_SB_DQ<25> @T6G_MB_LIB.T6G(SCH_1):M_I_CPU0_SB_DQ(25)    I22 @T6G_MB_LIB.T6G(SCH_1):PAGE93
   278 M_I_CPU0_SB_DQ<26> @T6G_MB_LIB.T6G(SCH_1):M_I_CPU0_SB_DQ(26)    I22 @T6G_MB_LIB.T6G(SCH_1):PAGE93
   280 M_I_CPU0_SB_DQ<27> @T6G_MB_LIB.T6G(SCH_1):M_I_CPU0_SB_DQ(27)    I22 @T6G_MB_LIB.T6G(SCH_1):PAGE93
   140 M_I_CPU0_SB_DQ<28> @T6G_MB_LIB.T6G(SCH_1):M_I_CPU0_SB_DQ(28)    I22 @T6G_MB_LIB.T6G(SCH_1):PAGE93
   142 M_I_CPU0_SB_DQ<29> @T6G_MB_LIB.T6G(SCH_1):M_I_CPU0_SB_DQ(29)    I22 @T6G_MB_LIB.T6G(SCH_1):PAGE93
   285 M_I_CPU0_SB_DQ<30> @T6G_MB_LIB.T6G(SCH_1):M_I_CPU0_SB_DQ(30)    I22 @T6G_MB_LIB.T6G(SCH_1):PAGE93
   287 M_I_CPU0_SB_DQ<31> @T6G_MB_LIB.T6G(SCH_1):M_I_CPU0_SB_DQ(31)    I22 @T6G_MB_LIB.T6G(SCH_1):PAGE93
     7 M_I_CPU0_SA_DQ<0> @T6G_MB_LIB.T6G(SCH_1):M_I_CPU0_SA_DQ(0)    I22 @T6G_MB_LIB.T6G(SCH_1):PAGE93
     9 M_I_CPU0_SA_DQ<1> @T6G_MB_LIB.T6G(SCH_1):M_I_CPU0_SA_DQ(1)    I22 @T6G_MB_LIB.T6G(SCH_1):PAGE93
   152 M_I_CPU0_SA_DQ<2> @T6G_MB_LIB.T6G(SCH_1):M_I_CPU0_SA_DQ(2)    I22 @T6G_MB_LIB.T6G(SCH_1):PAGE93
   154 M_I_CPU0_SA_DQ<3> @T6G_MB_LIB.T6G(SCH_1):M_I_CPU0_SA_DQ(3)    I22 @T6G_MB_LIB.T6G(SCH_1):PAGE93
    14 M_I_CPU0_SA_DQ<4> @T6G_MB_LIB.T6G(SCH_1):M_I_CPU0_SA_DQ(4)    I22 @T6G_MB_LIB.T6G(SCH_1):PAGE93
    16 M_I_CPU0_SA_DQ<5> @T6G_MB_LIB.T6G(SCH_1):M_I_CPU0_SA_DQ(5)    I22 @T6G_MB_LIB.T6G(SCH_1):PAGE93
   159 M_I_CPU0_SA_DQ<6> @T6G_MB_LIB.T6G(SCH_1):M_I_CPU0_SA_DQ(6)    I22 @T6G_MB_LIB.T6G(SCH_1):PAGE93
   161 M_I_CPU0_SA_DQ<7> @T6G_MB_LIB.T6G(SCH_1):M_I_CPU0_SA_DQ(7)    I22 @T6G_MB_LIB.T6G(SCH_1):PAGE93
    18 M_I_CPU0_SA_DQ<8> @T6G_MB_LIB.T6G(SCH_1):M_I_CPU0_SA_DQ(8)    I22 @T6G_MB_LIB.T6G(SCH_1):PAGE93
    20 M_I_CPU0_SA_DQ<9> @T6G_MB_LIB.T6G(SCH_1):M_I_CPU0_SA_DQ(9)    I22 @T6G_MB_LIB.T6G(SCH_1):PAGE93
   163 M_I_CPU0_SA_DQ<10> @T6G_MB_LIB.T6G(SCH_1):M_I_CPU0_SA_DQ(10)    I22 @T6G_MB_LIB.T6G(SCH_1):PAGE93
   165 M_I_CPU0_SA_DQ<11> @T6G_MB_LIB.T6G(SCH_1):M_I_CPU0_SA_DQ(11)    I22 @T6G_MB_LIB.T6G(SCH_1):PAGE93
    25 M_I_CPU0_SA_DQ<12> @T6G_MB_LIB.T6G(SCH_1):M_I_CPU0_SA_DQ(12)    I22 @T6G_MB_LIB.T6G(SCH_1):PAGE93
    27 M_I_CPU0_SA_DQ<13> @T6G_MB_LIB.T6G(SCH_1):M_I_CPU0_SA_DQ(13)    I22 @T6G_MB_LIB.T6G(SCH_1):PAGE93
   170 M_I_CPU0_SA_DQ<14> @T6G_MB_LIB.T6G(SCH_1):M_I_CPU0_SA_DQ(14)    I22 @T6G_MB_LIB.T6G(SCH_1):PAGE93
   172 M_I_CPU0_SA_DQ<15> @T6G_MB_LIB.T6G(SCH_1):M_I_CPU0_SA_DQ(15)    I22 @T6G_MB_LIB.T6G(SCH_1):PAGE93
    29 M_I_CPU0_SA_DQ<16> @T6G_MB_LIB.T6G(SCH_1):M_I_CPU0_SA_DQ(16)    I22 @T6G_MB_LIB.T6G(SCH_1):PAGE93
    31 M_I_CPU0_SA_DQ<17> @T6G_MB_LIB.T6G(SCH_1):M_I_CPU0_SA_DQ(17)    I22 @T6G_MB_LIB.T6G(SCH_1):PAGE93
   174 M_I_CPU0_SA_DQ<18> @T6G_MB_LIB.T6G(SCH_1):M_I_CPU0_SA_DQ(18)    I22 @T6G_MB_LIB.T6G(SCH_1):PAGE93
   176 M_I_CPU0_SA_DQ<19> @T6G_MB_LIB.T6G(SCH_1):M_I_CPU0_SA_DQ(19)    I22 @T6G_MB_LIB.T6G(SCH_1):PAGE93
    36 M_I_CPU0_SA_DQ<20> @T6G_MB_LIB.T6G(SCH_1):M_I_CPU0_SA_DQ(20)    I22 @T6G_MB_LIB.T6G(SCH_1):PAGE93
    38 M_I_CPU0_SA_DQ<21> @T6G_MB_LIB.T6G(SCH_1):M_I_CPU0_SA_DQ(21)    I22 @T6G_MB_LIB.T6G(SCH_1):PAGE93
   181 M_I_CPU0_SA_DQ<22> @T6G_MB_LIB.T6G(SCH_1):M_I_CPU0_SA_DQ(22)    I22 @T6G_MB_LIB.T6G(SCH_1):PAGE93
   183 M_I_CPU0_SA_DQ<23> @T6G_MB_LIB.T6G(SCH_1):M_I_CPU0_SA_DQ(23)    I22 @T6G_MB_LIB.T6G(SCH_1):PAGE93
    40 M_I_CPU0_SA_DQ<24> @T6G_MB_LIB.T6G(SCH_1):M_I_CPU0_SA_DQ(24)    I22 @T6G_MB_LIB.T6G(SCH_1):PAGE93
    42 M_I_CPU0_SA_DQ<25> @T6G_MB_LIB.T6G(SCH_1):M_I_CPU0_SA_DQ(25)    I22 @T6G_MB_LIB.T6G(SCH_1):PAGE93
   185 M_I_CPU0_SA_DQ<26> @T6G_MB_LIB.T6G(SCH_1):M_I_CPU0_SA_DQ(26)    I22 @T6G_MB_LIB.T6G(SCH_1):PAGE93
   187 M_I_CPU0_SA_DQ<27> @T6G_MB_LIB.T6G(SCH_1):M_I_CPU0_SA_DQ(27)    I22 @T6G_MB_LIB.T6G(SCH_1):PAGE93
    47 M_I_CPU0_SA_DQ<28> @T6G_MB_LIB.T6G(SCH_1):M_I_CPU0_SA_DQ(28)    I22 @T6G_MB_LIB.T6G(SCH_1):PAGE93
    49 M_I_CPU0_SA_DQ<29> @T6G_MB_LIB.T6G(SCH_1):M_I_CPU0_SA_DQ(29)    I22 @T6G_MB_LIB.T6G(SCH_1):PAGE93
   192 M_I_CPU0_SA_DQ<30> @T6G_MB_LIB.T6G(SCH_1):M_I_CPU0_SA_DQ(30)    I22 @T6G_MB_LIB.T6G(SCH_1):PAGE93
   229 M_I_CPU0_SB_CS_N<1> @T6G_MB_LIB.T6G(SCH_1):M_I_CPU0_SB_CS_N(1)    I22 @T6G_MB_LIB.T6G(SCH_1):PAGE93
   209 M_I_CPU0_SA_CS_N<1> @T6G_MB_LIB.T6G(SCH_1):M_I_CPU0_SA_CS_N(1)    I22 @T6G_MB_LIB.T6G(SCH_1):PAGE93
    84 M_I_CPU0_SB_CS_N<0> @T6G_MB_LIB.T6G(SCH_1):M_I_CPU0_SB_CS_N(0)    I22 @T6G_MB_LIB.T6G(SCH_1):PAGE93
    64 M_I_CPU0_SA_CS_N<0> @T6G_MB_LIB.T6G(SCH_1):M_I_CPU0_SA_CS_N(0)    I22 @T6G_MB_LIB.T6G(SCH_1):PAGE93
   217 M_I_CPU0_CLK_DP<0> @T6G_MB_LIB.T6G(SCH_1):M_I_CPU0_CLK_DP(0)    I22 @T6G_MB_LIB.T6G(SCH_1):PAGE93
   218 M_I_CPU0_CLK_DN<0> @T6G_MB_LIB.T6G(SCH_1):M_I_CPU0_CLK_DN(0)    I22 @T6G_MB_LIB.T6G(SCH_1):PAGE93
    96 M_I_CPU0_SB_CB<0> @T6G_MB_LIB.T6G(SCH_1):M_I_CPU0_SB_CB(0)    I22 @T6G_MB_LIB.T6G(SCH_1):PAGE93
    98 M_I_CPU0_SB_CB<1> @T6G_MB_LIB.T6G(SCH_1):M_I_CPU0_SB_CB(1)    I22 @T6G_MB_LIB.T6G(SCH_1):PAGE93
   241 M_I_CPU0_SB_CB<2> @T6G_MB_LIB.T6G(SCH_1):M_I_CPU0_SB_CB(2)    I22 @T6G_MB_LIB.T6G(SCH_1):PAGE93
   243 M_I_CPU0_SB_CB<3> @T6G_MB_LIB.T6G(SCH_1):M_I_CPU0_SB_CB(3)    I22 @T6G_MB_LIB.T6G(SCH_1):PAGE93
    89 M_I_CPU0_SB_CB<4> @T6G_MB_LIB.T6G(SCH_1):M_I_CPU0_SB_CB(4)    I22 @T6G_MB_LIB.T6G(SCH_1):PAGE93
    91 M_I_CPU0_SB_CB<5> @T6G_MB_LIB.T6G(SCH_1):M_I_CPU0_SB_CB(5)    I22 @T6G_MB_LIB.T6G(SCH_1):PAGE93
   234 M_I_CPU0_SB_CB<6> @T6G_MB_LIB.T6G(SCH_1):M_I_CPU0_SB_CB(6)    I22 @T6G_MB_LIB.T6G(SCH_1):PAGE93
    51 M_I_CPU0_SA_CB<0> @T6G_MB_LIB.T6G(SCH_1):M_I_CPU0_SA_CB(0)    I22 @T6G_MB_LIB.T6G(SCH_1):PAGE93
   196 M_I_CPU0_SA_CB<2> @T6G_MB_LIB.T6G(SCH_1):M_I_CPU0_SA_CB(2)    I22 @T6G_MB_LIB.T6G(SCH_1):PAGE93
   198 M_I_CPU0_SA_CB<3> @T6G_MB_LIB.T6G(SCH_1):M_I_CPU0_SA_CB(3)    I22 @T6G_MB_LIB.T6G(SCH_1):PAGE93
    60 M_I_CPU0_SA_CB<5> @T6G_MB_LIB.T6G(SCH_1):M_I_CPU0_SA_CB(5)    I22 @T6G_MB_LIB.T6G(SCH_1):PAGE93
   203 M_I_CPU0_SA_CB<6> @T6G_MB_LIB.T6G(SCH_1):M_I_CPU0_SA_CB(6)    I22 @T6G_MB_LIB.T6G(SCH_1):PAGE93
    82 M_I_CPU0_SB_CA<6> @T6G_MB_LIB.T6G(SCH_1):M_I_CPU0_SB_CA(6)    I22 @T6G_MB_LIB.T6G(SCH_1):PAGE93
    72 M_I_CPU0_SA_CA<6> @T6G_MB_LIB.T6G(SCH_1):M_I_CPU0_SA_CA(6)    I22 @T6G_MB_LIB.T6G(SCH_1):PAGE93
   225 M_I_CPU0_SB_CA<5> @T6G_MB_LIB.T6G(SCH_1):M_I_CPU0_SB_CA(5)    I22 @T6G_MB_LIB.T6G(SCH_1):PAGE93
   215 M_I_CPU0_SA_CA<5> @T6G_MB_LIB.T6G(SCH_1):M_I_CPU0_SA_CA(5)    I22 @T6G_MB_LIB.T6G(SCH_1):PAGE93
    80 M_I_CPU0_SB_CA<4> @T6G_MB_LIB.T6G(SCH_1):M_I_CPU0_SB_CA(4)    I22 @T6G_MB_LIB.T6G(SCH_1):PAGE93
    70 M_I_CPU0_SA_CA<4> @T6G_MB_LIB.T6G(SCH_1):M_I_CPU0_SA_CA(4)    I22 @T6G_MB_LIB.T6G(SCH_1):PAGE93
   223 M_I_CPU0_SB_CA<3> @T6G_MB_LIB.T6G(SCH_1):M_I_CPU0_SB_CA(3)    I22 @T6G_MB_LIB.T6G(SCH_1):PAGE93
   213 M_I_CPU0_SA_CA<3> @T6G_MB_LIB.T6G(SCH_1):M_I_CPU0_SA_CA(3)    I22 @T6G_MB_LIB.T6G(SCH_1):PAGE93
    78 M_I_CPU0_SB_CA<2> @T6G_MB_LIB.T6G(SCH_1):M_I_CPU0_SB_CA(2)    I22 @T6G_MB_LIB.T6G(SCH_1):PAGE93
    68 M_I_CPU0_SA_CA<2> @T6G_MB_LIB.T6G(SCH_1):M_I_CPU0_SA_CA(2)    I22 @T6G_MB_LIB.T6G(SCH_1):PAGE93
   221 M_I_CPU0_SB_CA<1> @T6G_MB_LIB.T6G(SCH_1):M_I_CPU0_SB_CA(1)    I22 @T6G_MB_LIB.T6G(SCH_1):PAGE93
   211 M_I_CPU0_SA_CA<1> @T6G_MB_LIB.T6G(SCH_1):M_I_CPU0_SA_CA(1)    I22 @T6G_MB_LIB.T6G(SCH_1):PAGE93
    76 M_I_CPU0_SB_CA<0> @T6G_MB_LIB.T6G(SCH_1):M_I_CPU0_SB_CA(0)    I22 @T6G_MB_LIB.T6G(SCH_1):PAGE93
    66 M_I_CPU0_SA_CA<0> @T6G_MB_LIB.T6G(SCH_1):M_I_CPU0_SA_CA(0)    I22 @T6G_MB_LIB.T6G(SCH_1):PAGE93
    62 M_I_CPU0_ALERT_N @T6G_MB_LIB.T6G(SCH_1):M_I_CPU0_ALERT_N    I22 @T6G_MB_LIB.T6G(SCH_1):PAGE93
   236 M_I_CPU0_SB_CB<7> @T6G_MB_LIB.T6G(SCH_1):M_I_CPU0_SB_CB(7)    I22 @T6G_MB_LIB.T6G(SCH_1):PAGE93
    53 M_I_CPU0_SA_CB<1> @T6G_MB_LIB.T6G(SCH_1):M_I_CPU0_SA_CB(1)    I22 @T6G_MB_LIB.T6G(SCH_1):PAGE93
    58 M_I_CPU0_SA_CB<4> @T6G_MB_LIB.T6G(SCH_1):M_I_CPU0_SA_CB(4)    I22 @T6G_MB_LIB.T6G(SCH_1):PAGE93
   205 M_I_CPU0_SA_CB<7> @T6G_MB_LIB.T6G(SCH_1):M_I_CPU0_SA_CB(7)    I22 @T6G_MB_LIB.T6G(SCH_1):PAGE93
   194 M_I_CPU0_SA_DQ<31> @T6G_MB_LIB.T6G(SCH_1):M_I_CPU0_SA_DQ(31)    I22 @T6G_MB_LIB.T6G(SCH_1):PAGE93
    93 M_I_CPU0_SB_DQS_DP<9> @T6G_MB_LIB.T6G(SCH_1):M_I_CPU0_SB_DQS_DP(9)   I236 @T6G_MB_LIB.T6G(SCH_1):PAGE93
    94 M_I_CPU0_SB_DQS_DN<9> @T6G_MB_LIB.T6G(SCH_1):M_I_CPU0_SB_DQS_DN(9)   I236 @T6G_MB_LIB.T6G(SCH_1):PAGE93
   201 M_I_CPU0_SA_DQS_DP<9> @T6G_MB_LIB.T6G(SCH_1):M_I_CPU0_SA_DQS_DP(9)   I236 @T6G_MB_LIB.T6G(SCH_1):PAGE93
   200 M_I_CPU0_SA_DQS_DN<9> @T6G_MB_LIB.T6G(SCH_1):M_I_CPU0_SA_DQS_DN(9)   I236 @T6G_MB_LIB.T6G(SCH_1):PAGE93
   190 M_I_CPU0_SA_DQS_DP<8> @T6G_MB_LIB.T6G(SCH_1):M_I_CPU0_SA_DQS_DP(8)   I236 @T6G_MB_LIB.T6G(SCH_1):PAGE93
   189 M_I_CPU0_SA_DQS_DN<8> @T6G_MB_LIB.T6G(SCH_1):M_I_CPU0_SA_DQS_DN(8)   I236 @T6G_MB_LIB.T6G(SCH_1):PAGE93
   271 M_I_CPU0_SB_DQS_DN<7> @T6G_MB_LIB.T6G(SCH_1):M_I_CPU0_SB_DQS_DN(7)   I236 @T6G_MB_LIB.T6G(SCH_1):PAGE93
   179 M_I_CPU0_SA_DQS_DP<7> @T6G_MB_LIB.T6G(SCH_1):M_I_CPU0_SA_DQS_DP(7)   I236 @T6G_MB_LIB.T6G(SCH_1):PAGE93
   261 M_I_CPU0_SB_DQS_DP<6> @T6G_MB_LIB.T6G(SCH_1):M_I_CPU0_SB_DQS_DP(6)   I236 @T6G_MB_LIB.T6G(SCH_1):PAGE93
   260 M_I_CPU0_SB_DQS_DN<6> @T6G_MB_LIB.T6G(SCH_1):M_I_CPU0_SB_DQS_DN(6)   I236 @T6G_MB_LIB.T6G(SCH_1):PAGE93
   167 M_I_CPU0_SA_DQS_DN<6> @T6G_MB_LIB.T6G(SCH_1):M_I_CPU0_SA_DQS_DN(6)   I236 @T6G_MB_LIB.T6G(SCH_1):PAGE93
   250 M_I_CPU0_SB_DQS_DP<5> @T6G_MB_LIB.T6G(SCH_1):M_I_CPU0_SB_DQS_DP(5)   I236 @T6G_MB_LIB.T6G(SCH_1):PAGE93
   249 M_I_CPU0_SB_DQS_DN<5> @T6G_MB_LIB.T6G(SCH_1):M_I_CPU0_SB_DQS_DN(5)   I236 @T6G_MB_LIB.T6G(SCH_1):PAGE93
   157 M_I_CPU0_SA_DQS_DP<5> @T6G_MB_LIB.T6G(SCH_1):M_I_CPU0_SA_DQS_DP(5)   I236 @T6G_MB_LIB.T6G(SCH_1):PAGE93
   156 M_I_CPU0_SA_DQS_DN<5> @T6G_MB_LIB.T6G(SCH_1):M_I_CPU0_SA_DQS_DN(5)   I236 @T6G_MB_LIB.T6G(SCH_1):PAGE93
   239 M_I_CPU0_SB_DQS_DP<4> @T6G_MB_LIB.T6G(SCH_1):M_I_CPU0_SB_DQS_DP(4)   I236 @T6G_MB_LIB.T6G(SCH_1):PAGE93
   238 M_I_CPU0_SB_DQS_DN<4> @T6G_MB_LIB.T6G(SCH_1):M_I_CPU0_SB_DQS_DN(4)   I236 @T6G_MB_LIB.T6G(SCH_1):PAGE93
    55 M_I_CPU0_SA_DQS_DP<4> @T6G_MB_LIB.T6G(SCH_1):M_I_CPU0_SA_DQS_DP(4)   I236 @T6G_MB_LIB.T6G(SCH_1):PAGE93
    56 M_I_CPU0_SA_DQS_DN<4> @T6G_MB_LIB.T6G(SCH_1):M_I_CPU0_SA_DQS_DN(4)   I236 @T6G_MB_LIB.T6G(SCH_1):PAGE93
   137 M_I_CPU0_SB_DQS_DP<3> @T6G_MB_LIB.T6G(SCH_1):M_I_CPU0_SB_DQS_DP(3)   I236 @T6G_MB_LIB.T6G(SCH_1):PAGE93
   138 M_I_CPU0_SB_DQS_DN<3> @T6G_MB_LIB.T6G(SCH_1):M_I_CPU0_SB_DQS_DN(3)   I236 @T6G_MB_LIB.T6G(SCH_1):PAGE93
    44 M_I_CPU0_SA_DQS_DP<3> @T6G_MB_LIB.T6G(SCH_1):M_I_CPU0_SA_DQS_DP(3)   I236 @T6G_MB_LIB.T6G(SCH_1):PAGE93
    45 M_I_CPU0_SA_DQS_DN<3> @T6G_MB_LIB.T6G(SCH_1):M_I_CPU0_SA_DQS_DN(3)   I236 @T6G_MB_LIB.T6G(SCH_1):PAGE93
   126 M_I_CPU0_SB_DQS_DP<2> @T6G_MB_LIB.T6G(SCH_1):M_I_CPU0_SB_DQS_DP(2)   I236 @T6G_MB_LIB.T6G(SCH_1):PAGE93
   127 M_I_CPU0_SB_DQS_DN<2> @T6G_MB_LIB.T6G(SCH_1):M_I_CPU0_SB_DQS_DN(2)   I236 @T6G_MB_LIB.T6G(SCH_1):PAGE93
    33 M_I_CPU0_SA_DQS_DP<2> @T6G_MB_LIB.T6G(SCH_1):M_I_CPU0_SA_DQS_DP(2)   I236 @T6G_MB_LIB.T6G(SCH_1):PAGE93
    34 M_I_CPU0_SA_DQS_DN<2> @T6G_MB_LIB.T6G(SCH_1):M_I_CPU0_SA_DQS_DN(2)   I236 @T6G_MB_LIB.T6G(SCH_1):PAGE93
   115 M_I_CPU0_SB_DQS_DP<1> @T6G_MB_LIB.T6G(SCH_1):M_I_CPU0_SB_DQS_DP(1)   I236 @T6G_MB_LIB.T6G(SCH_1):PAGE93
   116 M_I_CPU0_SB_DQS_DN<1> @T6G_MB_LIB.T6G(SCH_1):M_I_CPU0_SB_DQS_DN(1)   I236 @T6G_MB_LIB.T6G(SCH_1):PAGE93
    22 M_I_CPU0_SA_DQS_DP<1> @T6G_MB_LIB.T6G(SCH_1):M_I_CPU0_SA_DQS_DP(1)   I236 @T6G_MB_LIB.T6G(SCH_1):PAGE93
    23 M_I_CPU0_SA_DQS_DN<1> @T6G_MB_LIB.T6G(SCH_1):M_I_CPU0_SA_DQS_DN(1)   I236 @T6G_MB_LIB.T6G(SCH_1):PAGE93
   104 M_I_CPU0_SB_DQS_DP<0> @T6G_MB_LIB.T6G(SCH_1):M_I_CPU0_SB_DQS_DP(0)   I236 @T6G_MB_LIB.T6G(SCH_1):PAGE93
   105 M_I_CPU0_SB_DQS_DN<0> @T6G_MB_LIB.T6G(SCH_1):M_I_CPU0_SB_DQS_DN(0)   I236 @T6G_MB_LIB.T6G(SCH_1):PAGE93
    11 M_I_CPU0_SA_DQS_DP<0> @T6G_MB_LIB.T6G(SCH_1):M_I_CPU0_SA_DQS_DP(0)   I236 @T6G_MB_LIB.T6G(SCH_1):PAGE93
    12 M_I_CPU0_SA_DQS_DN<0> @T6G_MB_LIB.T6G(SCH_1):M_I_CPU0_SA_DQS_DN(0)   I236 @T6G_MB_LIB.T6G(SCH_1):PAGE93
   272 M_I_CPU0_SB_DQS_DP<7> @T6G_MB_LIB.T6G(SCH_1):M_I_CPU0_SB_DQS_DP(7)   I236 @T6G_MB_LIB.T6G(SCH_1):PAGE93
   282 M_I_CPU0_SB_DQS_DN<8> @T6G_MB_LIB.T6G(SCH_1):M_I_CPU0_SB_DQS_DN(8)   I236 @T6G_MB_LIB.T6G(SCH_1):PAGE93
   283 M_I_CPU0_SB_DQS_DP<8> @T6G_MB_LIB.T6G(SCH_1):M_I_CPU0_SB_DQS_DP(8)   I236 @T6G_MB_LIB.T6G(SCH_1):PAGE93
   168 M_I_CPU0_SA_DQS_DP<6> @T6G_MB_LIB.T6G(SCH_1):M_I_CPU0_SA_DQS_DP(6)   I236 @T6G_MB_LIB.T6G(SCH_1):PAGE93
   178 M_I_CPU0_SA_DQS_DN<7> @T6G_MB_LIB.T6G(SCH_1):M_I_CPU0_SA_DQS_DN(7)   I236 @T6G_MB_LIB.T6G(SCH_1):PAGE93
     6    GND @T6G_MB_LIB.T6G(SCH_1):GND   I143 @T6G_MB_LIB.T6G(SCH_1):PAGE93
     8    GND @T6G_MB_LIB.T6G(SCH_1):GND   I143 @T6G_MB_LIB.T6G(SCH_1):PAGE93
    10    GND @T6G_MB_LIB.T6G(SCH_1):GND   I143 @T6G_MB_LIB.T6G(SCH_1):PAGE93
    13    GND @T6G_MB_LIB.T6G(SCH_1):GND   I143 @T6G_MB_LIB.T6G(SCH_1):PAGE93
    15    GND @T6G_MB_LIB.T6G(SCH_1):GND   I143 @T6G_MB_LIB.T6G(SCH_1):PAGE93
    17    GND @T6G_MB_LIB.T6G(SCH_1):GND   I143 @T6G_MB_LIB.T6G(SCH_1):PAGE93
    19    GND @T6G_MB_LIB.T6G(SCH_1):GND   I143 @T6G_MB_LIB.T6G(SCH_1):PAGE93
    21    GND @T6G_MB_LIB.T6G(SCH_1):GND   I143 @T6G_MB_LIB.T6G(SCH_1):PAGE93
    24    GND @T6G_MB_LIB.T6G(SCH_1):GND   I143 @T6G_MB_LIB.T6G(SCH_1):PAGE93
    26    GND @T6G_MB_LIB.T6G(SCH_1):GND   I143 @T6G_MB_LIB.T6G(SCH_1):PAGE93
    28    GND @T6G_MB_LIB.T6G(SCH_1):GND   I143 @T6G_MB_LIB.T6G(SCH_1):PAGE93
    30    GND @T6G_MB_LIB.T6G(SCH_1):GND   I143 @T6G_MB_LIB.T6G(SCH_1):PAGE93
    32    GND @T6G_MB_LIB.T6G(SCH_1):GND   I143 @T6G_MB_LIB.T6G(SCH_1):PAGE93
    35    GND @T6G_MB_LIB.T6G(SCH_1):GND   I143 @T6G_MB_LIB.T6G(SCH_1):PAGE93
    37    GND @T6G_MB_LIB.T6G(SCH_1):GND   I143 @T6G_MB_LIB.T6G(SCH_1):PAGE93
    39    GND @T6G_MB_LIB.T6G(SCH_1):GND   I143 @T6G_MB_LIB.T6G(SCH_1):PAGE93
    41    GND @T6G_MB_LIB.T6G(SCH_1):GND   I143 @T6G_MB_LIB.T6G(SCH_1):PAGE93
    43    GND @T6G_MB_LIB.T6G(SCH_1):GND   I143 @T6G_MB_LIB.T6G(SCH_1):PAGE93
    46    GND @T6G_MB_LIB.T6G(SCH_1):GND   I143 @T6G_MB_LIB.T6G(SCH_1):PAGE93
    48    GND @T6G_MB_LIB.T6G(SCH_1):GND   I143 @T6G_MB_LIB.T6G(SCH_1):PAGE93
    50    GND @T6G_MB_LIB.T6G(SCH_1):GND   I143 @T6G_MB_LIB.T6G(SCH_1):PAGE93
    52    GND @T6G_MB_LIB.T6G(SCH_1):GND   I143 @T6G_MB_LIB.T6G(SCH_1):PAGE93
    54    GND @T6G_MB_LIB.T6G(SCH_1):GND   I143 @T6G_MB_LIB.T6G(SCH_1):PAGE93
    57    GND @T6G_MB_LIB.T6G(SCH_1):GND   I143 @T6G_MB_LIB.T6G(SCH_1):PAGE93
    59    GND @T6G_MB_LIB.T6G(SCH_1):GND   I143 @T6G_MB_LIB.T6G(SCH_1):PAGE93
    61    GND @T6G_MB_LIB.T6G(SCH_1):GND   I143 @T6G_MB_LIB.T6G(SCH_1):PAGE93
    63    GND @T6G_MB_LIB.T6G(SCH_1):GND   I143 @T6G_MB_LIB.T6G(SCH_1):PAGE93
    65    GND @T6G_MB_LIB.T6G(SCH_1):GND   I143 @T6G_MB_LIB.T6G(SCH_1):PAGE93
    67    GND @T6G_MB_LIB.T6G(SCH_1):GND   I143 @T6G_MB_LIB.T6G(SCH_1):PAGE93
    69    GND @T6G_MB_LIB.T6G(SCH_1):GND   I143 @T6G_MB_LIB.T6G(SCH_1):PAGE93
    71    GND @T6G_MB_LIB.T6G(SCH_1):GND   I143 @T6G_MB_LIB.T6G(SCH_1):PAGE93
    73    GND @T6G_MB_LIB.T6G(SCH_1):GND   I143 @T6G_MB_LIB.T6G(SCH_1):PAGE93
    75    GND @T6G_MB_LIB.T6G(SCH_1):GND   I143 @T6G_MB_LIB.T6G(SCH_1):PAGE93
    77    GND @T6G_MB_LIB.T6G(SCH_1):GND   I143 @T6G_MB_LIB.T6G(SCH_1):PAGE93
    79    GND @T6G_MB_LIB.T6G(SCH_1):GND   I143 @T6G_MB_LIB.T6G(SCH_1):PAGE93
    81    GND @T6G_MB_LIB.T6G(SCH_1):GND   I143 @T6G_MB_LIB.T6G(SCH_1):PAGE93
    83    GND @T6G_MB_LIB.T6G(SCH_1):GND   I143 @T6G_MB_LIB.T6G(SCH_1):PAGE93
    85    GND @T6G_MB_LIB.T6G(SCH_1):GND   I143 @T6G_MB_LIB.T6G(SCH_1):PAGE93
    88    GND @T6G_MB_LIB.T6G(SCH_1):GND   I143 @T6G_MB_LIB.T6G(SCH_1):PAGE93
    90    GND @T6G_MB_LIB.T6G(SCH_1):GND   I143 @T6G_MB_LIB.T6G(SCH_1):PAGE93
    92    GND @T6G_MB_LIB.T6G(SCH_1):GND   I143 @T6G_MB_LIB.T6G(SCH_1):PAGE93
    95    GND @T6G_MB_LIB.T6G(SCH_1):GND   I143 @T6G_MB_LIB.T6G(SCH_1):PAGE93
    97    GND @T6G_MB_LIB.T6G(SCH_1):GND   I143 @T6G_MB_LIB.T6G(SCH_1):PAGE93
    99    GND @T6G_MB_LIB.T6G(SCH_1):GND   I143 @T6G_MB_LIB.T6G(SCH_1):PAGE93
   101    GND @T6G_MB_LIB.T6G(SCH_1):GND   I143 @T6G_MB_LIB.T6G(SCH_1):PAGE93
   103    GND @T6G_MB_LIB.T6G(SCH_1):GND   I143 @T6G_MB_LIB.T6G(SCH_1):PAGE93
   106    GND @T6G_MB_LIB.T6G(SCH_1):GND   I143 @T6G_MB_LIB.T6G(SCH_1):PAGE93
   108    GND @T6G_MB_LIB.T6G(SCH_1):GND   I143 @T6G_MB_LIB.T6G(SCH_1):PAGE93
   110    GND @T6G_MB_LIB.T6G(SCH_1):GND   I143 @T6G_MB_LIB.T6G(SCH_1):PAGE93
   112    GND @T6G_MB_LIB.T6G(SCH_1):GND   I143 @T6G_MB_LIB.T6G(SCH_1):PAGE93
   114    GND @T6G_MB_LIB.T6G(SCH_1):GND   I143 @T6G_MB_LIB.T6G(SCH_1):PAGE93
   117    GND @T6G_MB_LIB.T6G(SCH_1):GND   I143 @T6G_MB_LIB.T6G(SCH_1):PAGE93
   119    GND @T6G_MB_LIB.T6G(SCH_1):GND   I143 @T6G_MB_LIB.T6G(SCH_1):PAGE93
   121    GND @T6G_MB_LIB.T6G(SCH_1):GND   I143 @T6G_MB_LIB.T6G(SCH_1):PAGE93
   123    GND @T6G_MB_LIB.T6G(SCH_1):GND   I143 @T6G_MB_LIB.T6G(SCH_1):PAGE93
   125    GND @T6G_MB_LIB.T6G(SCH_1):GND   I143 @T6G_MB_LIB.T6G(SCH_1):PAGE93
   128    GND @T6G_MB_LIB.T6G(SCH_1):GND   I143 @T6G_MB_LIB.T6G(SCH_1):PAGE93
   130    GND @T6G_MB_LIB.T6G(SCH_1):GND   I143 @T6G_MB_LIB.T6G(SCH_1):PAGE93
   134    GND @T6G_MB_LIB.T6G(SCH_1):GND   I143 @T6G_MB_LIB.T6G(SCH_1):PAGE93
   143    GND @T6G_MB_LIB.T6G(SCH_1):GND   I143 @T6G_MB_LIB.T6G(SCH_1):PAGE93
   151    GND @T6G_MB_LIB.T6G(SCH_1):GND   I143 @T6G_MB_LIB.T6G(SCH_1):PAGE93
   153    GND @T6G_MB_LIB.T6G(SCH_1):GND   I143 @T6G_MB_LIB.T6G(SCH_1):PAGE93
   155    GND @T6G_MB_LIB.T6G(SCH_1):GND   I143 @T6G_MB_LIB.T6G(SCH_1):PAGE93
   158    GND @T6G_MB_LIB.T6G(SCH_1):GND   I143 @T6G_MB_LIB.T6G(SCH_1):PAGE93
   160    GND @T6G_MB_LIB.T6G(SCH_1):GND   I143 @T6G_MB_LIB.T6G(SCH_1):PAGE93
   162    GND @T6G_MB_LIB.T6G(SCH_1):GND   I143 @T6G_MB_LIB.T6G(SCH_1):PAGE93
   164    GND @T6G_MB_LIB.T6G(SCH_1):GND   I143 @T6G_MB_LIB.T6G(SCH_1):PAGE93
   166    GND @T6G_MB_LIB.T6G(SCH_1):GND   I143 @T6G_MB_LIB.T6G(SCH_1):PAGE93
   169    GND @T6G_MB_LIB.T6G(SCH_1):GND   I143 @T6G_MB_LIB.T6G(SCH_1):PAGE93
   171    GND @T6G_MB_LIB.T6G(SCH_1):GND   I143 @T6G_MB_LIB.T6G(SCH_1):PAGE93
   173    GND @T6G_MB_LIB.T6G(SCH_1):GND   I143 @T6G_MB_LIB.T6G(SCH_1):PAGE93
   175    GND @T6G_MB_LIB.T6G(SCH_1):GND   I143 @T6G_MB_LIB.T6G(SCH_1):PAGE93
   177    GND @T6G_MB_LIB.T6G(SCH_1):GND   I143 @T6G_MB_LIB.T6G(SCH_1):PAGE93
   180    GND @T6G_MB_LIB.T6G(SCH_1):GND   I143 @T6G_MB_LIB.T6G(SCH_1):PAGE93
   182    GND @T6G_MB_LIB.T6G(SCH_1):GND   I143 @T6G_MB_LIB.T6G(SCH_1):PAGE93
   184    GND @T6G_MB_LIB.T6G(SCH_1):GND   I143 @T6G_MB_LIB.T6G(SCH_1):PAGE93
   186    GND @T6G_MB_LIB.T6G(SCH_1):GND   I143 @T6G_MB_LIB.T6G(SCH_1):PAGE93
   188    GND @T6G_MB_LIB.T6G(SCH_1):GND   I143 @T6G_MB_LIB.T6G(SCH_1):PAGE93
   191    GND @T6G_MB_LIB.T6G(SCH_1):GND   I143 @T6G_MB_LIB.T6G(SCH_1):PAGE93
   193    GND @T6G_MB_LIB.T6G(SCH_1):GND   I143 @T6G_MB_LIB.T6G(SCH_1):PAGE93
   195    GND @T6G_MB_LIB.T6G(SCH_1):GND   I143 @T6G_MB_LIB.T6G(SCH_1):PAGE93
   197    GND @T6G_MB_LIB.T6G(SCH_1):GND   I143 @T6G_MB_LIB.T6G(SCH_1):PAGE93
   199    GND @T6G_MB_LIB.T6G(SCH_1):GND   I143 @T6G_MB_LIB.T6G(SCH_1):PAGE93
   202    GND @T6G_MB_LIB.T6G(SCH_1):GND   I143 @T6G_MB_LIB.T6G(SCH_1):PAGE93
   204    GND @T6G_MB_LIB.T6G(SCH_1):GND   I143 @T6G_MB_LIB.T6G(SCH_1):PAGE93
   206    GND @T6G_MB_LIB.T6G(SCH_1):GND   I143 @T6G_MB_LIB.T6G(SCH_1):PAGE93
   208    GND @T6G_MB_LIB.T6G(SCH_1):GND   I143 @T6G_MB_LIB.T6G(SCH_1):PAGE93
   210    GND @T6G_MB_LIB.T6G(SCH_1):GND   I143 @T6G_MB_LIB.T6G(SCH_1):PAGE93
   212    GND @T6G_MB_LIB.T6G(SCH_1):GND   I143 @T6G_MB_LIB.T6G(SCH_1):PAGE93
   214    GND @T6G_MB_LIB.T6G(SCH_1):GND   I143 @T6G_MB_LIB.T6G(SCH_1):PAGE93
   216    GND @T6G_MB_LIB.T6G(SCH_1):GND   I143 @T6G_MB_LIB.T6G(SCH_1):PAGE93
   219    GND @T6G_MB_LIB.T6G(SCH_1):GND   I143 @T6G_MB_LIB.T6G(SCH_1):PAGE93
   222    GND @T6G_MB_LIB.T6G(SCH_1):GND   I143 @T6G_MB_LIB.T6G(SCH_1):PAGE93
   224    GND @T6G_MB_LIB.T6G(SCH_1):GND   I143 @T6G_MB_LIB.T6G(SCH_1):PAGE93
   226    GND @T6G_MB_LIB.T6G(SCH_1):GND   I143 @T6G_MB_LIB.T6G(SCH_1):PAGE93
   228    GND @T6G_MB_LIB.T6G(SCH_1):GND   I143 @T6G_MB_LIB.T6G(SCH_1):PAGE93
   233    GND @T6G_MB_LIB.T6G(SCH_1):GND   I143 @T6G_MB_LIB.T6G(SCH_1):PAGE93
   237    GND @T6G_MB_LIB.T6G(SCH_1):GND   I143 @T6G_MB_LIB.T6G(SCH_1):PAGE93
   242    GND @T6G_MB_LIB.T6G(SCH_1):GND   I143 @T6G_MB_LIB.T6G(SCH_1):PAGE93
   244    GND @T6G_MB_LIB.T6G(SCH_1):GND   I143 @T6G_MB_LIB.T6G(SCH_1):PAGE93
   246    GND @T6G_MB_LIB.T6G(SCH_1):GND   I143 @T6G_MB_LIB.T6G(SCH_1):PAGE93
   248    GND @T6G_MB_LIB.T6G(SCH_1):GND   I143 @T6G_MB_LIB.T6G(SCH_1):PAGE93
   251    GND @T6G_MB_LIB.T6G(SCH_1):GND   I143 @T6G_MB_LIB.T6G(SCH_1):PAGE93
   253    GND @T6G_MB_LIB.T6G(SCH_1):GND   I143 @T6G_MB_LIB.T6G(SCH_1):PAGE93
   255    GND @T6G_MB_LIB.T6G(SCH_1):GND   I143 @T6G_MB_LIB.T6G(SCH_1):PAGE93
   257    GND @T6G_MB_LIB.T6G(SCH_1):GND   I143 @T6G_MB_LIB.T6G(SCH_1):PAGE93
   259    GND @T6G_MB_LIB.T6G(SCH_1):GND   I143 @T6G_MB_LIB.T6G(SCH_1):PAGE93
   262    GND @T6G_MB_LIB.T6G(SCH_1):GND   I143 @T6G_MB_LIB.T6G(SCH_1):PAGE93
   264    GND @T6G_MB_LIB.T6G(SCH_1):GND   I143 @T6G_MB_LIB.T6G(SCH_1):PAGE93
   266    GND @T6G_MB_LIB.T6G(SCH_1):GND   I143 @T6G_MB_LIB.T6G(SCH_1):PAGE93
   268    GND @T6G_MB_LIB.T6G(SCH_1):GND   I143 @T6G_MB_LIB.T6G(SCH_1):PAGE93
   270    GND @T6G_MB_LIB.T6G(SCH_1):GND   I143 @T6G_MB_LIB.T6G(SCH_1):PAGE93
   273    GND @T6G_MB_LIB.T6G(SCH_1):GND   I143 @T6G_MB_LIB.T6G(SCH_1):PAGE93
   275    GND @T6G_MB_LIB.T6G(SCH_1):GND   I143 @T6G_MB_LIB.T6G(SCH_1):PAGE93
   277    GND @T6G_MB_LIB.T6G(SCH_1):GND   I143 @T6G_MB_LIB.T6G(SCH_1):PAGE93
   279    GND @T6G_MB_LIB.T6G(SCH_1):GND   I143 @T6G_MB_LIB.T6G(SCH_1):PAGE93
   281    GND @T6G_MB_LIB.T6G(SCH_1):GND   I143 @T6G_MB_LIB.T6G(SCH_1):PAGE93
   284    GND @T6G_MB_LIB.T6G(SCH_1):GND   I143 @T6G_MB_LIB.T6G(SCH_1):PAGE93
   286    GND @T6G_MB_LIB.T6G(SCH_1):GND   I143 @T6G_MB_LIB.T6G(SCH_1):PAGE93
   288    GND @T6G_MB_LIB.T6G(SCH_1):GND   I143 @T6G_MB_LIB.T6G(SCH_1):PAGE93
     1 P12V_MEM_CPU0 @T6G_MB_LIB.T6G(SCH_1):P12V_MEM_CPU0   I143 @T6G_MB_LIB.T6G(SCH_1):PAGE93
   145 P12V_MEM_CPU0 @T6G_MB_LIB.T6G(SCH_1):P12V_MEM_CPU0   I143 @T6G_MB_LIB.T6G(SCH_1):PAGE93
   146 P12V_MEM_CPU0 @T6G_MB_LIB.T6G(SCH_1):P12V_MEM_CPU0   I143 @T6G_MB_LIB.T6G(SCH_1):PAGE93
   230    GND @T6G_MB_LIB.T6G(SCH_1):GND   I143 @T6G_MB_LIB.T6G(SCH_1):PAGE93
   235    GND @T6G_MB_LIB.T6G(SCH_1):GND   I143 @T6G_MB_LIB.T6G(SCH_1):PAGE93
   240    GND @T6G_MB_LIB.T6G(SCH_1):GND   I143 @T6G_MB_LIB.T6G(SCH_1):PAGE93
   132    GND @T6G_MB_LIB.T6G(SCH_1):GND   I143 @T6G_MB_LIB.T6G(SCH_1):PAGE93
   136    GND @T6G_MB_LIB.T6G(SCH_1):GND   I143 @T6G_MB_LIB.T6G(SCH_1):PAGE93
   139    GND @T6G_MB_LIB.T6G(SCH_1):GND   I143 @T6G_MB_LIB.T6G(SCH_1):PAGE93
   141    GND @T6G_MB_LIB.T6G(SCH_1):GND   I143 @T6G_MB_LIB.T6G(SCH_1):PAGE93
    G1    GND @T6G_MB_LIB.T6G(SCH_1):GND   I143 @T6G_MB_LIB.T6G(SCH_1):PAGE93
    G2    GND @T6G_MB_LIB.T6G(SCH_1):GND   I143 @T6G_MB_LIB.T6G(SCH_1):PAGE93
    G3    GND @T6G_MB_LIB.T6G(SCH_1):GND   I143 @T6G_MB_LIB.T6G(SCH_1):PAGE93

 J19 SCONN288_DDR506112002KQ-SCONN288_DDR506112002KQ,SMA
     3 P3V3_AUX @T6G_MB_LIB.T6G(SCH_1):P3V3_AUX   I350 @T6G_MB_LIB.T6G(SCH_1):PAGE88
     2     NC     NC   I350 @T6G_MB_LIB.T6G(SCH_1):PAGE88
   144     NC     NC   I350 @T6G_MB_LIB.T6G(SCH_1):PAGE88
   149     NC     NC   I350 @T6G_MB_LIB.T6G(SCH_1):PAGE88
   150     NC     NC   I350 @T6G_MB_LIB.T6G(SCH_1):PAGE88
   220     NC     NC   I350 @T6G_MB_LIB.T6G(SCH_1):PAGE88
   231     NC     NC   I350 @T6G_MB_LIB.T6G(SCH_1):PAGE88
   232     NC     NC   I350 @T6G_MB_LIB.T6G(SCH_1):PAGE88
   207 M_D_CPU0_RESET_N @T6G_MB_LIB.T6G(SCH_1):M_D_CPU0_RESET_N   I350 @T6G_MB_LIB.T6G(SCH_1):PAGE88
   147 PWRGD_CHD_CPU0_DIMM @T6G_MB_LIB.T6G(SCH_1):PWRGD_CHD_CPU0_DIMM   I350 @T6G_MB_LIB.T6G(SCH_1):PAGE88
   227 M_D_CPU0_SB_PAR @T6G_MB_LIB.T6G(SCH_1):M_D_CPU0_SB_PAR   I350 @T6G_MB_LIB.T6G(SCH_1):PAGE88
    74 M_D_CPU0_SA_PAR @T6G_MB_LIB.T6G(SCH_1):M_D_CPU0_SA_PAR   I350 @T6G_MB_LIB.T6G(SCH_1):PAGE88
    87 M_D_CPU0_SB_RSP<0> @T6G_MB_LIB.T6G(SCH_1):M_D_CPU0_SB_RSP(0)   I350 @T6G_MB_LIB.T6G(SCH_1):PAGE88
    86 M_D_CPU0_SA_RSP<0> @T6G_MB_LIB.T6G(SCH_1):M_D_CPU0_SA_RSP(0)   I350 @T6G_MB_LIB.T6G(SCH_1):PAGE88
     5 I3C_SPD_DDRD_CPU0_SDA @T6G_MB_LIB.T6G(SCH_1):I3C_SPD_DDRD_CPU0_SDA   I350 @T6G_MB_LIB.T6G(SCH_1):PAGE88
     4 I3C_SPD_DDRD_CPU0_SCL @T6G_MB_LIB.T6G(SCH_1):I3C_SPD_DDRD_CPU0_SCL   I350 @T6G_MB_LIB.T6G(SCH_1):PAGE88
   148 PD_CHD_CPU0_DIMM_SAA @T6G_MB_LIB.T6G(SCH_1):PD_CHD_CPU0_DIMM_SAA   I350 @T6G_MB_LIB.T6G(SCH_1):PAGE88
   100 M_D_CPU0_SB_DQ<0> @T6G_MB_LIB.T6G(SCH_1):M_D_CPU0_SB_DQ(0)   I350 @T6G_MB_LIB.T6G(SCH_1):PAGE88
   102 M_D_CPU0_SB_DQ<1> @T6G_MB_LIB.T6G(SCH_1):M_D_CPU0_SB_DQ(1)   I350 @T6G_MB_LIB.T6G(SCH_1):PAGE88
   245 M_D_CPU0_SB_DQ<2> @T6G_MB_LIB.T6G(SCH_1):M_D_CPU0_SB_DQ(2)   I350 @T6G_MB_LIB.T6G(SCH_1):PAGE88
   247 M_D_CPU0_SB_DQ<3> @T6G_MB_LIB.T6G(SCH_1):M_D_CPU0_SB_DQ(3)   I350 @T6G_MB_LIB.T6G(SCH_1):PAGE88
   107 M_D_CPU0_SB_DQ<4> @T6G_MB_LIB.T6G(SCH_1):M_D_CPU0_SB_DQ(4)   I350 @T6G_MB_LIB.T6G(SCH_1):PAGE88
   109 M_D_CPU0_SB_DQ<5> @T6G_MB_LIB.T6G(SCH_1):M_D_CPU0_SB_DQ(5)   I350 @T6G_MB_LIB.T6G(SCH_1):PAGE88
   252 M_D_CPU0_SB_DQ<6> @T6G_MB_LIB.T6G(SCH_1):M_D_CPU0_SB_DQ(6)   I350 @T6G_MB_LIB.T6G(SCH_1):PAGE88
   254 M_D_CPU0_SB_DQ<7> @T6G_MB_LIB.T6G(SCH_1):M_D_CPU0_SB_DQ(7)   I350 @T6G_MB_LIB.T6G(SCH_1):PAGE88
   111 M_D_CPU0_SB_DQ<8> @T6G_MB_LIB.T6G(SCH_1):M_D_CPU0_SB_DQ(8)   I350 @T6G_MB_LIB.T6G(SCH_1):PAGE88
   113 M_D_CPU0_SB_DQ<9> @T6G_MB_LIB.T6G(SCH_1):M_D_CPU0_SB_DQ(9)   I350 @T6G_MB_LIB.T6G(SCH_1):PAGE88
   256 M_D_CPU0_SB_DQ<10> @T6G_MB_LIB.T6G(SCH_1):M_D_CPU0_SB_DQ(10)   I350 @T6G_MB_LIB.T6G(SCH_1):PAGE88
   258 M_D_CPU0_SB_DQ<11> @T6G_MB_LIB.T6G(SCH_1):M_D_CPU0_SB_DQ(11)   I350 @T6G_MB_LIB.T6G(SCH_1):PAGE88
   118 M_D_CPU0_SB_DQ<12> @T6G_MB_LIB.T6G(SCH_1):M_D_CPU0_SB_DQ(12)   I350 @T6G_MB_LIB.T6G(SCH_1):PAGE88
   120 M_D_CPU0_SB_DQ<13> @T6G_MB_LIB.T6G(SCH_1):M_D_CPU0_SB_DQ(13)   I350 @T6G_MB_LIB.T6G(SCH_1):PAGE88
   263 M_D_CPU0_SB_DQ<14> @T6G_MB_LIB.T6G(SCH_1):M_D_CPU0_SB_DQ(14)   I350 @T6G_MB_LIB.T6G(SCH_1):PAGE88
   265 M_D_CPU0_SB_DQ<15> @T6G_MB_LIB.T6G(SCH_1):M_D_CPU0_SB_DQ(15)   I350 @T6G_MB_LIB.T6G(SCH_1):PAGE88
   122 M_D_CPU0_SB_DQ<16> @T6G_MB_LIB.T6G(SCH_1):M_D_CPU0_SB_DQ(16)   I350 @T6G_MB_LIB.T6G(SCH_1):PAGE88
   124 M_D_CPU0_SB_DQ<17> @T6G_MB_LIB.T6G(SCH_1):M_D_CPU0_SB_DQ(17)   I350 @T6G_MB_LIB.T6G(SCH_1):PAGE88
   267 M_D_CPU0_SB_DQ<18> @T6G_MB_LIB.T6G(SCH_1):M_D_CPU0_SB_DQ(18)   I350 @T6G_MB_LIB.T6G(SCH_1):PAGE88
   269 M_D_CPU0_SB_DQ<19> @T6G_MB_LIB.T6G(SCH_1):M_D_CPU0_SB_DQ(19)   I350 @T6G_MB_LIB.T6G(SCH_1):PAGE88
   129 M_D_CPU0_SB_DQ<20> @T6G_MB_LIB.T6G(SCH_1):M_D_CPU0_SB_DQ(20)   I350 @T6G_MB_LIB.T6G(SCH_1):PAGE88
   131 M_D_CPU0_SB_DQ<21> @T6G_MB_LIB.T6G(SCH_1):M_D_CPU0_SB_DQ(21)   I350 @T6G_MB_LIB.T6G(SCH_1):PAGE88
   274 M_D_CPU0_SB_DQ<22> @T6G_MB_LIB.T6G(SCH_1):M_D_CPU0_SB_DQ(22)   I350 @T6G_MB_LIB.T6G(SCH_1):PAGE88
   276 M_D_CPU0_SB_DQ<23> @T6G_MB_LIB.T6G(SCH_1):M_D_CPU0_SB_DQ(23)   I350 @T6G_MB_LIB.T6G(SCH_1):PAGE88
   133 M_D_CPU0_SB_DQ<24> @T6G_MB_LIB.T6G(SCH_1):M_D_CPU0_SB_DQ(24)   I350 @T6G_MB_LIB.T6G(SCH_1):PAGE88
   135 M_D_CPU0_SB_DQ<25> @T6G_MB_LIB.T6G(SCH_1):M_D_CPU0_SB_DQ(25)   I350 @T6G_MB_LIB.T6G(SCH_1):PAGE88
   278 M_D_CPU0_SB_DQ<26> @T6G_MB_LIB.T6G(SCH_1):M_D_CPU0_SB_DQ(26)   I350 @T6G_MB_LIB.T6G(SCH_1):PAGE88
   280 M_D_CPU0_SB_DQ<27> @T6G_MB_LIB.T6G(SCH_1):M_D_CPU0_SB_DQ(27)   I350 @T6G_MB_LIB.T6G(SCH_1):PAGE88
   140 M_D_CPU0_SB_DQ<28> @T6G_MB_LIB.T6G(SCH_1):M_D_CPU0_SB_DQ(28)   I350 @T6G_MB_LIB.T6G(SCH_1):PAGE88
   142 M_D_CPU0_SB_DQ<29> @T6G_MB_LIB.T6G(SCH_1):M_D_CPU0_SB_DQ(29)   I350 @T6G_MB_LIB.T6G(SCH_1):PAGE88
   285 M_D_CPU0_SB_DQ<30> @T6G_MB_LIB.T6G(SCH_1):M_D_CPU0_SB_DQ(30)   I350 @T6G_MB_LIB.T6G(SCH_1):PAGE88
   287 M_D_CPU0_SB_DQ<31> @T6G_MB_LIB.T6G(SCH_1):M_D_CPU0_SB_DQ(31)   I350 @T6G_MB_LIB.T6G(SCH_1):PAGE88
     7 M_D_CPU0_SA_DQ<0> @T6G_MB_LIB.T6G(SCH_1):M_D_CPU0_SA_DQ(0)   I350 @T6G_MB_LIB.T6G(SCH_1):PAGE88
     9 M_D_CPU0_SA_DQ<1> @T6G_MB_LIB.T6G(SCH_1):M_D_CPU0_SA_DQ(1)   I350 @T6G_MB_LIB.T6G(SCH_1):PAGE88
   152 M_D_CPU0_SA_DQ<2> @T6G_MB_LIB.T6G(SCH_1):M_D_CPU0_SA_DQ(2)   I350 @T6G_MB_LIB.T6G(SCH_1):PAGE88
   154 M_D_CPU0_SA_DQ<3> @T6G_MB_LIB.T6G(SCH_1):M_D_CPU0_SA_DQ(3)   I350 @T6G_MB_LIB.T6G(SCH_1):PAGE88
    14 M_D_CPU0_SA_DQ<4> @T6G_MB_LIB.T6G(SCH_1):M_D_CPU0_SA_DQ(4)   I350 @T6G_MB_LIB.T6G(SCH_1):PAGE88
    16 M_D_CPU0_SA_DQ<5> @T6G_MB_LIB.T6G(SCH_1):M_D_CPU0_SA_DQ(5)   I350 @T6G_MB_LIB.T6G(SCH_1):PAGE88
   159 M_D_CPU0_SA_DQ<6> @T6G_MB_LIB.T6G(SCH_1):M_D_CPU0_SA_DQ(6)   I350 @T6G_MB_LIB.T6G(SCH_1):PAGE88
   161 M_D_CPU0_SA_DQ<7> @T6G_MB_LIB.T6G(SCH_1):M_D_CPU0_SA_DQ(7)   I350 @T6G_MB_LIB.T6G(SCH_1):PAGE88
    18 M_D_CPU0_SA_DQ<8> @T6G_MB_LIB.T6G(SCH_1):M_D_CPU0_SA_DQ(8)   I350 @T6G_MB_LIB.T6G(SCH_1):PAGE88
    20 M_D_CPU0_SA_DQ<9> @T6G_MB_LIB.T6G(SCH_1):M_D_CPU0_SA_DQ(9)   I350 @T6G_MB_LIB.T6G(SCH_1):PAGE88
   163 M_D_CPU0_SA_DQ<10> @T6G_MB_LIB.T6G(SCH_1):M_D_CPU0_SA_DQ(10)   I350 @T6G_MB_LIB.T6G(SCH_1):PAGE88
   165 M_D_CPU0_SA_DQ<11> @T6G_MB_LIB.T6G(SCH_1):M_D_CPU0_SA_DQ(11)   I350 @T6G_MB_LIB.T6G(SCH_1):PAGE88
    25 M_D_CPU0_SA_DQ<12> @T6G_MB_LIB.T6G(SCH_1):M_D_CPU0_SA_DQ(12)   I350 @T6G_MB_LIB.T6G(SCH_1):PAGE88
    27 M_D_CPU0_SA_DQ<13> @T6G_MB_LIB.T6G(SCH_1):M_D_CPU0_SA_DQ(13)   I350 @T6G_MB_LIB.T6G(SCH_1):PAGE88
   170 M_D_CPU0_SA_DQ<14> @T6G_MB_LIB.T6G(SCH_1):M_D_CPU0_SA_DQ(14)   I350 @T6G_MB_LIB.T6G(SCH_1):PAGE88
   172 M_D_CPU0_SA_DQ<15> @T6G_MB_LIB.T6G(SCH_1):M_D_CPU0_SA_DQ(15)   I350 @T6G_MB_LIB.T6G(SCH_1):PAGE88
    29 M_D_CPU0_SA_DQ<16> @T6G_MB_LIB.T6G(SCH_1):M_D_CPU0_SA_DQ(16)   I350 @T6G_MB_LIB.T6G(SCH_1):PAGE88
    31 M_D_CPU0_SA_DQ<17> @T6G_MB_LIB.T6G(SCH_1):M_D_CPU0_SA_DQ(17)   I350 @T6G_MB_LIB.T6G(SCH_1):PAGE88
   174 M_D_CPU0_SA_DQ<18> @T6G_MB_LIB.T6G(SCH_1):M_D_CPU0_SA_DQ(18)   I350 @T6G_MB_LIB.T6G(SCH_1):PAGE88
   176 M_D_CPU0_SA_DQ<19> @T6G_MB_LIB.T6G(SCH_1):M_D_CPU0_SA_DQ(19)   I350 @T6G_MB_LIB.T6G(SCH_1):PAGE88
    36 M_D_CPU0_SA_DQ<20> @T6G_MB_LIB.T6G(SCH_1):M_D_CPU0_SA_DQ(20)   I350 @T6G_MB_LIB.T6G(SCH_1):PAGE88
    38 M_D_CPU0_SA_DQ<21> @T6G_MB_LIB.T6G(SCH_1):M_D_CPU0_SA_DQ(21)   I350 @T6G_MB_LIB.T6G(SCH_1):PAGE88
   181 M_D_CPU0_SA_DQ<22> @T6G_MB_LIB.T6G(SCH_1):M_D_CPU0_SA_DQ(22)   I350 @T6G_MB_LIB.T6G(SCH_1):PAGE88
   183 M_D_CPU0_SA_DQ<23> @T6G_MB_LIB.T6G(SCH_1):M_D_CPU0_SA_DQ(23)   I350 @T6G_MB_LIB.T6G(SCH_1):PAGE88
    40 M_D_CPU0_SA_DQ<24> @T6G_MB_LIB.T6G(SCH_1):M_D_CPU0_SA_DQ(24)   I350 @T6G_MB_LIB.T6G(SCH_1):PAGE88
    42 M_D_CPU0_SA_DQ<25> @T6G_MB_LIB.T6G(SCH_1):M_D_CPU0_SA_DQ(25)   I350 @T6G_MB_LIB.T6G(SCH_1):PAGE88
   185 M_D_CPU0_SA_DQ<26> @T6G_MB_LIB.T6G(SCH_1):M_D_CPU0_SA_DQ(26)   I350 @T6G_MB_LIB.T6G(SCH_1):PAGE88
   187 M_D_CPU0_SA_DQ<27> @T6G_MB_LIB.T6G(SCH_1):M_D_CPU0_SA_DQ(27)   I350 @T6G_MB_LIB.T6G(SCH_1):PAGE88
    47 M_D_CPU0_SA_DQ<28> @T6G_MB_LIB.T6G(SCH_1):M_D_CPU0_SA_DQ(28)   I350 @T6G_MB_LIB.T6G(SCH_1):PAGE88
    49 M_D_CPU0_SA_DQ<29> @T6G_MB_LIB.T6G(SCH_1):M_D_CPU0_SA_DQ(29)   I350 @T6G_MB_LIB.T6G(SCH_1):PAGE88
   192 M_D_CPU0_SA_DQ<30> @T6G_MB_LIB.T6G(SCH_1):M_D_CPU0_SA_DQ(30)   I350 @T6G_MB_LIB.T6G(SCH_1):PAGE88
   229 M_D_CPU0_SB_CS_N<1> @T6G_MB_LIB.T6G(SCH_1):M_D_CPU0_SB_CS_N(1)   I350 @T6G_MB_LIB.T6G(SCH_1):PAGE88
   209 M_D_CPU0_SA_CS_N<1> @T6G_MB_LIB.T6G(SCH_1):M_D_CPU0_SA_CS_N(1)   I350 @T6G_MB_LIB.T6G(SCH_1):PAGE88
    84 M_D_CPU0_SB_CS_N<0> @T6G_MB_LIB.T6G(SCH_1):M_D_CPU0_SB_CS_N(0)   I350 @T6G_MB_LIB.T6G(SCH_1):PAGE88
    64 M_D_CPU0_SA_CS_N<0> @T6G_MB_LIB.T6G(SCH_1):M_D_CPU0_SA_CS_N(0)   I350 @T6G_MB_LIB.T6G(SCH_1):PAGE88
   217 M_D_CPU0_CLK_DP<0> @T6G_MB_LIB.T6G(SCH_1):M_D_CPU0_CLK_DP(0)   I350 @T6G_MB_LIB.T6G(SCH_1):PAGE88
   218 M_D_CPU0_CLK_DN<0> @T6G_MB_LIB.T6G(SCH_1):M_D_CPU0_CLK_DN(0)   I350 @T6G_MB_LIB.T6G(SCH_1):PAGE88
    96 M_D_CPU0_SB_CB<0> @T6G_MB_LIB.T6G(SCH_1):M_D_CPU0_SB_CB(0)   I350 @T6G_MB_LIB.T6G(SCH_1):PAGE88
    98 M_D_CPU0_SB_CB<1> @T6G_MB_LIB.T6G(SCH_1):M_D_CPU0_SB_CB(1)   I350 @T6G_MB_LIB.T6G(SCH_1):PAGE88
   241 M_D_CPU0_SB_CB<2> @T6G_MB_LIB.T6G(SCH_1):M_D_CPU0_SB_CB(2)   I350 @T6G_MB_LIB.T6G(SCH_1):PAGE88
   243 M_D_CPU0_SB_CB<3> @T6G_MB_LIB.T6G(SCH_1):M_D_CPU0_SB_CB(3)   I350 @T6G_MB_LIB.T6G(SCH_1):PAGE88
    89 M_D_CPU0_SB_CB<4> @T6G_MB_LIB.T6G(SCH_1):M_D_CPU0_SB_CB(4)   I350 @T6G_MB_LIB.T6G(SCH_1):PAGE88
    91 M_D_CPU0_SB_CB<5> @T6G_MB_LIB.T6G(SCH_1):M_D_CPU0_SB_CB(5)   I350 @T6G_MB_LIB.T6G(SCH_1):PAGE88
   234 M_D_CPU0_SB_CB<6> @T6G_MB_LIB.T6G(SCH_1):M_D_CPU0_SB_CB(6)   I350 @T6G_MB_LIB.T6G(SCH_1):PAGE88
    51 M_D_CPU0_SA_CB<0> @T6G_MB_LIB.T6G(SCH_1):M_D_CPU0_SA_CB(0)   I350 @T6G_MB_LIB.T6G(SCH_1):PAGE88
   196 M_D_CPU0_SA_CB<2> @T6G_MB_LIB.T6G(SCH_1):M_D_CPU0_SA_CB(2)   I350 @T6G_MB_LIB.T6G(SCH_1):PAGE88
   198 M_D_CPU0_SA_CB<3> @T6G_MB_LIB.T6G(SCH_1):M_D_CPU0_SA_CB(3)   I350 @T6G_MB_LIB.T6G(SCH_1):PAGE88
    60 M_D_CPU0_SA_CB<5> @T6G_MB_LIB.T6G(SCH_1):M_D_CPU0_SA_CB(5)   I350 @T6G_MB_LIB.T6G(SCH_1):PAGE88
   203 M_D_CPU0_SA_CB<6> @T6G_MB_LIB.T6G(SCH_1):M_D_CPU0_SA_CB(6)   I350 @T6G_MB_LIB.T6G(SCH_1):PAGE88
    82 M_D_CPU0_SB_CA<6> @T6G_MB_LIB.T6G(SCH_1):M_D_CPU0_SB_CA(6)   I350 @T6G_MB_LIB.T6G(SCH_1):PAGE88
    72 M_D_CPU0_SA_CA<6> @T6G_MB_LIB.T6G(SCH_1):M_D_CPU0_SA_CA(6)   I350 @T6G_MB_LIB.T6G(SCH_1):PAGE88
   225 M_D_CPU0_SB_CA<5> @T6G_MB_LIB.T6G(SCH_1):M_D_CPU0_SB_CA(5)   I350 @T6G_MB_LIB.T6G(SCH_1):PAGE88
   215 M_D_CPU0_SA_CA<5> @T6G_MB_LIB.T6G(SCH_1):M_D_CPU0_SA_CA(5)   I350 @T6G_MB_LIB.T6G(SCH_1):PAGE88
    80 M_D_CPU0_SB_CA<4> @T6G_MB_LIB.T6G(SCH_1):M_D_CPU0_SB_CA(4)   I350 @T6G_MB_LIB.T6G(SCH_1):PAGE88
    70 M_D_CPU0_SA_CA<4> @T6G_MB_LIB.T6G(SCH_1):M_D_CPU0_SA_CA(4)   I350 @T6G_MB_LIB.T6G(SCH_1):PAGE88
   223 M_D_CPU0_SB_CA<3> @T6G_MB_LIB.T6G(SCH_1):M_D_CPU0_SB_CA(3)   I350 @T6G_MB_LIB.T6G(SCH_1):PAGE88
   213 M_D_CPU0_SA_CA<3> @T6G_MB_LIB.T6G(SCH_1):M_D_CPU0_SA_CA(3)   I350 @T6G_MB_LIB.T6G(SCH_1):PAGE88
    78 M_D_CPU0_SB_CA<2> @T6G_MB_LIB.T6G(SCH_1):M_D_CPU0_SB_CA(2)   I350 @T6G_MB_LIB.T6G(SCH_1):PAGE88
    68 M_D_CPU0_SA_CA<2> @T6G_MB_LIB.T6G(SCH_1):M_D_CPU0_SA_CA(2)   I350 @T6G_MB_LIB.T6G(SCH_1):PAGE88
   221 M_D_CPU0_SB_CA<1> @T6G_MB_LIB.T6G(SCH_1):M_D_CPU0_SB_CA(1)   I350 @T6G_MB_LIB.T6G(SCH_1):PAGE88
   211 M_D_CPU0_SA_CA<1> @T6G_MB_LIB.T6G(SCH_1):M_D_CPU0_SA_CA(1)   I350 @T6G_MB_LIB.T6G(SCH_1):PAGE88
    76 M_D_CPU0_SB_CA<0> @T6G_MB_LIB.T6G(SCH_1):M_D_CPU0_SB_CA(0)   I350 @T6G_MB_LIB.T6G(SCH_1):PAGE88
    66 M_D_CPU0_SA_CA<0> @T6G_MB_LIB.T6G(SCH_1):M_D_CPU0_SA_CA(0)   I350 @T6G_MB_LIB.T6G(SCH_1):PAGE88
    62 M_D_CPU0_ALERT_N @T6G_MB_LIB.T6G(SCH_1):M_D_CPU0_ALERT_N   I350 @T6G_MB_LIB.T6G(SCH_1):PAGE88
   236 M_D_CPU0_SB_CB<7> @T6G_MB_LIB.T6G(SCH_1):M_D_CPU0_SB_CB(7)   I350 @T6G_MB_LIB.T6G(SCH_1):PAGE88
    53 M_D_CPU0_SA_CB<1> @T6G_MB_LIB.T6G(SCH_1):M_D_CPU0_SA_CB(1)   I350 @T6G_MB_LIB.T6G(SCH_1):PAGE88
    58 M_D_CPU0_SA_CB<4> @T6G_MB_LIB.T6G(SCH_1):M_D_CPU0_SA_CB(4)   I350 @T6G_MB_LIB.T6G(SCH_1):PAGE88
   205 M_D_CPU0_SA_CB<7> @T6G_MB_LIB.T6G(SCH_1):M_D_CPU0_SA_CB(7)   I350 @T6G_MB_LIB.T6G(SCH_1):PAGE88
   194 M_D_CPU0_SA_DQ<31> @T6G_MB_LIB.T6G(SCH_1):M_D_CPU0_SA_DQ(31)   I350 @T6G_MB_LIB.T6G(SCH_1):PAGE88
    93 M_D_CPU0_SB_DQS_DP<9> @T6G_MB_LIB.T6G(SCH_1):M_D_CPU0_SB_DQS_DP(9)   I415 @T6G_MB_LIB.T6G(SCH_1):PAGE88
    94 M_D_CPU0_SB_DQS_DN<9> @T6G_MB_LIB.T6G(SCH_1):M_D_CPU0_SB_DQS_DN(9)   I415 @T6G_MB_LIB.T6G(SCH_1):PAGE88
   201 M_D_CPU0_SA_DQS_DP<9> @T6G_MB_LIB.T6G(SCH_1):M_D_CPU0_SA_DQS_DP(9)   I415 @T6G_MB_LIB.T6G(SCH_1):PAGE88
   200 M_D_CPU0_SA_DQS_DN<9> @T6G_MB_LIB.T6G(SCH_1):M_D_CPU0_SA_DQS_DN(9)   I415 @T6G_MB_LIB.T6G(SCH_1):PAGE88
   190 M_D_CPU0_SA_DQS_DP<8> @T6G_MB_LIB.T6G(SCH_1):M_D_CPU0_SA_DQS_DP(8)   I415 @T6G_MB_LIB.T6G(SCH_1):PAGE88
   189 M_D_CPU0_SA_DQS_DN<8> @T6G_MB_LIB.T6G(SCH_1):M_D_CPU0_SA_DQS_DN(8)   I415 @T6G_MB_LIB.T6G(SCH_1):PAGE88
   271 M_D_CPU0_SB_DQS_DN<7> @T6G_MB_LIB.T6G(SCH_1):M_D_CPU0_SB_DQS_DN(7)   I415 @T6G_MB_LIB.T6G(SCH_1):PAGE88
   179 M_D_CPU0_SA_DQS_DP<7> @T6G_MB_LIB.T6G(SCH_1):M_D_CPU0_SA_DQS_DP(7)   I415 @T6G_MB_LIB.T6G(SCH_1):PAGE88
   261 M_D_CPU0_SB_DQS_DP<6> @T6G_MB_LIB.T6G(SCH_1):M_D_CPU0_SB_DQS_DP(6)   I415 @T6G_MB_LIB.T6G(SCH_1):PAGE88
   260 M_D_CPU0_SB_DQS_DN<6> @T6G_MB_LIB.T6G(SCH_1):M_D_CPU0_SB_DQS_DN(6)   I415 @T6G_MB_LIB.T6G(SCH_1):PAGE88
   167 M_D_CPU0_SA_DQS_DN<6> @T6G_MB_LIB.T6G(SCH_1):M_D_CPU0_SA_DQS_DN(6)   I415 @T6G_MB_LIB.T6G(SCH_1):PAGE88
   250 M_D_CPU0_SB_DQS_DP<5> @T6G_MB_LIB.T6G(SCH_1):M_D_CPU0_SB_DQS_DP(5)   I415 @T6G_MB_LIB.T6G(SCH_1):PAGE88
   249 M_D_CPU0_SB_DQS_DN<5> @T6G_MB_LIB.T6G(SCH_1):M_D_CPU0_SB_DQS_DN(5)   I415 @T6G_MB_LIB.T6G(SCH_1):PAGE88
   157 M_D_CPU0_SA_DQS_DP<5> @T6G_MB_LIB.T6G(SCH_1):M_D_CPU0_SA_DQS_DP(5)   I415 @T6G_MB_LIB.T6G(SCH_1):PAGE88
   156 M_D_CPU0_SA_DQS_DN<5> @T6G_MB_LIB.T6G(SCH_1):M_D_CPU0_SA_DQS_DN(5)   I415 @T6G_MB_LIB.T6G(SCH_1):PAGE88
   239 M_D_CPU0_SB_DQS_DP<4> @T6G_MB_LIB.T6G(SCH_1):M_D_CPU0_SB_DQS_DP(4)   I415 @T6G_MB_LIB.T6G(SCH_1):PAGE88
   238 M_D_CPU0_SB_DQS_DN<4> @T6G_MB_LIB.T6G(SCH_1):M_D_CPU0_SB_DQS_DN(4)   I415 @T6G_MB_LIB.T6G(SCH_1):PAGE88
    55 M_D_CPU0_SA_DQS_DP<4> @T6G_MB_LIB.T6G(SCH_1):M_D_CPU0_SA_DQS_DP(4)   I415 @T6G_MB_LIB.T6G(SCH_1):PAGE88
    56 M_D_CPU0_SA_DQS_DN<4> @T6G_MB_LIB.T6G(SCH_1):M_D_CPU0_SA_DQS_DN(4)   I415 @T6G_MB_LIB.T6G(SCH_1):PAGE88
   137 M_D_CPU0_SB_DQS_DP<3> @T6G_MB_LIB.T6G(SCH_1):M_D_CPU0_SB_DQS_DP(3)   I415 @T6G_MB_LIB.T6G(SCH_1):PAGE88
   138 M_D_CPU0_SB_DQS_DN<3> @T6G_MB_LIB.T6G(SCH_1):M_D_CPU0_SB_DQS_DN(3)   I415 @T6G_MB_LIB.T6G(SCH_1):PAGE88
    44 M_D_CPU0_SA_DQS_DP<3> @T6G_MB_LIB.T6G(SCH_1):M_D_CPU0_SA_DQS_DP(3)   I415 @T6G_MB_LIB.T6G(SCH_1):PAGE88
    45 M_D_CPU0_SA_DQS_DN<3> @T6G_MB_LIB.T6G(SCH_1):M_D_CPU0_SA_DQS_DN(3)   I415 @T6G_MB_LIB.T6G(SCH_1):PAGE88
   126 M_D_CPU0_SB_DQS_DP<2> @T6G_MB_LIB.T6G(SCH_1):M_D_CPU0_SB_DQS_DP(2)   I415 @T6G_MB_LIB.T6G(SCH_1):PAGE88
   127 M_D_CPU0_SB_DQS_DN<2> @T6G_MB_LIB.T6G(SCH_1):M_D_CPU0_SB_DQS_DN(2)   I415 @T6G_MB_LIB.T6G(SCH_1):PAGE88
    33 M_D_CPU0_SA_DQS_DP<2> @T6G_MB_LIB.T6G(SCH_1):M_D_CPU0_SA_DQS_DP(2)   I415 @T6G_MB_LIB.T6G(SCH_1):PAGE88
    34 M_D_CPU0_SA_DQS_DN<2> @T6G_MB_LIB.T6G(SCH_1):M_D_CPU0_SA_DQS_DN(2)   I415 @T6G_MB_LIB.T6G(SCH_1):PAGE88
   115 M_D_CPU0_SB_DQS_DP<1> @T6G_MB_LIB.T6G(SCH_1):M_D_CPU0_SB_DQS_DP(1)   I415 @T6G_MB_LIB.T6G(SCH_1):PAGE88
   116 M_D_CPU0_SB_DQS_DN<1> @T6G_MB_LIB.T6G(SCH_1):M_D_CPU0_SB_DQS_DN(1)   I415 @T6G_MB_LIB.T6G(SCH_1):PAGE88
    22 M_D_CPU0_SA_DQS_DP<1> @T6G_MB_LIB.T6G(SCH_1):M_D_CPU0_SA_DQS_DP(1)   I415 @T6G_MB_LIB.T6G(SCH_1):PAGE88
    23 M_D_CPU0_SA_DQS_DN<1> @T6G_MB_LIB.T6G(SCH_1):M_D_CPU0_SA_DQS_DN(1)   I415 @T6G_MB_LIB.T6G(SCH_1):PAGE88
   104 M_D_CPU0_SB_DQS_DP<0> @T6G_MB_LIB.T6G(SCH_1):M_D_CPU0_SB_DQS_DP(0)   I415 @T6G_MB_LIB.T6G(SCH_1):PAGE88
   105 M_D_CPU0_SB_DQS_DN<0> @T6G_MB_LIB.T6G(SCH_1):M_D_CPU0_SB_DQS_DN(0)   I415 @T6G_MB_LIB.T6G(SCH_1):PAGE88
    11 M_D_CPU0_SA_DQS_DP<0> @T6G_MB_LIB.T6G(SCH_1):M_D_CPU0_SA_DQS_DP(0)   I415 @T6G_MB_LIB.T6G(SCH_1):PAGE88
    12 M_D_CPU0_SA_DQS_DN<0> @T6G_MB_LIB.T6G(SCH_1):M_D_CPU0_SA_DQS_DN(0)   I415 @T6G_MB_LIB.T6G(SCH_1):PAGE88
   272 M_D_CPU0_SB_DQS_DP<7> @T6G_MB_LIB.T6G(SCH_1):M_D_CPU0_SB_DQS_DP(7)   I415 @T6G_MB_LIB.T6G(SCH_1):PAGE88
   282 M_D_CPU0_SB_DQS_DN<8> @T6G_MB_LIB.T6G(SCH_1):M_D_CPU0_SB_DQS_DN(8)   I415 @T6G_MB_LIB.T6G(SCH_1):PAGE88
   283 M_D_CPU0_SB_DQS_DP<8> @T6G_MB_LIB.T6G(SCH_1):M_D_CPU0_SB_DQS_DP(8)   I415 @T6G_MB_LIB.T6G(SCH_1):PAGE88
   168 M_D_CPU0_SA_DQS_DP<6> @T6G_MB_LIB.T6G(SCH_1):M_D_CPU0_SA_DQS_DP(6)   I415 @T6G_MB_LIB.T6G(SCH_1):PAGE88
   178 M_D_CPU0_SA_DQS_DN<7> @T6G_MB_LIB.T6G(SCH_1):M_D_CPU0_SA_DQS_DN(7)   I415 @T6G_MB_LIB.T6G(SCH_1):PAGE88
     6    GND @T6G_MB_LIB.T6G(SCH_1):GND   I352 @T6G_MB_LIB.T6G(SCH_1):PAGE88
     8    GND @T6G_MB_LIB.T6G(SCH_1):GND   I352 @T6G_MB_LIB.T6G(SCH_1):PAGE88
    10    GND @T6G_MB_LIB.T6G(SCH_1):GND   I352 @T6G_MB_LIB.T6G(SCH_1):PAGE88
    13    GND @T6G_MB_LIB.T6G(SCH_1):GND   I352 @T6G_MB_LIB.T6G(SCH_1):PAGE88
    15    GND @T6G_MB_LIB.T6G(SCH_1):GND   I352 @T6G_MB_LIB.T6G(SCH_1):PAGE88
    17    GND @T6G_MB_LIB.T6G(SCH_1):GND   I352 @T6G_MB_LIB.T6G(SCH_1):PAGE88
    19    GND @T6G_MB_LIB.T6G(SCH_1):GND   I352 @T6G_MB_LIB.T6G(SCH_1):PAGE88
    21    GND @T6G_MB_LIB.T6G(SCH_1):GND   I352 @T6G_MB_LIB.T6G(SCH_1):PAGE88
    24    GND @T6G_MB_LIB.T6G(SCH_1):GND   I352 @T6G_MB_LIB.T6G(SCH_1):PAGE88
    26    GND @T6G_MB_LIB.T6G(SCH_1):GND   I352 @T6G_MB_LIB.T6G(SCH_1):PAGE88
    28    GND @T6G_MB_LIB.T6G(SCH_1):GND   I352 @T6G_MB_LIB.T6G(SCH_1):PAGE88
    30    GND @T6G_MB_LIB.T6G(SCH_1):GND   I352 @T6G_MB_LIB.T6G(SCH_1):PAGE88
    32    GND @T6G_MB_LIB.T6G(SCH_1):GND   I352 @T6G_MB_LIB.T6G(SCH_1):PAGE88
    35    GND @T6G_MB_LIB.T6G(SCH_1):GND   I352 @T6G_MB_LIB.T6G(SCH_1):PAGE88
    37    GND @T6G_MB_LIB.T6G(SCH_1):GND   I352 @T6G_MB_LIB.T6G(SCH_1):PAGE88
    39    GND @T6G_MB_LIB.T6G(SCH_1):GND   I352 @T6G_MB_LIB.T6G(SCH_1):PAGE88
    41    GND @T6G_MB_LIB.T6G(SCH_1):GND   I352 @T6G_MB_LIB.T6G(SCH_1):PAGE88
    43    GND @T6G_MB_LIB.T6G(SCH_1):GND   I352 @T6G_MB_LIB.T6G(SCH_1):PAGE88
    46    GND @T6G_MB_LIB.T6G(SCH_1):GND   I352 @T6G_MB_LIB.T6G(SCH_1):PAGE88
    48    GND @T6G_MB_LIB.T6G(SCH_1):GND   I352 @T6G_MB_LIB.T6G(SCH_1):PAGE88
    50    GND @T6G_MB_LIB.T6G(SCH_1):GND   I352 @T6G_MB_LIB.T6G(SCH_1):PAGE88
    52    GND @T6G_MB_LIB.T6G(SCH_1):GND   I352 @T6G_MB_LIB.T6G(SCH_1):PAGE88
    54    GND @T6G_MB_LIB.T6G(SCH_1):GND   I352 @T6G_MB_LIB.T6G(SCH_1):PAGE88
    57    GND @T6G_MB_LIB.T6G(SCH_1):GND   I352 @T6G_MB_LIB.T6G(SCH_1):PAGE88
    59    GND @T6G_MB_LIB.T6G(SCH_1):GND   I352 @T6G_MB_LIB.T6G(SCH_1):PAGE88
    61    GND @T6G_MB_LIB.T6G(SCH_1):GND   I352 @T6G_MB_LIB.T6G(SCH_1):PAGE88
    63    GND @T6G_MB_LIB.T6G(SCH_1):GND   I352 @T6G_MB_LIB.T6G(SCH_1):PAGE88
    65    GND @T6G_MB_LIB.T6G(SCH_1):GND   I352 @T6G_MB_LIB.T6G(SCH_1):PAGE88
    67    GND @T6G_MB_LIB.T6G(SCH_1):GND   I352 @T6G_MB_LIB.T6G(SCH_1):PAGE88
    69    GND @T6G_MB_LIB.T6G(SCH_1):GND   I352 @T6G_MB_LIB.T6G(SCH_1):PAGE88
    71    GND @T6G_MB_LIB.T6G(SCH_1):GND   I352 @T6G_MB_LIB.T6G(SCH_1):PAGE88
    73    GND @T6G_MB_LIB.T6G(SCH_1):GND   I352 @T6G_MB_LIB.T6G(SCH_1):PAGE88
    75    GND @T6G_MB_LIB.T6G(SCH_1):GND   I352 @T6G_MB_LIB.T6G(SCH_1):PAGE88
    77    GND @T6G_MB_LIB.T6G(SCH_1):GND   I352 @T6G_MB_LIB.T6G(SCH_1):PAGE88
    79    GND @T6G_MB_LIB.T6G(SCH_1):GND   I352 @T6G_MB_LIB.T6G(SCH_1):PAGE88
    81    GND @T6G_MB_LIB.T6G(SCH_1):GND   I352 @T6G_MB_LIB.T6G(SCH_1):PAGE88
    83    GND @T6G_MB_LIB.T6G(SCH_1):GND   I352 @T6G_MB_LIB.T6G(SCH_1):PAGE88
    85    GND @T6G_MB_LIB.T6G(SCH_1):GND   I352 @T6G_MB_LIB.T6G(SCH_1):PAGE88
    88    GND @T6G_MB_LIB.T6G(SCH_1):GND   I352 @T6G_MB_LIB.T6G(SCH_1):PAGE88
    90    GND @T6G_MB_LIB.T6G(SCH_1):GND   I352 @T6G_MB_LIB.T6G(SCH_1):PAGE88
    92    GND @T6G_MB_LIB.T6G(SCH_1):GND   I352 @T6G_MB_LIB.T6G(SCH_1):PAGE88
    95    GND @T6G_MB_LIB.T6G(SCH_1):GND   I352 @T6G_MB_LIB.T6G(SCH_1):PAGE88
    97    GND @T6G_MB_LIB.T6G(SCH_1):GND   I352 @T6G_MB_LIB.T6G(SCH_1):PAGE88
    99    GND @T6G_MB_LIB.T6G(SCH_1):GND   I352 @T6G_MB_LIB.T6G(SCH_1):PAGE88
   101    GND @T6G_MB_LIB.T6G(SCH_1):GND   I352 @T6G_MB_LIB.T6G(SCH_1):PAGE88
   103    GND @T6G_MB_LIB.T6G(SCH_1):GND   I352 @T6G_MB_LIB.T6G(SCH_1):PAGE88
   106    GND @T6G_MB_LIB.T6G(SCH_1):GND   I352 @T6G_MB_LIB.T6G(SCH_1):PAGE88
   108    GND @T6G_MB_LIB.T6G(SCH_1):GND   I352 @T6G_MB_LIB.T6G(SCH_1):PAGE88
   110    GND @T6G_MB_LIB.T6G(SCH_1):GND   I352 @T6G_MB_LIB.T6G(SCH_1):PAGE88
   112    GND @T6G_MB_LIB.T6G(SCH_1):GND   I352 @T6G_MB_LIB.T6G(SCH_1):PAGE88
   114    GND @T6G_MB_LIB.T6G(SCH_1):GND   I352 @T6G_MB_LIB.T6G(SCH_1):PAGE88
   117    GND @T6G_MB_LIB.T6G(SCH_1):GND   I352 @T6G_MB_LIB.T6G(SCH_1):PAGE88
   119    GND @T6G_MB_LIB.T6G(SCH_1):GND   I352 @T6G_MB_LIB.T6G(SCH_1):PAGE88
   121    GND @T6G_MB_LIB.T6G(SCH_1):GND   I352 @T6G_MB_LIB.T6G(SCH_1):PAGE88
   123    GND @T6G_MB_LIB.T6G(SCH_1):GND   I352 @T6G_MB_LIB.T6G(SCH_1):PAGE88
   125    GND @T6G_MB_LIB.T6G(SCH_1):GND   I352 @T6G_MB_LIB.T6G(SCH_1):PAGE88
   128    GND @T6G_MB_LIB.T6G(SCH_1):GND   I352 @T6G_MB_LIB.T6G(SCH_1):PAGE88
   130    GND @T6G_MB_LIB.T6G(SCH_1):GND   I352 @T6G_MB_LIB.T6G(SCH_1):PAGE88
   134    GND @T6G_MB_LIB.T6G(SCH_1):GND   I352 @T6G_MB_LIB.T6G(SCH_1):PAGE88
   143    GND @T6G_MB_LIB.T6G(SCH_1):GND   I352 @T6G_MB_LIB.T6G(SCH_1):PAGE88
   151    GND @T6G_MB_LIB.T6G(SCH_1):GND   I352 @T6G_MB_LIB.T6G(SCH_1):PAGE88
   153    GND @T6G_MB_LIB.T6G(SCH_1):GND   I352 @T6G_MB_LIB.T6G(SCH_1):PAGE88
   155    GND @T6G_MB_LIB.T6G(SCH_1):GND   I352 @T6G_MB_LIB.T6G(SCH_1):PAGE88
   158    GND @T6G_MB_LIB.T6G(SCH_1):GND   I352 @T6G_MB_LIB.T6G(SCH_1):PAGE88
   160    GND @T6G_MB_LIB.T6G(SCH_1):GND   I352 @T6G_MB_LIB.T6G(SCH_1):PAGE88
   162    GND @T6G_MB_LIB.T6G(SCH_1):GND   I352 @T6G_MB_LIB.T6G(SCH_1):PAGE88
   164    GND @T6G_MB_LIB.T6G(SCH_1):GND   I352 @T6G_MB_LIB.T6G(SCH_1):PAGE88
   166    GND @T6G_MB_LIB.T6G(SCH_1):GND   I352 @T6G_MB_LIB.T6G(SCH_1):PAGE88
   169    GND @T6G_MB_LIB.T6G(SCH_1):GND   I352 @T6G_MB_LIB.T6G(SCH_1):PAGE88
   171    GND @T6G_MB_LIB.T6G(SCH_1):GND   I352 @T6G_MB_LIB.T6G(SCH_1):PAGE88
   173    GND @T6G_MB_LIB.T6G(SCH_1):GND   I352 @T6G_MB_LIB.T6G(SCH_1):PAGE88
   175    GND @T6G_MB_LIB.T6G(SCH_1):GND   I352 @T6G_MB_LIB.T6G(SCH_1):PAGE88
   177    GND @T6G_MB_LIB.T6G(SCH_1):GND   I352 @T6G_MB_LIB.T6G(SCH_1):PAGE88
   180    GND @T6G_MB_LIB.T6G(SCH_1):GND   I352 @T6G_MB_LIB.T6G(SCH_1):PAGE88
   182    GND @T6G_MB_LIB.T6G(SCH_1):GND   I352 @T6G_MB_LIB.T6G(SCH_1):PAGE88
   184    GND @T6G_MB_LIB.T6G(SCH_1):GND   I352 @T6G_MB_LIB.T6G(SCH_1):PAGE88
   186    GND @T6G_MB_LIB.T6G(SCH_1):GND   I352 @T6G_MB_LIB.T6G(SCH_1):PAGE88
   188    GND @T6G_MB_LIB.T6G(SCH_1):GND   I352 @T6G_MB_LIB.T6G(SCH_1):PAGE88
   191    GND @T6G_MB_LIB.T6G(SCH_1):GND   I352 @T6G_MB_LIB.T6G(SCH_1):PAGE88
   193    GND @T6G_MB_LIB.T6G(SCH_1):GND   I352 @T6G_MB_LIB.T6G(SCH_1):PAGE88
   195    GND @T6G_MB_LIB.T6G(SCH_1):GND   I352 @T6G_MB_LIB.T6G(SCH_1):PAGE88
   197    GND @T6G_MB_LIB.T6G(SCH_1):GND   I352 @T6G_MB_LIB.T6G(SCH_1):PAGE88
   199    GND @T6G_MB_LIB.T6G(SCH_1):GND   I352 @T6G_MB_LIB.T6G(SCH_1):PAGE88
   202    GND @T6G_MB_LIB.T6G(SCH_1):GND   I352 @T6G_MB_LIB.T6G(SCH_1):PAGE88
   204    GND @T6G_MB_LIB.T6G(SCH_1):GND   I352 @T6G_MB_LIB.T6G(SCH_1):PAGE88
   206    GND @T6G_MB_LIB.T6G(SCH_1):GND   I352 @T6G_MB_LIB.T6G(SCH_1):PAGE88
   208    GND @T6G_MB_LIB.T6G(SCH_1):GND   I352 @T6G_MB_LIB.T6G(SCH_1):PAGE88
   210    GND @T6G_MB_LIB.T6G(SCH_1):GND   I352 @T6G_MB_LIB.T6G(SCH_1):PAGE88
   212    GND @T6G_MB_LIB.T6G(SCH_1):GND   I352 @T6G_MB_LIB.T6G(SCH_1):PAGE88
   214    GND @T6G_MB_LIB.T6G(SCH_1):GND   I352 @T6G_MB_LIB.T6G(SCH_1):PAGE88
   216    GND @T6G_MB_LIB.T6G(SCH_1):GND   I352 @T6G_MB_LIB.T6G(SCH_1):PAGE88
   219    GND @T6G_MB_LIB.T6G(SCH_1):GND   I352 @T6G_MB_LIB.T6G(SCH_1):PAGE88
   222    GND @T6G_MB_LIB.T6G(SCH_1):GND   I352 @T6G_MB_LIB.T6G(SCH_1):PAGE88
   224    GND @T6G_MB_LIB.T6G(SCH_1):GND   I352 @T6G_MB_LIB.T6G(SCH_1):PAGE88
   226    GND @T6G_MB_LIB.T6G(SCH_1):GND   I352 @T6G_MB_LIB.T6G(SCH_1):PAGE88
   228    GND @T6G_MB_LIB.T6G(SCH_1):GND   I352 @T6G_MB_LIB.T6G(SCH_1):PAGE88
   233    GND @T6G_MB_LIB.T6G(SCH_1):GND   I352 @T6G_MB_LIB.T6G(SCH_1):PAGE88
   237    GND @T6G_MB_LIB.T6G(SCH_1):GND   I352 @T6G_MB_LIB.T6G(SCH_1):PAGE88
   242    GND @T6G_MB_LIB.T6G(SCH_1):GND   I352 @T6G_MB_LIB.T6G(SCH_1):PAGE88
   244    GND @T6G_MB_LIB.T6G(SCH_1):GND   I352 @T6G_MB_LIB.T6G(SCH_1):PAGE88
   246    GND @T6G_MB_LIB.T6G(SCH_1):GND   I352 @T6G_MB_LIB.T6G(SCH_1):PAGE88
   248    GND @T6G_MB_LIB.T6G(SCH_1):GND   I352 @T6G_MB_LIB.T6G(SCH_1):PAGE88
   251    GND @T6G_MB_LIB.T6G(SCH_1):GND   I352 @T6G_MB_LIB.T6G(SCH_1):PAGE88
   253    GND @T6G_MB_LIB.T6G(SCH_1):GND   I352 @T6G_MB_LIB.T6G(SCH_1):PAGE88
   255    GND @T6G_MB_LIB.T6G(SCH_1):GND   I352 @T6G_MB_LIB.T6G(SCH_1):PAGE88
   257    GND @T6G_MB_LIB.T6G(SCH_1):GND   I352 @T6G_MB_LIB.T6G(SCH_1):PAGE88
   259    GND @T6G_MB_LIB.T6G(SCH_1):GND   I352 @T6G_MB_LIB.T6G(SCH_1):PAGE88
   262    GND @T6G_MB_LIB.T6G(SCH_1):GND   I352 @T6G_MB_LIB.T6G(SCH_1):PAGE88
   264    GND @T6G_MB_LIB.T6G(SCH_1):GND   I352 @T6G_MB_LIB.T6G(SCH_1):PAGE88
   266    GND @T6G_MB_LIB.T6G(SCH_1):GND   I352 @T6G_MB_LIB.T6G(SCH_1):PAGE88
   268    GND @T6G_MB_LIB.T6G(SCH_1):GND   I352 @T6G_MB_LIB.T6G(SCH_1):PAGE88
   270    GND @T6G_MB_LIB.T6G(SCH_1):GND   I352 @T6G_MB_LIB.T6G(SCH_1):PAGE88
   273    GND @T6G_MB_LIB.T6G(SCH_1):GND   I352 @T6G_MB_LIB.T6G(SCH_1):PAGE88
   275    GND @T6G_MB_LIB.T6G(SCH_1):GND   I352 @T6G_MB_LIB.T6G(SCH_1):PAGE88
   277    GND @T6G_MB_LIB.T6G(SCH_1):GND   I352 @T6G_MB_LIB.T6G(SCH_1):PAGE88
   279    GND @T6G_MB_LIB.T6G(SCH_1):GND   I352 @T6G_MB_LIB.T6G(SCH_1):PAGE88
   281    GND @T6G_MB_LIB.T6G(SCH_1):GND   I352 @T6G_MB_LIB.T6G(SCH_1):PAGE88
   284    GND @T6G_MB_LIB.T6G(SCH_1):GND   I352 @T6G_MB_LIB.T6G(SCH_1):PAGE88
   286    GND @T6G_MB_LIB.T6G(SCH_1):GND   I352 @T6G_MB_LIB.T6G(SCH_1):PAGE88
   288    GND @T6G_MB_LIB.T6G(SCH_1):GND   I352 @T6G_MB_LIB.T6G(SCH_1):PAGE88
     1 P12V_MEM_CPU0 @T6G_MB_LIB.T6G(SCH_1):P12V_MEM_CPU0   I352 @T6G_MB_LIB.T6G(SCH_1):PAGE88
   145 P12V_MEM_CPU0 @T6G_MB_LIB.T6G(SCH_1):P12V_MEM_CPU0   I352 @T6G_MB_LIB.T6G(SCH_1):PAGE88
   146 P12V_MEM_CPU0 @T6G_MB_LIB.T6G(SCH_1):P12V_MEM_CPU0   I352 @T6G_MB_LIB.T6G(SCH_1):PAGE88
   230    GND @T6G_MB_LIB.T6G(SCH_1):GND   I352 @T6G_MB_LIB.T6G(SCH_1):PAGE88
   235    GND @T6G_MB_LIB.T6G(SCH_1):GND   I352 @T6G_MB_LIB.T6G(SCH_1):PAGE88
   240    GND @T6G_MB_LIB.T6G(SCH_1):GND   I352 @T6G_MB_LIB.T6G(SCH_1):PAGE88
   132    GND @T6G_MB_LIB.T6G(SCH_1):GND   I352 @T6G_MB_LIB.T6G(SCH_1):PAGE88
   136    GND @T6G_MB_LIB.T6G(SCH_1):GND   I352 @T6G_MB_LIB.T6G(SCH_1):PAGE88
   139    GND @T6G_MB_LIB.T6G(SCH_1):GND   I352 @T6G_MB_LIB.T6G(SCH_1):PAGE88
   141    GND @T6G_MB_LIB.T6G(SCH_1):GND   I352 @T6G_MB_LIB.T6G(SCH_1):PAGE88
    G1    GND @T6G_MB_LIB.T6G(SCH_1):GND   I352 @T6G_MB_LIB.T6G(SCH_1):PAGE88
    G2    GND @T6G_MB_LIB.T6G(SCH_1):GND   I352 @T6G_MB_LIB.T6G(SCH_1):PAGE88
    G3    GND @T6G_MB_LIB.T6G(SCH_1):GND   I352 @T6G_MB_LIB.T6G(SCH_1):PAGE88

 J20 SCONN288_DDR506112002KQ-SCONN288_DDR506112002KQ,SMA
     3 P3V3_AUX @T6G_MB_LIB.T6G(SCH_1):P3V3_AUX    I22 @T6G_MB_LIB.T6G(SCH_1):PAGE95
     2     NC     NC    I22 @T6G_MB_LIB.T6G(SCH_1):PAGE95
   144     NC     NC    I22 @T6G_MB_LIB.T6G(SCH_1):PAGE95
   149     NC     NC    I22 @T6G_MB_LIB.T6G(SCH_1):PAGE95
   150     NC     NC    I22 @T6G_MB_LIB.T6G(SCH_1):PAGE95
   220     NC     NC    I22 @T6G_MB_LIB.T6G(SCH_1):PAGE95
   231     NC     NC    I22 @T6G_MB_LIB.T6G(SCH_1):PAGE95
   232     NC     NC    I22 @T6G_MB_LIB.T6G(SCH_1):PAGE95
   207 M_K_CPU0_RESET_N @T6G_MB_LIB.T6G(SCH_1):M_K_CPU0_RESET_N    I22 @T6G_MB_LIB.T6G(SCH_1):PAGE95
   147 PWRGD_CHK_CPU0_DIMM @T6G_MB_LIB.T6G(SCH_1):PWRGD_CHK_CPU0_DIMM    I22 @T6G_MB_LIB.T6G(SCH_1):PAGE95
   227 M_K_CPU0_SB_PAR @T6G_MB_LIB.T6G(SCH_1):M_K_CPU0_SB_PAR    I22 @T6G_MB_LIB.T6G(SCH_1):PAGE95
    74 M_K_CPU0_SA_PAR @T6G_MB_LIB.T6G(SCH_1):M_K_CPU0_SA_PAR    I22 @T6G_MB_LIB.T6G(SCH_1):PAGE95
    87 M_K_CPU0_SB_RSP<0> @T6G_MB_LIB.T6G(SCH_1):M_K_CPU0_SB_RSP(0)    I22 @T6G_MB_LIB.T6G(SCH_1):PAGE95
    86 M_K_CPU0_SA_RSP<0> @T6G_MB_LIB.T6G(SCH_1):M_K_CPU0_SA_RSP(0)    I22 @T6G_MB_LIB.T6G(SCH_1):PAGE95
     5 I3C_SPD_DDRK_CPU0_SDA @T6G_MB_LIB.T6G(SCH_1):I3C_SPD_DDRK_CPU0_SDA    I22 @T6G_MB_LIB.T6G(SCH_1):PAGE95
     4 I3C_SPD_DDRK_CPU0_SCL @T6G_MB_LIB.T6G(SCH_1):I3C_SPD_DDRK_CPU0_SCL    I22 @T6G_MB_LIB.T6G(SCH_1):PAGE95
   148 PD_CHK_CPU0_DIMM_SAA @T6G_MB_LIB.T6G(SCH_1):PD_CHK_CPU0_DIMM_SAA    I22 @T6G_MB_LIB.T6G(SCH_1):PAGE95
   100 M_K_CPU0_SB_DQ<0> @T6G_MB_LIB.T6G(SCH_1):M_K_CPU0_SB_DQ(0)    I22 @T6G_MB_LIB.T6G(SCH_1):PAGE95
   102 M_K_CPU0_SB_DQ<1> @T6G_MB_LIB.T6G(SCH_1):M_K_CPU0_SB_DQ(1)    I22 @T6G_MB_LIB.T6G(SCH_1):PAGE95
   245 M_K_CPU0_SB_DQ<2> @T6G_MB_LIB.T6G(SCH_1):M_K_CPU0_SB_DQ(2)    I22 @T6G_MB_LIB.T6G(SCH_1):PAGE95
   247 M_K_CPU0_SB_DQ<3> @T6G_MB_LIB.T6G(SCH_1):M_K_CPU0_SB_DQ(3)    I22 @T6G_MB_LIB.T6G(SCH_1):PAGE95
   107 M_K_CPU0_SB_DQ<4> @T6G_MB_LIB.T6G(SCH_1):M_K_CPU0_SB_DQ(4)    I22 @T6G_MB_LIB.T6G(SCH_1):PAGE95
   109 M_K_CPU0_SB_DQ<5> @T6G_MB_LIB.T6G(SCH_1):M_K_CPU0_SB_DQ(5)    I22 @T6G_MB_LIB.T6G(SCH_1):PAGE95
   252 M_K_CPU0_SB_DQ<6> @T6G_MB_LIB.T6G(SCH_1):M_K_CPU0_SB_DQ(6)    I22 @T6G_MB_LIB.T6G(SCH_1):PAGE95
   254 M_K_CPU0_SB_DQ<7> @T6G_MB_LIB.T6G(SCH_1):M_K_CPU0_SB_DQ(7)    I22 @T6G_MB_LIB.T6G(SCH_1):PAGE95
   111 M_K_CPU0_SB_DQ<8> @T6G_MB_LIB.T6G(SCH_1):M_K_CPU0_SB_DQ(8)    I22 @T6G_MB_LIB.T6G(SCH_1):PAGE95
   113 M_K_CPU0_SB_DQ<9> @T6G_MB_LIB.T6G(SCH_1):M_K_CPU0_SB_DQ(9)    I22 @T6G_MB_LIB.T6G(SCH_1):PAGE95
   256 M_K_CPU0_SB_DQ<10> @T6G_MB_LIB.T6G(SCH_1):M_K_CPU0_SB_DQ(10)    I22 @T6G_MB_LIB.T6G(SCH_1):PAGE95
   258 M_K_CPU0_SB_DQ<11> @T6G_MB_LIB.T6G(SCH_1):M_K_CPU0_SB_DQ(11)    I22 @T6G_MB_LIB.T6G(SCH_1):PAGE95
   118 M_K_CPU0_SB_DQ<12> @T6G_MB_LIB.T6G(SCH_1):M_K_CPU0_SB_DQ(12)    I22 @T6G_MB_LIB.T6G(SCH_1):PAGE95
   120 M_K_CPU0_SB_DQ<13> @T6G_MB_LIB.T6G(SCH_1):M_K_CPU0_SB_DQ(13)    I22 @T6G_MB_LIB.T6G(SCH_1):PAGE95
   263 M_K_CPU0_SB_DQ<14> @T6G_MB_LIB.T6G(SCH_1):M_K_CPU0_SB_DQ(14)    I22 @T6G_MB_LIB.T6G(SCH_1):PAGE95
   265 M_K_CPU0_SB_DQ<15> @T6G_MB_LIB.T6G(SCH_1):M_K_CPU0_SB_DQ(15)    I22 @T6G_MB_LIB.T6G(SCH_1):PAGE95
   122 M_K_CPU0_SB_DQ<16> @T6G_MB_LIB.T6G(SCH_1):M_K_CPU0_SB_DQ(16)    I22 @T6G_MB_LIB.T6G(SCH_1):PAGE95
   124 M_K_CPU0_SB_DQ<17> @T6G_MB_LIB.T6G(SCH_1):M_K_CPU0_SB_DQ(17)    I22 @T6G_MB_LIB.T6G(SCH_1):PAGE95
   267 M_K_CPU0_SB_DQ<18> @T6G_MB_LIB.T6G(SCH_1):M_K_CPU0_SB_DQ(18)    I22 @T6G_MB_LIB.T6G(SCH_1):PAGE95
   269 M_K_CPU0_SB_DQ<19> @T6G_MB_LIB.T6G(SCH_1):M_K_CPU0_SB_DQ(19)    I22 @T6G_MB_LIB.T6G(SCH_1):PAGE95
   129 M_K_CPU0_SB_DQ<20> @T6G_MB_LIB.T6G(SCH_1):M_K_CPU0_SB_DQ(20)    I22 @T6G_MB_LIB.T6G(SCH_1):PAGE95
   131 M_K_CPU0_SB_DQ<21> @T6G_MB_LIB.T6G(SCH_1):M_K_CPU0_SB_DQ(21)    I22 @T6G_MB_LIB.T6G(SCH_1):PAGE95
   274 M_K_CPU0_SB_DQ<22> @T6G_MB_LIB.T6G(SCH_1):M_K_CPU0_SB_DQ(22)    I22 @T6G_MB_LIB.T6G(SCH_1):PAGE95
   276 M_K_CPU0_SB_DQ<23> @T6G_MB_LIB.T6G(SCH_1):M_K_CPU0_SB_DQ(23)    I22 @T6G_MB_LIB.T6G(SCH_1):PAGE95
   133 M_K_CPU0_SB_DQ<24> @T6G_MB_LIB.T6G(SCH_1):M_K_CPU0_SB_DQ(24)    I22 @T6G_MB_LIB.T6G(SCH_1):PAGE95
   135 M_K_CPU0_SB_DQ<25> @T6G_MB_LIB.T6G(SCH_1):M_K_CPU0_SB_DQ(25)    I22 @T6G_MB_LIB.T6G(SCH_1):PAGE95
   278 M_K_CPU0_SB_DQ<26> @T6G_MB_LIB.T6G(SCH_1):M_K_CPU0_SB_DQ(26)    I22 @T6G_MB_LIB.T6G(SCH_1):PAGE95
   280 M_K_CPU0_SB_DQ<27> @T6G_MB_LIB.T6G(SCH_1):M_K_CPU0_SB_DQ(27)    I22 @T6G_MB_LIB.T6G(SCH_1):PAGE95
   140 M_K_CPU0_SB_DQ<28> @T6G_MB_LIB.T6G(SCH_1):M_K_CPU0_SB_DQ(28)    I22 @T6G_MB_LIB.T6G(SCH_1):PAGE95
   142 M_K_CPU0_SB_DQ<29> @T6G_MB_LIB.T6G(SCH_1):M_K_CPU0_SB_DQ(29)    I22 @T6G_MB_LIB.T6G(SCH_1):PAGE95
   285 M_K_CPU0_SB_DQ<30> @T6G_MB_LIB.T6G(SCH_1):M_K_CPU0_SB_DQ(30)    I22 @T6G_MB_LIB.T6G(SCH_1):PAGE95
   287 M_K_CPU0_SB_DQ<31> @T6G_MB_LIB.T6G(SCH_1):M_K_CPU0_SB_DQ(31)    I22 @T6G_MB_LIB.T6G(SCH_1):PAGE95
     7 M_K_CPU0_SA_DQ<0> @T6G_MB_LIB.T6G(SCH_1):M_K_CPU0_SA_DQ(0)    I22 @T6G_MB_LIB.T6G(SCH_1):PAGE95
     9 M_K_CPU0_SA_DQ<1> @T6G_MB_LIB.T6G(SCH_1):M_K_CPU0_SA_DQ(1)    I22 @T6G_MB_LIB.T6G(SCH_1):PAGE95
   152 M_K_CPU0_SA_DQ<2> @T6G_MB_LIB.T6G(SCH_1):M_K_CPU0_SA_DQ(2)    I22 @T6G_MB_LIB.T6G(SCH_1):PAGE95
   154 M_K_CPU0_SA_DQ<3> @T6G_MB_LIB.T6G(SCH_1):M_K_CPU0_SA_DQ(3)    I22 @T6G_MB_LIB.T6G(SCH_1):PAGE95
    14 M_K_CPU0_SA_DQ<4> @T6G_MB_LIB.T6G(SCH_1):M_K_CPU0_SA_DQ(4)    I22 @T6G_MB_LIB.T6G(SCH_1):PAGE95
    16 M_K_CPU0_SA_DQ<5> @T6G_MB_LIB.T6G(SCH_1):M_K_CPU0_SA_DQ(5)    I22 @T6G_MB_LIB.T6G(SCH_1):PAGE95
   159 M_K_CPU0_SA_DQ<6> @T6G_MB_LIB.T6G(SCH_1):M_K_CPU0_SA_DQ(6)    I22 @T6G_MB_LIB.T6G(SCH_1):PAGE95
   161 M_K_CPU0_SA_DQ<7> @T6G_MB_LIB.T6G(SCH_1):M_K_CPU0_SA_DQ(7)    I22 @T6G_MB_LIB.T6G(SCH_1):PAGE95
    18 M_K_CPU0_SA_DQ<8> @T6G_MB_LIB.T6G(SCH_1):M_K_CPU0_SA_DQ(8)    I22 @T6G_MB_LIB.T6G(SCH_1):PAGE95
    20 M_K_CPU0_SA_DQ<9> @T6G_MB_LIB.T6G(SCH_1):M_K_CPU0_SA_DQ(9)    I22 @T6G_MB_LIB.T6G(SCH_1):PAGE95
   163 M_K_CPU0_SA_DQ<10> @T6G_MB_LIB.T6G(SCH_1):M_K_CPU0_SA_DQ(10)    I22 @T6G_MB_LIB.T6G(SCH_1):PAGE95
   165 M_K_CPU0_SA_DQ<11> @T6G_MB_LIB.T6G(SCH_1):M_K_CPU0_SA_DQ(11)    I22 @T6G_MB_LIB.T6G(SCH_1):PAGE95
    25 M_K_CPU0_SA_DQ<12> @T6G_MB_LIB.T6G(SCH_1):M_K_CPU0_SA_DQ(12)    I22 @T6G_MB_LIB.T6G(SCH_1):PAGE95
    27 M_K_CPU0_SA_DQ<13> @T6G_MB_LIB.T6G(SCH_1):M_K_CPU0_SA_DQ(13)    I22 @T6G_MB_LIB.T6G(SCH_1):PAGE95
   170 M_K_CPU0_SA_DQ<14> @T6G_MB_LIB.T6G(SCH_1):M_K_CPU0_SA_DQ(14)    I22 @T6G_MB_LIB.T6G(SCH_1):PAGE95
   172 M_K_CPU0_SA_DQ<15> @T6G_MB_LIB.T6G(SCH_1):M_K_CPU0_SA_DQ(15)    I22 @T6G_MB_LIB.T6G(SCH_1):PAGE95
    29 M_K_CPU0_SA_DQ<16> @T6G_MB_LIB.T6G(SCH_1):M_K_CPU0_SA_DQ(16)    I22 @T6G_MB_LIB.T6G(SCH_1):PAGE95
    31 M_K_CPU0_SA_DQ<17> @T6G_MB_LIB.T6G(SCH_1):M_K_CPU0_SA_DQ(17)    I22 @T6G_MB_LIB.T6G(SCH_1):PAGE95
   174 M_K_CPU0_SA_DQ<18> @T6G_MB_LIB.T6G(SCH_1):M_K_CPU0_SA_DQ(18)    I22 @T6G_MB_LIB.T6G(SCH_1):PAGE95
   176 M_K_CPU0_SA_DQ<19> @T6G_MB_LIB.T6G(SCH_1):M_K_CPU0_SA_DQ(19)    I22 @T6G_MB_LIB.T6G(SCH_1):PAGE95
    36 M_K_CPU0_SA_DQ<20> @T6G_MB_LIB.T6G(SCH_1):M_K_CPU0_SA_DQ(20)    I22 @T6G_MB_LIB.T6G(SCH_1):PAGE95
    38 M_K_CPU0_SA_DQ<21> @T6G_MB_LIB.T6G(SCH_1):M_K_CPU0_SA_DQ(21)    I22 @T6G_MB_LIB.T6G(SCH_1):PAGE95
   181 M_K_CPU0_SA_DQ<22> @T6G_MB_LIB.T6G(SCH_1):M_K_CPU0_SA_DQ(22)    I22 @T6G_MB_LIB.T6G(SCH_1):PAGE95
   183 M_K_CPU0_SA_DQ<23> @T6G_MB_LIB.T6G(SCH_1):M_K_CPU0_SA_DQ(23)    I22 @T6G_MB_LIB.T6G(SCH_1):PAGE95
    40 M_K_CPU0_SA_DQ<24> @T6G_MB_LIB.T6G(SCH_1):M_K_CPU0_SA_DQ(24)    I22 @T6G_MB_LIB.T6G(SCH_1):PAGE95
    42 M_K_CPU0_SA_DQ<25> @T6G_MB_LIB.T6G(SCH_1):M_K_CPU0_SA_DQ(25)    I22 @T6G_MB_LIB.T6G(SCH_1):PAGE95
   185 M_K_CPU0_SA_DQ<26> @T6G_MB_LIB.T6G(SCH_1):M_K_CPU0_SA_DQ(26)    I22 @T6G_MB_LIB.T6G(SCH_1):PAGE95
   187 M_K_CPU0_SA_DQ<27> @T6G_MB_LIB.T6G(SCH_1):M_K_CPU0_SA_DQ(27)    I22 @T6G_MB_LIB.T6G(SCH_1):PAGE95
    47 M_K_CPU0_SA_DQ<28> @T6G_MB_LIB.T6G(SCH_1):M_K_CPU0_SA_DQ(28)    I22 @T6G_MB_LIB.T6G(SCH_1):PAGE95
    49 M_K_CPU0_SA_DQ<29> @T6G_MB_LIB.T6G(SCH_1):M_K_CPU0_SA_DQ(29)    I22 @T6G_MB_LIB.T6G(SCH_1):PAGE95
   192 M_K_CPU0_SA_DQ<30> @T6G_MB_LIB.T6G(SCH_1):M_K_CPU0_SA_DQ(30)    I22 @T6G_MB_LIB.T6G(SCH_1):PAGE95
   229 M_K_CPU0_SB_CS_N<1> @T6G_MB_LIB.T6G(SCH_1):M_K_CPU0_SB_CS_N(1)    I22 @T6G_MB_LIB.T6G(SCH_1):PAGE95
   209 M_K_CPU0_SA_CS_N<1> @T6G_MB_LIB.T6G(SCH_1):M_K_CPU0_SA_CS_N(1)    I22 @T6G_MB_LIB.T6G(SCH_1):PAGE95
    84 M_K_CPU0_SB_CS_N<0> @T6G_MB_LIB.T6G(SCH_1):M_K_CPU0_SB_CS_N(0)    I22 @T6G_MB_LIB.T6G(SCH_1):PAGE95
    64 M_K_CPU0_SA_CS_N<0> @T6G_MB_LIB.T6G(SCH_1):M_K_CPU0_SA_CS_N(0)    I22 @T6G_MB_LIB.T6G(SCH_1):PAGE95
   217 M_K_CPU0_CLK_DP<0> @T6G_MB_LIB.T6G(SCH_1):M_K_CPU0_CLK_DP(0)    I22 @T6G_MB_LIB.T6G(SCH_1):PAGE95
   218 M_K_CPU0_CLK_DN<0> @T6G_MB_LIB.T6G(SCH_1):M_K_CPU0_CLK_DN(0)    I22 @T6G_MB_LIB.T6G(SCH_1):PAGE95
    96 M_K_CPU0_SB_CB<0> @T6G_MB_LIB.T6G(SCH_1):M_K_CPU0_SB_CB(0)    I22 @T6G_MB_LIB.T6G(SCH_1):PAGE95
    98 M_K_CPU0_SB_CB<1> @T6G_MB_LIB.T6G(SCH_1):M_K_CPU0_SB_CB(1)    I22 @T6G_MB_LIB.T6G(SCH_1):PAGE95
   241 M_K_CPU0_SB_CB<2> @T6G_MB_LIB.T6G(SCH_1):M_K_CPU0_SB_CB(2)    I22 @T6G_MB_LIB.T6G(SCH_1):PAGE95
   243 M_K_CPU0_SB_CB<3> @T6G_MB_LIB.T6G(SCH_1):M_K_CPU0_SB_CB(3)    I22 @T6G_MB_LIB.T6G(SCH_1):PAGE95
    89 M_K_CPU0_SB_CB<4> @T6G_MB_LIB.T6G(SCH_1):M_K_CPU0_SB_CB(4)    I22 @T6G_MB_LIB.T6G(SCH_1):PAGE95
    91 M_K_CPU0_SB_CB<5> @T6G_MB_LIB.T6G(SCH_1):M_K_CPU0_SB_CB(5)    I22 @T6G_MB_LIB.T6G(SCH_1):PAGE95
   234 M_K_CPU0_SB_CB<6> @T6G_MB_LIB.T6G(SCH_1):M_K_CPU0_SB_CB(6)    I22 @T6G_MB_LIB.T6G(SCH_1):PAGE95
    51 M_K_CPU0_SA_CB<0> @T6G_MB_LIB.T6G(SCH_1):M_K_CPU0_SA_CB(0)    I22 @T6G_MB_LIB.T6G(SCH_1):PAGE95
   196 M_K_CPU0_SA_CB<2> @T6G_MB_LIB.T6G(SCH_1):M_K_CPU0_SA_CB(2)    I22 @T6G_MB_LIB.T6G(SCH_1):PAGE95
   198 M_K_CPU0_SA_CB<3> @T6G_MB_LIB.T6G(SCH_1):M_K_CPU0_SA_CB(3)    I22 @T6G_MB_LIB.T6G(SCH_1):PAGE95
    60 M_K_CPU0_SA_CB<5> @T6G_MB_LIB.T6G(SCH_1):M_K_CPU0_SA_CB(5)    I22 @T6G_MB_LIB.T6G(SCH_1):PAGE95
   203 M_K_CPU0_SA_CB<6> @T6G_MB_LIB.T6G(SCH_1):M_K_CPU0_SA_CB(6)    I22 @T6G_MB_LIB.T6G(SCH_1):PAGE95
    82 M_K_CPU0_SB_CA<6> @T6G_MB_LIB.T6G(SCH_1):M_K_CPU0_SB_CA(6)    I22 @T6G_MB_LIB.T6G(SCH_1):PAGE95
    72 M_K_CPU0_SA_CA<6> @T6G_MB_LIB.T6G(SCH_1):M_K_CPU0_SA_CA(6)    I22 @T6G_MB_LIB.T6G(SCH_1):PAGE95
   225 M_K_CPU0_SB_CA<5> @T6G_MB_LIB.T6G(SCH_1):M_K_CPU0_SB_CA(5)    I22 @T6G_MB_LIB.T6G(SCH_1):PAGE95
   215 M_K_CPU0_SA_CA<5> @T6G_MB_LIB.T6G(SCH_1):M_K_CPU0_SA_CA(5)    I22 @T6G_MB_LIB.T6G(SCH_1):PAGE95
    80 M_K_CPU0_SB_CA<4> @T6G_MB_LIB.T6G(SCH_1):M_K_CPU0_SB_CA(4)    I22 @T6G_MB_LIB.T6G(SCH_1):PAGE95
    70 M_K_CPU0_SA_CA<4> @T6G_MB_LIB.T6G(SCH_1):M_K_CPU0_SA_CA(4)    I22 @T6G_MB_LIB.T6G(SCH_1):PAGE95
   223 M_K_CPU0_SB_CA<3> @T6G_MB_LIB.T6G(SCH_1):M_K_CPU0_SB_CA(3)    I22 @T6G_MB_LIB.T6G(SCH_1):PAGE95
   213 M_K_CPU0_SA_CA<3> @T6G_MB_LIB.T6G(SCH_1):M_K_CPU0_SA_CA(3)    I22 @T6G_MB_LIB.T6G(SCH_1):PAGE95
    78 M_K_CPU0_SB_CA<2> @T6G_MB_LIB.T6G(SCH_1):M_K_CPU0_SB_CA(2)    I22 @T6G_MB_LIB.T6G(SCH_1):PAGE95
    68 M_K_CPU0_SA_CA<2> @T6G_MB_LIB.T6G(SCH_1):M_K_CPU0_SA_CA(2)    I22 @T6G_MB_LIB.T6G(SCH_1):PAGE95
   221 M_K_CPU0_SB_CA<1> @T6G_MB_LIB.T6G(SCH_1):M_K_CPU0_SB_CA(1)    I22 @T6G_MB_LIB.T6G(SCH_1):PAGE95
   211 M_K_CPU0_SA_CA<1> @T6G_MB_LIB.T6G(SCH_1):M_K_CPU0_SA_CA(1)    I22 @T6G_MB_LIB.T6G(SCH_1):PAGE95
    76 M_K_CPU0_SB_CA<0> @T6G_MB_LIB.T6G(SCH_1):M_K_CPU0_SB_CA(0)    I22 @T6G_MB_LIB.T6G(SCH_1):PAGE95
    66 M_K_CPU0_SA_CA<0> @T6G_MB_LIB.T6G(SCH_1):M_K_CPU0_SA_CA(0)    I22 @T6G_MB_LIB.T6G(SCH_1):PAGE95
    62 M_K_CPU0_ALERT_N @T6G_MB_LIB.T6G(SCH_1):M_K_CPU0_ALERT_N    I22 @T6G_MB_LIB.T6G(SCH_1):PAGE95
   236 M_K_CPU0_SB_CB<7> @T6G_MB_LIB.T6G(SCH_1):M_K_CPU0_SB_CB(7)    I22 @T6G_MB_LIB.T6G(SCH_1):PAGE95
    53 M_K_CPU0_SA_CB<1> @T6G_MB_LIB.T6G(SCH_1):M_K_CPU0_SA_CB(1)    I22 @T6G_MB_LIB.T6G(SCH_1):PAGE95
    58 M_K_CPU0_SA_CB<4> @T6G_MB_LIB.T6G(SCH_1):M_K_CPU0_SA_CB(4)    I22 @T6G_MB_LIB.T6G(SCH_1):PAGE95
   205 M_K_CPU0_SA_CB<7> @T6G_MB_LIB.T6G(SCH_1):M_K_CPU0_SA_CB(7)    I22 @T6G_MB_LIB.T6G(SCH_1):PAGE95
   194 M_K_CPU0_SA_DQ<31> @T6G_MB_LIB.T6G(SCH_1):M_K_CPU0_SA_DQ(31)    I22 @T6G_MB_LIB.T6G(SCH_1):PAGE95
    93 M_K_CPU0_SB_DQS_DP<9> @T6G_MB_LIB.T6G(SCH_1):M_K_CPU0_SB_DQS_DP(9)   I236 @T6G_MB_LIB.T6G(SCH_1):PAGE95
    94 M_K_CPU0_SB_DQS_DN<9> @T6G_MB_LIB.T6G(SCH_1):M_K_CPU0_SB_DQS_DN(9)   I236 @T6G_MB_LIB.T6G(SCH_1):PAGE95
   201 M_K_CPU0_SA_DQS_DP<9> @T6G_MB_LIB.T6G(SCH_1):M_K_CPU0_SA_DQS_DP(9)   I236 @T6G_MB_LIB.T6G(SCH_1):PAGE95
   200 M_K_CPU0_SA_DQS_DN<9> @T6G_MB_LIB.T6G(SCH_1):M_K_CPU0_SA_DQS_DN(9)   I236 @T6G_MB_LIB.T6G(SCH_1):PAGE95
   190 M_K_CPU0_SA_DQS_DP<8> @T6G_MB_LIB.T6G(SCH_1):M_K_CPU0_SA_DQS_DP(8)   I236 @T6G_MB_LIB.T6G(SCH_1):PAGE95
   189 M_K_CPU0_SA_DQS_DN<8> @T6G_MB_LIB.T6G(SCH_1):M_K_CPU0_SA_DQS_DN(8)   I236 @T6G_MB_LIB.T6G(SCH_1):PAGE95
   271 M_K_CPU0_SB_DQS_DN<7> @T6G_MB_LIB.T6G(SCH_1):M_K_CPU0_SB_DQS_DN(7)   I236 @T6G_MB_LIB.T6G(SCH_1):PAGE95
   179 M_K_CPU0_SA_DQS_DP<7> @T6G_MB_LIB.T6G(SCH_1):M_K_CPU0_SA_DQS_DP(7)   I236 @T6G_MB_LIB.T6G(SCH_1):PAGE95
   261 M_K_CPU0_SB_DQS_DP<6> @T6G_MB_LIB.T6G(SCH_1):M_K_CPU0_SB_DQS_DP(6)   I236 @T6G_MB_LIB.T6G(SCH_1):PAGE95
   260 M_K_CPU0_SB_DQS_DN<6> @T6G_MB_LIB.T6G(SCH_1):M_K_CPU0_SB_DQS_DN(6)   I236 @T6G_MB_LIB.T6G(SCH_1):PAGE95
   167 M_K_CPU0_SA_DQS_DN<6> @T6G_MB_LIB.T6G(SCH_1):M_K_CPU0_SA_DQS_DN(6)   I236 @T6G_MB_LIB.T6G(SCH_1):PAGE95
   250 M_K_CPU0_SB_DQS_DP<5> @T6G_MB_LIB.T6G(SCH_1):M_K_CPU0_SB_DQS_DP(5)   I236 @T6G_MB_LIB.T6G(SCH_1):PAGE95
   249 M_K_CPU0_SB_DQS_DN<5> @T6G_MB_LIB.T6G(SCH_1):M_K_CPU0_SB_DQS_DN(5)   I236 @T6G_MB_LIB.T6G(SCH_1):PAGE95
   157 M_K_CPU0_SA_DQS_DP<5> @T6G_MB_LIB.T6G(SCH_1):M_K_CPU0_SA_DQS_DP(5)   I236 @T6G_MB_LIB.T6G(SCH_1):PAGE95
   156 M_K_CPU0_SA_DQS_DN<5> @T6G_MB_LIB.T6G(SCH_1):M_K_CPU0_SA_DQS_DN(5)   I236 @T6G_MB_LIB.T6G(SCH_1):PAGE95
   239 M_K_CPU0_SB_DQS_DP<4> @T6G_MB_LIB.T6G(SCH_1):M_K_CPU0_SB_DQS_DP(4)   I236 @T6G_MB_LIB.T6G(SCH_1):PAGE95
   238 M_K_CPU0_SB_DQS_DN<4> @T6G_MB_LIB.T6G(SCH_1):M_K_CPU0_SB_DQS_DN(4)   I236 @T6G_MB_LIB.T6G(SCH_1):PAGE95
    55 M_K_CPU0_SA_DQS_DP<4> @T6G_MB_LIB.T6G(SCH_1):M_K_CPU0_SA_DQS_DP(4)   I236 @T6G_MB_LIB.T6G(SCH_1):PAGE95
    56 M_K_CPU0_SA_DQS_DN<4> @T6G_MB_LIB.T6G(SCH_1):M_K_CPU0_SA_DQS_DN(4)   I236 @T6G_MB_LIB.T6G(SCH_1):PAGE95
   137 M_K_CPU0_SB_DQS_DP<3> @T6G_MB_LIB.T6G(SCH_1):M_K_CPU0_SB_DQS_DP(3)   I236 @T6G_MB_LIB.T6G(SCH_1):PAGE95
   138 M_K_CPU0_SB_DQS_DN<3> @T6G_MB_LIB.T6G(SCH_1):M_K_CPU0_SB_DQS_DN(3)   I236 @T6G_MB_LIB.T6G(SCH_1):PAGE95
    44 M_K_CPU0_SA_DQS_DP<3> @T6G_MB_LIB.T6G(SCH_1):M_K_CPU0_SA_DQS_DP(3)   I236 @T6G_MB_LIB.T6G(SCH_1):PAGE95
    45 M_K_CPU0_SA_DQS_DN<3> @T6G_MB_LIB.T6G(SCH_1):M_K_CPU0_SA_DQS_DN(3)   I236 @T6G_MB_LIB.T6G(SCH_1):PAGE95
   126 M_K_CPU0_SB_DQS_DP<2> @T6G_MB_LIB.T6G(SCH_1):M_K_CPU0_SB_DQS_DP(2)   I236 @T6G_MB_LIB.T6G(SCH_1):PAGE95
   127 M_K_CPU0_SB_DQS_DN<2> @T6G_MB_LIB.T6G(SCH_1):M_K_CPU0_SB_DQS_DN(2)   I236 @T6G_MB_LIB.T6G(SCH_1):PAGE95
    33 M_K_CPU0_SA_DQS_DP<2> @T6G_MB_LIB.T6G(SCH_1):M_K_CPU0_SA_DQS_DP(2)   I236 @T6G_MB_LIB.T6G(SCH_1):PAGE95
    34 M_K_CPU0_SA_DQS_DN<2> @T6G_MB_LIB.T6G(SCH_1):M_K_CPU0_SA_DQS_DN(2)   I236 @T6G_MB_LIB.T6G(SCH_1):PAGE95
   115 M_K_CPU0_SB_DQS_DP<1> @T6G_MB_LIB.T6G(SCH_1):M_K_CPU0_SB_DQS_DP(1)   I236 @T6G_MB_LIB.T6G(SCH_1):PAGE95
   116 M_K_CPU0_SB_DQS_DN<1> @T6G_MB_LIB.T6G(SCH_1):M_K_CPU0_SB_DQS_DN(1)   I236 @T6G_MB_LIB.T6G(SCH_1):PAGE95
    22 M_K_CPU0_SA_DQS_DP<1> @T6G_MB_LIB.T6G(SCH_1):M_K_CPU0_SA_DQS_DP(1)   I236 @T6G_MB_LIB.T6G(SCH_1):PAGE95
    23 M_K_CPU0_SA_DQS_DN<1> @T6G_MB_LIB.T6G(SCH_1):M_K_CPU0_SA_DQS_DN(1)   I236 @T6G_MB_LIB.T6G(SCH_1):PAGE95
   104 M_K_CPU0_SB_DQS_DP<0> @T6G_MB_LIB.T6G(SCH_1):M_K_CPU0_SB_DQS_DP(0)   I236 @T6G_MB_LIB.T6G(SCH_1):PAGE95
   105 M_K_CPU0_SB_DQS_DN<0> @T6G_MB_LIB.T6G(SCH_1):M_K_CPU0_SB_DQS_DN(0)   I236 @T6G_MB_LIB.T6G(SCH_1):PAGE95
    11 M_K_CPU0_SA_DQS_DP<0> @T6G_MB_LIB.T6G(SCH_1):M_K_CPU0_SA_DQS_DP(0)   I236 @T6G_MB_LIB.T6G(SCH_1):PAGE95
    12 M_K_CPU0_SA_DQS_DN<0> @T6G_MB_LIB.T6G(SCH_1):M_K_CPU0_SA_DQS_DN(0)   I236 @T6G_MB_LIB.T6G(SCH_1):PAGE95
   272 M_K_CPU0_SB_DQS_DP<7> @T6G_MB_LIB.T6G(SCH_1):M_K_CPU0_SB_DQS_DP(7)   I236 @T6G_MB_LIB.T6G(SCH_1):PAGE95
   282 M_K_CPU0_SB_DQS_DN<8> @T6G_MB_LIB.T6G(SCH_1):M_K_CPU0_SB_DQS_DN(8)   I236 @T6G_MB_LIB.T6G(SCH_1):PAGE95
   283 M_K_CPU0_SB_DQS_DP<8> @T6G_MB_LIB.T6G(SCH_1):M_K_CPU0_SB_DQS_DP(8)   I236 @T6G_MB_LIB.T6G(SCH_1):PAGE95
   168 M_K_CPU0_SA_DQS_DP<6> @T6G_MB_LIB.T6G(SCH_1):M_K_CPU0_SA_DQS_DP(6)   I236 @T6G_MB_LIB.T6G(SCH_1):PAGE95
   178 M_K_CPU0_SA_DQS_DN<7> @T6G_MB_LIB.T6G(SCH_1):M_K_CPU0_SA_DQS_DN(7)   I236 @T6G_MB_LIB.T6G(SCH_1):PAGE95
     6    GND @T6G_MB_LIB.T6G(SCH_1):GND   I177 @T6G_MB_LIB.T6G(SCH_1):PAGE95
     8    GND @T6G_MB_LIB.T6G(SCH_1):GND   I177 @T6G_MB_LIB.T6G(SCH_1):PAGE95
    10    GND @T6G_MB_LIB.T6G(SCH_1):GND   I177 @T6G_MB_LIB.T6G(SCH_1):PAGE95
    13    GND @T6G_MB_LIB.T6G(SCH_1):GND   I177 @T6G_MB_LIB.T6G(SCH_1):PAGE95
    15    GND @T6G_MB_LIB.T6G(SCH_1):GND   I177 @T6G_MB_LIB.T6G(SCH_1):PAGE95
    17    GND @T6G_MB_LIB.T6G(SCH_1):GND   I177 @T6G_MB_LIB.T6G(SCH_1):PAGE95
    19    GND @T6G_MB_LIB.T6G(SCH_1):GND   I177 @T6G_MB_LIB.T6G(SCH_1):PAGE95
    21    GND @T6G_MB_LIB.T6G(SCH_1):GND   I177 @T6G_MB_LIB.T6G(SCH_1):PAGE95
    24    GND @T6G_MB_LIB.T6G(SCH_1):GND   I177 @T6G_MB_LIB.T6G(SCH_1):PAGE95
    26    GND @T6G_MB_LIB.T6G(SCH_1):GND   I177 @T6G_MB_LIB.T6G(SCH_1):PAGE95
    28    GND @T6G_MB_LIB.T6G(SCH_1):GND   I177 @T6G_MB_LIB.T6G(SCH_1):PAGE95
    30    GND @T6G_MB_LIB.T6G(SCH_1):GND   I177 @T6G_MB_LIB.T6G(SCH_1):PAGE95
    32    GND @T6G_MB_LIB.T6G(SCH_1):GND   I177 @T6G_MB_LIB.T6G(SCH_1):PAGE95
    35    GND @T6G_MB_LIB.T6G(SCH_1):GND   I177 @T6G_MB_LIB.T6G(SCH_1):PAGE95
    37    GND @T6G_MB_LIB.T6G(SCH_1):GND   I177 @T6G_MB_LIB.T6G(SCH_1):PAGE95
    39    GND @T6G_MB_LIB.T6G(SCH_1):GND   I177 @T6G_MB_LIB.T6G(SCH_1):PAGE95
    41    GND @T6G_MB_LIB.T6G(SCH_1):GND   I177 @T6G_MB_LIB.T6G(SCH_1):PAGE95
    43    GND @T6G_MB_LIB.T6G(SCH_1):GND   I177 @T6G_MB_LIB.T6G(SCH_1):PAGE95
    46    GND @T6G_MB_LIB.T6G(SCH_1):GND   I177 @T6G_MB_LIB.T6G(SCH_1):PAGE95
    48    GND @T6G_MB_LIB.T6G(SCH_1):GND   I177 @T6G_MB_LIB.T6G(SCH_1):PAGE95
    50    GND @T6G_MB_LIB.T6G(SCH_1):GND   I177 @T6G_MB_LIB.T6G(SCH_1):PAGE95
    52    GND @T6G_MB_LIB.T6G(SCH_1):GND   I177 @T6G_MB_LIB.T6G(SCH_1):PAGE95
    54    GND @T6G_MB_LIB.T6G(SCH_1):GND   I177 @T6G_MB_LIB.T6G(SCH_1):PAGE95
    57    GND @T6G_MB_LIB.T6G(SCH_1):GND   I177 @T6G_MB_LIB.T6G(SCH_1):PAGE95
    59    GND @T6G_MB_LIB.T6G(SCH_1):GND   I177 @T6G_MB_LIB.T6G(SCH_1):PAGE95
    61    GND @T6G_MB_LIB.T6G(SCH_1):GND   I177 @T6G_MB_LIB.T6G(SCH_1):PAGE95
    63    GND @T6G_MB_LIB.T6G(SCH_1):GND   I177 @T6G_MB_LIB.T6G(SCH_1):PAGE95
    65    GND @T6G_MB_LIB.T6G(SCH_1):GND   I177 @T6G_MB_LIB.T6G(SCH_1):PAGE95
    67    GND @T6G_MB_LIB.T6G(SCH_1):GND   I177 @T6G_MB_LIB.T6G(SCH_1):PAGE95
    69    GND @T6G_MB_LIB.T6G(SCH_1):GND   I177 @T6G_MB_LIB.T6G(SCH_1):PAGE95
    71    GND @T6G_MB_LIB.T6G(SCH_1):GND   I177 @T6G_MB_LIB.T6G(SCH_1):PAGE95
    73    GND @T6G_MB_LIB.T6G(SCH_1):GND   I177 @T6G_MB_LIB.T6G(SCH_1):PAGE95
    75    GND @T6G_MB_LIB.T6G(SCH_1):GND   I177 @T6G_MB_LIB.T6G(SCH_1):PAGE95
    77    GND @T6G_MB_LIB.T6G(SCH_1):GND   I177 @T6G_MB_LIB.T6G(SCH_1):PAGE95
    79    GND @T6G_MB_LIB.T6G(SCH_1):GND   I177 @T6G_MB_LIB.T6G(SCH_1):PAGE95
    81    GND @T6G_MB_LIB.T6G(SCH_1):GND   I177 @T6G_MB_LIB.T6G(SCH_1):PAGE95
    83    GND @T6G_MB_LIB.T6G(SCH_1):GND   I177 @T6G_MB_LIB.T6G(SCH_1):PAGE95
    85    GND @T6G_MB_LIB.T6G(SCH_1):GND   I177 @T6G_MB_LIB.T6G(SCH_1):PAGE95
    88    GND @T6G_MB_LIB.T6G(SCH_1):GND   I177 @T6G_MB_LIB.T6G(SCH_1):PAGE95
    90    GND @T6G_MB_LIB.T6G(SCH_1):GND   I177 @T6G_MB_LIB.T6G(SCH_1):PAGE95
    92    GND @T6G_MB_LIB.T6G(SCH_1):GND   I177 @T6G_MB_LIB.T6G(SCH_1):PAGE95
    95    GND @T6G_MB_LIB.T6G(SCH_1):GND   I177 @T6G_MB_LIB.T6G(SCH_1):PAGE95
    97    GND @T6G_MB_LIB.T6G(SCH_1):GND   I177 @T6G_MB_LIB.T6G(SCH_1):PAGE95
    99    GND @T6G_MB_LIB.T6G(SCH_1):GND   I177 @T6G_MB_LIB.T6G(SCH_1):PAGE95
   101    GND @T6G_MB_LIB.T6G(SCH_1):GND   I177 @T6G_MB_LIB.T6G(SCH_1):PAGE95
   103    GND @T6G_MB_LIB.T6G(SCH_1):GND   I177 @T6G_MB_LIB.T6G(SCH_1):PAGE95
   106    GND @T6G_MB_LIB.T6G(SCH_1):GND   I177 @T6G_MB_LIB.T6G(SCH_1):PAGE95
   108    GND @T6G_MB_LIB.T6G(SCH_1):GND   I177 @T6G_MB_LIB.T6G(SCH_1):PAGE95
   110    GND @T6G_MB_LIB.T6G(SCH_1):GND   I177 @T6G_MB_LIB.T6G(SCH_1):PAGE95
   112    GND @T6G_MB_LIB.T6G(SCH_1):GND   I177 @T6G_MB_LIB.T6G(SCH_1):PAGE95
   114    GND @T6G_MB_LIB.T6G(SCH_1):GND   I177 @T6G_MB_LIB.T6G(SCH_1):PAGE95
   117    GND @T6G_MB_LIB.T6G(SCH_1):GND   I177 @T6G_MB_LIB.T6G(SCH_1):PAGE95
   119    GND @T6G_MB_LIB.T6G(SCH_1):GND   I177 @T6G_MB_LIB.T6G(SCH_1):PAGE95
   121    GND @T6G_MB_LIB.T6G(SCH_1):GND   I177 @T6G_MB_LIB.T6G(SCH_1):PAGE95
   123    GND @T6G_MB_LIB.T6G(SCH_1):GND   I177 @T6G_MB_LIB.T6G(SCH_1):PAGE95
   125    GND @T6G_MB_LIB.T6G(SCH_1):GND   I177 @T6G_MB_LIB.T6G(SCH_1):PAGE95
   128    GND @T6G_MB_LIB.T6G(SCH_1):GND   I177 @T6G_MB_LIB.T6G(SCH_1):PAGE95
   130    GND @T6G_MB_LIB.T6G(SCH_1):GND   I177 @T6G_MB_LIB.T6G(SCH_1):PAGE95
   134    GND @T6G_MB_LIB.T6G(SCH_1):GND   I177 @T6G_MB_LIB.T6G(SCH_1):PAGE95
   143    GND @T6G_MB_LIB.T6G(SCH_1):GND   I177 @T6G_MB_LIB.T6G(SCH_1):PAGE95
   151    GND @T6G_MB_LIB.T6G(SCH_1):GND   I177 @T6G_MB_LIB.T6G(SCH_1):PAGE95
   153    GND @T6G_MB_LIB.T6G(SCH_1):GND   I177 @T6G_MB_LIB.T6G(SCH_1):PAGE95
   155    GND @T6G_MB_LIB.T6G(SCH_1):GND   I177 @T6G_MB_LIB.T6G(SCH_1):PAGE95
   158    GND @T6G_MB_LIB.T6G(SCH_1):GND   I177 @T6G_MB_LIB.T6G(SCH_1):PAGE95
   160    GND @T6G_MB_LIB.T6G(SCH_1):GND   I177 @T6G_MB_LIB.T6G(SCH_1):PAGE95
   162    GND @T6G_MB_LIB.T6G(SCH_1):GND   I177 @T6G_MB_LIB.T6G(SCH_1):PAGE95
   164    GND @T6G_MB_LIB.T6G(SCH_1):GND   I177 @T6G_MB_LIB.T6G(SCH_1):PAGE95
   166    GND @T6G_MB_LIB.T6G(SCH_1):GND   I177 @T6G_MB_LIB.T6G(SCH_1):PAGE95
   169    GND @T6G_MB_LIB.T6G(SCH_1):GND   I177 @T6G_MB_LIB.T6G(SCH_1):PAGE95
   171    GND @T6G_MB_LIB.T6G(SCH_1):GND   I177 @T6G_MB_LIB.T6G(SCH_1):PAGE95
   173    GND @T6G_MB_LIB.T6G(SCH_1):GND   I177 @T6G_MB_LIB.T6G(SCH_1):PAGE95
   175    GND @T6G_MB_LIB.T6G(SCH_1):GND   I177 @T6G_MB_LIB.T6G(SCH_1):PAGE95
   177    GND @T6G_MB_LIB.T6G(SCH_1):GND   I177 @T6G_MB_LIB.T6G(SCH_1):PAGE95
   180    GND @T6G_MB_LIB.T6G(SCH_1):GND   I177 @T6G_MB_LIB.T6G(SCH_1):PAGE95
   182    GND @T6G_MB_LIB.T6G(SCH_1):GND   I177 @T6G_MB_LIB.T6G(SCH_1):PAGE95
   184    GND @T6G_MB_LIB.T6G(SCH_1):GND   I177 @T6G_MB_LIB.T6G(SCH_1):PAGE95
   186    GND @T6G_MB_LIB.T6G(SCH_1):GND   I177 @T6G_MB_LIB.T6G(SCH_1):PAGE95
   188    GND @T6G_MB_LIB.T6G(SCH_1):GND   I177 @T6G_MB_LIB.T6G(SCH_1):PAGE95
   191    GND @T6G_MB_LIB.T6G(SCH_1):GND   I177 @T6G_MB_LIB.T6G(SCH_1):PAGE95
   193    GND @T6G_MB_LIB.T6G(SCH_1):GND   I177 @T6G_MB_LIB.T6G(SCH_1):PAGE95
   195    GND @T6G_MB_LIB.T6G(SCH_1):GND   I177 @T6G_MB_LIB.T6G(SCH_1):PAGE95
   197    GND @T6G_MB_LIB.T6G(SCH_1):GND   I177 @T6G_MB_LIB.T6G(SCH_1):PAGE95
   199    GND @T6G_MB_LIB.T6G(SCH_1):GND   I177 @T6G_MB_LIB.T6G(SCH_1):PAGE95
   202    GND @T6G_MB_LIB.T6G(SCH_1):GND   I177 @T6G_MB_LIB.T6G(SCH_1):PAGE95
   204    GND @T6G_MB_LIB.T6G(SCH_1):GND   I177 @T6G_MB_LIB.T6G(SCH_1):PAGE95
   206    GND @T6G_MB_LIB.T6G(SCH_1):GND   I177 @T6G_MB_LIB.T6G(SCH_1):PAGE95
   208    GND @T6G_MB_LIB.T6G(SCH_1):GND   I177 @T6G_MB_LIB.T6G(SCH_1):PAGE95
   210    GND @T6G_MB_LIB.T6G(SCH_1):GND   I177 @T6G_MB_LIB.T6G(SCH_1):PAGE95
   212    GND @T6G_MB_LIB.T6G(SCH_1):GND   I177 @T6G_MB_LIB.T6G(SCH_1):PAGE95
   214    GND @T6G_MB_LIB.T6G(SCH_1):GND   I177 @T6G_MB_LIB.T6G(SCH_1):PAGE95
   216    GND @T6G_MB_LIB.T6G(SCH_1):GND   I177 @T6G_MB_LIB.T6G(SCH_1):PAGE95
   219    GND @T6G_MB_LIB.T6G(SCH_1):GND   I177 @T6G_MB_LIB.T6G(SCH_1):PAGE95
   222    GND @T6G_MB_LIB.T6G(SCH_1):GND   I177 @T6G_MB_LIB.T6G(SCH_1):PAGE95
   224    GND @T6G_MB_LIB.T6G(SCH_1):GND   I177 @T6G_MB_LIB.T6G(SCH_1):PAGE95
   226    GND @T6G_MB_LIB.T6G(SCH_1):GND   I177 @T6G_MB_LIB.T6G(SCH_1):PAGE95
   228    GND @T6G_MB_LIB.T6G(SCH_1):GND   I177 @T6G_MB_LIB.T6G(SCH_1):PAGE95
   233    GND @T6G_MB_LIB.T6G(SCH_1):GND   I177 @T6G_MB_LIB.T6G(SCH_1):PAGE95
   237    GND @T6G_MB_LIB.T6G(SCH_1):GND   I177 @T6G_MB_LIB.T6G(SCH_1):PAGE95
   242    GND @T6G_MB_LIB.T6G(SCH_1):GND   I177 @T6G_MB_LIB.T6G(SCH_1):PAGE95
   244    GND @T6G_MB_LIB.T6G(SCH_1):GND   I177 @T6G_MB_LIB.T6G(SCH_1):PAGE95
   246    GND @T6G_MB_LIB.T6G(SCH_1):GND   I177 @T6G_MB_LIB.T6G(SCH_1):PAGE95
   248    GND @T6G_MB_LIB.T6G(SCH_1):GND   I177 @T6G_MB_LIB.T6G(SCH_1):PAGE95
   251    GND @T6G_MB_LIB.T6G(SCH_1):GND   I177 @T6G_MB_LIB.T6G(SCH_1):PAGE95
   253    GND @T6G_MB_LIB.T6G(SCH_1):GND   I177 @T6G_MB_LIB.T6G(SCH_1):PAGE95
   255    GND @T6G_MB_LIB.T6G(SCH_1):GND   I177 @T6G_MB_LIB.T6G(SCH_1):PAGE95
   257    GND @T6G_MB_LIB.T6G(SCH_1):GND   I177 @T6G_MB_LIB.T6G(SCH_1):PAGE95
   259    GND @T6G_MB_LIB.T6G(SCH_1):GND   I177 @T6G_MB_LIB.T6G(SCH_1):PAGE95
   262    GND @T6G_MB_LIB.T6G(SCH_1):GND   I177 @T6G_MB_LIB.T6G(SCH_1):PAGE95
   264    GND @T6G_MB_LIB.T6G(SCH_1):GND   I177 @T6G_MB_LIB.T6G(SCH_1):PAGE95
   266    GND @T6G_MB_LIB.T6G(SCH_1):GND   I177 @T6G_MB_LIB.T6G(SCH_1):PAGE95
   268    GND @T6G_MB_LIB.T6G(SCH_1):GND   I177 @T6G_MB_LIB.T6G(SCH_1):PAGE95
   270    GND @T6G_MB_LIB.T6G(SCH_1):GND   I177 @T6G_MB_LIB.T6G(SCH_1):PAGE95
   273    GND @T6G_MB_LIB.T6G(SCH_1):GND   I177 @T6G_MB_LIB.T6G(SCH_1):PAGE95
   275    GND @T6G_MB_LIB.T6G(SCH_1):GND   I177 @T6G_MB_LIB.T6G(SCH_1):PAGE95
   277    GND @T6G_MB_LIB.T6G(SCH_1):GND   I177 @T6G_MB_LIB.T6G(SCH_1):PAGE95
   279    GND @T6G_MB_LIB.T6G(SCH_1):GND   I177 @T6G_MB_LIB.T6G(SCH_1):PAGE95
   281    GND @T6G_MB_LIB.T6G(SCH_1):GND   I177 @T6G_MB_LIB.T6G(SCH_1):PAGE95
   284    GND @T6G_MB_LIB.T6G(SCH_1):GND   I177 @T6G_MB_LIB.T6G(SCH_1):PAGE95
   286    GND @T6G_MB_LIB.T6G(SCH_1):GND   I177 @T6G_MB_LIB.T6G(SCH_1):PAGE95
   288    GND @T6G_MB_LIB.T6G(SCH_1):GND   I177 @T6G_MB_LIB.T6G(SCH_1):PAGE95
     1 P12V_MEM_CPU0 @T6G_MB_LIB.T6G(SCH_1):P12V_MEM_CPU0   I177 @T6G_MB_LIB.T6G(SCH_1):PAGE95
   145 P12V_MEM_CPU0 @T6G_MB_LIB.T6G(SCH_1):P12V_MEM_CPU0   I177 @T6G_MB_LIB.T6G(SCH_1):PAGE95
   146 P12V_MEM_CPU0 @T6G_MB_LIB.T6G(SCH_1):P12V_MEM_CPU0   I177 @T6G_MB_LIB.T6G(SCH_1):PAGE95
   230    GND @T6G_MB_LIB.T6G(SCH_1):GND   I177 @T6G_MB_LIB.T6G(SCH_1):PAGE95
   235    GND @T6G_MB_LIB.T6G(SCH_1):GND   I177 @T6G_MB_LIB.T6G(SCH_1):PAGE95
   240    GND @T6G_MB_LIB.T6G(SCH_1):GND   I177 @T6G_MB_LIB.T6G(SCH_1):PAGE95
   132    GND @T6G_MB_LIB.T6G(SCH_1):GND   I177 @T6G_MB_LIB.T6G(SCH_1):PAGE95
   136    GND @T6G_MB_LIB.T6G(SCH_1):GND   I177 @T6G_MB_LIB.T6G(SCH_1):PAGE95
   139    GND @T6G_MB_LIB.T6G(SCH_1):GND   I177 @T6G_MB_LIB.T6G(SCH_1):PAGE95
   141    GND @T6G_MB_LIB.T6G(SCH_1):GND   I177 @T6G_MB_LIB.T6G(SCH_1):PAGE95
    G1    GND @T6G_MB_LIB.T6G(SCH_1):GND   I177 @T6G_MB_LIB.T6G(SCH_1):PAGE95
    G2    GND @T6G_MB_LIB.T6G(SCH_1):GND   I177 @T6G_MB_LIB.T6G(SCH_1):PAGE95
    G3    GND @T6G_MB_LIB.T6G(SCH_1):GND   I177 @T6G_MB_LIB.T6G(SCH_1):PAGE95

 J21 SCONN288_DDR506112002KQ-SCONN288_DDR506112002KQ,SMA
     3 P3V3_AUX @T6G_MB_LIB.T6G(SCH_1):P3V3_AUX   I348 @T6G_MB_LIB.T6G(SCH_1):PAGE89
     2     NC     NC   I348 @T6G_MB_LIB.T6G(SCH_1):PAGE89
   144     NC     NC   I348 @T6G_MB_LIB.T6G(SCH_1):PAGE89
   149     NC     NC   I348 @T6G_MB_LIB.T6G(SCH_1):PAGE89
   150     NC     NC   I348 @T6G_MB_LIB.T6G(SCH_1):PAGE89
   220     NC     NC   I348 @T6G_MB_LIB.T6G(SCH_1):PAGE89
   231     NC     NC   I348 @T6G_MB_LIB.T6G(SCH_1):PAGE89
   232     NC     NC   I348 @T6G_MB_LIB.T6G(SCH_1):PAGE89
   207 M_E_CPU0_RESET_N @T6G_MB_LIB.T6G(SCH_1):M_E_CPU0_RESET_N   I348 @T6G_MB_LIB.T6G(SCH_1):PAGE89
   147 PWRGD_CHE_CPU0_DIMM @T6G_MB_LIB.T6G(SCH_1):PWRGD_CHE_CPU0_DIMM   I348 @T6G_MB_LIB.T6G(SCH_1):PAGE89
   227 M_E_CPU0_SB_PAR @T6G_MB_LIB.T6G(SCH_1):M_E_CPU0_SB_PAR   I348 @T6G_MB_LIB.T6G(SCH_1):PAGE89
    74 M_E_CPU0_SA_PAR @T6G_MB_LIB.T6G(SCH_1):M_E_CPU0_SA_PAR   I348 @T6G_MB_LIB.T6G(SCH_1):PAGE89
    87 M_E_CPU0_SB_RSP<0> @T6G_MB_LIB.T6G(SCH_1):M_E_CPU0_SB_RSP(0)   I348 @T6G_MB_LIB.T6G(SCH_1):PAGE89
    86 M_E_CPU0_SA_RSP<0> @T6G_MB_LIB.T6G(SCH_1):M_E_CPU0_SA_RSP(0)   I348 @T6G_MB_LIB.T6G(SCH_1):PAGE89
     5 I3C_SPD_DDRE_CPU0_SDA @T6G_MB_LIB.T6G(SCH_1):I3C_SPD_DDRE_CPU0_SDA   I348 @T6G_MB_LIB.T6G(SCH_1):PAGE89
     4 I3C_SPD_DDRE_CPU0_SCL @T6G_MB_LIB.T6G(SCH_1):I3C_SPD_DDRE_CPU0_SCL   I348 @T6G_MB_LIB.T6G(SCH_1):PAGE89
   148 PD_CHE_CPU0_DIMM_SAA @T6G_MB_LIB.T6G(SCH_1):PD_CHE_CPU0_DIMM_SAA   I348 @T6G_MB_LIB.T6G(SCH_1):PAGE89
   100 M_E_CPU0_SB_DQ<0> @T6G_MB_LIB.T6G(SCH_1):M_E_CPU0_SB_DQ(0)   I348 @T6G_MB_LIB.T6G(SCH_1):PAGE89
   102 M_E_CPU0_SB_DQ<1> @T6G_MB_LIB.T6G(SCH_1):M_E_CPU0_SB_DQ(1)   I348 @T6G_MB_LIB.T6G(SCH_1):PAGE89
   245 M_E_CPU0_SB_DQ<2> @T6G_MB_LIB.T6G(SCH_1):M_E_CPU0_SB_DQ(2)   I348 @T6G_MB_LIB.T6G(SCH_1):PAGE89
   247 M_E_CPU0_SB_DQ<3> @T6G_MB_LIB.T6G(SCH_1):M_E_CPU0_SB_DQ(3)   I348 @T6G_MB_LIB.T6G(SCH_1):PAGE89
   107 M_E_CPU0_SB_DQ<4> @T6G_MB_LIB.T6G(SCH_1):M_E_CPU0_SB_DQ(4)   I348 @T6G_MB_LIB.T6G(SCH_1):PAGE89
   109 M_E_CPU0_SB_DQ<5> @T6G_MB_LIB.T6G(SCH_1):M_E_CPU0_SB_DQ(5)   I348 @T6G_MB_LIB.T6G(SCH_1):PAGE89
   252 M_E_CPU0_SB_DQ<6> @T6G_MB_LIB.T6G(SCH_1):M_E_CPU0_SB_DQ(6)   I348 @T6G_MB_LIB.T6G(SCH_1):PAGE89
   254 M_E_CPU0_SB_DQ<7> @T6G_MB_LIB.T6G(SCH_1):M_E_CPU0_SB_DQ(7)   I348 @T6G_MB_LIB.T6G(SCH_1):PAGE89
   111 M_E_CPU0_SB_DQ<8> @T6G_MB_LIB.T6G(SCH_1):M_E_CPU0_SB_DQ(8)   I348 @T6G_MB_LIB.T6G(SCH_1):PAGE89
   113 M_E_CPU0_SB_DQ<9> @T6G_MB_LIB.T6G(SCH_1):M_E_CPU0_SB_DQ(9)   I348 @T6G_MB_LIB.T6G(SCH_1):PAGE89
   256 M_E_CPU0_SB_DQ<10> @T6G_MB_LIB.T6G(SCH_1):M_E_CPU0_SB_DQ(10)   I348 @T6G_MB_LIB.T6G(SCH_1):PAGE89
   258 M_E_CPU0_SB_DQ<11> @T6G_MB_LIB.T6G(SCH_1):M_E_CPU0_SB_DQ(11)   I348 @T6G_MB_LIB.T6G(SCH_1):PAGE89
   118 M_E_CPU0_SB_DQ<12> @T6G_MB_LIB.T6G(SCH_1):M_E_CPU0_SB_DQ(12)   I348 @T6G_MB_LIB.T6G(SCH_1):PAGE89
   120 M_E_CPU0_SB_DQ<13> @T6G_MB_LIB.T6G(SCH_1):M_E_CPU0_SB_DQ(13)   I348 @T6G_MB_LIB.T6G(SCH_1):PAGE89
   263 M_E_CPU0_SB_DQ<14> @T6G_MB_LIB.T6G(SCH_1):M_E_CPU0_SB_DQ(14)   I348 @T6G_MB_LIB.T6G(SCH_1):PAGE89
   265 M_E_CPU0_SB_DQ<15> @T6G_MB_LIB.T6G(SCH_1):M_E_CPU0_SB_DQ(15)   I348 @T6G_MB_LIB.T6G(SCH_1):PAGE89
   122 M_E_CPU0_SB_DQ<16> @T6G_MB_LIB.T6G(SCH_1):M_E_CPU0_SB_DQ(16)   I348 @T6G_MB_LIB.T6G(SCH_1):PAGE89
   124 M_E_CPU0_SB_DQ<17> @T6G_MB_LIB.T6G(SCH_1):M_E_CPU0_SB_DQ(17)   I348 @T6G_MB_LIB.T6G(SCH_1):PAGE89
   267 M_E_CPU0_SB_DQ<18> @T6G_MB_LIB.T6G(SCH_1):M_E_CPU0_SB_DQ(18)   I348 @T6G_MB_LIB.T6G(SCH_1):PAGE89
   269 M_E_CPU0_SB_DQ<19> @T6G_MB_LIB.T6G(SCH_1):M_E_CPU0_SB_DQ(19)   I348 @T6G_MB_LIB.T6G(SCH_1):PAGE89
   129 M_E_CPU0_SB_DQ<20> @T6G_MB_LIB.T6G(SCH_1):M_E_CPU0_SB_DQ(20)   I348 @T6G_MB_LIB.T6G(SCH_1):PAGE89
   131 M_E_CPU0_SB_DQ<21> @T6G_MB_LIB.T6G(SCH_1):M_E_CPU0_SB_DQ(21)   I348 @T6G_MB_LIB.T6G(SCH_1):PAGE89
   274 M_E_CPU0_SB_DQ<22> @T6G_MB_LIB.T6G(SCH_1):M_E_CPU0_SB_DQ(22)   I348 @T6G_MB_LIB.T6G(SCH_1):PAGE89
   276 M_E_CPU0_SB_DQ<23> @T6G_MB_LIB.T6G(SCH_1):M_E_CPU0_SB_DQ(23)   I348 @T6G_MB_LIB.T6G(SCH_1):PAGE89
   133 M_E_CPU0_SB_DQ<24> @T6G_MB_LIB.T6G(SCH_1):M_E_CPU0_SB_DQ(24)   I348 @T6G_MB_LIB.T6G(SCH_1):PAGE89
   135 M_E_CPU0_SB_DQ<25> @T6G_MB_LIB.T6G(SCH_1):M_E_CPU0_SB_DQ(25)   I348 @T6G_MB_LIB.T6G(SCH_1):PAGE89
   278 M_E_CPU0_SB_DQ<26> @T6G_MB_LIB.T6G(SCH_1):M_E_CPU0_SB_DQ(26)   I348 @T6G_MB_LIB.T6G(SCH_1):PAGE89
   280 M_E_CPU0_SB_DQ<27> @T6G_MB_LIB.T6G(SCH_1):M_E_CPU0_SB_DQ(27)   I348 @T6G_MB_LIB.T6G(SCH_1):PAGE89
   140 M_E_CPU0_SB_DQ<28> @T6G_MB_LIB.T6G(SCH_1):M_E_CPU0_SB_DQ(28)   I348 @T6G_MB_LIB.T6G(SCH_1):PAGE89
   142 M_E_CPU0_SB_DQ<29> @T6G_MB_LIB.T6G(SCH_1):M_E_CPU0_SB_DQ(29)   I348 @T6G_MB_LIB.T6G(SCH_1):PAGE89
   285 M_E_CPU0_SB_DQ<30> @T6G_MB_LIB.T6G(SCH_1):M_E_CPU0_SB_DQ(30)   I348 @T6G_MB_LIB.T6G(SCH_1):PAGE89
   287 M_E_CPU0_SB_DQ<31> @T6G_MB_LIB.T6G(SCH_1):M_E_CPU0_SB_DQ(31)   I348 @T6G_MB_LIB.T6G(SCH_1):PAGE89
     7 M_E_CPU0_SA_DQ<0> @T6G_MB_LIB.T6G(SCH_1):M_E_CPU0_SA_DQ(0)   I348 @T6G_MB_LIB.T6G(SCH_1):PAGE89
     9 M_E_CPU0_SA_DQ<1> @T6G_MB_LIB.T6G(SCH_1):M_E_CPU0_SA_DQ(1)   I348 @T6G_MB_LIB.T6G(SCH_1):PAGE89
   152 M_E_CPU0_SA_DQ<2> @T6G_MB_LIB.T6G(SCH_1):M_E_CPU0_SA_DQ(2)   I348 @T6G_MB_LIB.T6G(SCH_1):PAGE89
   154 M_E_CPU0_SA_DQ<3> @T6G_MB_LIB.T6G(SCH_1):M_E_CPU0_SA_DQ(3)   I348 @T6G_MB_LIB.T6G(SCH_1):PAGE89
    14 M_E_CPU0_SA_DQ<4> @T6G_MB_LIB.T6G(SCH_1):M_E_CPU0_SA_DQ(4)   I348 @T6G_MB_LIB.T6G(SCH_1):PAGE89
    16 M_E_CPU0_SA_DQ<5> @T6G_MB_LIB.T6G(SCH_1):M_E_CPU0_SA_DQ(5)   I348 @T6G_MB_LIB.T6G(SCH_1):PAGE89
   159 M_E_CPU0_SA_DQ<6> @T6G_MB_LIB.T6G(SCH_1):M_E_CPU0_SA_DQ(6)   I348 @T6G_MB_LIB.T6G(SCH_1):PAGE89
   161 M_E_CPU0_SA_DQ<7> @T6G_MB_LIB.T6G(SCH_1):M_E_CPU0_SA_DQ(7)   I348 @T6G_MB_LIB.T6G(SCH_1):PAGE89
    18 M_E_CPU0_SA_DQ<8> @T6G_MB_LIB.T6G(SCH_1):M_E_CPU0_SA_DQ(8)   I348 @T6G_MB_LIB.T6G(SCH_1):PAGE89
    20 M_E_CPU0_SA_DQ<9> @T6G_MB_LIB.T6G(SCH_1):M_E_CPU0_SA_DQ(9)   I348 @T6G_MB_LIB.T6G(SCH_1):PAGE89
   163 M_E_CPU0_SA_DQ<10> @T6G_MB_LIB.T6G(SCH_1):M_E_CPU0_SA_DQ(10)   I348 @T6G_MB_LIB.T6G(SCH_1):PAGE89
   165 M_E_CPU0_SA_DQ<11> @T6G_MB_LIB.T6G(SCH_1):M_E_CPU0_SA_DQ(11)   I348 @T6G_MB_LIB.T6G(SCH_1):PAGE89
    25 M_E_CPU0_SA_DQ<12> @T6G_MB_LIB.T6G(SCH_1):M_E_CPU0_SA_DQ(12)   I348 @T6G_MB_LIB.T6G(SCH_1):PAGE89
    27 M_E_CPU0_SA_DQ<13> @T6G_MB_LIB.T6G(SCH_1):M_E_CPU0_SA_DQ(13)   I348 @T6G_MB_LIB.T6G(SCH_1):PAGE89
   170 M_E_CPU0_SA_DQ<14> @T6G_MB_LIB.T6G(SCH_1):M_E_CPU0_SA_DQ(14)   I348 @T6G_MB_LIB.T6G(SCH_1):PAGE89
   172 M_E_CPU0_SA_DQ<15> @T6G_MB_LIB.T6G(SCH_1):M_E_CPU0_SA_DQ(15)   I348 @T6G_MB_LIB.T6G(SCH_1):PAGE89
    29 M_E_CPU0_SA_DQ<16> @T6G_MB_LIB.T6G(SCH_1):M_E_CPU0_SA_DQ(16)   I348 @T6G_MB_LIB.T6G(SCH_1):PAGE89
    31 M_E_CPU0_SA_DQ<17> @T6G_MB_LIB.T6G(SCH_1):M_E_CPU0_SA_DQ(17)   I348 @T6G_MB_LIB.T6G(SCH_1):PAGE89
   174 M_E_CPU0_SA_DQ<18> @T6G_MB_LIB.T6G(SCH_1):M_E_CPU0_SA_DQ(18)   I348 @T6G_MB_LIB.T6G(SCH_1):PAGE89
   176 M_E_CPU0_SA_DQ<19> @T6G_MB_LIB.T6G(SCH_1):M_E_CPU0_SA_DQ(19)   I348 @T6G_MB_LIB.T6G(SCH_1):PAGE89
    36 M_E_CPU0_SA_DQ<20> @T6G_MB_LIB.T6G(SCH_1):M_E_CPU0_SA_DQ(20)   I348 @T6G_MB_LIB.T6G(SCH_1):PAGE89
    38 M_E_CPU0_SA_DQ<21> @T6G_MB_LIB.T6G(SCH_1):M_E_CPU0_SA_DQ(21)   I348 @T6G_MB_LIB.T6G(SCH_1):PAGE89
   181 M_E_CPU0_SA_DQ<22> @T6G_MB_LIB.T6G(SCH_1):M_E_CPU0_SA_DQ(22)   I348 @T6G_MB_LIB.T6G(SCH_1):PAGE89
   183 M_E_CPU0_SA_DQ<23> @T6G_MB_LIB.T6G(SCH_1):M_E_CPU0_SA_DQ(23)   I348 @T6G_MB_LIB.T6G(SCH_1):PAGE89
    40 M_E_CPU0_SA_DQ<24> @T6G_MB_LIB.T6G(SCH_1):M_E_CPU0_SA_DQ(24)   I348 @T6G_MB_LIB.T6G(SCH_1):PAGE89
    42 M_E_CPU0_SA_DQ<25> @T6G_MB_LIB.T6G(SCH_1):M_E_CPU0_SA_DQ(25)   I348 @T6G_MB_LIB.T6G(SCH_1):PAGE89
   185 M_E_CPU0_SA_DQ<26> @T6G_MB_LIB.T6G(SCH_1):M_E_CPU0_SA_DQ(26)   I348 @T6G_MB_LIB.T6G(SCH_1):PAGE89
   187 M_E_CPU0_SA_DQ<27> @T6G_MB_LIB.T6G(SCH_1):M_E_CPU0_SA_DQ(27)   I348 @T6G_MB_LIB.T6G(SCH_1):PAGE89
    47 M_E_CPU0_SA_DQ<28> @T6G_MB_LIB.T6G(SCH_1):M_E_CPU0_SA_DQ(28)   I348 @T6G_MB_LIB.T6G(SCH_1):PAGE89
    49 M_E_CPU0_SA_DQ<29> @T6G_MB_LIB.T6G(SCH_1):M_E_CPU0_SA_DQ(29)   I348 @T6G_MB_LIB.T6G(SCH_1):PAGE89
   192 M_E_CPU0_SA_DQ<30> @T6G_MB_LIB.T6G(SCH_1):M_E_CPU0_SA_DQ(30)   I348 @T6G_MB_LIB.T6G(SCH_1):PAGE89
   229 M_E_CPU0_SB_CS_N<1> @T6G_MB_LIB.T6G(SCH_1):M_E_CPU0_SB_CS_N(1)   I348 @T6G_MB_LIB.T6G(SCH_1):PAGE89
   209 M_E_CPU0_SA_CS_N<1> @T6G_MB_LIB.T6G(SCH_1):M_E_CPU0_SA_CS_N(1)   I348 @T6G_MB_LIB.T6G(SCH_1):PAGE89
    84 M_E_CPU0_SB_CS_N<0> @T6G_MB_LIB.T6G(SCH_1):M_E_CPU0_SB_CS_N(0)   I348 @T6G_MB_LIB.T6G(SCH_1):PAGE89
    64 M_E_CPU0_SA_CS_N<0> @T6G_MB_LIB.T6G(SCH_1):M_E_CPU0_SA_CS_N(0)   I348 @T6G_MB_LIB.T6G(SCH_1):PAGE89
   217 M_E_CPU0_CLK_DP<0> @T6G_MB_LIB.T6G(SCH_1):M_E_CPU0_CLK_DP(0)   I348 @T6G_MB_LIB.T6G(SCH_1):PAGE89
   218 M_E_CPU0_CLK_DN<0> @T6G_MB_LIB.T6G(SCH_1):M_E_CPU0_CLK_DN(0)   I348 @T6G_MB_LIB.T6G(SCH_1):PAGE89
    96 M_E_CPU0_SB_CB<0> @T6G_MB_LIB.T6G(SCH_1):M_E_CPU0_SB_CB(0)   I348 @T6G_MB_LIB.T6G(SCH_1):PAGE89
    98 M_E_CPU0_SB_CB<1> @T6G_MB_LIB.T6G(SCH_1):M_E_CPU0_SB_CB(1)   I348 @T6G_MB_LIB.T6G(SCH_1):PAGE89
   241 M_E_CPU0_SB_CB<2> @T6G_MB_LIB.T6G(SCH_1):M_E_CPU0_SB_CB(2)   I348 @T6G_MB_LIB.T6G(SCH_1):PAGE89
   243 M_E_CPU0_SB_CB<3> @T6G_MB_LIB.T6G(SCH_1):M_E_CPU0_SB_CB(3)   I348 @T6G_MB_LIB.T6G(SCH_1):PAGE89
    89 M_E_CPU0_SB_CB<4> @T6G_MB_LIB.T6G(SCH_1):M_E_CPU0_SB_CB(4)   I348 @T6G_MB_LIB.T6G(SCH_1):PAGE89
    91 M_E_CPU0_SB_CB<5> @T6G_MB_LIB.T6G(SCH_1):M_E_CPU0_SB_CB(5)   I348 @T6G_MB_LIB.T6G(SCH_1):PAGE89
   234 M_E_CPU0_SB_CB<6> @T6G_MB_LIB.T6G(SCH_1):M_E_CPU0_SB_CB(6)   I348 @T6G_MB_LIB.T6G(SCH_1):PAGE89
    51 M_E_CPU0_SA_CB<0> @T6G_MB_LIB.T6G(SCH_1):M_E_CPU0_SA_CB(0)   I348 @T6G_MB_LIB.T6G(SCH_1):PAGE89
   196 M_E_CPU0_SA_CB<2> @T6G_MB_LIB.T6G(SCH_1):M_E_CPU0_SA_CB(2)   I348 @T6G_MB_LIB.T6G(SCH_1):PAGE89
   198 M_E_CPU0_SA_CB<3> @T6G_MB_LIB.T6G(SCH_1):M_E_CPU0_SA_CB(3)   I348 @T6G_MB_LIB.T6G(SCH_1):PAGE89
    60 M_E_CPU0_SA_CB<5> @T6G_MB_LIB.T6G(SCH_1):M_E_CPU0_SA_CB(5)   I348 @T6G_MB_LIB.T6G(SCH_1):PAGE89
   203 M_E_CPU0_SA_CB<6> @T6G_MB_LIB.T6G(SCH_1):M_E_CPU0_SA_CB(6)   I348 @T6G_MB_LIB.T6G(SCH_1):PAGE89
    82 M_E_CPU0_SB_CA<6> @T6G_MB_LIB.T6G(SCH_1):M_E_CPU0_SB_CA(6)   I348 @T6G_MB_LIB.T6G(SCH_1):PAGE89
    72 M_E_CPU0_SA_CA<6> @T6G_MB_LIB.T6G(SCH_1):M_E_CPU0_SA_CA(6)   I348 @T6G_MB_LIB.T6G(SCH_1):PAGE89
   225 M_E_CPU0_SB_CA<5> @T6G_MB_LIB.T6G(SCH_1):M_E_CPU0_SB_CA(5)   I348 @T6G_MB_LIB.T6G(SCH_1):PAGE89
   215 M_E_CPU0_SA_CA<5> @T6G_MB_LIB.T6G(SCH_1):M_E_CPU0_SA_CA(5)   I348 @T6G_MB_LIB.T6G(SCH_1):PAGE89
    80 M_E_CPU0_SB_CA<4> @T6G_MB_LIB.T6G(SCH_1):M_E_CPU0_SB_CA(4)   I348 @T6G_MB_LIB.T6G(SCH_1):PAGE89
    70 M_E_CPU0_SA_CA<4> @T6G_MB_LIB.T6G(SCH_1):M_E_CPU0_SA_CA(4)   I348 @T6G_MB_LIB.T6G(SCH_1):PAGE89
   223 M_E_CPU0_SB_CA<3> @T6G_MB_LIB.T6G(SCH_1):M_E_CPU0_SB_CA(3)   I348 @T6G_MB_LIB.T6G(SCH_1):PAGE89
   213 M_E_CPU0_SA_CA<3> @T6G_MB_LIB.T6G(SCH_1):M_E_CPU0_SA_CA(3)   I348 @T6G_MB_LIB.T6G(SCH_1):PAGE89
    78 M_E_CPU0_SB_CA<2> @T6G_MB_LIB.T6G(SCH_1):M_E_CPU0_SB_CA(2)   I348 @T6G_MB_LIB.T6G(SCH_1):PAGE89
    68 M_E_CPU0_SA_CA<2> @T6G_MB_LIB.T6G(SCH_1):M_E_CPU0_SA_CA(2)   I348 @T6G_MB_LIB.T6G(SCH_1):PAGE89
   221 M_E_CPU0_SB_CA<1> @T6G_MB_LIB.T6G(SCH_1):M_E_CPU0_SB_CA(1)   I348 @T6G_MB_LIB.T6G(SCH_1):PAGE89
   211 M_E_CPU0_SA_CA<1> @T6G_MB_LIB.T6G(SCH_1):M_E_CPU0_SA_CA(1)   I348 @T6G_MB_LIB.T6G(SCH_1):PAGE89
    76 M_E_CPU0_SB_CA<0> @T6G_MB_LIB.T6G(SCH_1):M_E_CPU0_SB_CA(0)   I348 @T6G_MB_LIB.T6G(SCH_1):PAGE89
    66 M_E_CPU0_SA_CA<0> @T6G_MB_LIB.T6G(SCH_1):M_E_CPU0_SA_CA(0)   I348 @T6G_MB_LIB.T6G(SCH_1):PAGE89
    62 M_E_CPU0_ALERT_N @T6G_MB_LIB.T6G(SCH_1):M_E_CPU0_ALERT_N   I348 @T6G_MB_LIB.T6G(SCH_1):PAGE89
   236 M_E_CPU0_SB_CB<7> @T6G_MB_LIB.T6G(SCH_1):M_E_CPU0_SB_CB(7)   I348 @T6G_MB_LIB.T6G(SCH_1):PAGE89
    53 M_E_CPU0_SA_CB<1> @T6G_MB_LIB.T6G(SCH_1):M_E_CPU0_SA_CB(1)   I348 @T6G_MB_LIB.T6G(SCH_1):PAGE89
    58 M_E_CPU0_SA_CB<4> @T6G_MB_LIB.T6G(SCH_1):M_E_CPU0_SA_CB(4)   I348 @T6G_MB_LIB.T6G(SCH_1):PAGE89
   205 M_E_CPU0_SA_CB<7> @T6G_MB_LIB.T6G(SCH_1):M_E_CPU0_SA_CB(7)   I348 @T6G_MB_LIB.T6G(SCH_1):PAGE89
   194 M_E_CPU0_SA_DQ<31> @T6G_MB_LIB.T6G(SCH_1):M_E_CPU0_SA_DQ(31)   I348 @T6G_MB_LIB.T6G(SCH_1):PAGE89
    93 M_E_CPU0_SB_DQS_DP<9> @T6G_MB_LIB.T6G(SCH_1):M_E_CPU0_SB_DQS_DP(9)   I410 @T6G_MB_LIB.T6G(SCH_1):PAGE89
    94 M_E_CPU0_SB_DQS_DN<9> @T6G_MB_LIB.T6G(SCH_1):M_E_CPU0_SB_DQS_DN(9)   I410 @T6G_MB_LIB.T6G(SCH_1):PAGE89
   201 M_E_CPU0_SA_DQS_DP<9> @T6G_MB_LIB.T6G(SCH_1):M_E_CPU0_SA_DQS_DP(9)   I410 @T6G_MB_LIB.T6G(SCH_1):PAGE89
   200 M_E_CPU0_SA_DQS_DN<9> @T6G_MB_LIB.T6G(SCH_1):M_E_CPU0_SA_DQS_DN(9)   I410 @T6G_MB_LIB.T6G(SCH_1):PAGE89
   190 M_E_CPU0_SA_DQS_DP<8> @T6G_MB_LIB.T6G(SCH_1):M_E_CPU0_SA_DQS_DP(8)   I410 @T6G_MB_LIB.T6G(SCH_1):PAGE89
   189 M_E_CPU0_SA_DQS_DN<8> @T6G_MB_LIB.T6G(SCH_1):M_E_CPU0_SA_DQS_DN(8)   I410 @T6G_MB_LIB.T6G(SCH_1):PAGE89
   271 M_E_CPU0_SB_DQS_DN<7> @T6G_MB_LIB.T6G(SCH_1):M_E_CPU0_SB_DQS_DN(7)   I410 @T6G_MB_LIB.T6G(SCH_1):PAGE89
   179 M_E_CPU0_SA_DQS_DP<7> @T6G_MB_LIB.T6G(SCH_1):M_E_CPU0_SA_DQS_DP(7)   I410 @T6G_MB_LIB.T6G(SCH_1):PAGE89
   261 M_E_CPU0_SB_DQS_DP<6> @T6G_MB_LIB.T6G(SCH_1):M_E_CPU0_SB_DQS_DP(6)   I410 @T6G_MB_LIB.T6G(SCH_1):PAGE89
   260 M_E_CPU0_SB_DQS_DN<6> @T6G_MB_LIB.T6G(SCH_1):M_E_CPU0_SB_DQS_DN(6)   I410 @T6G_MB_LIB.T6G(SCH_1):PAGE89
   167 M_E_CPU0_SA_DQS_DN<6> @T6G_MB_LIB.T6G(SCH_1):M_E_CPU0_SA_DQS_DN(6)   I410 @T6G_MB_LIB.T6G(SCH_1):PAGE89
   250 M_E_CPU0_SB_DQS_DP<5> @T6G_MB_LIB.T6G(SCH_1):M_E_CPU0_SB_DQS_DP(5)   I410 @T6G_MB_LIB.T6G(SCH_1):PAGE89
   249 M_E_CPU0_SB_DQS_DN<5> @T6G_MB_LIB.T6G(SCH_1):M_E_CPU0_SB_DQS_DN(5)   I410 @T6G_MB_LIB.T6G(SCH_1):PAGE89
   157 M_E_CPU0_SA_DQS_DP<5> @T6G_MB_LIB.T6G(SCH_1):M_E_CPU0_SA_DQS_DP(5)   I410 @T6G_MB_LIB.T6G(SCH_1):PAGE89
   156 M_E_CPU0_SA_DQS_DN<5> @T6G_MB_LIB.T6G(SCH_1):M_E_CPU0_SA_DQS_DN(5)   I410 @T6G_MB_LIB.T6G(SCH_1):PAGE89
   239 M_E_CPU0_SB_DQS_DP<4> @T6G_MB_LIB.T6G(SCH_1):M_E_CPU0_SB_DQS_DP(4)   I410 @T6G_MB_LIB.T6G(SCH_1):PAGE89
   238 M_E_CPU0_SB_DQS_DN<4> @T6G_MB_LIB.T6G(SCH_1):M_E_CPU0_SB_DQS_DN(4)   I410 @T6G_MB_LIB.T6G(SCH_1):PAGE89
    55 M_E_CPU0_SA_DQS_DP<4> @T6G_MB_LIB.T6G(SCH_1):M_E_CPU0_SA_DQS_DP(4)   I410 @T6G_MB_LIB.T6G(SCH_1):PAGE89
    56 M_E_CPU0_SA_DQS_DN<4> @T6G_MB_LIB.T6G(SCH_1):M_E_CPU0_SA_DQS_DN(4)   I410 @T6G_MB_LIB.T6G(SCH_1):PAGE89
   137 M_E_CPU0_SB_DQS_DP<3> @T6G_MB_LIB.T6G(SCH_1):M_E_CPU0_SB_DQS_DP(3)   I410 @T6G_MB_LIB.T6G(SCH_1):PAGE89
   138 M_E_CPU0_SB_DQS_DN<3> @T6G_MB_LIB.T6G(SCH_1):M_E_CPU0_SB_DQS_DN(3)   I410 @T6G_MB_LIB.T6G(SCH_1):PAGE89
    44 M_E_CPU0_SA_DQS_DP<3> @T6G_MB_LIB.T6G(SCH_1):M_E_CPU0_SA_DQS_DP(3)   I410 @T6G_MB_LIB.T6G(SCH_1):PAGE89
    45 M_E_CPU0_SA_DQS_DN<3> @T6G_MB_LIB.T6G(SCH_1):M_E_CPU0_SA_DQS_DN(3)   I410 @T6G_MB_LIB.T6G(SCH_1):PAGE89
   126 M_E_CPU0_SB_DQS_DP<2> @T6G_MB_LIB.T6G(SCH_1):M_E_CPU0_SB_DQS_DP(2)   I410 @T6G_MB_LIB.T6G(SCH_1):PAGE89
   127 M_E_CPU0_SB_DQS_DN<2> @T6G_MB_LIB.T6G(SCH_1):M_E_CPU0_SB_DQS_DN(2)   I410 @T6G_MB_LIB.T6G(SCH_1):PAGE89
    33 M_E_CPU0_SA_DQS_DP<2> @T6G_MB_LIB.T6G(SCH_1):M_E_CPU0_SA_DQS_DP(2)   I410 @T6G_MB_LIB.T6G(SCH_1):PAGE89
    34 M_E_CPU0_SA_DQS_DN<2> @T6G_MB_LIB.T6G(SCH_1):M_E_CPU0_SA_DQS_DN(2)   I410 @T6G_MB_LIB.T6G(SCH_1):PAGE89
   115 M_E_CPU0_SB_DQS_DP<1> @T6G_MB_LIB.T6G(SCH_1):M_E_CPU0_SB_DQS_DP(1)   I410 @T6G_MB_LIB.T6G(SCH_1):PAGE89
   116 M_E_CPU0_SB_DQS_DN<1> @T6G_MB_LIB.T6G(SCH_1):M_E_CPU0_SB_DQS_DN(1)   I410 @T6G_MB_LIB.T6G(SCH_1):PAGE89
    22 M_E_CPU0_SA_DQS_DP<1> @T6G_MB_LIB.T6G(SCH_1):M_E_CPU0_SA_DQS_DP(1)   I410 @T6G_MB_LIB.T6G(SCH_1):PAGE89
    23 M_E_CPU0_SA_DQS_DN<1> @T6G_MB_LIB.T6G(SCH_1):M_E_CPU0_SA_DQS_DN(1)   I410 @T6G_MB_LIB.T6G(SCH_1):PAGE89
   104 M_E_CPU0_SB_DQS_DP<0> @T6G_MB_LIB.T6G(SCH_1):M_E_CPU0_SB_DQS_DP(0)   I410 @T6G_MB_LIB.T6G(SCH_1):PAGE89
   105 M_E_CPU0_SB_DQS_DN<0> @T6G_MB_LIB.T6G(SCH_1):M_E_CPU0_SB_DQS_DN(0)   I410 @T6G_MB_LIB.T6G(SCH_1):PAGE89
    11 M_E_CPU0_SA_DQS_DP<0> @T6G_MB_LIB.T6G(SCH_1):M_E_CPU0_SA_DQS_DP(0)   I410 @T6G_MB_LIB.T6G(SCH_1):PAGE89
    12 M_E_CPU0_SA_DQS_DN<0> @T6G_MB_LIB.T6G(SCH_1):M_E_CPU0_SA_DQS_DN(0)   I410 @T6G_MB_LIB.T6G(SCH_1):PAGE89
   272 M_E_CPU0_SB_DQS_DP<7> @T6G_MB_LIB.T6G(SCH_1):M_E_CPU0_SB_DQS_DP(7)   I410 @T6G_MB_LIB.T6G(SCH_1):PAGE89
   282 M_E_CPU0_SB_DQS_DN<8> @T6G_MB_LIB.T6G(SCH_1):M_E_CPU0_SB_DQS_DN(8)   I410 @T6G_MB_LIB.T6G(SCH_1):PAGE89
   283 M_E_CPU0_SB_DQS_DP<8> @T6G_MB_LIB.T6G(SCH_1):M_E_CPU0_SB_DQS_DP(8)   I410 @T6G_MB_LIB.T6G(SCH_1):PAGE89
   168 M_E_CPU0_SA_DQS_DP<6> @T6G_MB_LIB.T6G(SCH_1):M_E_CPU0_SA_DQS_DP(6)   I410 @T6G_MB_LIB.T6G(SCH_1):PAGE89
   178 M_E_CPU0_SA_DQS_DN<7> @T6G_MB_LIB.T6G(SCH_1):M_E_CPU0_SA_DQS_DN(7)   I410 @T6G_MB_LIB.T6G(SCH_1):PAGE89
     6    GND @T6G_MB_LIB.T6G(SCH_1):GND   I350 @T6G_MB_LIB.T6G(SCH_1):PAGE89
     8    GND @T6G_MB_LIB.T6G(SCH_1):GND   I350 @T6G_MB_LIB.T6G(SCH_1):PAGE89
    10    GND @T6G_MB_LIB.T6G(SCH_1):GND   I350 @T6G_MB_LIB.T6G(SCH_1):PAGE89
    13    GND @T6G_MB_LIB.T6G(SCH_1):GND   I350 @T6G_MB_LIB.T6G(SCH_1):PAGE89
    15    GND @T6G_MB_LIB.T6G(SCH_1):GND   I350 @T6G_MB_LIB.T6G(SCH_1):PAGE89
    17    GND @T6G_MB_LIB.T6G(SCH_1):GND   I350 @T6G_MB_LIB.T6G(SCH_1):PAGE89
    19    GND @T6G_MB_LIB.T6G(SCH_1):GND   I350 @T6G_MB_LIB.T6G(SCH_1):PAGE89
    21    GND @T6G_MB_LIB.T6G(SCH_1):GND   I350 @T6G_MB_LIB.T6G(SCH_1):PAGE89
    24    GND @T6G_MB_LIB.T6G(SCH_1):GND   I350 @T6G_MB_LIB.T6G(SCH_1):PAGE89
    26    GND @T6G_MB_LIB.T6G(SCH_1):GND   I350 @T6G_MB_LIB.T6G(SCH_1):PAGE89
    28    GND @T6G_MB_LIB.T6G(SCH_1):GND   I350 @T6G_MB_LIB.T6G(SCH_1):PAGE89
    30    GND @T6G_MB_LIB.T6G(SCH_1):GND   I350 @T6G_MB_LIB.T6G(SCH_1):PAGE89
    32    GND @T6G_MB_LIB.T6G(SCH_1):GND   I350 @T6G_MB_LIB.T6G(SCH_1):PAGE89
    35    GND @T6G_MB_LIB.T6G(SCH_1):GND   I350 @T6G_MB_LIB.T6G(SCH_1):PAGE89
    37    GND @T6G_MB_LIB.T6G(SCH_1):GND   I350 @T6G_MB_LIB.T6G(SCH_1):PAGE89
    39    GND @T6G_MB_LIB.T6G(SCH_1):GND   I350 @T6G_MB_LIB.T6G(SCH_1):PAGE89
    41    GND @T6G_MB_LIB.T6G(SCH_1):GND   I350 @T6G_MB_LIB.T6G(SCH_1):PAGE89
    43    GND @T6G_MB_LIB.T6G(SCH_1):GND   I350 @T6G_MB_LIB.T6G(SCH_1):PAGE89
    46    GND @T6G_MB_LIB.T6G(SCH_1):GND   I350 @T6G_MB_LIB.T6G(SCH_1):PAGE89
    48    GND @T6G_MB_LIB.T6G(SCH_1):GND   I350 @T6G_MB_LIB.T6G(SCH_1):PAGE89
    50    GND @T6G_MB_LIB.T6G(SCH_1):GND   I350 @T6G_MB_LIB.T6G(SCH_1):PAGE89
    52    GND @T6G_MB_LIB.T6G(SCH_1):GND   I350 @T6G_MB_LIB.T6G(SCH_1):PAGE89
    54    GND @T6G_MB_LIB.T6G(SCH_1):GND   I350 @T6G_MB_LIB.T6G(SCH_1):PAGE89
    57    GND @T6G_MB_LIB.T6G(SCH_1):GND   I350 @T6G_MB_LIB.T6G(SCH_1):PAGE89
    59    GND @T6G_MB_LIB.T6G(SCH_1):GND   I350 @T6G_MB_LIB.T6G(SCH_1):PAGE89
    61    GND @T6G_MB_LIB.T6G(SCH_1):GND   I350 @T6G_MB_LIB.T6G(SCH_1):PAGE89
    63    GND @T6G_MB_LIB.T6G(SCH_1):GND   I350 @T6G_MB_LIB.T6G(SCH_1):PAGE89
    65    GND @T6G_MB_LIB.T6G(SCH_1):GND   I350 @T6G_MB_LIB.T6G(SCH_1):PAGE89
    67    GND @T6G_MB_LIB.T6G(SCH_1):GND   I350 @T6G_MB_LIB.T6G(SCH_1):PAGE89
    69    GND @T6G_MB_LIB.T6G(SCH_1):GND   I350 @T6G_MB_LIB.T6G(SCH_1):PAGE89
    71    GND @T6G_MB_LIB.T6G(SCH_1):GND   I350 @T6G_MB_LIB.T6G(SCH_1):PAGE89
    73    GND @T6G_MB_LIB.T6G(SCH_1):GND   I350 @T6G_MB_LIB.T6G(SCH_1):PAGE89
    75    GND @T6G_MB_LIB.T6G(SCH_1):GND   I350 @T6G_MB_LIB.T6G(SCH_1):PAGE89
    77    GND @T6G_MB_LIB.T6G(SCH_1):GND   I350 @T6G_MB_LIB.T6G(SCH_1):PAGE89
    79    GND @T6G_MB_LIB.T6G(SCH_1):GND   I350 @T6G_MB_LIB.T6G(SCH_1):PAGE89
    81    GND @T6G_MB_LIB.T6G(SCH_1):GND   I350 @T6G_MB_LIB.T6G(SCH_1):PAGE89
    83    GND @T6G_MB_LIB.T6G(SCH_1):GND   I350 @T6G_MB_LIB.T6G(SCH_1):PAGE89
    85    GND @T6G_MB_LIB.T6G(SCH_1):GND   I350 @T6G_MB_LIB.T6G(SCH_1):PAGE89
    88    GND @T6G_MB_LIB.T6G(SCH_1):GND   I350 @T6G_MB_LIB.T6G(SCH_1):PAGE89
    90    GND @T6G_MB_LIB.T6G(SCH_1):GND   I350 @T6G_MB_LIB.T6G(SCH_1):PAGE89
    92    GND @T6G_MB_LIB.T6G(SCH_1):GND   I350 @T6G_MB_LIB.T6G(SCH_1):PAGE89
    95    GND @T6G_MB_LIB.T6G(SCH_1):GND   I350 @T6G_MB_LIB.T6G(SCH_1):PAGE89
    97    GND @T6G_MB_LIB.T6G(SCH_1):GND   I350 @T6G_MB_LIB.T6G(SCH_1):PAGE89
    99    GND @T6G_MB_LIB.T6G(SCH_1):GND   I350 @T6G_MB_LIB.T6G(SCH_1):PAGE89
   101    GND @T6G_MB_LIB.T6G(SCH_1):GND   I350 @T6G_MB_LIB.T6G(SCH_1):PAGE89
   103    GND @T6G_MB_LIB.T6G(SCH_1):GND   I350 @T6G_MB_LIB.T6G(SCH_1):PAGE89
   106    GND @T6G_MB_LIB.T6G(SCH_1):GND   I350 @T6G_MB_LIB.T6G(SCH_1):PAGE89
   108    GND @T6G_MB_LIB.T6G(SCH_1):GND   I350 @T6G_MB_LIB.T6G(SCH_1):PAGE89
   110    GND @T6G_MB_LIB.T6G(SCH_1):GND   I350 @T6G_MB_LIB.T6G(SCH_1):PAGE89
   112    GND @T6G_MB_LIB.T6G(SCH_1):GND   I350 @T6G_MB_LIB.T6G(SCH_1):PAGE89
   114    GND @T6G_MB_LIB.T6G(SCH_1):GND   I350 @T6G_MB_LIB.T6G(SCH_1):PAGE89
   117    GND @T6G_MB_LIB.T6G(SCH_1):GND   I350 @T6G_MB_LIB.T6G(SCH_1):PAGE89
   119    GND @T6G_MB_LIB.T6G(SCH_1):GND   I350 @T6G_MB_LIB.T6G(SCH_1):PAGE89
   121    GND @T6G_MB_LIB.T6G(SCH_1):GND   I350 @T6G_MB_LIB.T6G(SCH_1):PAGE89
   123    GND @T6G_MB_LIB.T6G(SCH_1):GND   I350 @T6G_MB_LIB.T6G(SCH_1):PAGE89
   125    GND @T6G_MB_LIB.T6G(SCH_1):GND   I350 @T6G_MB_LIB.T6G(SCH_1):PAGE89
   128    GND @T6G_MB_LIB.T6G(SCH_1):GND   I350 @T6G_MB_LIB.T6G(SCH_1):PAGE89
   130    GND @T6G_MB_LIB.T6G(SCH_1):GND   I350 @T6G_MB_LIB.T6G(SCH_1):PAGE89
   134    GND @T6G_MB_LIB.T6G(SCH_1):GND   I350 @T6G_MB_LIB.T6G(SCH_1):PAGE89
   143    GND @T6G_MB_LIB.T6G(SCH_1):GND   I350 @T6G_MB_LIB.T6G(SCH_1):PAGE89
   151    GND @T6G_MB_LIB.T6G(SCH_1):GND   I350 @T6G_MB_LIB.T6G(SCH_1):PAGE89
   153    GND @T6G_MB_LIB.T6G(SCH_1):GND   I350 @T6G_MB_LIB.T6G(SCH_1):PAGE89
   155    GND @T6G_MB_LIB.T6G(SCH_1):GND   I350 @T6G_MB_LIB.T6G(SCH_1):PAGE89
   158    GND @T6G_MB_LIB.T6G(SCH_1):GND   I350 @T6G_MB_LIB.T6G(SCH_1):PAGE89
   160    GND @T6G_MB_LIB.T6G(SCH_1):GND   I350 @T6G_MB_LIB.T6G(SCH_1):PAGE89
   162    GND @T6G_MB_LIB.T6G(SCH_1):GND   I350 @T6G_MB_LIB.T6G(SCH_1):PAGE89
   164    GND @T6G_MB_LIB.T6G(SCH_1):GND   I350 @T6G_MB_LIB.T6G(SCH_1):PAGE89
   166    GND @T6G_MB_LIB.T6G(SCH_1):GND   I350 @T6G_MB_LIB.T6G(SCH_1):PAGE89
   169    GND @T6G_MB_LIB.T6G(SCH_1):GND   I350 @T6G_MB_LIB.T6G(SCH_1):PAGE89
   171    GND @T6G_MB_LIB.T6G(SCH_1):GND   I350 @T6G_MB_LIB.T6G(SCH_1):PAGE89
   173    GND @T6G_MB_LIB.T6G(SCH_1):GND   I350 @T6G_MB_LIB.T6G(SCH_1):PAGE89
   175    GND @T6G_MB_LIB.T6G(SCH_1):GND   I350 @T6G_MB_LIB.T6G(SCH_1):PAGE89
   177    GND @T6G_MB_LIB.T6G(SCH_1):GND   I350 @T6G_MB_LIB.T6G(SCH_1):PAGE89
   180    GND @T6G_MB_LIB.T6G(SCH_1):GND   I350 @T6G_MB_LIB.T6G(SCH_1):PAGE89
   182    GND @T6G_MB_LIB.T6G(SCH_1):GND   I350 @T6G_MB_LIB.T6G(SCH_1):PAGE89
   184    GND @T6G_MB_LIB.T6G(SCH_1):GND   I350 @T6G_MB_LIB.T6G(SCH_1):PAGE89
   186    GND @T6G_MB_LIB.T6G(SCH_1):GND   I350 @T6G_MB_LIB.T6G(SCH_1):PAGE89
   188    GND @T6G_MB_LIB.T6G(SCH_1):GND   I350 @T6G_MB_LIB.T6G(SCH_1):PAGE89
   191    GND @T6G_MB_LIB.T6G(SCH_1):GND   I350 @T6G_MB_LIB.T6G(SCH_1):PAGE89
   193    GND @T6G_MB_LIB.T6G(SCH_1):GND   I350 @T6G_MB_LIB.T6G(SCH_1):PAGE89
   195    GND @T6G_MB_LIB.T6G(SCH_1):GND   I350 @T6G_MB_LIB.T6G(SCH_1):PAGE89
   197    GND @T6G_MB_LIB.T6G(SCH_1):GND   I350 @T6G_MB_LIB.T6G(SCH_1):PAGE89
   199    GND @T6G_MB_LIB.T6G(SCH_1):GND   I350 @T6G_MB_LIB.T6G(SCH_1):PAGE89
   202    GND @T6G_MB_LIB.T6G(SCH_1):GND   I350 @T6G_MB_LIB.T6G(SCH_1):PAGE89
   204    GND @T6G_MB_LIB.T6G(SCH_1):GND   I350 @T6G_MB_LIB.T6G(SCH_1):PAGE89
   206    GND @T6G_MB_LIB.T6G(SCH_1):GND   I350 @T6G_MB_LIB.T6G(SCH_1):PAGE89
   208    GND @T6G_MB_LIB.T6G(SCH_1):GND   I350 @T6G_MB_LIB.T6G(SCH_1):PAGE89
   210    GND @T6G_MB_LIB.T6G(SCH_1):GND   I350 @T6G_MB_LIB.T6G(SCH_1):PAGE89
   212    GND @T6G_MB_LIB.T6G(SCH_1):GND   I350 @T6G_MB_LIB.T6G(SCH_1):PAGE89
   214    GND @T6G_MB_LIB.T6G(SCH_1):GND   I350 @T6G_MB_LIB.T6G(SCH_1):PAGE89
   216    GND @T6G_MB_LIB.T6G(SCH_1):GND   I350 @T6G_MB_LIB.T6G(SCH_1):PAGE89
   219    GND @T6G_MB_LIB.T6G(SCH_1):GND   I350 @T6G_MB_LIB.T6G(SCH_1):PAGE89
   222    GND @T6G_MB_LIB.T6G(SCH_1):GND   I350 @T6G_MB_LIB.T6G(SCH_1):PAGE89
   224    GND @T6G_MB_LIB.T6G(SCH_1):GND   I350 @T6G_MB_LIB.T6G(SCH_1):PAGE89
   226    GND @T6G_MB_LIB.T6G(SCH_1):GND   I350 @T6G_MB_LIB.T6G(SCH_1):PAGE89
   228    GND @T6G_MB_LIB.T6G(SCH_1):GND   I350 @T6G_MB_LIB.T6G(SCH_1):PAGE89
   233    GND @T6G_MB_LIB.T6G(SCH_1):GND   I350 @T6G_MB_LIB.T6G(SCH_1):PAGE89
   237    GND @T6G_MB_LIB.T6G(SCH_1):GND   I350 @T6G_MB_LIB.T6G(SCH_1):PAGE89
   242    GND @T6G_MB_LIB.T6G(SCH_1):GND   I350 @T6G_MB_LIB.T6G(SCH_1):PAGE89
   244    GND @T6G_MB_LIB.T6G(SCH_1):GND   I350 @T6G_MB_LIB.T6G(SCH_1):PAGE89
   246    GND @T6G_MB_LIB.T6G(SCH_1):GND   I350 @T6G_MB_LIB.T6G(SCH_1):PAGE89
   248    GND @T6G_MB_LIB.T6G(SCH_1):GND   I350 @T6G_MB_LIB.T6G(SCH_1):PAGE89
   251    GND @T6G_MB_LIB.T6G(SCH_1):GND   I350 @T6G_MB_LIB.T6G(SCH_1):PAGE89
   253    GND @T6G_MB_LIB.T6G(SCH_1):GND   I350 @T6G_MB_LIB.T6G(SCH_1):PAGE89
   255    GND @T6G_MB_LIB.T6G(SCH_1):GND   I350 @T6G_MB_LIB.T6G(SCH_1):PAGE89
   257    GND @T6G_MB_LIB.T6G(SCH_1):GND   I350 @T6G_MB_LIB.T6G(SCH_1):PAGE89
   259    GND @T6G_MB_LIB.T6G(SCH_1):GND   I350 @T6G_MB_LIB.T6G(SCH_1):PAGE89
   262    GND @T6G_MB_LIB.T6G(SCH_1):GND   I350 @T6G_MB_LIB.T6G(SCH_1):PAGE89
   264    GND @T6G_MB_LIB.T6G(SCH_1):GND   I350 @T6G_MB_LIB.T6G(SCH_1):PAGE89
   266    GND @T6G_MB_LIB.T6G(SCH_1):GND   I350 @T6G_MB_LIB.T6G(SCH_1):PAGE89
   268    GND @T6G_MB_LIB.T6G(SCH_1):GND   I350 @T6G_MB_LIB.T6G(SCH_1):PAGE89
   270    GND @T6G_MB_LIB.T6G(SCH_1):GND   I350 @T6G_MB_LIB.T6G(SCH_1):PAGE89
   273    GND @T6G_MB_LIB.T6G(SCH_1):GND   I350 @T6G_MB_LIB.T6G(SCH_1):PAGE89
   275    GND @T6G_MB_LIB.T6G(SCH_1):GND   I350 @T6G_MB_LIB.T6G(SCH_1):PAGE89
   277    GND @T6G_MB_LIB.T6G(SCH_1):GND   I350 @T6G_MB_LIB.T6G(SCH_1):PAGE89
   279    GND @T6G_MB_LIB.T6G(SCH_1):GND   I350 @T6G_MB_LIB.T6G(SCH_1):PAGE89
   281    GND @T6G_MB_LIB.T6G(SCH_1):GND   I350 @T6G_MB_LIB.T6G(SCH_1):PAGE89
   284    GND @T6G_MB_LIB.T6G(SCH_1):GND   I350 @T6G_MB_LIB.T6G(SCH_1):PAGE89
   286    GND @T6G_MB_LIB.T6G(SCH_1):GND   I350 @T6G_MB_LIB.T6G(SCH_1):PAGE89
   288    GND @T6G_MB_LIB.T6G(SCH_1):GND   I350 @T6G_MB_LIB.T6G(SCH_1):PAGE89
     1 P12V_MEM_CPU0 @T6G_MB_LIB.T6G(SCH_1):P12V_MEM_CPU0   I350 @T6G_MB_LIB.T6G(SCH_1):PAGE89
   145 P12V_MEM_CPU0 @T6G_MB_LIB.T6G(SCH_1):P12V_MEM_CPU0   I350 @T6G_MB_LIB.T6G(SCH_1):PAGE89
   146 P12V_MEM_CPU0 @T6G_MB_LIB.T6G(SCH_1):P12V_MEM_CPU0   I350 @T6G_MB_LIB.T6G(SCH_1):PAGE89
   230    GND @T6G_MB_LIB.T6G(SCH_1):GND   I350 @T6G_MB_LIB.T6G(SCH_1):PAGE89
   235    GND @T6G_MB_LIB.T6G(SCH_1):GND   I350 @T6G_MB_LIB.T6G(SCH_1):PAGE89
   240    GND @T6G_MB_LIB.T6G(SCH_1):GND   I350 @T6G_MB_LIB.T6G(SCH_1):PAGE89
   132    GND @T6G_MB_LIB.T6G(SCH_1):GND   I350 @T6G_MB_LIB.T6G(SCH_1):PAGE89
   136    GND @T6G_MB_LIB.T6G(SCH_1):GND   I350 @T6G_MB_LIB.T6G(SCH_1):PAGE89
   139    GND @T6G_MB_LIB.T6G(SCH_1):GND   I350 @T6G_MB_LIB.T6G(SCH_1):PAGE89
   141    GND @T6G_MB_LIB.T6G(SCH_1):GND   I350 @T6G_MB_LIB.T6G(SCH_1):PAGE89
    G1    GND @T6G_MB_LIB.T6G(SCH_1):GND   I350 @T6G_MB_LIB.T6G(SCH_1):PAGE89
    G2    GND @T6G_MB_LIB.T6G(SCH_1):GND   I350 @T6G_MB_LIB.T6G(SCH_1):PAGE89
    G3    GND @T6G_MB_LIB.T6G(SCH_1):GND   I350 @T6G_MB_LIB.T6G(SCH_1):PAGE89

 J23 SCONN288_DDR506112002KQ-SCONN288_DDR506112002KQ,SMA
     3 P3V3_AUX @T6G_MB_LIB.T6G(SCH_1):P3V3_AUX   I350 @T6G_MB_LIB.T6G(SCH_1):PAGE90
     2     NC     NC   I350 @T6G_MB_LIB.T6G(SCH_1):PAGE90
   144     NC     NC   I350 @T6G_MB_LIB.T6G(SCH_1):PAGE90
   149     NC     NC   I350 @T6G_MB_LIB.T6G(SCH_1):PAGE90
   150     NC     NC   I350 @T6G_MB_LIB.T6G(SCH_1):PAGE90
   220     NC     NC   I350 @T6G_MB_LIB.T6G(SCH_1):PAGE90
   231     NC     NC   I350 @T6G_MB_LIB.T6G(SCH_1):PAGE90
   232     NC     NC   I350 @T6G_MB_LIB.T6G(SCH_1):PAGE90
   207 M_F_CPU0_RESET_N @T6G_MB_LIB.T6G(SCH_1):M_F_CPU0_RESET_N   I350 @T6G_MB_LIB.T6G(SCH_1):PAGE90
   147 PWRGD_CHF_CPU0_DIMM @T6G_MB_LIB.T6G(SCH_1):PWRGD_CHF_CPU0_DIMM   I350 @T6G_MB_LIB.T6G(SCH_1):PAGE90
   227 M_F_CPU0_SB_PAR @T6G_MB_LIB.T6G(SCH_1):M_F_CPU0_SB_PAR   I350 @T6G_MB_LIB.T6G(SCH_1):PAGE90
    74 M_F_CPU0_SA_PAR @T6G_MB_LIB.T6G(SCH_1):M_F_CPU0_SA_PAR   I350 @T6G_MB_LIB.T6G(SCH_1):PAGE90
    87 M_F_CPU0_SB_RSP<0> @T6G_MB_LIB.T6G(SCH_1):M_F_CPU0_SB_RSP(0)   I350 @T6G_MB_LIB.T6G(SCH_1):PAGE90
    86 M_F_CPU0_SA_RSP<0> @T6G_MB_LIB.T6G(SCH_1):M_F_CPU0_SA_RSP(0)   I350 @T6G_MB_LIB.T6G(SCH_1):PAGE90
     5 I3C_SPD_DDRF_CPU0_SDA @T6G_MB_LIB.T6G(SCH_1):I3C_SPD_DDRF_CPU0_SDA   I350 @T6G_MB_LIB.T6G(SCH_1):PAGE90
     4 I3C_SPD_DDRF_CPU0_SCL @T6G_MB_LIB.T6G(SCH_1):I3C_SPD_DDRF_CPU0_SCL   I350 @T6G_MB_LIB.T6G(SCH_1):PAGE90
   148 PD_CHF_CPU0_DIMM_SAA @T6G_MB_LIB.T6G(SCH_1):PD_CHF_CPU0_DIMM_SAA   I350 @T6G_MB_LIB.T6G(SCH_1):PAGE90
   100 M_F_CPU0_SB_DQ<0> @T6G_MB_LIB.T6G(SCH_1):M_F_CPU0_SB_DQ(0)   I350 @T6G_MB_LIB.T6G(SCH_1):PAGE90
   102 M_F_CPU0_SB_DQ<1> @T6G_MB_LIB.T6G(SCH_1):M_F_CPU0_SB_DQ(1)   I350 @T6G_MB_LIB.T6G(SCH_1):PAGE90
   245 M_F_CPU0_SB_DQ<2> @T6G_MB_LIB.T6G(SCH_1):M_F_CPU0_SB_DQ(2)   I350 @T6G_MB_LIB.T6G(SCH_1):PAGE90
   247 M_F_CPU0_SB_DQ<3> @T6G_MB_LIB.T6G(SCH_1):M_F_CPU0_SB_DQ(3)   I350 @T6G_MB_LIB.T6G(SCH_1):PAGE90
   107 M_F_CPU0_SB_DQ<4> @T6G_MB_LIB.T6G(SCH_1):M_F_CPU0_SB_DQ(4)   I350 @T6G_MB_LIB.T6G(SCH_1):PAGE90
   109 M_F_CPU0_SB_DQ<5> @T6G_MB_LIB.T6G(SCH_1):M_F_CPU0_SB_DQ(5)   I350 @T6G_MB_LIB.T6G(SCH_1):PAGE90
   252 M_F_CPU0_SB_DQ<6> @T6G_MB_LIB.T6G(SCH_1):M_F_CPU0_SB_DQ(6)   I350 @T6G_MB_LIB.T6G(SCH_1):PAGE90
   254 M_F_CPU0_SB_DQ<7> @T6G_MB_LIB.T6G(SCH_1):M_F_CPU0_SB_DQ(7)   I350 @T6G_MB_LIB.T6G(SCH_1):PAGE90
   111 M_F_CPU0_SB_DQ<8> @T6G_MB_LIB.T6G(SCH_1):M_F_CPU0_SB_DQ(8)   I350 @T6G_MB_LIB.T6G(SCH_1):PAGE90
   113 M_F_CPU0_SB_DQ<9> @T6G_MB_LIB.T6G(SCH_1):M_F_CPU0_SB_DQ(9)   I350 @T6G_MB_LIB.T6G(SCH_1):PAGE90
   256 M_F_CPU0_SB_DQ<10> @T6G_MB_LIB.T6G(SCH_1):M_F_CPU0_SB_DQ(10)   I350 @T6G_MB_LIB.T6G(SCH_1):PAGE90
   258 M_F_CPU0_SB_DQ<11> @T6G_MB_LIB.T6G(SCH_1):M_F_CPU0_SB_DQ(11)   I350 @T6G_MB_LIB.T6G(SCH_1):PAGE90
   118 M_F_CPU0_SB_DQ<12> @T6G_MB_LIB.T6G(SCH_1):M_F_CPU0_SB_DQ(12)   I350 @T6G_MB_LIB.T6G(SCH_1):PAGE90
   120 M_F_CPU0_SB_DQ<13> @T6G_MB_LIB.T6G(SCH_1):M_F_CPU0_SB_DQ(13)   I350 @T6G_MB_LIB.T6G(SCH_1):PAGE90
   263 M_F_CPU0_SB_DQ<14> @T6G_MB_LIB.T6G(SCH_1):M_F_CPU0_SB_DQ(14)   I350 @T6G_MB_LIB.T6G(SCH_1):PAGE90
   265 M_F_CPU0_SB_DQ<15> @T6G_MB_LIB.T6G(SCH_1):M_F_CPU0_SB_DQ(15)   I350 @T6G_MB_LIB.T6G(SCH_1):PAGE90
   122 M_F_CPU0_SB_DQ<16> @T6G_MB_LIB.T6G(SCH_1):M_F_CPU0_SB_DQ(16)   I350 @T6G_MB_LIB.T6G(SCH_1):PAGE90
   124 M_F_CPU0_SB_DQ<17> @T6G_MB_LIB.T6G(SCH_1):M_F_CPU0_SB_DQ(17)   I350 @T6G_MB_LIB.T6G(SCH_1):PAGE90
   267 M_F_CPU0_SB_DQ<18> @T6G_MB_LIB.T6G(SCH_1):M_F_CPU0_SB_DQ(18)   I350 @T6G_MB_LIB.T6G(SCH_1):PAGE90
   269 M_F_CPU0_SB_DQ<19> @T6G_MB_LIB.T6G(SCH_1):M_F_CPU0_SB_DQ(19)   I350 @T6G_MB_LIB.T6G(SCH_1):PAGE90
   129 M_F_CPU0_SB_DQ<20> @T6G_MB_LIB.T6G(SCH_1):M_F_CPU0_SB_DQ(20)   I350 @T6G_MB_LIB.T6G(SCH_1):PAGE90
   131 M_F_CPU0_SB_DQ<21> @T6G_MB_LIB.T6G(SCH_1):M_F_CPU0_SB_DQ(21)   I350 @T6G_MB_LIB.T6G(SCH_1):PAGE90
   274 M_F_CPU0_SB_DQ<22> @T6G_MB_LIB.T6G(SCH_1):M_F_CPU0_SB_DQ(22)   I350 @T6G_MB_LIB.T6G(SCH_1):PAGE90
   276 M_F_CPU0_SB_DQ<23> @T6G_MB_LIB.T6G(SCH_1):M_F_CPU0_SB_DQ(23)   I350 @T6G_MB_LIB.T6G(SCH_1):PAGE90
   133 M_F_CPU0_SB_DQ<24> @T6G_MB_LIB.T6G(SCH_1):M_F_CPU0_SB_DQ(24)   I350 @T6G_MB_LIB.T6G(SCH_1):PAGE90
   135 M_F_CPU0_SB_DQ<25> @T6G_MB_LIB.T6G(SCH_1):M_F_CPU0_SB_DQ(25)   I350 @T6G_MB_LIB.T6G(SCH_1):PAGE90
   278 M_F_CPU0_SB_DQ<26> @T6G_MB_LIB.T6G(SCH_1):M_F_CPU0_SB_DQ(26)   I350 @T6G_MB_LIB.T6G(SCH_1):PAGE90
   280 M_F_CPU0_SB_DQ<27> @T6G_MB_LIB.T6G(SCH_1):M_F_CPU0_SB_DQ(27)   I350 @T6G_MB_LIB.T6G(SCH_1):PAGE90
   140 M_F_CPU0_SB_DQ<28> @T6G_MB_LIB.T6G(SCH_1):M_F_CPU0_SB_DQ(28)   I350 @T6G_MB_LIB.T6G(SCH_1):PAGE90
   142 M_F_CPU0_SB_DQ<29> @T6G_MB_LIB.T6G(SCH_1):M_F_CPU0_SB_DQ(29)   I350 @T6G_MB_LIB.T6G(SCH_1):PAGE90
   285 M_F_CPU0_SB_DQ<30> @T6G_MB_LIB.T6G(SCH_1):M_F_CPU0_SB_DQ(30)   I350 @T6G_MB_LIB.T6G(SCH_1):PAGE90
   287 M_F_CPU0_SB_DQ<31> @T6G_MB_LIB.T6G(SCH_1):M_F_CPU0_SB_DQ(31)   I350 @T6G_MB_LIB.T6G(SCH_1):PAGE90
     7 M_F_CPU0_SA_DQ<0> @T6G_MB_LIB.T6G(SCH_1):M_F_CPU0_SA_DQ(0)   I350 @T6G_MB_LIB.T6G(SCH_1):PAGE90
     9 M_F_CPU0_SA_DQ<1> @T6G_MB_LIB.T6G(SCH_1):M_F_CPU0_SA_DQ(1)   I350 @T6G_MB_LIB.T6G(SCH_1):PAGE90
   152 M_F_CPU0_SA_DQ<2> @T6G_MB_LIB.T6G(SCH_1):M_F_CPU0_SA_DQ(2)   I350 @T6G_MB_LIB.T6G(SCH_1):PAGE90
   154 M_F_CPU0_SA_DQ<3> @T6G_MB_LIB.T6G(SCH_1):M_F_CPU0_SA_DQ(3)   I350 @T6G_MB_LIB.T6G(SCH_1):PAGE90
    14 M_F_CPU0_SA_DQ<4> @T6G_MB_LIB.T6G(SCH_1):M_F_CPU0_SA_DQ(4)   I350 @T6G_MB_LIB.T6G(SCH_1):PAGE90
    16 M_F_CPU0_SA_DQ<5> @T6G_MB_LIB.T6G(SCH_1):M_F_CPU0_SA_DQ(5)   I350 @T6G_MB_LIB.T6G(SCH_1):PAGE90
   159 M_F_CPU0_SA_DQ<6> @T6G_MB_LIB.T6G(SCH_1):M_F_CPU0_SA_DQ(6)   I350 @T6G_MB_LIB.T6G(SCH_1):PAGE90
   161 M_F_CPU0_SA_DQ<7> @T6G_MB_LIB.T6G(SCH_1):M_F_CPU0_SA_DQ(7)   I350 @T6G_MB_LIB.T6G(SCH_1):PAGE90
    18 M_F_CPU0_SA_DQ<8> @T6G_MB_LIB.T6G(SCH_1):M_F_CPU0_SA_DQ(8)   I350 @T6G_MB_LIB.T6G(SCH_1):PAGE90
    20 M_F_CPU0_SA_DQ<9> @T6G_MB_LIB.T6G(SCH_1):M_F_CPU0_SA_DQ(9)   I350 @T6G_MB_LIB.T6G(SCH_1):PAGE90
   163 M_F_CPU0_SA_DQ<10> @T6G_MB_LIB.T6G(SCH_1):M_F_CPU0_SA_DQ(10)   I350 @T6G_MB_LIB.T6G(SCH_1):PAGE90
   165 M_F_CPU0_SA_DQ<11> @T6G_MB_LIB.T6G(SCH_1):M_F_CPU0_SA_DQ(11)   I350 @T6G_MB_LIB.T6G(SCH_1):PAGE90
    25 M_F_CPU0_SA_DQ<12> @T6G_MB_LIB.T6G(SCH_1):M_F_CPU0_SA_DQ(12)   I350 @T6G_MB_LIB.T6G(SCH_1):PAGE90
    27 M_F_CPU0_SA_DQ<13> @T6G_MB_LIB.T6G(SCH_1):M_F_CPU0_SA_DQ(13)   I350 @T6G_MB_LIB.T6G(SCH_1):PAGE90
   170 M_F_CPU0_SA_DQ<14> @T6G_MB_LIB.T6G(SCH_1):M_F_CPU0_SA_DQ(14)   I350 @T6G_MB_LIB.T6G(SCH_1):PAGE90
   172 M_F_CPU0_SA_DQ<15> @T6G_MB_LIB.T6G(SCH_1):M_F_CPU0_SA_DQ(15)   I350 @T6G_MB_LIB.T6G(SCH_1):PAGE90
    29 M_F_CPU0_SA_DQ<16> @T6G_MB_LIB.T6G(SCH_1):M_F_CPU0_SA_DQ(16)   I350 @T6G_MB_LIB.T6G(SCH_1):PAGE90
    31 M_F_CPU0_SA_DQ<17> @T6G_MB_LIB.T6G(SCH_1):M_F_CPU0_SA_DQ(17)   I350 @T6G_MB_LIB.T6G(SCH_1):PAGE90
   174 M_F_CPU0_SA_DQ<18> @T6G_MB_LIB.T6G(SCH_1):M_F_CPU0_SA_DQ(18)   I350 @T6G_MB_LIB.T6G(SCH_1):PAGE90
   176 M_F_CPU0_SA_DQ<19> @T6G_MB_LIB.T6G(SCH_1):M_F_CPU0_SA_DQ(19)   I350 @T6G_MB_LIB.T6G(SCH_1):PAGE90
    36 M_F_CPU0_SA_DQ<20> @T6G_MB_LIB.T6G(SCH_1):M_F_CPU0_SA_DQ(20)   I350 @T6G_MB_LIB.T6G(SCH_1):PAGE90
    38 M_F_CPU0_SA_DQ<21> @T6G_MB_LIB.T6G(SCH_1):M_F_CPU0_SA_DQ(21)   I350 @T6G_MB_LIB.T6G(SCH_1):PAGE90
   181 M_F_CPU0_SA_DQ<22> @T6G_MB_LIB.T6G(SCH_1):M_F_CPU0_SA_DQ(22)   I350 @T6G_MB_LIB.T6G(SCH_1):PAGE90
   183 M_F_CPU0_SA_DQ<23> @T6G_MB_LIB.T6G(SCH_1):M_F_CPU0_SA_DQ(23)   I350 @T6G_MB_LIB.T6G(SCH_1):PAGE90
    40 M_F_CPU0_SA_DQ<24> @T6G_MB_LIB.T6G(SCH_1):M_F_CPU0_SA_DQ(24)   I350 @T6G_MB_LIB.T6G(SCH_1):PAGE90
    42 M_F_CPU0_SA_DQ<25> @T6G_MB_LIB.T6G(SCH_1):M_F_CPU0_SA_DQ(25)   I350 @T6G_MB_LIB.T6G(SCH_1):PAGE90
   185 M_F_CPU0_SA_DQ<26> @T6G_MB_LIB.T6G(SCH_1):M_F_CPU0_SA_DQ(26)   I350 @T6G_MB_LIB.T6G(SCH_1):PAGE90
   187 M_F_CPU0_SA_DQ<27> @T6G_MB_LIB.T6G(SCH_1):M_F_CPU0_SA_DQ(27)   I350 @T6G_MB_LIB.T6G(SCH_1):PAGE90
    47 M_F_CPU0_SA_DQ<28> @T6G_MB_LIB.T6G(SCH_1):M_F_CPU0_SA_DQ(28)   I350 @T6G_MB_LIB.T6G(SCH_1):PAGE90
    49 M_F_CPU0_SA_DQ<29> @T6G_MB_LIB.T6G(SCH_1):M_F_CPU0_SA_DQ(29)   I350 @T6G_MB_LIB.T6G(SCH_1):PAGE90
   192 M_F_CPU0_SA_DQ<30> @T6G_MB_LIB.T6G(SCH_1):M_F_CPU0_SA_DQ(30)   I350 @T6G_MB_LIB.T6G(SCH_1):PAGE90
   229 M_F_CPU0_SB_CS_N<1> @T6G_MB_LIB.T6G(SCH_1):M_F_CPU0_SB_CS_N(1)   I350 @T6G_MB_LIB.T6G(SCH_1):PAGE90
   209 M_F_CPU0_SA_CS_N<1> @T6G_MB_LIB.T6G(SCH_1):M_F_CPU0_SA_CS_N(1)   I350 @T6G_MB_LIB.T6G(SCH_1):PAGE90
    84 M_F_CPU0_SB_CS_N<0> @T6G_MB_LIB.T6G(SCH_1):M_F_CPU0_SB_CS_N(0)   I350 @T6G_MB_LIB.T6G(SCH_1):PAGE90
    64 M_F_CPU0_SA_CS_N<0> @T6G_MB_LIB.T6G(SCH_1):M_F_CPU0_SA_CS_N(0)   I350 @T6G_MB_LIB.T6G(SCH_1):PAGE90
   217 M_F_CPU0_CLK_DP<0> @T6G_MB_LIB.T6G(SCH_1):M_F_CPU0_CLK_DP(0)   I350 @T6G_MB_LIB.T6G(SCH_1):PAGE90
   218 M_F_CPU0_CLK_DN<0> @T6G_MB_LIB.T6G(SCH_1):M_F_CPU0_CLK_DN(0)   I350 @T6G_MB_LIB.T6G(SCH_1):PAGE90
    96 M_F_CPU0_SB_CB<0> @T6G_MB_LIB.T6G(SCH_1):M_F_CPU0_SB_CB(0)   I350 @T6G_MB_LIB.T6G(SCH_1):PAGE90
    98 M_F_CPU0_SB_CB<1> @T6G_MB_LIB.T6G(SCH_1):M_F_CPU0_SB_CB(1)   I350 @T6G_MB_LIB.T6G(SCH_1):PAGE90
   241 M_F_CPU0_SB_CB<2> @T6G_MB_LIB.T6G(SCH_1):M_F_CPU0_SB_CB(2)   I350 @T6G_MB_LIB.T6G(SCH_1):PAGE90
   243 M_F_CPU0_SB_CB<3> @T6G_MB_LIB.T6G(SCH_1):M_F_CPU0_SB_CB(3)   I350 @T6G_MB_LIB.T6G(SCH_1):PAGE90
    89 M_F_CPU0_SB_CB<4> @T6G_MB_LIB.T6G(SCH_1):M_F_CPU0_SB_CB(4)   I350 @T6G_MB_LIB.T6G(SCH_1):PAGE90
    91 M_F_CPU0_SB_CB<5> @T6G_MB_LIB.T6G(SCH_1):M_F_CPU0_SB_CB(5)   I350 @T6G_MB_LIB.T6G(SCH_1):PAGE90
   234 M_F_CPU0_SB_CB<6> @T6G_MB_LIB.T6G(SCH_1):M_F_CPU0_SB_CB(6)   I350 @T6G_MB_LIB.T6G(SCH_1):PAGE90
    51 M_F_CPU0_SA_CB<0> @T6G_MB_LIB.T6G(SCH_1):M_F_CPU0_SA_CB(0)   I350 @T6G_MB_LIB.T6G(SCH_1):PAGE90
   196 M_F_CPU0_SA_CB<2> @T6G_MB_LIB.T6G(SCH_1):M_F_CPU0_SA_CB(2)   I350 @T6G_MB_LIB.T6G(SCH_1):PAGE90
   198 M_F_CPU0_SA_CB<3> @T6G_MB_LIB.T6G(SCH_1):M_F_CPU0_SA_CB(3)   I350 @T6G_MB_LIB.T6G(SCH_1):PAGE90
    60 M_F_CPU0_SA_CB<5> @T6G_MB_LIB.T6G(SCH_1):M_F_CPU0_SA_CB(5)   I350 @T6G_MB_LIB.T6G(SCH_1):PAGE90
   203 M_F_CPU0_SA_CB<6> @T6G_MB_LIB.T6G(SCH_1):M_F_CPU0_SA_CB(6)   I350 @T6G_MB_LIB.T6G(SCH_1):PAGE90
    82 M_F_CPU0_SB_CA<6> @T6G_MB_LIB.T6G(SCH_1):M_F_CPU0_SB_CA(6)   I350 @T6G_MB_LIB.T6G(SCH_1):PAGE90
    72 M_F_CPU0_SA_CA<6> @T6G_MB_LIB.T6G(SCH_1):M_F_CPU0_SA_CA(6)   I350 @T6G_MB_LIB.T6G(SCH_1):PAGE90
   225 M_F_CPU0_SB_CA<5> @T6G_MB_LIB.T6G(SCH_1):M_F_CPU0_SB_CA(5)   I350 @T6G_MB_LIB.T6G(SCH_1):PAGE90
   215 M_F_CPU0_SA_CA<5> @T6G_MB_LIB.T6G(SCH_1):M_F_CPU0_SA_CA(5)   I350 @T6G_MB_LIB.T6G(SCH_1):PAGE90
    80 M_F_CPU0_SB_CA<4> @T6G_MB_LIB.T6G(SCH_1):M_F_CPU0_SB_CA(4)   I350 @T6G_MB_LIB.T6G(SCH_1):PAGE90
    70 M_F_CPU0_SA_CA<4> @T6G_MB_LIB.T6G(SCH_1):M_F_CPU0_SA_CA(4)   I350 @T6G_MB_LIB.T6G(SCH_1):PAGE90
   223 M_F_CPU0_SB_CA<3> @T6G_MB_LIB.T6G(SCH_1):M_F_CPU0_SB_CA(3)   I350 @T6G_MB_LIB.T6G(SCH_1):PAGE90
   213 M_F_CPU0_SA_CA<3> @T6G_MB_LIB.T6G(SCH_1):M_F_CPU0_SA_CA(3)   I350 @T6G_MB_LIB.T6G(SCH_1):PAGE90
    78 M_F_CPU0_SB_CA<2> @T6G_MB_LIB.T6G(SCH_1):M_F_CPU0_SB_CA(2)   I350 @T6G_MB_LIB.T6G(SCH_1):PAGE90
    68 M_F_CPU0_SA_CA<2> @T6G_MB_LIB.T6G(SCH_1):M_F_CPU0_SA_CA(2)   I350 @T6G_MB_LIB.T6G(SCH_1):PAGE90
   221 M_F_CPU0_SB_CA<1> @T6G_MB_LIB.T6G(SCH_1):M_F_CPU0_SB_CA(1)   I350 @T6G_MB_LIB.T6G(SCH_1):PAGE90
   211 M_F_CPU0_SA_CA<1> @T6G_MB_LIB.T6G(SCH_1):M_F_CPU0_SA_CA(1)   I350 @T6G_MB_LIB.T6G(SCH_1):PAGE90
    76 M_F_CPU0_SB_CA<0> @T6G_MB_LIB.T6G(SCH_1):M_F_CPU0_SB_CA(0)   I350 @T6G_MB_LIB.T6G(SCH_1):PAGE90
    66 M_F_CPU0_SA_CA<0> @T6G_MB_LIB.T6G(SCH_1):M_F_CPU0_SA_CA(0)   I350 @T6G_MB_LIB.T6G(SCH_1):PAGE90
    62 M_F_CPU0_ALERT_N @T6G_MB_LIB.T6G(SCH_1):M_F_CPU0_ALERT_N   I350 @T6G_MB_LIB.T6G(SCH_1):PAGE90
   236 M_F_CPU0_SB_CB<7> @T6G_MB_LIB.T6G(SCH_1):M_F_CPU0_SB_CB(7)   I350 @T6G_MB_LIB.T6G(SCH_1):PAGE90
    53 M_F_CPU0_SA_CB<1> @T6G_MB_LIB.T6G(SCH_1):M_F_CPU0_SA_CB(1)   I350 @T6G_MB_LIB.T6G(SCH_1):PAGE90
    58 M_F_CPU0_SA_CB<4> @T6G_MB_LIB.T6G(SCH_1):M_F_CPU0_SA_CB(4)   I350 @T6G_MB_LIB.T6G(SCH_1):PAGE90
   205 M_F_CPU0_SA_CB<7> @T6G_MB_LIB.T6G(SCH_1):M_F_CPU0_SA_CB(7)   I350 @T6G_MB_LIB.T6G(SCH_1):PAGE90
   194 M_F_CPU0_SA_DQ<31> @T6G_MB_LIB.T6G(SCH_1):M_F_CPU0_SA_DQ(31)   I350 @T6G_MB_LIB.T6G(SCH_1):PAGE90
    93 M_F_CPU0_SB_DQS_DP<9> @T6G_MB_LIB.T6G(SCH_1):M_F_CPU0_SB_DQS_DP(9)   I412 @T6G_MB_LIB.T6G(SCH_1):PAGE90
    94 M_F_CPU0_SB_DQS_DN<9> @T6G_MB_LIB.T6G(SCH_1):M_F_CPU0_SB_DQS_DN(9)   I412 @T6G_MB_LIB.T6G(SCH_1):PAGE90
   201 M_F_CPU0_SA_DQS_DP<9> @T6G_MB_LIB.T6G(SCH_1):M_F_CPU0_SA_DQS_DP(9)   I412 @T6G_MB_LIB.T6G(SCH_1):PAGE90
   200 M_F_CPU0_SA_DQS_DN<9> @T6G_MB_LIB.T6G(SCH_1):M_F_CPU0_SA_DQS_DN(9)   I412 @T6G_MB_LIB.T6G(SCH_1):PAGE90
   190 M_F_CPU0_SA_DQS_DP<8> @T6G_MB_LIB.T6G(SCH_1):M_F_CPU0_SA_DQS_DP(8)   I412 @T6G_MB_LIB.T6G(SCH_1):PAGE90
   189 M_F_CPU0_SA_DQS_DN<8> @T6G_MB_LIB.T6G(SCH_1):M_F_CPU0_SA_DQS_DN(8)   I412 @T6G_MB_LIB.T6G(SCH_1):PAGE90
   271 M_F_CPU0_SB_DQS_DN<7> @T6G_MB_LIB.T6G(SCH_1):M_F_CPU0_SB_DQS_DN(7)   I412 @T6G_MB_LIB.T6G(SCH_1):PAGE90
   179 M_F_CPU0_SA_DQS_DP<7> @T6G_MB_LIB.T6G(SCH_1):M_F_CPU0_SA_DQS_DP(7)   I412 @T6G_MB_LIB.T6G(SCH_1):PAGE90
   261 M_F_CPU0_SB_DQS_DP<6> @T6G_MB_LIB.T6G(SCH_1):M_F_CPU0_SB_DQS_DP(6)   I412 @T6G_MB_LIB.T6G(SCH_1):PAGE90
   260 M_F_CPU0_SB_DQS_DN<6> @T6G_MB_LIB.T6G(SCH_1):M_F_CPU0_SB_DQS_DN(6)   I412 @T6G_MB_LIB.T6G(SCH_1):PAGE90
   167 M_F_CPU0_SA_DQS_DN<6> @T6G_MB_LIB.T6G(SCH_1):M_F_CPU0_SA_DQS_DN(6)   I412 @T6G_MB_LIB.T6G(SCH_1):PAGE90
   250 M_F_CPU0_SB_DQS_DP<5> @T6G_MB_LIB.T6G(SCH_1):M_F_CPU0_SB_DQS_DP(5)   I412 @T6G_MB_LIB.T6G(SCH_1):PAGE90
   249 M_F_CPU0_SB_DQS_DN<5> @T6G_MB_LIB.T6G(SCH_1):M_F_CPU0_SB_DQS_DN(5)   I412 @T6G_MB_LIB.T6G(SCH_1):PAGE90
   157 M_F_CPU0_SA_DQS_DP<5> @T6G_MB_LIB.T6G(SCH_1):M_F_CPU0_SA_DQS_DP(5)   I412 @T6G_MB_LIB.T6G(SCH_1):PAGE90
   156 M_F_CPU0_SA_DQS_DN<5> @T6G_MB_LIB.T6G(SCH_1):M_F_CPU0_SA_DQS_DN(5)   I412 @T6G_MB_LIB.T6G(SCH_1):PAGE90
   239 M_F_CPU0_SB_DQS_DP<4> @T6G_MB_LIB.T6G(SCH_1):M_F_CPU0_SB_DQS_DP(4)   I412 @T6G_MB_LIB.T6G(SCH_1):PAGE90
   238 M_F_CPU0_SB_DQS_DN<4> @T6G_MB_LIB.T6G(SCH_1):M_F_CPU0_SB_DQS_DN(4)   I412 @T6G_MB_LIB.T6G(SCH_1):PAGE90
    55 M_F_CPU0_SA_DQS_DP<4> @T6G_MB_LIB.T6G(SCH_1):M_F_CPU0_SA_DQS_DP(4)   I412 @T6G_MB_LIB.T6G(SCH_1):PAGE90
    56 M_F_CPU0_SA_DQS_DN<4> @T6G_MB_LIB.T6G(SCH_1):M_F_CPU0_SA_DQS_DN(4)   I412 @T6G_MB_LIB.T6G(SCH_1):PAGE90
   137 M_F_CPU0_SB_DQS_DP<3> @T6G_MB_LIB.T6G(SCH_1):M_F_CPU0_SB_DQS_DP(3)   I412 @T6G_MB_LIB.T6G(SCH_1):PAGE90
   138 M_F_CPU0_SB_DQS_DN<3> @T6G_MB_LIB.T6G(SCH_1):M_F_CPU0_SB_DQS_DN(3)   I412 @T6G_MB_LIB.T6G(SCH_1):PAGE90
    44 M_F_CPU0_SA_DQS_DP<3> @T6G_MB_LIB.T6G(SCH_1):M_F_CPU0_SA_DQS_DP(3)   I412 @T6G_MB_LIB.T6G(SCH_1):PAGE90
    45 M_F_CPU0_SA_DQS_DN<3> @T6G_MB_LIB.T6G(SCH_1):M_F_CPU0_SA_DQS_DN(3)   I412 @T6G_MB_LIB.T6G(SCH_1):PAGE90
   126 M_F_CPU0_SB_DQS_DP<2> @T6G_MB_LIB.T6G(SCH_1):M_F_CPU0_SB_DQS_DP(2)   I412 @T6G_MB_LIB.T6G(SCH_1):PAGE90
   127 M_F_CPU0_SB_DQS_DN<2> @T6G_MB_LIB.T6G(SCH_1):M_F_CPU0_SB_DQS_DN(2)   I412 @T6G_MB_LIB.T6G(SCH_1):PAGE90
    33 M_F_CPU0_SA_DQS_DP<2> @T6G_MB_LIB.T6G(SCH_1):M_F_CPU0_SA_DQS_DP(2)   I412 @T6G_MB_LIB.T6G(SCH_1):PAGE90
    34 M_F_CPU0_SA_DQS_DN<2> @T6G_MB_LIB.T6G(SCH_1):M_F_CPU0_SA_DQS_DN(2)   I412 @T6G_MB_LIB.T6G(SCH_1):PAGE90
   115 M_F_CPU0_SB_DQS_DP<1> @T6G_MB_LIB.T6G(SCH_1):M_F_CPU0_SB_DQS_DP(1)   I412 @T6G_MB_LIB.T6G(SCH_1):PAGE90
   116 M_F_CPU0_SB_DQS_DN<1> @T6G_MB_LIB.T6G(SCH_1):M_F_CPU0_SB_DQS_DN(1)   I412 @T6G_MB_LIB.T6G(SCH_1):PAGE90
    22 M_F_CPU0_SA_DQS_DP<1> @T6G_MB_LIB.T6G(SCH_1):M_F_CPU0_SA_DQS_DP(1)   I412 @T6G_MB_LIB.T6G(SCH_1):PAGE90
    23 M_F_CPU0_SA_DQS_DN<1> @T6G_MB_LIB.T6G(SCH_1):M_F_CPU0_SA_DQS_DN(1)   I412 @T6G_MB_LIB.T6G(SCH_1):PAGE90
   104 M_F_CPU0_SB_DQS_DP<0> @T6G_MB_LIB.T6G(SCH_1):M_F_CPU0_SB_DQS_DP(0)   I412 @T6G_MB_LIB.T6G(SCH_1):PAGE90
   105 M_F_CPU0_SB_DQS_DN<0> @T6G_MB_LIB.T6G(SCH_1):M_F_CPU0_SB_DQS_DN(0)   I412 @T6G_MB_LIB.T6G(SCH_1):PAGE90
    11 M_F_CPU0_SA_DQS_DP<0> @T6G_MB_LIB.T6G(SCH_1):M_F_CPU0_SA_DQS_DP(0)   I412 @T6G_MB_LIB.T6G(SCH_1):PAGE90
    12 M_F_CPU0_SA_DQS_DN<0> @T6G_MB_LIB.T6G(SCH_1):M_F_CPU0_SA_DQS_DN(0)   I412 @T6G_MB_LIB.T6G(SCH_1):PAGE90
   272 M_F_CPU0_SB_DQS_DP<7> @T6G_MB_LIB.T6G(SCH_1):M_F_CPU0_SB_DQS_DP(7)   I412 @T6G_MB_LIB.T6G(SCH_1):PAGE90
   282 M_F_CPU0_SB_DQS_DN<8> @T6G_MB_LIB.T6G(SCH_1):M_F_CPU0_SB_DQS_DN(8)   I412 @T6G_MB_LIB.T6G(SCH_1):PAGE90
   283 M_F_CPU0_SB_DQS_DP<8> @T6G_MB_LIB.T6G(SCH_1):M_F_CPU0_SB_DQS_DP(8)   I412 @T6G_MB_LIB.T6G(SCH_1):PAGE90
   168 M_F_CPU0_SA_DQS_DP<6> @T6G_MB_LIB.T6G(SCH_1):M_F_CPU0_SA_DQS_DP(6)   I412 @T6G_MB_LIB.T6G(SCH_1):PAGE90
   178 M_F_CPU0_SA_DQS_DN<7> @T6G_MB_LIB.T6G(SCH_1):M_F_CPU0_SA_DQS_DN(7)   I412 @T6G_MB_LIB.T6G(SCH_1):PAGE90
     6    GND @T6G_MB_LIB.T6G(SCH_1):GND   I352 @T6G_MB_LIB.T6G(SCH_1):PAGE90
     8    GND @T6G_MB_LIB.T6G(SCH_1):GND   I352 @T6G_MB_LIB.T6G(SCH_1):PAGE90
    10    GND @T6G_MB_LIB.T6G(SCH_1):GND   I352 @T6G_MB_LIB.T6G(SCH_1):PAGE90
    13    GND @T6G_MB_LIB.T6G(SCH_1):GND   I352 @T6G_MB_LIB.T6G(SCH_1):PAGE90
    15    GND @T6G_MB_LIB.T6G(SCH_1):GND   I352 @T6G_MB_LIB.T6G(SCH_1):PAGE90
    17    GND @T6G_MB_LIB.T6G(SCH_1):GND   I352 @T6G_MB_LIB.T6G(SCH_1):PAGE90
    19    GND @T6G_MB_LIB.T6G(SCH_1):GND   I352 @T6G_MB_LIB.T6G(SCH_1):PAGE90
    21    GND @T6G_MB_LIB.T6G(SCH_1):GND   I352 @T6G_MB_LIB.T6G(SCH_1):PAGE90
    24    GND @T6G_MB_LIB.T6G(SCH_1):GND   I352 @T6G_MB_LIB.T6G(SCH_1):PAGE90
    26    GND @T6G_MB_LIB.T6G(SCH_1):GND   I352 @T6G_MB_LIB.T6G(SCH_1):PAGE90
    28    GND @T6G_MB_LIB.T6G(SCH_1):GND   I352 @T6G_MB_LIB.T6G(SCH_1):PAGE90
    30    GND @T6G_MB_LIB.T6G(SCH_1):GND   I352 @T6G_MB_LIB.T6G(SCH_1):PAGE90
    32    GND @T6G_MB_LIB.T6G(SCH_1):GND   I352 @T6G_MB_LIB.T6G(SCH_1):PAGE90
    35    GND @T6G_MB_LIB.T6G(SCH_1):GND   I352 @T6G_MB_LIB.T6G(SCH_1):PAGE90
    37    GND @T6G_MB_LIB.T6G(SCH_1):GND   I352 @T6G_MB_LIB.T6G(SCH_1):PAGE90
    39    GND @T6G_MB_LIB.T6G(SCH_1):GND   I352 @T6G_MB_LIB.T6G(SCH_1):PAGE90
    41    GND @T6G_MB_LIB.T6G(SCH_1):GND   I352 @T6G_MB_LIB.T6G(SCH_1):PAGE90
    43    GND @T6G_MB_LIB.T6G(SCH_1):GND   I352 @T6G_MB_LIB.T6G(SCH_1):PAGE90
    46    GND @T6G_MB_LIB.T6G(SCH_1):GND   I352 @T6G_MB_LIB.T6G(SCH_1):PAGE90
    48    GND @T6G_MB_LIB.T6G(SCH_1):GND   I352 @T6G_MB_LIB.T6G(SCH_1):PAGE90
    50    GND @T6G_MB_LIB.T6G(SCH_1):GND   I352 @T6G_MB_LIB.T6G(SCH_1):PAGE90
    52    GND @T6G_MB_LIB.T6G(SCH_1):GND   I352 @T6G_MB_LIB.T6G(SCH_1):PAGE90
    54    GND @T6G_MB_LIB.T6G(SCH_1):GND   I352 @T6G_MB_LIB.T6G(SCH_1):PAGE90
    57    GND @T6G_MB_LIB.T6G(SCH_1):GND   I352 @T6G_MB_LIB.T6G(SCH_1):PAGE90
    59    GND @T6G_MB_LIB.T6G(SCH_1):GND   I352 @T6G_MB_LIB.T6G(SCH_1):PAGE90
    61    GND @T6G_MB_LIB.T6G(SCH_1):GND   I352 @T6G_MB_LIB.T6G(SCH_1):PAGE90
    63    GND @T6G_MB_LIB.T6G(SCH_1):GND   I352 @T6G_MB_LIB.T6G(SCH_1):PAGE90
    65    GND @T6G_MB_LIB.T6G(SCH_1):GND   I352 @T6G_MB_LIB.T6G(SCH_1):PAGE90
    67    GND @T6G_MB_LIB.T6G(SCH_1):GND   I352 @T6G_MB_LIB.T6G(SCH_1):PAGE90
    69    GND @T6G_MB_LIB.T6G(SCH_1):GND   I352 @T6G_MB_LIB.T6G(SCH_1):PAGE90
    71    GND @T6G_MB_LIB.T6G(SCH_1):GND   I352 @T6G_MB_LIB.T6G(SCH_1):PAGE90
    73    GND @T6G_MB_LIB.T6G(SCH_1):GND   I352 @T6G_MB_LIB.T6G(SCH_1):PAGE90
    75    GND @T6G_MB_LIB.T6G(SCH_1):GND   I352 @T6G_MB_LIB.T6G(SCH_1):PAGE90
    77    GND @T6G_MB_LIB.T6G(SCH_1):GND   I352 @T6G_MB_LIB.T6G(SCH_1):PAGE90
    79    GND @T6G_MB_LIB.T6G(SCH_1):GND   I352 @T6G_MB_LIB.T6G(SCH_1):PAGE90
    81    GND @T6G_MB_LIB.T6G(SCH_1):GND   I352 @T6G_MB_LIB.T6G(SCH_1):PAGE90
    83    GND @T6G_MB_LIB.T6G(SCH_1):GND   I352 @T6G_MB_LIB.T6G(SCH_1):PAGE90
    85    GND @T6G_MB_LIB.T6G(SCH_1):GND   I352 @T6G_MB_LIB.T6G(SCH_1):PAGE90
    88    GND @T6G_MB_LIB.T6G(SCH_1):GND   I352 @T6G_MB_LIB.T6G(SCH_1):PAGE90
    90    GND @T6G_MB_LIB.T6G(SCH_1):GND   I352 @T6G_MB_LIB.T6G(SCH_1):PAGE90
    92    GND @T6G_MB_LIB.T6G(SCH_1):GND   I352 @T6G_MB_LIB.T6G(SCH_1):PAGE90
    95    GND @T6G_MB_LIB.T6G(SCH_1):GND   I352 @T6G_MB_LIB.T6G(SCH_1):PAGE90
    97    GND @T6G_MB_LIB.T6G(SCH_1):GND   I352 @T6G_MB_LIB.T6G(SCH_1):PAGE90
    99    GND @T6G_MB_LIB.T6G(SCH_1):GND   I352 @T6G_MB_LIB.T6G(SCH_1):PAGE90
   101    GND @T6G_MB_LIB.T6G(SCH_1):GND   I352 @T6G_MB_LIB.T6G(SCH_1):PAGE90
   103    GND @T6G_MB_LIB.T6G(SCH_1):GND   I352 @T6G_MB_LIB.T6G(SCH_1):PAGE90
   106    GND @T6G_MB_LIB.T6G(SCH_1):GND   I352 @T6G_MB_LIB.T6G(SCH_1):PAGE90
   108    GND @T6G_MB_LIB.T6G(SCH_1):GND   I352 @T6G_MB_LIB.T6G(SCH_1):PAGE90
   110    GND @T6G_MB_LIB.T6G(SCH_1):GND   I352 @T6G_MB_LIB.T6G(SCH_1):PAGE90
   112    GND @T6G_MB_LIB.T6G(SCH_1):GND   I352 @T6G_MB_LIB.T6G(SCH_1):PAGE90
   114    GND @T6G_MB_LIB.T6G(SCH_1):GND   I352 @T6G_MB_LIB.T6G(SCH_1):PAGE90
   117    GND @T6G_MB_LIB.T6G(SCH_1):GND   I352 @T6G_MB_LIB.T6G(SCH_1):PAGE90
   119    GND @T6G_MB_LIB.T6G(SCH_1):GND   I352 @T6G_MB_LIB.T6G(SCH_1):PAGE90
   121    GND @T6G_MB_LIB.T6G(SCH_1):GND   I352 @T6G_MB_LIB.T6G(SCH_1):PAGE90
   123    GND @T6G_MB_LIB.T6G(SCH_1):GND   I352 @T6G_MB_LIB.T6G(SCH_1):PAGE90
   125    GND @T6G_MB_LIB.T6G(SCH_1):GND   I352 @T6G_MB_LIB.T6G(SCH_1):PAGE90
   128    GND @T6G_MB_LIB.T6G(SCH_1):GND   I352 @T6G_MB_LIB.T6G(SCH_1):PAGE90
   130    GND @T6G_MB_LIB.T6G(SCH_1):GND   I352 @T6G_MB_LIB.T6G(SCH_1):PAGE90
   134    GND @T6G_MB_LIB.T6G(SCH_1):GND   I352 @T6G_MB_LIB.T6G(SCH_1):PAGE90
   143    GND @T6G_MB_LIB.T6G(SCH_1):GND   I352 @T6G_MB_LIB.T6G(SCH_1):PAGE90
   151    GND @T6G_MB_LIB.T6G(SCH_1):GND   I352 @T6G_MB_LIB.T6G(SCH_1):PAGE90
   153    GND @T6G_MB_LIB.T6G(SCH_1):GND   I352 @T6G_MB_LIB.T6G(SCH_1):PAGE90
   155    GND @T6G_MB_LIB.T6G(SCH_1):GND   I352 @T6G_MB_LIB.T6G(SCH_1):PAGE90
   158    GND @T6G_MB_LIB.T6G(SCH_1):GND   I352 @T6G_MB_LIB.T6G(SCH_1):PAGE90
   160    GND @T6G_MB_LIB.T6G(SCH_1):GND   I352 @T6G_MB_LIB.T6G(SCH_1):PAGE90
   162    GND @T6G_MB_LIB.T6G(SCH_1):GND   I352 @T6G_MB_LIB.T6G(SCH_1):PAGE90
   164    GND @T6G_MB_LIB.T6G(SCH_1):GND   I352 @T6G_MB_LIB.T6G(SCH_1):PAGE90
   166    GND @T6G_MB_LIB.T6G(SCH_1):GND   I352 @T6G_MB_LIB.T6G(SCH_1):PAGE90
   169    GND @T6G_MB_LIB.T6G(SCH_1):GND   I352 @T6G_MB_LIB.T6G(SCH_1):PAGE90
   171    GND @T6G_MB_LIB.T6G(SCH_1):GND   I352 @T6G_MB_LIB.T6G(SCH_1):PAGE90
   173    GND @T6G_MB_LIB.T6G(SCH_1):GND   I352 @T6G_MB_LIB.T6G(SCH_1):PAGE90
   175    GND @T6G_MB_LIB.T6G(SCH_1):GND   I352 @T6G_MB_LIB.T6G(SCH_1):PAGE90
   177    GND @T6G_MB_LIB.T6G(SCH_1):GND   I352 @T6G_MB_LIB.T6G(SCH_1):PAGE90
   180    GND @T6G_MB_LIB.T6G(SCH_1):GND   I352 @T6G_MB_LIB.T6G(SCH_1):PAGE90
   182    GND @T6G_MB_LIB.T6G(SCH_1):GND   I352 @T6G_MB_LIB.T6G(SCH_1):PAGE90
   184    GND @T6G_MB_LIB.T6G(SCH_1):GND   I352 @T6G_MB_LIB.T6G(SCH_1):PAGE90
   186    GND @T6G_MB_LIB.T6G(SCH_1):GND   I352 @T6G_MB_LIB.T6G(SCH_1):PAGE90
   188    GND @T6G_MB_LIB.T6G(SCH_1):GND   I352 @T6G_MB_LIB.T6G(SCH_1):PAGE90
   191    GND @T6G_MB_LIB.T6G(SCH_1):GND   I352 @T6G_MB_LIB.T6G(SCH_1):PAGE90
   193    GND @T6G_MB_LIB.T6G(SCH_1):GND   I352 @T6G_MB_LIB.T6G(SCH_1):PAGE90
   195    GND @T6G_MB_LIB.T6G(SCH_1):GND   I352 @T6G_MB_LIB.T6G(SCH_1):PAGE90
   197    GND @T6G_MB_LIB.T6G(SCH_1):GND   I352 @T6G_MB_LIB.T6G(SCH_1):PAGE90
   199    GND @T6G_MB_LIB.T6G(SCH_1):GND   I352 @T6G_MB_LIB.T6G(SCH_1):PAGE90
   202    GND @T6G_MB_LIB.T6G(SCH_1):GND   I352 @T6G_MB_LIB.T6G(SCH_1):PAGE90
   204    GND @T6G_MB_LIB.T6G(SCH_1):GND   I352 @T6G_MB_LIB.T6G(SCH_1):PAGE90
   206    GND @T6G_MB_LIB.T6G(SCH_1):GND   I352 @T6G_MB_LIB.T6G(SCH_1):PAGE90
   208    GND @T6G_MB_LIB.T6G(SCH_1):GND   I352 @T6G_MB_LIB.T6G(SCH_1):PAGE90
   210    GND @T6G_MB_LIB.T6G(SCH_1):GND   I352 @T6G_MB_LIB.T6G(SCH_1):PAGE90
   212    GND @T6G_MB_LIB.T6G(SCH_1):GND   I352 @T6G_MB_LIB.T6G(SCH_1):PAGE90
   214    GND @T6G_MB_LIB.T6G(SCH_1):GND   I352 @T6G_MB_LIB.T6G(SCH_1):PAGE90
   216    GND @T6G_MB_LIB.T6G(SCH_1):GND   I352 @T6G_MB_LIB.T6G(SCH_1):PAGE90
   219    GND @T6G_MB_LIB.T6G(SCH_1):GND   I352 @T6G_MB_LIB.T6G(SCH_1):PAGE90
   222    GND @T6G_MB_LIB.T6G(SCH_1):GND   I352 @T6G_MB_LIB.T6G(SCH_1):PAGE90
   224    GND @T6G_MB_LIB.T6G(SCH_1):GND   I352 @T6G_MB_LIB.T6G(SCH_1):PAGE90
   226    GND @T6G_MB_LIB.T6G(SCH_1):GND   I352 @T6G_MB_LIB.T6G(SCH_1):PAGE90
   228    GND @T6G_MB_LIB.T6G(SCH_1):GND   I352 @T6G_MB_LIB.T6G(SCH_1):PAGE90
   233    GND @T6G_MB_LIB.T6G(SCH_1):GND   I352 @T6G_MB_LIB.T6G(SCH_1):PAGE90
   237    GND @T6G_MB_LIB.T6G(SCH_1):GND   I352 @T6G_MB_LIB.T6G(SCH_1):PAGE90
   242    GND @T6G_MB_LIB.T6G(SCH_1):GND   I352 @T6G_MB_LIB.T6G(SCH_1):PAGE90
   244    GND @T6G_MB_LIB.T6G(SCH_1):GND   I352 @T6G_MB_LIB.T6G(SCH_1):PAGE90
   246    GND @T6G_MB_LIB.T6G(SCH_1):GND   I352 @T6G_MB_LIB.T6G(SCH_1):PAGE90
   248    GND @T6G_MB_LIB.T6G(SCH_1):GND   I352 @T6G_MB_LIB.T6G(SCH_1):PAGE90
   251    GND @T6G_MB_LIB.T6G(SCH_1):GND   I352 @T6G_MB_LIB.T6G(SCH_1):PAGE90
   253    GND @T6G_MB_LIB.T6G(SCH_1):GND   I352 @T6G_MB_LIB.T6G(SCH_1):PAGE90
   255    GND @T6G_MB_LIB.T6G(SCH_1):GND   I352 @T6G_MB_LIB.T6G(SCH_1):PAGE90
   257    GND @T6G_MB_LIB.T6G(SCH_1):GND   I352 @T6G_MB_LIB.T6G(SCH_1):PAGE90
   259    GND @T6G_MB_LIB.T6G(SCH_1):GND   I352 @T6G_MB_LIB.T6G(SCH_1):PAGE90
   262    GND @T6G_MB_LIB.T6G(SCH_1):GND   I352 @T6G_MB_LIB.T6G(SCH_1):PAGE90
   264    GND @T6G_MB_LIB.T6G(SCH_1):GND   I352 @T6G_MB_LIB.T6G(SCH_1):PAGE90
   266    GND @T6G_MB_LIB.T6G(SCH_1):GND   I352 @T6G_MB_LIB.T6G(SCH_1):PAGE90
   268    GND @T6G_MB_LIB.T6G(SCH_1):GND   I352 @T6G_MB_LIB.T6G(SCH_1):PAGE90
   270    GND @T6G_MB_LIB.T6G(SCH_1):GND   I352 @T6G_MB_LIB.T6G(SCH_1):PAGE90
   273    GND @T6G_MB_LIB.T6G(SCH_1):GND   I352 @T6G_MB_LIB.T6G(SCH_1):PAGE90
   275    GND @T6G_MB_LIB.T6G(SCH_1):GND   I352 @T6G_MB_LIB.T6G(SCH_1):PAGE90
   277    GND @T6G_MB_LIB.T6G(SCH_1):GND   I352 @T6G_MB_LIB.T6G(SCH_1):PAGE90
   279    GND @T6G_MB_LIB.T6G(SCH_1):GND   I352 @T6G_MB_LIB.T6G(SCH_1):PAGE90
   281    GND @T6G_MB_LIB.T6G(SCH_1):GND   I352 @T6G_MB_LIB.T6G(SCH_1):PAGE90
   284    GND @T6G_MB_LIB.T6G(SCH_1):GND   I352 @T6G_MB_LIB.T6G(SCH_1):PAGE90
   286    GND @T6G_MB_LIB.T6G(SCH_1):GND   I352 @T6G_MB_LIB.T6G(SCH_1):PAGE90
   288    GND @T6G_MB_LIB.T6G(SCH_1):GND   I352 @T6G_MB_LIB.T6G(SCH_1):PAGE90
     1 P12V_MEM_CPU0 @T6G_MB_LIB.T6G(SCH_1):P12V_MEM_CPU0   I352 @T6G_MB_LIB.T6G(SCH_1):PAGE90
   145 P12V_MEM_CPU0 @T6G_MB_LIB.T6G(SCH_1):P12V_MEM_CPU0   I352 @T6G_MB_LIB.T6G(SCH_1):PAGE90
   146 P12V_MEM_CPU0 @T6G_MB_LIB.T6G(SCH_1):P12V_MEM_CPU0   I352 @T6G_MB_LIB.T6G(SCH_1):PAGE90
   230    GND @T6G_MB_LIB.T6G(SCH_1):GND   I352 @T6G_MB_LIB.T6G(SCH_1):PAGE90
   235    GND @T6G_MB_LIB.T6G(SCH_1):GND   I352 @T6G_MB_LIB.T6G(SCH_1):PAGE90
   240    GND @T6G_MB_LIB.T6G(SCH_1):GND   I352 @T6G_MB_LIB.T6G(SCH_1):PAGE90
   132    GND @T6G_MB_LIB.T6G(SCH_1):GND   I352 @T6G_MB_LIB.T6G(SCH_1):PAGE90
   136    GND @T6G_MB_LIB.T6G(SCH_1):GND   I352 @T6G_MB_LIB.T6G(SCH_1):PAGE90
   139    GND @T6G_MB_LIB.T6G(SCH_1):GND   I352 @T6G_MB_LIB.T6G(SCH_1):PAGE90
   141    GND @T6G_MB_LIB.T6G(SCH_1):GND   I352 @T6G_MB_LIB.T6G(SCH_1):PAGE90
    G1    GND @T6G_MB_LIB.T6G(SCH_1):GND   I352 @T6G_MB_LIB.T6G(SCH_1):PAGE90
    G2    GND @T6G_MB_LIB.T6G(SCH_1):GND   I352 @T6G_MB_LIB.T6G(SCH_1):PAGE90
    G3    GND @T6G_MB_LIB.T6G(SCH_1):GND   I352 @T6G_MB_LIB.T6G(SCH_1):PAGE90

 J24 SCONN288_DDR506112002KQ-SCONN288_DDR506112002KQ,SMA
     3 P3V3_AUX @T6G_MB_LIB.T6G(SCH_1):P3V3_AUX    I22 @T6G_MB_LIB.T6G(SCH_1):PAGE97
     2     NC     NC    I22 @T6G_MB_LIB.T6G(SCH_1):PAGE97
   144     NC     NC    I22 @T6G_MB_LIB.T6G(SCH_1):PAGE97
   149     NC     NC    I22 @T6G_MB_LIB.T6G(SCH_1):PAGE97
   150     NC     NC    I22 @T6G_MB_LIB.T6G(SCH_1):PAGE97
   220     NC     NC    I22 @T6G_MB_LIB.T6G(SCH_1):PAGE97
   231     NC     NC    I22 @T6G_MB_LIB.T6G(SCH_1):PAGE97
   232     NC     NC    I22 @T6G_MB_LIB.T6G(SCH_1):PAGE97
   207 M_A_CPU1_RESET_N @T6G_MB_LIB.T6G(SCH_1):M_A_CPU1_RESET_N    I22 @T6G_MB_LIB.T6G(SCH_1):PAGE97
   147 PWRGD_CHA_CPU1_DIMM0 @T6G_MB_LIB.T6G(SCH_1):PWRGD_CHA_CPU1_DIMM0    I22 @T6G_MB_LIB.T6G(SCH_1):PAGE97
   227 M_A_CPU1_SB_PAR @T6G_MB_LIB.T6G(SCH_1):M_A_CPU1_SB_PAR    I22 @T6G_MB_LIB.T6G(SCH_1):PAGE97
    74 M_A_CPU1_SA_PAR @T6G_MB_LIB.T6G(SCH_1):M_A_CPU1_SA_PAR    I22 @T6G_MB_LIB.T6G(SCH_1):PAGE97
    87 M_A_CPU1_SB_RSP<0> @T6G_MB_LIB.T6G(SCH_1):M_A_CPU1_SB_RSP(0)    I22 @T6G_MB_LIB.T6G(SCH_1):PAGE97
    86 M_A_CPU1_SA_RSP<0> @T6G_MB_LIB.T6G(SCH_1):M_A_CPU1_SA_RSP(0)    I22 @T6G_MB_LIB.T6G(SCH_1):PAGE97
     5 I3C_SPD_DDRA_CPU1_SDA @T6G_MB_LIB.T6G(SCH_1):I3C_SPD_DDRA_CPU1_SDA    I22 @T6G_MB_LIB.T6G(SCH_1):PAGE97
     4 I3C_SPD_DDRA_CPU1_SCL @T6G_MB_LIB.T6G(SCH_1):I3C_SPD_DDRA_CPU1_SCL    I22 @T6G_MB_LIB.T6G(SCH_1):PAGE97
   148 PD_CHA_CPU1_DIMM0_SAA @T6G_MB_LIB.T6G(SCH_1):PD_CHA_CPU1_DIMM0_SAA    I22 @T6G_MB_LIB.T6G(SCH_1):PAGE97
   100 M_A_CPU1_SB_DQ<0> @T6G_MB_LIB.T6G(SCH_1):M_A_CPU1_SB_DQ(0)    I22 @T6G_MB_LIB.T6G(SCH_1):PAGE97
   102 M_A_CPU1_SB_DQ<1> @T6G_MB_LIB.T6G(SCH_1):M_A_CPU1_SB_DQ(1)    I22 @T6G_MB_LIB.T6G(SCH_1):PAGE97
   245 M_A_CPU1_SB_DQ<2> @T6G_MB_LIB.T6G(SCH_1):M_A_CPU1_SB_DQ(2)    I22 @T6G_MB_LIB.T6G(SCH_1):PAGE97
   247 M_A_CPU1_SB_DQ<3> @T6G_MB_LIB.T6G(SCH_1):M_A_CPU1_SB_DQ(3)    I22 @T6G_MB_LIB.T6G(SCH_1):PAGE97
   107 M_A_CPU1_SB_DQ<4> @T6G_MB_LIB.T6G(SCH_1):M_A_CPU1_SB_DQ(4)    I22 @T6G_MB_LIB.T6G(SCH_1):PAGE97
   109 M_A_CPU1_SB_DQ<5> @T6G_MB_LIB.T6G(SCH_1):M_A_CPU1_SB_DQ(5)    I22 @T6G_MB_LIB.T6G(SCH_1):PAGE97
   252 M_A_CPU1_SB_DQ<6> @T6G_MB_LIB.T6G(SCH_1):M_A_CPU1_SB_DQ(6)    I22 @T6G_MB_LIB.T6G(SCH_1):PAGE97
   254 M_A_CPU1_SB_DQ<7> @T6G_MB_LIB.T6G(SCH_1):M_A_CPU1_SB_DQ(7)    I22 @T6G_MB_LIB.T6G(SCH_1):PAGE97
   111 M_A_CPU1_SB_DQ<8> @T6G_MB_LIB.T6G(SCH_1):M_A_CPU1_SB_DQ(8)    I22 @T6G_MB_LIB.T6G(SCH_1):PAGE97
   113 M_A_CPU1_SB_DQ<9> @T6G_MB_LIB.T6G(SCH_1):M_A_CPU1_SB_DQ(9)    I22 @T6G_MB_LIB.T6G(SCH_1):PAGE97
   256 M_A_CPU1_SB_DQ<10> @T6G_MB_LIB.T6G(SCH_1):M_A_CPU1_SB_DQ(10)    I22 @T6G_MB_LIB.T6G(SCH_1):PAGE97
   258 M_A_CPU1_SB_DQ<11> @T6G_MB_LIB.T6G(SCH_1):M_A_CPU1_SB_DQ(11)    I22 @T6G_MB_LIB.T6G(SCH_1):PAGE97
   118 M_A_CPU1_SB_DQ<12> @T6G_MB_LIB.T6G(SCH_1):M_A_CPU1_SB_DQ(12)    I22 @T6G_MB_LIB.T6G(SCH_1):PAGE97
   120 M_A_CPU1_SB_DQ<13> @T6G_MB_LIB.T6G(SCH_1):M_A_CPU1_SB_DQ(13)    I22 @T6G_MB_LIB.T6G(SCH_1):PAGE97
   263 M_A_CPU1_SB_DQ<14> @T6G_MB_LIB.T6G(SCH_1):M_A_CPU1_SB_DQ(14)    I22 @T6G_MB_LIB.T6G(SCH_1):PAGE97
   265 M_A_CPU1_SB_DQ<15> @T6G_MB_LIB.T6G(SCH_1):M_A_CPU1_SB_DQ(15)    I22 @T6G_MB_LIB.T6G(SCH_1):PAGE97
   122 M_A_CPU1_SB_DQ<16> @T6G_MB_LIB.T6G(SCH_1):M_A_CPU1_SB_DQ(16)    I22 @T6G_MB_LIB.T6G(SCH_1):PAGE97
   124 M_A_CPU1_SB_DQ<17> @T6G_MB_LIB.T6G(SCH_1):M_A_CPU1_SB_DQ(17)    I22 @T6G_MB_LIB.T6G(SCH_1):PAGE97
   267 M_A_CPU1_SB_DQ<18> @T6G_MB_LIB.T6G(SCH_1):M_A_CPU1_SB_DQ(18)    I22 @T6G_MB_LIB.T6G(SCH_1):PAGE97
   269 M_A_CPU1_SB_DQ<19> @T6G_MB_LIB.T6G(SCH_1):M_A_CPU1_SB_DQ(19)    I22 @T6G_MB_LIB.T6G(SCH_1):PAGE97
   129 M_A_CPU1_SB_DQ<20> @T6G_MB_LIB.T6G(SCH_1):M_A_CPU1_SB_DQ(20)    I22 @T6G_MB_LIB.T6G(SCH_1):PAGE97
   131 M_A_CPU1_SB_DQ<21> @T6G_MB_LIB.T6G(SCH_1):M_A_CPU1_SB_DQ(21)    I22 @T6G_MB_LIB.T6G(SCH_1):PAGE97
   274 M_A_CPU1_SB_DQ<22> @T6G_MB_LIB.T6G(SCH_1):M_A_CPU1_SB_DQ(22)    I22 @T6G_MB_LIB.T6G(SCH_1):PAGE97
   276 M_A_CPU1_SB_DQ<23> @T6G_MB_LIB.T6G(SCH_1):M_A_CPU1_SB_DQ(23)    I22 @T6G_MB_LIB.T6G(SCH_1):PAGE97
   133 M_A_CPU1_SB_DQ<24> @T6G_MB_LIB.T6G(SCH_1):M_A_CPU1_SB_DQ(24)    I22 @T6G_MB_LIB.T6G(SCH_1):PAGE97
   135 M_A_CPU1_SB_DQ<25> @T6G_MB_LIB.T6G(SCH_1):M_A_CPU1_SB_DQ(25)    I22 @T6G_MB_LIB.T6G(SCH_1):PAGE97
   278 M_A_CPU1_SB_DQ<26> @T6G_MB_LIB.T6G(SCH_1):M_A_CPU1_SB_DQ(26)    I22 @T6G_MB_LIB.T6G(SCH_1):PAGE97
   280 M_A_CPU1_SB_DQ<27> @T6G_MB_LIB.T6G(SCH_1):M_A_CPU1_SB_DQ(27)    I22 @T6G_MB_LIB.T6G(SCH_1):PAGE97
   140 M_A_CPU1_SB_DQ<28> @T6G_MB_LIB.T6G(SCH_1):M_A_CPU1_SB_DQ(28)    I22 @T6G_MB_LIB.T6G(SCH_1):PAGE97
   142 M_A_CPU1_SB_DQ<29> @T6G_MB_LIB.T6G(SCH_1):M_A_CPU1_SB_DQ(29)    I22 @T6G_MB_LIB.T6G(SCH_1):PAGE97
   285 M_A_CPU1_SB_DQ<30> @T6G_MB_LIB.T6G(SCH_1):M_A_CPU1_SB_DQ(30)    I22 @T6G_MB_LIB.T6G(SCH_1):PAGE97
   287 M_A_CPU1_SB_DQ<31> @T6G_MB_LIB.T6G(SCH_1):M_A_CPU1_SB_DQ(31)    I22 @T6G_MB_LIB.T6G(SCH_1):PAGE97
     7 M_A_CPU1_SA_DQ<0> @T6G_MB_LIB.T6G(SCH_1):M_A_CPU1_SA_DQ(0)    I22 @T6G_MB_LIB.T6G(SCH_1):PAGE97
     9 M_A_CPU1_SA_DQ<1> @T6G_MB_LIB.T6G(SCH_1):M_A_CPU1_SA_DQ(1)    I22 @T6G_MB_LIB.T6G(SCH_1):PAGE97
   152 M_A_CPU1_SA_DQ<2> @T6G_MB_LIB.T6G(SCH_1):M_A_CPU1_SA_DQ(2)    I22 @T6G_MB_LIB.T6G(SCH_1):PAGE97
   154 M_A_CPU1_SA_DQ<3> @T6G_MB_LIB.T6G(SCH_1):M_A_CPU1_SA_DQ(3)    I22 @T6G_MB_LIB.T6G(SCH_1):PAGE97
    14 M_A_CPU1_SA_DQ<4> @T6G_MB_LIB.T6G(SCH_1):M_A_CPU1_SA_DQ(4)    I22 @T6G_MB_LIB.T6G(SCH_1):PAGE97
    16 M_A_CPU1_SA_DQ<5> @T6G_MB_LIB.T6G(SCH_1):M_A_CPU1_SA_DQ(5)    I22 @T6G_MB_LIB.T6G(SCH_1):PAGE97
   159 M_A_CPU1_SA_DQ<6> @T6G_MB_LIB.T6G(SCH_1):M_A_CPU1_SA_DQ(6)    I22 @T6G_MB_LIB.T6G(SCH_1):PAGE97
   161 M_A_CPU1_SA_DQ<7> @T6G_MB_LIB.T6G(SCH_1):M_A_CPU1_SA_DQ(7)    I22 @T6G_MB_LIB.T6G(SCH_1):PAGE97
    18 M_A_CPU1_SA_DQ<8> @T6G_MB_LIB.T6G(SCH_1):M_A_CPU1_SA_DQ(8)    I22 @T6G_MB_LIB.T6G(SCH_1):PAGE97
    20 M_A_CPU1_SA_DQ<9> @T6G_MB_LIB.T6G(SCH_1):M_A_CPU1_SA_DQ(9)    I22 @T6G_MB_LIB.T6G(SCH_1):PAGE97
   163 M_A_CPU1_SA_DQ<10> @T6G_MB_LIB.T6G(SCH_1):M_A_CPU1_SA_DQ(10)    I22 @T6G_MB_LIB.T6G(SCH_1):PAGE97
   165 M_A_CPU1_SA_DQ<11> @T6G_MB_LIB.T6G(SCH_1):M_A_CPU1_SA_DQ(11)    I22 @T6G_MB_LIB.T6G(SCH_1):PAGE97
    25 M_A_CPU1_SA_DQ<12> @T6G_MB_LIB.T6G(SCH_1):M_A_CPU1_SA_DQ(12)    I22 @T6G_MB_LIB.T6G(SCH_1):PAGE97
    27 M_A_CPU1_SA_DQ<13> @T6G_MB_LIB.T6G(SCH_1):M_A_CPU1_SA_DQ(13)    I22 @T6G_MB_LIB.T6G(SCH_1):PAGE97
   170 M_A_CPU1_SA_DQ<14> @T6G_MB_LIB.T6G(SCH_1):M_A_CPU1_SA_DQ(14)    I22 @T6G_MB_LIB.T6G(SCH_1):PAGE97
   172 M_A_CPU1_SA_DQ<15> @T6G_MB_LIB.T6G(SCH_1):M_A_CPU1_SA_DQ(15)    I22 @T6G_MB_LIB.T6G(SCH_1):PAGE97
    29 M_A_CPU1_SA_DQ<16> @T6G_MB_LIB.T6G(SCH_1):M_A_CPU1_SA_DQ(16)    I22 @T6G_MB_LIB.T6G(SCH_1):PAGE97
    31 M_A_CPU1_SA_DQ<17> @T6G_MB_LIB.T6G(SCH_1):M_A_CPU1_SA_DQ(17)    I22 @T6G_MB_LIB.T6G(SCH_1):PAGE97
   174 M_A_CPU1_SA_DQ<18> @T6G_MB_LIB.T6G(SCH_1):M_A_CPU1_SA_DQ(18)    I22 @T6G_MB_LIB.T6G(SCH_1):PAGE97
   176 M_A_CPU1_SA_DQ<19> @T6G_MB_LIB.T6G(SCH_1):M_A_CPU1_SA_DQ(19)    I22 @T6G_MB_LIB.T6G(SCH_1):PAGE97
    36 M_A_CPU1_SA_DQ<20> @T6G_MB_LIB.T6G(SCH_1):M_A_CPU1_SA_DQ(20)    I22 @T6G_MB_LIB.T6G(SCH_1):PAGE97
    38 M_A_CPU1_SA_DQ<21> @T6G_MB_LIB.T6G(SCH_1):M_A_CPU1_SA_DQ(21)    I22 @T6G_MB_LIB.T6G(SCH_1):PAGE97
   181 M_A_CPU1_SA_DQ<22> @T6G_MB_LIB.T6G(SCH_1):M_A_CPU1_SA_DQ(22)    I22 @T6G_MB_LIB.T6G(SCH_1):PAGE97
   183 M_A_CPU1_SA_DQ<23> @T6G_MB_LIB.T6G(SCH_1):M_A_CPU1_SA_DQ(23)    I22 @T6G_MB_LIB.T6G(SCH_1):PAGE97
    40 M_A_CPU1_SA_DQ<24> @T6G_MB_LIB.T6G(SCH_1):M_A_CPU1_SA_DQ(24)    I22 @T6G_MB_LIB.T6G(SCH_1):PAGE97
    42 M_A_CPU1_SA_DQ<25> @T6G_MB_LIB.T6G(SCH_1):M_A_CPU1_SA_DQ(25)    I22 @T6G_MB_LIB.T6G(SCH_1):PAGE97
   185 M_A_CPU1_SA_DQ<26> @T6G_MB_LIB.T6G(SCH_1):M_A_CPU1_SA_DQ(26)    I22 @T6G_MB_LIB.T6G(SCH_1):PAGE97
   187 M_A_CPU1_SA_DQ<27> @T6G_MB_LIB.T6G(SCH_1):M_A_CPU1_SA_DQ(27)    I22 @T6G_MB_LIB.T6G(SCH_1):PAGE97
    47 M_A_CPU1_SA_DQ<28> @T6G_MB_LIB.T6G(SCH_1):M_A_CPU1_SA_DQ(28)    I22 @T6G_MB_LIB.T6G(SCH_1):PAGE97
    49 M_A_CPU1_SA_DQ<29> @T6G_MB_LIB.T6G(SCH_1):M_A_CPU1_SA_DQ(29)    I22 @T6G_MB_LIB.T6G(SCH_1):PAGE97
   192 M_A_CPU1_SA_DQ<30> @T6G_MB_LIB.T6G(SCH_1):M_A_CPU1_SA_DQ(30)    I22 @T6G_MB_LIB.T6G(SCH_1):PAGE97
   229 M_A_CPU1_SB_CS_N<1> @T6G_MB_LIB.T6G(SCH_1):M_A_CPU1_SB_CS_N(1)    I22 @T6G_MB_LIB.T6G(SCH_1):PAGE97
   209 M_A_CPU1_SA_CS_N<1> @T6G_MB_LIB.T6G(SCH_1):M_A_CPU1_SA_CS_N(1)    I22 @T6G_MB_LIB.T6G(SCH_1):PAGE97
    84 M_A_CPU1_SB_CS_N<0> @T6G_MB_LIB.T6G(SCH_1):M_A_CPU1_SB_CS_N(0)    I22 @T6G_MB_LIB.T6G(SCH_1):PAGE97
    64 M_A_CPU1_SA_CS_N<0> @T6G_MB_LIB.T6G(SCH_1):M_A_CPU1_SA_CS_N(0)    I22 @T6G_MB_LIB.T6G(SCH_1):PAGE97
   217 M_A_CPU1_CLK_DP<0> @T6G_MB_LIB.T6G(SCH_1):M_A_CPU1_CLK_DP(0)    I22 @T6G_MB_LIB.T6G(SCH_1):PAGE97
   218 M_A_CPU1_CLK_DN<0> @T6G_MB_LIB.T6G(SCH_1):M_A_CPU1_CLK_DN(0)    I22 @T6G_MB_LIB.T6G(SCH_1):PAGE97
    96 M_A_CPU1_SB_CB<0> @T6G_MB_LIB.T6G(SCH_1):M_A_CPU1_SB_CB(0)    I22 @T6G_MB_LIB.T6G(SCH_1):PAGE97
    98 M_A_CPU1_SB_CB<1> @T6G_MB_LIB.T6G(SCH_1):M_A_CPU1_SB_CB(1)    I22 @T6G_MB_LIB.T6G(SCH_1):PAGE97
   241 M_A_CPU1_SB_CB<2> @T6G_MB_LIB.T6G(SCH_1):M_A_CPU1_SB_CB(2)    I22 @T6G_MB_LIB.T6G(SCH_1):PAGE97
   243 M_A_CPU1_SB_CB<3> @T6G_MB_LIB.T6G(SCH_1):M_A_CPU1_SB_CB(3)    I22 @T6G_MB_LIB.T6G(SCH_1):PAGE97
    89 M_A_CPU1_SB_CB<4> @T6G_MB_LIB.T6G(SCH_1):M_A_CPU1_SB_CB(4)    I22 @T6G_MB_LIB.T6G(SCH_1):PAGE97
    91 M_A_CPU1_SB_CB<5> @T6G_MB_LIB.T6G(SCH_1):M_A_CPU1_SB_CB(5)    I22 @T6G_MB_LIB.T6G(SCH_1):PAGE97
   234 M_A_CPU1_SB_CB<6> @T6G_MB_LIB.T6G(SCH_1):M_A_CPU1_SB_CB(6)    I22 @T6G_MB_LIB.T6G(SCH_1):PAGE97
    51 M_A_CPU1_SA_CB<0> @T6G_MB_LIB.T6G(SCH_1):M_A_CPU1_SA_CB(0)    I22 @T6G_MB_LIB.T6G(SCH_1):PAGE97
   196 M_A_CPU1_SA_CB<2> @T6G_MB_LIB.T6G(SCH_1):M_A_CPU1_SA_CB(2)    I22 @T6G_MB_LIB.T6G(SCH_1):PAGE97
   198 M_A_CPU1_SA_CB<3> @T6G_MB_LIB.T6G(SCH_1):M_A_CPU1_SA_CB(3)    I22 @T6G_MB_LIB.T6G(SCH_1):PAGE97
    60 M_A_CPU1_SA_CB<5> @T6G_MB_LIB.T6G(SCH_1):M_A_CPU1_SA_CB(5)    I22 @T6G_MB_LIB.T6G(SCH_1):PAGE97
   203 M_A_CPU1_SA_CB<6> @T6G_MB_LIB.T6G(SCH_1):M_A_CPU1_SA_CB(6)    I22 @T6G_MB_LIB.T6G(SCH_1):PAGE97
    82 M_A_CPU1_SB_CA<6> @T6G_MB_LIB.T6G(SCH_1):M_A_CPU1_SB_CA(6)    I22 @T6G_MB_LIB.T6G(SCH_1):PAGE97
    72 M_A_CPU1_SA_CA<6> @T6G_MB_LIB.T6G(SCH_1):M_A_CPU1_SA_CA(6)    I22 @T6G_MB_LIB.T6G(SCH_1):PAGE97
   225 M_A_CPU1_SB_CA<5> @T6G_MB_LIB.T6G(SCH_1):M_A_CPU1_SB_CA(5)    I22 @T6G_MB_LIB.T6G(SCH_1):PAGE97
   215 M_A_CPU1_SA_CA<5> @T6G_MB_LIB.T6G(SCH_1):M_A_CPU1_SA_CA(5)    I22 @T6G_MB_LIB.T6G(SCH_1):PAGE97
    80 M_A_CPU1_SB_CA<4> @T6G_MB_LIB.T6G(SCH_1):M_A_CPU1_SB_CA(4)    I22 @T6G_MB_LIB.T6G(SCH_1):PAGE97
    70 M_A_CPU1_SA_CA<4> @T6G_MB_LIB.T6G(SCH_1):M_A_CPU1_SA_CA(4)    I22 @T6G_MB_LIB.T6G(SCH_1):PAGE97
   223 M_A_CPU1_SB_CA<3> @T6G_MB_LIB.T6G(SCH_1):M_A_CPU1_SB_CA(3)    I22 @T6G_MB_LIB.T6G(SCH_1):PAGE97
   213 M_A_CPU1_SA_CA<3> @T6G_MB_LIB.T6G(SCH_1):M_A_CPU1_SA_CA(3)    I22 @T6G_MB_LIB.T6G(SCH_1):PAGE97
    78 M_A_CPU1_SB_CA<2> @T6G_MB_LIB.T6G(SCH_1):M_A_CPU1_SB_CA(2)    I22 @T6G_MB_LIB.T6G(SCH_1):PAGE97
    68 M_A_CPU1_SA_CA<2> @T6G_MB_LIB.T6G(SCH_1):M_A_CPU1_SA_CA(2)    I22 @T6G_MB_LIB.T6G(SCH_1):PAGE97
   221 M_A_CPU1_SB_CA<1> @T6G_MB_LIB.T6G(SCH_1):M_A_CPU1_SB_CA(1)    I22 @T6G_MB_LIB.T6G(SCH_1):PAGE97
   211 M_A_CPU1_SA_CA<1> @T6G_MB_LIB.T6G(SCH_1):M_A_CPU1_SA_CA(1)    I22 @T6G_MB_LIB.T6G(SCH_1):PAGE97
    76 M_A_CPU1_SB_CA<0> @T6G_MB_LIB.T6G(SCH_1):M_A_CPU1_SB_CA(0)    I22 @T6G_MB_LIB.T6G(SCH_1):PAGE97
    66 M_A_CPU1_SA_CA<0> @T6G_MB_LIB.T6G(SCH_1):M_A_CPU1_SA_CA(0)    I22 @T6G_MB_LIB.T6G(SCH_1):PAGE97
    62 M_A_CPU1_ALERT_N @T6G_MB_LIB.T6G(SCH_1):M_A_CPU1_ALERT_N    I22 @T6G_MB_LIB.T6G(SCH_1):PAGE97
   236 M_A_CPU1_SB_CB<7> @T6G_MB_LIB.T6G(SCH_1):M_A_CPU1_SB_CB(7)    I22 @T6G_MB_LIB.T6G(SCH_1):PAGE97
    53 M_A_CPU1_SA_CB<1> @T6G_MB_LIB.T6G(SCH_1):M_A_CPU1_SA_CB(1)    I22 @T6G_MB_LIB.T6G(SCH_1):PAGE97
    58 M_A_CPU1_SA_CB<4> @T6G_MB_LIB.T6G(SCH_1):M_A_CPU1_SA_CB(4)    I22 @T6G_MB_LIB.T6G(SCH_1):PAGE97
   205 M_A_CPU1_SA_CB<7> @T6G_MB_LIB.T6G(SCH_1):M_A_CPU1_SA_CB(7)    I22 @T6G_MB_LIB.T6G(SCH_1):PAGE97
   194 M_A_CPU1_SA_DQ<31> @T6G_MB_LIB.T6G(SCH_1):M_A_CPU1_SA_DQ(31)    I22 @T6G_MB_LIB.T6G(SCH_1):PAGE97
    93 M_A_CPU1_SB_DQS_DP<9> @T6G_MB_LIB.T6G(SCH_1):M_A_CPU1_SB_DQS_DP(9)   I238 @T6G_MB_LIB.T6G(SCH_1):PAGE97
    94 M_A_CPU1_SB_DQS_DN<9> @T6G_MB_LIB.T6G(SCH_1):M_A_CPU1_SB_DQS_DN(9)   I238 @T6G_MB_LIB.T6G(SCH_1):PAGE97
   201 M_A_CPU1_SA_DQS_DP<9> @T6G_MB_LIB.T6G(SCH_1):M_A_CPU1_SA_DQS_DP(9)   I238 @T6G_MB_LIB.T6G(SCH_1):PAGE97
   200 M_A_CPU1_SA_DQS_DN<9> @T6G_MB_LIB.T6G(SCH_1):M_A_CPU1_SA_DQS_DN(9)   I238 @T6G_MB_LIB.T6G(SCH_1):PAGE97
   190 M_A_CPU1_SA_DQS_DP<8> @T6G_MB_LIB.T6G(SCH_1):M_A_CPU1_SA_DQS_DP(8)   I238 @T6G_MB_LIB.T6G(SCH_1):PAGE97
   189 M_A_CPU1_SA_DQS_DN<8> @T6G_MB_LIB.T6G(SCH_1):M_A_CPU1_SA_DQS_DN(8)   I238 @T6G_MB_LIB.T6G(SCH_1):PAGE97
   271 M_A_CPU1_SB_DQS_DN<7> @T6G_MB_LIB.T6G(SCH_1):M_A_CPU1_SB_DQS_DN(7)   I238 @T6G_MB_LIB.T6G(SCH_1):PAGE97
   179 M_A_CPU1_SA_DQS_DP<7> @T6G_MB_LIB.T6G(SCH_1):M_A_CPU1_SA_DQS_DP(7)   I238 @T6G_MB_LIB.T6G(SCH_1):PAGE97
   261 M_A_CPU1_SB_DQS_DP<6> @T6G_MB_LIB.T6G(SCH_1):M_A_CPU1_SB_DQS_DP(6)   I238 @T6G_MB_LIB.T6G(SCH_1):PAGE97
   260 M_A_CPU1_SB_DQS_DN<6> @T6G_MB_LIB.T6G(SCH_1):M_A_CPU1_SB_DQS_DN(6)   I238 @T6G_MB_LIB.T6G(SCH_1):PAGE97
   167 M_A_CPU1_SA_DQS_DN<6> @T6G_MB_LIB.T6G(SCH_1):M_A_CPU1_SA_DQS_DN(6)   I238 @T6G_MB_LIB.T6G(SCH_1):PAGE97
   250 M_A_CPU1_SB_DQS_DP<5> @T6G_MB_LIB.T6G(SCH_1):M_A_CPU1_SB_DQS_DP(5)   I238 @T6G_MB_LIB.T6G(SCH_1):PAGE97
   249 M_A_CPU1_SB_DQS_DN<5> @T6G_MB_LIB.T6G(SCH_1):M_A_CPU1_SB_DQS_DN(5)   I238 @T6G_MB_LIB.T6G(SCH_1):PAGE97
   157 M_A_CPU1_SA_DQS_DP<5> @T6G_MB_LIB.T6G(SCH_1):M_A_CPU1_SA_DQS_DP(5)   I238 @T6G_MB_LIB.T6G(SCH_1):PAGE97
   156 M_A_CPU1_SA_DQS_DN<5> @T6G_MB_LIB.T6G(SCH_1):M_A_CPU1_SA_DQS_DN(5)   I238 @T6G_MB_LIB.T6G(SCH_1):PAGE97
   239 M_A_CPU1_SB_DQS_DP<4> @T6G_MB_LIB.T6G(SCH_1):M_A_CPU1_SB_DQS_DP(4)   I238 @T6G_MB_LIB.T6G(SCH_1):PAGE97
   238 M_A_CPU1_SB_DQS_DN<4> @T6G_MB_LIB.T6G(SCH_1):M_A_CPU1_SB_DQS_DN(4)   I238 @T6G_MB_LIB.T6G(SCH_1):PAGE97
    55 M_A_CPU1_SA_DQS_DP<4> @T6G_MB_LIB.T6G(SCH_1):M_A_CPU1_SA_DQS_DP(4)   I238 @T6G_MB_LIB.T6G(SCH_1):PAGE97
    56 M_A_CPU1_SA_DQS_DN<4> @T6G_MB_LIB.T6G(SCH_1):M_A_CPU1_SA_DQS_DN(4)   I238 @T6G_MB_LIB.T6G(SCH_1):PAGE97
   137 M_A_CPU1_SB_DQS_DP<3> @T6G_MB_LIB.T6G(SCH_1):M_A_CPU1_SB_DQS_DP(3)   I238 @T6G_MB_LIB.T6G(SCH_1):PAGE97
   138 M_A_CPU1_SB_DQS_DN<3> @T6G_MB_LIB.T6G(SCH_1):M_A_CPU1_SB_DQS_DN(3)   I238 @T6G_MB_LIB.T6G(SCH_1):PAGE97
    44 M_A_CPU1_SA_DQS_DP<3> @T6G_MB_LIB.T6G(SCH_1):M_A_CPU1_SA_DQS_DP(3)   I238 @T6G_MB_LIB.T6G(SCH_1):PAGE97
    45 M_A_CPU1_SA_DQS_DN<3> @T6G_MB_LIB.T6G(SCH_1):M_A_CPU1_SA_DQS_DN(3)   I238 @T6G_MB_LIB.T6G(SCH_1):PAGE97
   126 M_A_CPU1_SB_DQS_DP<2> @T6G_MB_LIB.T6G(SCH_1):M_A_CPU1_SB_DQS_DP(2)   I238 @T6G_MB_LIB.T6G(SCH_1):PAGE97
   127 M_A_CPU1_SB_DQS_DN<2> @T6G_MB_LIB.T6G(SCH_1):M_A_CPU1_SB_DQS_DN(2)   I238 @T6G_MB_LIB.T6G(SCH_1):PAGE97
    33 M_A_CPU1_SA_DQS_DP<2> @T6G_MB_LIB.T6G(SCH_1):M_A_CPU1_SA_DQS_DP(2)   I238 @T6G_MB_LIB.T6G(SCH_1):PAGE97
    34 M_A_CPU1_SA_DQS_DN<2> @T6G_MB_LIB.T6G(SCH_1):M_A_CPU1_SA_DQS_DN(2)   I238 @T6G_MB_LIB.T6G(SCH_1):PAGE97
   115 M_A_CPU1_SB_DQS_DP<1> @T6G_MB_LIB.T6G(SCH_1):M_A_CPU1_SB_DQS_DP(1)   I238 @T6G_MB_LIB.T6G(SCH_1):PAGE97
   116 M_A_CPU1_SB_DQS_DN<1> @T6G_MB_LIB.T6G(SCH_1):M_A_CPU1_SB_DQS_DN(1)   I238 @T6G_MB_LIB.T6G(SCH_1):PAGE97
    22 M_A_CPU1_SA_DQS_DP<1> @T6G_MB_LIB.T6G(SCH_1):M_A_CPU1_SA_DQS_DP(1)   I238 @T6G_MB_LIB.T6G(SCH_1):PAGE97
    23 M_A_CPU1_SA_DQS_DN<1> @T6G_MB_LIB.T6G(SCH_1):M_A_CPU1_SA_DQS_DN(1)   I238 @T6G_MB_LIB.T6G(SCH_1):PAGE97
   104 M_A_CPU1_SB_DQS_DP<0> @T6G_MB_LIB.T6G(SCH_1):M_A_CPU1_SB_DQS_DP(0)   I238 @T6G_MB_LIB.T6G(SCH_1):PAGE97
   105 M_A_CPU1_SB_DQS_DN<0> @T6G_MB_LIB.T6G(SCH_1):M_A_CPU1_SB_DQS_DN(0)   I238 @T6G_MB_LIB.T6G(SCH_1):PAGE97
    11 M_A_CPU1_SA_DQS_DP<0> @T6G_MB_LIB.T6G(SCH_1):M_A_CPU1_SA_DQS_DP(0)   I238 @T6G_MB_LIB.T6G(SCH_1):PAGE97
    12 M_A_CPU1_SA_DQS_DN<0> @T6G_MB_LIB.T6G(SCH_1):M_A_CPU1_SA_DQS_DN(0)   I238 @T6G_MB_LIB.T6G(SCH_1):PAGE97
   272 M_A_CPU1_SB_DQS_DP<7> @T6G_MB_LIB.T6G(SCH_1):M_A_CPU1_SB_DQS_DP(7)   I238 @T6G_MB_LIB.T6G(SCH_1):PAGE97
   282 M_A_CPU1_SB_DQS_DN<8> @T6G_MB_LIB.T6G(SCH_1):M_A_CPU1_SB_DQS_DN(8)   I238 @T6G_MB_LIB.T6G(SCH_1):PAGE97
   283 M_A_CPU1_SB_DQS_DP<8> @T6G_MB_LIB.T6G(SCH_1):M_A_CPU1_SB_DQS_DP(8)   I238 @T6G_MB_LIB.T6G(SCH_1):PAGE97
   168 M_A_CPU1_SA_DQS_DP<6> @T6G_MB_LIB.T6G(SCH_1):M_A_CPU1_SA_DQS_DP(6)   I238 @T6G_MB_LIB.T6G(SCH_1):PAGE97
   178 M_A_CPU1_SA_DQS_DN<7> @T6G_MB_LIB.T6G(SCH_1):M_A_CPU1_SA_DQS_DN(7)   I238 @T6G_MB_LIB.T6G(SCH_1):PAGE97
     6    GND @T6G_MB_LIB.T6G(SCH_1):GND   I177 @T6G_MB_LIB.T6G(SCH_1):PAGE97
     8    GND @T6G_MB_LIB.T6G(SCH_1):GND   I177 @T6G_MB_LIB.T6G(SCH_1):PAGE97
    10    GND @T6G_MB_LIB.T6G(SCH_1):GND   I177 @T6G_MB_LIB.T6G(SCH_1):PAGE97
    13    GND @T6G_MB_LIB.T6G(SCH_1):GND   I177 @T6G_MB_LIB.T6G(SCH_1):PAGE97
    15    GND @T6G_MB_LIB.T6G(SCH_1):GND   I177 @T6G_MB_LIB.T6G(SCH_1):PAGE97
    17    GND @T6G_MB_LIB.T6G(SCH_1):GND   I177 @T6G_MB_LIB.T6G(SCH_1):PAGE97
    19    GND @T6G_MB_LIB.T6G(SCH_1):GND   I177 @T6G_MB_LIB.T6G(SCH_1):PAGE97
    21    GND @T6G_MB_LIB.T6G(SCH_1):GND   I177 @T6G_MB_LIB.T6G(SCH_1):PAGE97
    24    GND @T6G_MB_LIB.T6G(SCH_1):GND   I177 @T6G_MB_LIB.T6G(SCH_1):PAGE97
    26    GND @T6G_MB_LIB.T6G(SCH_1):GND   I177 @T6G_MB_LIB.T6G(SCH_1):PAGE97
    28    GND @T6G_MB_LIB.T6G(SCH_1):GND   I177 @T6G_MB_LIB.T6G(SCH_1):PAGE97
    30    GND @T6G_MB_LIB.T6G(SCH_1):GND   I177 @T6G_MB_LIB.T6G(SCH_1):PAGE97
    32    GND @T6G_MB_LIB.T6G(SCH_1):GND   I177 @T6G_MB_LIB.T6G(SCH_1):PAGE97
    35    GND @T6G_MB_LIB.T6G(SCH_1):GND   I177 @T6G_MB_LIB.T6G(SCH_1):PAGE97
    37    GND @T6G_MB_LIB.T6G(SCH_1):GND   I177 @T6G_MB_LIB.T6G(SCH_1):PAGE97
    39    GND @T6G_MB_LIB.T6G(SCH_1):GND   I177 @T6G_MB_LIB.T6G(SCH_1):PAGE97
    41    GND @T6G_MB_LIB.T6G(SCH_1):GND   I177 @T6G_MB_LIB.T6G(SCH_1):PAGE97
    43    GND @T6G_MB_LIB.T6G(SCH_1):GND   I177 @T6G_MB_LIB.T6G(SCH_1):PAGE97
    46    GND @T6G_MB_LIB.T6G(SCH_1):GND   I177 @T6G_MB_LIB.T6G(SCH_1):PAGE97
    48    GND @T6G_MB_LIB.T6G(SCH_1):GND   I177 @T6G_MB_LIB.T6G(SCH_1):PAGE97
    50    GND @T6G_MB_LIB.T6G(SCH_1):GND   I177 @T6G_MB_LIB.T6G(SCH_1):PAGE97
    52    GND @T6G_MB_LIB.T6G(SCH_1):GND   I177 @T6G_MB_LIB.T6G(SCH_1):PAGE97
    54    GND @T6G_MB_LIB.T6G(SCH_1):GND   I177 @T6G_MB_LIB.T6G(SCH_1):PAGE97
    57    GND @T6G_MB_LIB.T6G(SCH_1):GND   I177 @T6G_MB_LIB.T6G(SCH_1):PAGE97
    59    GND @T6G_MB_LIB.T6G(SCH_1):GND   I177 @T6G_MB_LIB.T6G(SCH_1):PAGE97
    61    GND @T6G_MB_LIB.T6G(SCH_1):GND   I177 @T6G_MB_LIB.T6G(SCH_1):PAGE97
    63    GND @T6G_MB_LIB.T6G(SCH_1):GND   I177 @T6G_MB_LIB.T6G(SCH_1):PAGE97
    65    GND @T6G_MB_LIB.T6G(SCH_1):GND   I177 @T6G_MB_LIB.T6G(SCH_1):PAGE97
    67    GND @T6G_MB_LIB.T6G(SCH_1):GND   I177 @T6G_MB_LIB.T6G(SCH_1):PAGE97
    69    GND @T6G_MB_LIB.T6G(SCH_1):GND   I177 @T6G_MB_LIB.T6G(SCH_1):PAGE97
    71    GND @T6G_MB_LIB.T6G(SCH_1):GND   I177 @T6G_MB_LIB.T6G(SCH_1):PAGE97
    73    GND @T6G_MB_LIB.T6G(SCH_1):GND   I177 @T6G_MB_LIB.T6G(SCH_1):PAGE97
    75    GND @T6G_MB_LIB.T6G(SCH_1):GND   I177 @T6G_MB_LIB.T6G(SCH_1):PAGE97
    77    GND @T6G_MB_LIB.T6G(SCH_1):GND   I177 @T6G_MB_LIB.T6G(SCH_1):PAGE97
    79    GND @T6G_MB_LIB.T6G(SCH_1):GND   I177 @T6G_MB_LIB.T6G(SCH_1):PAGE97
    81    GND @T6G_MB_LIB.T6G(SCH_1):GND   I177 @T6G_MB_LIB.T6G(SCH_1):PAGE97
    83    GND @T6G_MB_LIB.T6G(SCH_1):GND   I177 @T6G_MB_LIB.T6G(SCH_1):PAGE97
    85    GND @T6G_MB_LIB.T6G(SCH_1):GND   I177 @T6G_MB_LIB.T6G(SCH_1):PAGE97
    88    GND @T6G_MB_LIB.T6G(SCH_1):GND   I177 @T6G_MB_LIB.T6G(SCH_1):PAGE97
    90    GND @T6G_MB_LIB.T6G(SCH_1):GND   I177 @T6G_MB_LIB.T6G(SCH_1):PAGE97
    92    GND @T6G_MB_LIB.T6G(SCH_1):GND   I177 @T6G_MB_LIB.T6G(SCH_1):PAGE97
    95    GND @T6G_MB_LIB.T6G(SCH_1):GND   I177 @T6G_MB_LIB.T6G(SCH_1):PAGE97
    97    GND @T6G_MB_LIB.T6G(SCH_1):GND   I177 @T6G_MB_LIB.T6G(SCH_1):PAGE97
    99    GND @T6G_MB_LIB.T6G(SCH_1):GND   I177 @T6G_MB_LIB.T6G(SCH_1):PAGE97
   101    GND @T6G_MB_LIB.T6G(SCH_1):GND   I177 @T6G_MB_LIB.T6G(SCH_1):PAGE97
   103    GND @T6G_MB_LIB.T6G(SCH_1):GND   I177 @T6G_MB_LIB.T6G(SCH_1):PAGE97
   106    GND @T6G_MB_LIB.T6G(SCH_1):GND   I177 @T6G_MB_LIB.T6G(SCH_1):PAGE97
   108    GND @T6G_MB_LIB.T6G(SCH_1):GND   I177 @T6G_MB_LIB.T6G(SCH_1):PAGE97
   110    GND @T6G_MB_LIB.T6G(SCH_1):GND   I177 @T6G_MB_LIB.T6G(SCH_1):PAGE97
   112    GND @T6G_MB_LIB.T6G(SCH_1):GND   I177 @T6G_MB_LIB.T6G(SCH_1):PAGE97
   114    GND @T6G_MB_LIB.T6G(SCH_1):GND   I177 @T6G_MB_LIB.T6G(SCH_1):PAGE97
   117    GND @T6G_MB_LIB.T6G(SCH_1):GND   I177 @T6G_MB_LIB.T6G(SCH_1):PAGE97
   119    GND @T6G_MB_LIB.T6G(SCH_1):GND   I177 @T6G_MB_LIB.T6G(SCH_1):PAGE97
   121    GND @T6G_MB_LIB.T6G(SCH_1):GND   I177 @T6G_MB_LIB.T6G(SCH_1):PAGE97
   123    GND @T6G_MB_LIB.T6G(SCH_1):GND   I177 @T6G_MB_LIB.T6G(SCH_1):PAGE97
   125    GND @T6G_MB_LIB.T6G(SCH_1):GND   I177 @T6G_MB_LIB.T6G(SCH_1):PAGE97
   128    GND @T6G_MB_LIB.T6G(SCH_1):GND   I177 @T6G_MB_LIB.T6G(SCH_1):PAGE97
   130    GND @T6G_MB_LIB.T6G(SCH_1):GND   I177 @T6G_MB_LIB.T6G(SCH_1):PAGE97
   134    GND @T6G_MB_LIB.T6G(SCH_1):GND   I177 @T6G_MB_LIB.T6G(SCH_1):PAGE97
   143    GND @T6G_MB_LIB.T6G(SCH_1):GND   I177 @T6G_MB_LIB.T6G(SCH_1):PAGE97
   151    GND @T6G_MB_LIB.T6G(SCH_1):GND   I177 @T6G_MB_LIB.T6G(SCH_1):PAGE97
   153    GND @T6G_MB_LIB.T6G(SCH_1):GND   I177 @T6G_MB_LIB.T6G(SCH_1):PAGE97
   155    GND @T6G_MB_LIB.T6G(SCH_1):GND   I177 @T6G_MB_LIB.T6G(SCH_1):PAGE97
   158    GND @T6G_MB_LIB.T6G(SCH_1):GND   I177 @T6G_MB_LIB.T6G(SCH_1):PAGE97
   160    GND @T6G_MB_LIB.T6G(SCH_1):GND   I177 @T6G_MB_LIB.T6G(SCH_1):PAGE97
   162    GND @T6G_MB_LIB.T6G(SCH_1):GND   I177 @T6G_MB_LIB.T6G(SCH_1):PAGE97
   164    GND @T6G_MB_LIB.T6G(SCH_1):GND   I177 @T6G_MB_LIB.T6G(SCH_1):PAGE97
   166    GND @T6G_MB_LIB.T6G(SCH_1):GND   I177 @T6G_MB_LIB.T6G(SCH_1):PAGE97
   169    GND @T6G_MB_LIB.T6G(SCH_1):GND   I177 @T6G_MB_LIB.T6G(SCH_1):PAGE97
   171    GND @T6G_MB_LIB.T6G(SCH_1):GND   I177 @T6G_MB_LIB.T6G(SCH_1):PAGE97
   173    GND @T6G_MB_LIB.T6G(SCH_1):GND   I177 @T6G_MB_LIB.T6G(SCH_1):PAGE97
   175    GND @T6G_MB_LIB.T6G(SCH_1):GND   I177 @T6G_MB_LIB.T6G(SCH_1):PAGE97
   177    GND @T6G_MB_LIB.T6G(SCH_1):GND   I177 @T6G_MB_LIB.T6G(SCH_1):PAGE97
   180    GND @T6G_MB_LIB.T6G(SCH_1):GND   I177 @T6G_MB_LIB.T6G(SCH_1):PAGE97
   182    GND @T6G_MB_LIB.T6G(SCH_1):GND   I177 @T6G_MB_LIB.T6G(SCH_1):PAGE97
   184    GND @T6G_MB_LIB.T6G(SCH_1):GND   I177 @T6G_MB_LIB.T6G(SCH_1):PAGE97
   186    GND @T6G_MB_LIB.T6G(SCH_1):GND   I177 @T6G_MB_LIB.T6G(SCH_1):PAGE97
   188    GND @T6G_MB_LIB.T6G(SCH_1):GND   I177 @T6G_MB_LIB.T6G(SCH_1):PAGE97
   191    GND @T6G_MB_LIB.T6G(SCH_1):GND   I177 @T6G_MB_LIB.T6G(SCH_1):PAGE97
   193    GND @T6G_MB_LIB.T6G(SCH_1):GND   I177 @T6G_MB_LIB.T6G(SCH_1):PAGE97
   195    GND @T6G_MB_LIB.T6G(SCH_1):GND   I177 @T6G_MB_LIB.T6G(SCH_1):PAGE97
   197    GND @T6G_MB_LIB.T6G(SCH_1):GND   I177 @T6G_MB_LIB.T6G(SCH_1):PAGE97
   199    GND @T6G_MB_LIB.T6G(SCH_1):GND   I177 @T6G_MB_LIB.T6G(SCH_1):PAGE97
   202    GND @T6G_MB_LIB.T6G(SCH_1):GND   I177 @T6G_MB_LIB.T6G(SCH_1):PAGE97
   204    GND @T6G_MB_LIB.T6G(SCH_1):GND   I177 @T6G_MB_LIB.T6G(SCH_1):PAGE97
   206    GND @T6G_MB_LIB.T6G(SCH_1):GND   I177 @T6G_MB_LIB.T6G(SCH_1):PAGE97
   208    GND @T6G_MB_LIB.T6G(SCH_1):GND   I177 @T6G_MB_LIB.T6G(SCH_1):PAGE97
   210    GND @T6G_MB_LIB.T6G(SCH_1):GND   I177 @T6G_MB_LIB.T6G(SCH_1):PAGE97
   212    GND @T6G_MB_LIB.T6G(SCH_1):GND   I177 @T6G_MB_LIB.T6G(SCH_1):PAGE97
   214    GND @T6G_MB_LIB.T6G(SCH_1):GND   I177 @T6G_MB_LIB.T6G(SCH_1):PAGE97
   216    GND @T6G_MB_LIB.T6G(SCH_1):GND   I177 @T6G_MB_LIB.T6G(SCH_1):PAGE97
   219    GND @T6G_MB_LIB.T6G(SCH_1):GND   I177 @T6G_MB_LIB.T6G(SCH_1):PAGE97
   222    GND @T6G_MB_LIB.T6G(SCH_1):GND   I177 @T6G_MB_LIB.T6G(SCH_1):PAGE97
   224    GND @T6G_MB_LIB.T6G(SCH_1):GND   I177 @T6G_MB_LIB.T6G(SCH_1):PAGE97
   226    GND @T6G_MB_LIB.T6G(SCH_1):GND   I177 @T6G_MB_LIB.T6G(SCH_1):PAGE97
   228    GND @T6G_MB_LIB.T6G(SCH_1):GND   I177 @T6G_MB_LIB.T6G(SCH_1):PAGE97
   233    GND @T6G_MB_LIB.T6G(SCH_1):GND   I177 @T6G_MB_LIB.T6G(SCH_1):PAGE97
   237    GND @T6G_MB_LIB.T6G(SCH_1):GND   I177 @T6G_MB_LIB.T6G(SCH_1):PAGE97
   242    GND @T6G_MB_LIB.T6G(SCH_1):GND   I177 @T6G_MB_LIB.T6G(SCH_1):PAGE97
   244    GND @T6G_MB_LIB.T6G(SCH_1):GND   I177 @T6G_MB_LIB.T6G(SCH_1):PAGE97
   246    GND @T6G_MB_LIB.T6G(SCH_1):GND   I177 @T6G_MB_LIB.T6G(SCH_1):PAGE97
   248    GND @T6G_MB_LIB.T6G(SCH_1):GND   I177 @T6G_MB_LIB.T6G(SCH_1):PAGE97
   251    GND @T6G_MB_LIB.T6G(SCH_1):GND   I177 @T6G_MB_LIB.T6G(SCH_1):PAGE97
   253    GND @T6G_MB_LIB.T6G(SCH_1):GND   I177 @T6G_MB_LIB.T6G(SCH_1):PAGE97
   255    GND @T6G_MB_LIB.T6G(SCH_1):GND   I177 @T6G_MB_LIB.T6G(SCH_1):PAGE97
   257    GND @T6G_MB_LIB.T6G(SCH_1):GND   I177 @T6G_MB_LIB.T6G(SCH_1):PAGE97
   259    GND @T6G_MB_LIB.T6G(SCH_1):GND   I177 @T6G_MB_LIB.T6G(SCH_1):PAGE97
   262    GND @T6G_MB_LIB.T6G(SCH_1):GND   I177 @T6G_MB_LIB.T6G(SCH_1):PAGE97
   264    GND @T6G_MB_LIB.T6G(SCH_1):GND   I177 @T6G_MB_LIB.T6G(SCH_1):PAGE97
   266    GND @T6G_MB_LIB.T6G(SCH_1):GND   I177 @T6G_MB_LIB.T6G(SCH_1):PAGE97
   268    GND @T6G_MB_LIB.T6G(SCH_1):GND   I177 @T6G_MB_LIB.T6G(SCH_1):PAGE97
   270    GND @T6G_MB_LIB.T6G(SCH_1):GND   I177 @T6G_MB_LIB.T6G(SCH_1):PAGE97
   273    GND @T6G_MB_LIB.T6G(SCH_1):GND   I177 @T6G_MB_LIB.T6G(SCH_1):PAGE97
   275    GND @T6G_MB_LIB.T6G(SCH_1):GND   I177 @T6G_MB_LIB.T6G(SCH_1):PAGE97
   277    GND @T6G_MB_LIB.T6G(SCH_1):GND   I177 @T6G_MB_LIB.T6G(SCH_1):PAGE97
   279    GND @T6G_MB_LIB.T6G(SCH_1):GND   I177 @T6G_MB_LIB.T6G(SCH_1):PAGE97
   281    GND @T6G_MB_LIB.T6G(SCH_1):GND   I177 @T6G_MB_LIB.T6G(SCH_1):PAGE97
   284    GND @T6G_MB_LIB.T6G(SCH_1):GND   I177 @T6G_MB_LIB.T6G(SCH_1):PAGE97
   286    GND @T6G_MB_LIB.T6G(SCH_1):GND   I177 @T6G_MB_LIB.T6G(SCH_1):PAGE97
   288    GND @T6G_MB_LIB.T6G(SCH_1):GND   I177 @T6G_MB_LIB.T6G(SCH_1):PAGE97
     1 P12V_MEM_CPU1 @T6G_MB_LIB.T6G(SCH_1):P12V_MEM_CPU1   I177 @T6G_MB_LIB.T6G(SCH_1):PAGE97
   145 P12V_MEM_CPU1 @T6G_MB_LIB.T6G(SCH_1):P12V_MEM_CPU1   I177 @T6G_MB_LIB.T6G(SCH_1):PAGE97
   146 P12V_MEM_CPU1 @T6G_MB_LIB.T6G(SCH_1):P12V_MEM_CPU1   I177 @T6G_MB_LIB.T6G(SCH_1):PAGE97
   230    GND @T6G_MB_LIB.T6G(SCH_1):GND   I177 @T6G_MB_LIB.T6G(SCH_1):PAGE97
   235    GND @T6G_MB_LIB.T6G(SCH_1):GND   I177 @T6G_MB_LIB.T6G(SCH_1):PAGE97
   240    GND @T6G_MB_LIB.T6G(SCH_1):GND   I177 @T6G_MB_LIB.T6G(SCH_1):PAGE97
   132    GND @T6G_MB_LIB.T6G(SCH_1):GND   I177 @T6G_MB_LIB.T6G(SCH_1):PAGE97
   136    GND @T6G_MB_LIB.T6G(SCH_1):GND   I177 @T6G_MB_LIB.T6G(SCH_1):PAGE97
   139    GND @T6G_MB_LIB.T6G(SCH_1):GND   I177 @T6G_MB_LIB.T6G(SCH_1):PAGE97
   141    GND @T6G_MB_LIB.T6G(SCH_1):GND   I177 @T6G_MB_LIB.T6G(SCH_1):PAGE97
    G1    GND @T6G_MB_LIB.T6G(SCH_1):GND   I177 @T6G_MB_LIB.T6G(SCH_1):PAGE97
    G2    GND @T6G_MB_LIB.T6G(SCH_1):GND   I177 @T6G_MB_LIB.T6G(SCH_1):PAGE97
    G3    GND @T6G_MB_LIB.T6G(SCH_1):GND   I177 @T6G_MB_LIB.T6G(SCH_1):PAGE97

 J26 SCONN288_DDR506112002KQ-SCONN288_DDR506112002KQ,SMA
     3 P3V3_AUX @T6G_MB_LIB.T6G(SCH_1):P3V3_AUX    I22 @T6G_MB_LIB.T6G(SCH_1):PAGE98
     2     NC     NC    I22 @T6G_MB_LIB.T6G(SCH_1):PAGE98
   144     NC     NC    I22 @T6G_MB_LIB.T6G(SCH_1):PAGE98
   149     NC     NC    I22 @T6G_MB_LIB.T6G(SCH_1):PAGE98
   150     NC     NC    I22 @T6G_MB_LIB.T6G(SCH_1):PAGE98
   220     NC     NC    I22 @T6G_MB_LIB.T6G(SCH_1):PAGE98
   231     NC     NC    I22 @T6G_MB_LIB.T6G(SCH_1):PAGE98
   232     NC     NC    I22 @T6G_MB_LIB.T6G(SCH_1):PAGE98
   207 M_B_CPU1_RESET_N @T6G_MB_LIB.T6G(SCH_1):M_B_CPU1_RESET_N    I22 @T6G_MB_LIB.T6G(SCH_1):PAGE98
   147 PWRGD_CHB_CPU1_DIMM @T6G_MB_LIB.T6G(SCH_1):PWRGD_CHB_CPU1_DIMM    I22 @T6G_MB_LIB.T6G(SCH_1):PAGE98
   227 M_B_CPU1_SB_PAR @T6G_MB_LIB.T6G(SCH_1):M_B_CPU1_SB_PAR    I22 @T6G_MB_LIB.T6G(SCH_1):PAGE98
    74 M_B_CPU1_SA_PAR @T6G_MB_LIB.T6G(SCH_1):M_B_CPU1_SA_PAR    I22 @T6G_MB_LIB.T6G(SCH_1):PAGE98
    87 M_B_CPU1_SB_RSP<0> @T6G_MB_LIB.T6G(SCH_1):M_B_CPU1_SB_RSP(0)    I22 @T6G_MB_LIB.T6G(SCH_1):PAGE98
    86 M_B_CPU1_SA_RSP<0> @T6G_MB_LIB.T6G(SCH_1):M_B_CPU1_SA_RSP(0)    I22 @T6G_MB_LIB.T6G(SCH_1):PAGE98
     5 I3C_SPD_DDRB_CPU1_SDA @T6G_MB_LIB.T6G(SCH_1):I3C_SPD_DDRB_CPU1_SDA    I22 @T6G_MB_LIB.T6G(SCH_1):PAGE98
     4 I3C_SPD_DDRB_CPU1_SCL @T6G_MB_LIB.T6G(SCH_1):I3C_SPD_DDRB_CPU1_SCL    I22 @T6G_MB_LIB.T6G(SCH_1):PAGE98
   148 PD_CHB_CPU1_DIMM_SAA @T6G_MB_LIB.T6G(SCH_1):PD_CHB_CPU1_DIMM_SAA    I22 @T6G_MB_LIB.T6G(SCH_1):PAGE98
   100 M_B_CPU1_SB_DQ<0> @T6G_MB_LIB.T6G(SCH_1):M_B_CPU1_SB_DQ(0)    I22 @T6G_MB_LIB.T6G(SCH_1):PAGE98
   102 M_B_CPU1_SB_DQ<1> @T6G_MB_LIB.T6G(SCH_1):M_B_CPU1_SB_DQ(1)    I22 @T6G_MB_LIB.T6G(SCH_1):PAGE98
   245 M_B_CPU1_SB_DQ<2> @T6G_MB_LIB.T6G(SCH_1):M_B_CPU1_SB_DQ(2)    I22 @T6G_MB_LIB.T6G(SCH_1):PAGE98
   247 M_B_CPU1_SB_DQ<3> @T6G_MB_LIB.T6G(SCH_1):M_B_CPU1_SB_DQ(3)    I22 @T6G_MB_LIB.T6G(SCH_1):PAGE98
   107 M_B_CPU1_SB_DQ<4> @T6G_MB_LIB.T6G(SCH_1):M_B_CPU1_SB_DQ(4)    I22 @T6G_MB_LIB.T6G(SCH_1):PAGE98
   109 M_B_CPU1_SB_DQ<5> @T6G_MB_LIB.T6G(SCH_1):M_B_CPU1_SB_DQ(5)    I22 @T6G_MB_LIB.T6G(SCH_1):PAGE98
   252 M_B_CPU1_SB_DQ<6> @T6G_MB_LIB.T6G(SCH_1):M_B_CPU1_SB_DQ(6)    I22 @T6G_MB_LIB.T6G(SCH_1):PAGE98
   254 M_B_CPU1_SB_DQ<7> @T6G_MB_LIB.T6G(SCH_1):M_B_CPU1_SB_DQ(7)    I22 @T6G_MB_LIB.T6G(SCH_1):PAGE98
   111 M_B_CPU1_SB_DQ<8> @T6G_MB_LIB.T6G(SCH_1):M_B_CPU1_SB_DQ(8)    I22 @T6G_MB_LIB.T6G(SCH_1):PAGE98
   113 M_B_CPU1_SB_DQ<9> @T6G_MB_LIB.T6G(SCH_1):M_B_CPU1_SB_DQ(9)    I22 @T6G_MB_LIB.T6G(SCH_1):PAGE98
   256 M_B_CPU1_SB_DQ<10> @T6G_MB_LIB.T6G(SCH_1):M_B_CPU1_SB_DQ(10)    I22 @T6G_MB_LIB.T6G(SCH_1):PAGE98
   258 M_B_CPU1_SB_DQ<11> @T6G_MB_LIB.T6G(SCH_1):M_B_CPU1_SB_DQ(11)    I22 @T6G_MB_LIB.T6G(SCH_1):PAGE98
   118 M_B_CPU1_SB_DQ<12> @T6G_MB_LIB.T6G(SCH_1):M_B_CPU1_SB_DQ(12)    I22 @T6G_MB_LIB.T6G(SCH_1):PAGE98
   120 M_B_CPU1_SB_DQ<13> @T6G_MB_LIB.T6G(SCH_1):M_B_CPU1_SB_DQ(13)    I22 @T6G_MB_LIB.T6G(SCH_1):PAGE98
   263 M_B_CPU1_SB_DQ<14> @T6G_MB_LIB.T6G(SCH_1):M_B_CPU1_SB_DQ(14)    I22 @T6G_MB_LIB.T6G(SCH_1):PAGE98
   265 M_B_CPU1_SB_DQ<15> @T6G_MB_LIB.T6G(SCH_1):M_B_CPU1_SB_DQ(15)    I22 @T6G_MB_LIB.T6G(SCH_1):PAGE98
   122 M_B_CPU1_SB_DQ<16> @T6G_MB_LIB.T6G(SCH_1):M_B_CPU1_SB_DQ(16)    I22 @T6G_MB_LIB.T6G(SCH_1):PAGE98
   124 M_B_CPU1_SB_DQ<17> @T6G_MB_LIB.T6G(SCH_1):M_B_CPU1_SB_DQ(17)    I22 @T6G_MB_LIB.T6G(SCH_1):PAGE98
   267 M_B_CPU1_SB_DQ<18> @T6G_MB_LIB.T6G(SCH_1):M_B_CPU1_SB_DQ(18)    I22 @T6G_MB_LIB.T6G(SCH_1):PAGE98
   269 M_B_CPU1_SB_DQ<19> @T6G_MB_LIB.T6G(SCH_1):M_B_CPU1_SB_DQ(19)    I22 @T6G_MB_LIB.T6G(SCH_1):PAGE98
   129 M_B_CPU1_SB_DQ<20> @T6G_MB_LIB.T6G(SCH_1):M_B_CPU1_SB_DQ(20)    I22 @T6G_MB_LIB.T6G(SCH_1):PAGE98
   131 M_B_CPU1_SB_DQ<21> @T6G_MB_LIB.T6G(SCH_1):M_B_CPU1_SB_DQ(21)    I22 @T6G_MB_LIB.T6G(SCH_1):PAGE98
   274 M_B_CPU1_SB_DQ<22> @T6G_MB_LIB.T6G(SCH_1):M_B_CPU1_SB_DQ(22)    I22 @T6G_MB_LIB.T6G(SCH_1):PAGE98
   276 M_B_CPU1_SB_DQ<23> @T6G_MB_LIB.T6G(SCH_1):M_B_CPU1_SB_DQ(23)    I22 @T6G_MB_LIB.T6G(SCH_1):PAGE98
   133 M_B_CPU1_SB_DQ<24> @T6G_MB_LIB.T6G(SCH_1):M_B_CPU1_SB_DQ(24)    I22 @T6G_MB_LIB.T6G(SCH_1):PAGE98
   135 M_B_CPU1_SB_DQ<25> @T6G_MB_LIB.T6G(SCH_1):M_B_CPU1_SB_DQ(25)    I22 @T6G_MB_LIB.T6G(SCH_1):PAGE98
   278 M_B_CPU1_SB_DQ<26> @T6G_MB_LIB.T6G(SCH_1):M_B_CPU1_SB_DQ(26)    I22 @T6G_MB_LIB.T6G(SCH_1):PAGE98
   280 M_B_CPU1_SB_DQ<27> @T6G_MB_LIB.T6G(SCH_1):M_B_CPU1_SB_DQ(27)    I22 @T6G_MB_LIB.T6G(SCH_1):PAGE98
   140 M_B_CPU1_SB_DQ<28> @T6G_MB_LIB.T6G(SCH_1):M_B_CPU1_SB_DQ(28)    I22 @T6G_MB_LIB.T6G(SCH_1):PAGE98
   142 M_B_CPU1_SB_DQ<29> @T6G_MB_LIB.T6G(SCH_1):M_B_CPU1_SB_DQ(29)    I22 @T6G_MB_LIB.T6G(SCH_1):PAGE98
   285 M_B_CPU1_SB_DQ<30> @T6G_MB_LIB.T6G(SCH_1):M_B_CPU1_SB_DQ(30)    I22 @T6G_MB_LIB.T6G(SCH_1):PAGE98
   287 M_B_CPU1_SB_DQ<31> @T6G_MB_LIB.T6G(SCH_1):M_B_CPU1_SB_DQ(31)    I22 @T6G_MB_LIB.T6G(SCH_1):PAGE98
     7 M_B_CPU1_SA_DQ<0> @T6G_MB_LIB.T6G(SCH_1):M_B_CPU1_SA_DQ(0)    I22 @T6G_MB_LIB.T6G(SCH_1):PAGE98
     9 M_B_CPU1_SA_DQ<1> @T6G_MB_LIB.T6G(SCH_1):M_B_CPU1_SA_DQ(1)    I22 @T6G_MB_LIB.T6G(SCH_1):PAGE98
   152 M_B_CPU1_SA_DQ<2> @T6G_MB_LIB.T6G(SCH_1):M_B_CPU1_SA_DQ(2)    I22 @T6G_MB_LIB.T6G(SCH_1):PAGE98
   154 M_B_CPU1_SA_DQ<3> @T6G_MB_LIB.T6G(SCH_1):M_B_CPU1_SA_DQ(3)    I22 @T6G_MB_LIB.T6G(SCH_1):PAGE98
    14 M_B_CPU1_SA_DQ<4> @T6G_MB_LIB.T6G(SCH_1):M_B_CPU1_SA_DQ(4)    I22 @T6G_MB_LIB.T6G(SCH_1):PAGE98
    16 M_B_CPU1_SA_DQ<5> @T6G_MB_LIB.T6G(SCH_1):M_B_CPU1_SA_DQ(5)    I22 @T6G_MB_LIB.T6G(SCH_1):PAGE98
   159 M_B_CPU1_SA_DQ<6> @T6G_MB_LIB.T6G(SCH_1):M_B_CPU1_SA_DQ(6)    I22 @T6G_MB_LIB.T6G(SCH_1):PAGE98
   161 M_B_CPU1_SA_DQ<7> @T6G_MB_LIB.T6G(SCH_1):M_B_CPU1_SA_DQ(7)    I22 @T6G_MB_LIB.T6G(SCH_1):PAGE98
    18 M_B_CPU1_SA_DQ<8> @T6G_MB_LIB.T6G(SCH_1):M_B_CPU1_SA_DQ(8)    I22 @T6G_MB_LIB.T6G(SCH_1):PAGE98
    20 M_B_CPU1_SA_DQ<9> @T6G_MB_LIB.T6G(SCH_1):M_B_CPU1_SA_DQ(9)    I22 @T6G_MB_LIB.T6G(SCH_1):PAGE98
   163 M_B_CPU1_SA_DQ<10> @T6G_MB_LIB.T6G(SCH_1):M_B_CPU1_SA_DQ(10)    I22 @T6G_MB_LIB.T6G(SCH_1):PAGE98
   165 M_B_CPU1_SA_DQ<11> @T6G_MB_LIB.T6G(SCH_1):M_B_CPU1_SA_DQ(11)    I22 @T6G_MB_LIB.T6G(SCH_1):PAGE98
    25 M_B_CPU1_SA_DQ<12> @T6G_MB_LIB.T6G(SCH_1):M_B_CPU1_SA_DQ(12)    I22 @T6G_MB_LIB.T6G(SCH_1):PAGE98
    27 M_B_CPU1_SA_DQ<13> @T6G_MB_LIB.T6G(SCH_1):M_B_CPU1_SA_DQ(13)    I22 @T6G_MB_LIB.T6G(SCH_1):PAGE98
   170 M_B_CPU1_SA_DQ<14> @T6G_MB_LIB.T6G(SCH_1):M_B_CPU1_SA_DQ(14)    I22 @T6G_MB_LIB.T6G(SCH_1):PAGE98
   172 M_B_CPU1_SA_DQ<15> @T6G_MB_LIB.T6G(SCH_1):M_B_CPU1_SA_DQ(15)    I22 @T6G_MB_LIB.T6G(SCH_1):PAGE98
    29 M_B_CPU1_SA_DQ<16> @T6G_MB_LIB.T6G(SCH_1):M_B_CPU1_SA_DQ(16)    I22 @T6G_MB_LIB.T6G(SCH_1):PAGE98
    31 M_B_CPU1_SA_DQ<17> @T6G_MB_LIB.T6G(SCH_1):M_B_CPU1_SA_DQ(17)    I22 @T6G_MB_LIB.T6G(SCH_1):PAGE98
   174 M_B_CPU1_SA_DQ<18> @T6G_MB_LIB.T6G(SCH_1):M_B_CPU1_SA_DQ(18)    I22 @T6G_MB_LIB.T6G(SCH_1):PAGE98
   176 M_B_CPU1_SA_DQ<19> @T6G_MB_LIB.T6G(SCH_1):M_B_CPU1_SA_DQ(19)    I22 @T6G_MB_LIB.T6G(SCH_1):PAGE98
    36 M_B_CPU1_SA_DQ<20> @T6G_MB_LIB.T6G(SCH_1):M_B_CPU1_SA_DQ(20)    I22 @T6G_MB_LIB.T6G(SCH_1):PAGE98
    38 M_B_CPU1_SA_DQ<21> @T6G_MB_LIB.T6G(SCH_1):M_B_CPU1_SA_DQ(21)    I22 @T6G_MB_LIB.T6G(SCH_1):PAGE98
   181 M_B_CPU1_SA_DQ<22> @T6G_MB_LIB.T6G(SCH_1):M_B_CPU1_SA_DQ(22)    I22 @T6G_MB_LIB.T6G(SCH_1):PAGE98
   183 M_B_CPU1_SA_DQ<23> @T6G_MB_LIB.T6G(SCH_1):M_B_CPU1_SA_DQ(23)    I22 @T6G_MB_LIB.T6G(SCH_1):PAGE98
    40 M_B_CPU1_SA_DQ<24> @T6G_MB_LIB.T6G(SCH_1):M_B_CPU1_SA_DQ(24)    I22 @T6G_MB_LIB.T6G(SCH_1):PAGE98
    42 M_B_CPU1_SA_DQ<25> @T6G_MB_LIB.T6G(SCH_1):M_B_CPU1_SA_DQ(25)    I22 @T6G_MB_LIB.T6G(SCH_1):PAGE98
   185 M_B_CPU1_SA_DQ<26> @T6G_MB_LIB.T6G(SCH_1):M_B_CPU1_SA_DQ(26)    I22 @T6G_MB_LIB.T6G(SCH_1):PAGE98
   187 M_B_CPU1_SA_DQ<27> @T6G_MB_LIB.T6G(SCH_1):M_B_CPU1_SA_DQ(27)    I22 @T6G_MB_LIB.T6G(SCH_1):PAGE98
    47 M_B_CPU1_SA_DQ<28> @T6G_MB_LIB.T6G(SCH_1):M_B_CPU1_SA_DQ(28)    I22 @T6G_MB_LIB.T6G(SCH_1):PAGE98
    49 M_B_CPU1_SA_DQ<29> @T6G_MB_LIB.T6G(SCH_1):M_B_CPU1_SA_DQ(29)    I22 @T6G_MB_LIB.T6G(SCH_1):PAGE98
   192 M_B_CPU1_SA_DQ<30> @T6G_MB_LIB.T6G(SCH_1):M_B_CPU1_SA_DQ(30)    I22 @T6G_MB_LIB.T6G(SCH_1):PAGE98
   229 M_B_CPU1_SB_CS_N<1> @T6G_MB_LIB.T6G(SCH_1):M_B_CPU1_SB_CS_N(1)    I22 @T6G_MB_LIB.T6G(SCH_1):PAGE98
   209 M_B_CPU1_SA_CS_N<1> @T6G_MB_LIB.T6G(SCH_1):M_B_CPU1_SA_CS_N(1)    I22 @T6G_MB_LIB.T6G(SCH_1):PAGE98
    84 M_B_CPU1_SB_CS_N<0> @T6G_MB_LIB.T6G(SCH_1):M_B_CPU1_SB_CS_N(0)    I22 @T6G_MB_LIB.T6G(SCH_1):PAGE98
    64 M_B_CPU1_SA_CS_N<0> @T6G_MB_LIB.T6G(SCH_1):M_B_CPU1_SA_CS_N(0)    I22 @T6G_MB_LIB.T6G(SCH_1):PAGE98
   217 M_B_CPU1_CLK_DP<0> @T6G_MB_LIB.T6G(SCH_1):M_B_CPU1_CLK_DP(0)    I22 @T6G_MB_LIB.T6G(SCH_1):PAGE98
   218 M_B_CPU1_CLK_DN<0> @T6G_MB_LIB.T6G(SCH_1):M_B_CPU1_CLK_DN(0)    I22 @T6G_MB_LIB.T6G(SCH_1):PAGE98
    96 M_B_CPU1_SB_CB<0> @T6G_MB_LIB.T6G(SCH_1):M_B_CPU1_SB_CB(0)    I22 @T6G_MB_LIB.T6G(SCH_1):PAGE98
    98 M_B_CPU1_SB_CB<1> @T6G_MB_LIB.T6G(SCH_1):M_B_CPU1_SB_CB(1)    I22 @T6G_MB_LIB.T6G(SCH_1):PAGE98
   241 M_B_CPU1_SB_CB<2> @T6G_MB_LIB.T6G(SCH_1):M_B_CPU1_SB_CB(2)    I22 @T6G_MB_LIB.T6G(SCH_1):PAGE98
   243 M_B_CPU1_SB_CB<3> @T6G_MB_LIB.T6G(SCH_1):M_B_CPU1_SB_CB(3)    I22 @T6G_MB_LIB.T6G(SCH_1):PAGE98
    89 M_B_CPU1_SB_CB<4> @T6G_MB_LIB.T6G(SCH_1):M_B_CPU1_SB_CB(4)    I22 @T6G_MB_LIB.T6G(SCH_1):PAGE98
    91 M_B_CPU1_SB_CB<5> @T6G_MB_LIB.T6G(SCH_1):M_B_CPU1_SB_CB(5)    I22 @T6G_MB_LIB.T6G(SCH_1):PAGE98
   234 M_B_CPU1_SB_CB<6> @T6G_MB_LIB.T6G(SCH_1):M_B_CPU1_SB_CB(6)    I22 @T6G_MB_LIB.T6G(SCH_1):PAGE98
    51 M_B_CPU1_SA_CB<0> @T6G_MB_LIB.T6G(SCH_1):M_B_CPU1_SA_CB(0)    I22 @T6G_MB_LIB.T6G(SCH_1):PAGE98
   196 M_B_CPU1_SA_CB<2> @T6G_MB_LIB.T6G(SCH_1):M_B_CPU1_SA_CB(2)    I22 @T6G_MB_LIB.T6G(SCH_1):PAGE98
   198 M_B_CPU1_SA_CB<3> @T6G_MB_LIB.T6G(SCH_1):M_B_CPU1_SA_CB(3)    I22 @T6G_MB_LIB.T6G(SCH_1):PAGE98
    60 M_B_CPU1_SA_CB<5> @T6G_MB_LIB.T6G(SCH_1):M_B_CPU1_SA_CB(5)    I22 @T6G_MB_LIB.T6G(SCH_1):PAGE98
   203 M_B_CPU1_SA_CB<6> @T6G_MB_LIB.T6G(SCH_1):M_B_CPU1_SA_CB(6)    I22 @T6G_MB_LIB.T6G(SCH_1):PAGE98
    82 M_B_CPU1_SB_CA<6> @T6G_MB_LIB.T6G(SCH_1):M_B_CPU1_SB_CA(6)    I22 @T6G_MB_LIB.T6G(SCH_1):PAGE98
    72 M_B_CPU1_SA_CA<6> @T6G_MB_LIB.T6G(SCH_1):M_B_CPU1_SA_CA(6)    I22 @T6G_MB_LIB.T6G(SCH_1):PAGE98
   225 M_B_CPU1_SB_CA<5> @T6G_MB_LIB.T6G(SCH_1):M_B_CPU1_SB_CA(5)    I22 @T6G_MB_LIB.T6G(SCH_1):PAGE98
   215 M_B_CPU1_SA_CA<5> @T6G_MB_LIB.T6G(SCH_1):M_B_CPU1_SA_CA(5)    I22 @T6G_MB_LIB.T6G(SCH_1):PAGE98
    80 M_B_CPU1_SB_CA<4> @T6G_MB_LIB.T6G(SCH_1):M_B_CPU1_SB_CA(4)    I22 @T6G_MB_LIB.T6G(SCH_1):PAGE98
    70 M_B_CPU1_SA_CA<4> @T6G_MB_LIB.T6G(SCH_1):M_B_CPU1_SA_CA(4)    I22 @T6G_MB_LIB.T6G(SCH_1):PAGE98
   223 M_B_CPU1_SB_CA<3> @T6G_MB_LIB.T6G(SCH_1):M_B_CPU1_SB_CA(3)    I22 @T6G_MB_LIB.T6G(SCH_1):PAGE98
   213 M_B_CPU1_SA_CA<3> @T6G_MB_LIB.T6G(SCH_1):M_B_CPU1_SA_CA(3)    I22 @T6G_MB_LIB.T6G(SCH_1):PAGE98
    78 M_B_CPU1_SB_CA<2> @T6G_MB_LIB.T6G(SCH_1):M_B_CPU1_SB_CA(2)    I22 @T6G_MB_LIB.T6G(SCH_1):PAGE98
    68 M_B_CPU1_SA_CA<2> @T6G_MB_LIB.T6G(SCH_1):M_B_CPU1_SA_CA(2)    I22 @T6G_MB_LIB.T6G(SCH_1):PAGE98
   221 M_B_CPU1_SB_CA<1> @T6G_MB_LIB.T6G(SCH_1):M_B_CPU1_SB_CA(1)    I22 @T6G_MB_LIB.T6G(SCH_1):PAGE98
   211 M_B_CPU1_SA_CA<1> @T6G_MB_LIB.T6G(SCH_1):M_B_CPU1_SA_CA(1)    I22 @T6G_MB_LIB.T6G(SCH_1):PAGE98
    76 M_B_CPU1_SB_CA<0> @T6G_MB_LIB.T6G(SCH_1):M_B_CPU1_SB_CA(0)    I22 @T6G_MB_LIB.T6G(SCH_1):PAGE98
    66 M_B_CPU1_SA_CA<0> @T6G_MB_LIB.T6G(SCH_1):M_B_CPU1_SA_CA(0)    I22 @T6G_MB_LIB.T6G(SCH_1):PAGE98
    62 M_B_CPU1_ALERT_N @T6G_MB_LIB.T6G(SCH_1):M_B_CPU1_ALERT_N    I22 @T6G_MB_LIB.T6G(SCH_1):PAGE98
   236 M_B_CPU1_SB_CB<7> @T6G_MB_LIB.T6G(SCH_1):M_B_CPU1_SB_CB(7)    I22 @T6G_MB_LIB.T6G(SCH_1):PAGE98
    53 M_B_CPU1_SA_CB<1> @T6G_MB_LIB.T6G(SCH_1):M_B_CPU1_SA_CB(1)    I22 @T6G_MB_LIB.T6G(SCH_1):PAGE98
    58 M_B_CPU1_SA_CB<4> @T6G_MB_LIB.T6G(SCH_1):M_B_CPU1_SA_CB(4)    I22 @T6G_MB_LIB.T6G(SCH_1):PAGE98
   205 M_B_CPU1_SA_CB<7> @T6G_MB_LIB.T6G(SCH_1):M_B_CPU1_SA_CB(7)    I22 @T6G_MB_LIB.T6G(SCH_1):PAGE98
   194 M_B_CPU1_SA_DQ<31> @T6G_MB_LIB.T6G(SCH_1):M_B_CPU1_SA_DQ(31)    I22 @T6G_MB_LIB.T6G(SCH_1):PAGE98
    93 M_B_CPU1_SB_DQS_DP<9> @T6G_MB_LIB.T6G(SCH_1):M_B_CPU1_SB_DQS_DP(9)   I236 @T6G_MB_LIB.T6G(SCH_1):PAGE98
    94 M_B_CPU1_SB_DQS_DN<9> @T6G_MB_LIB.T6G(SCH_1):M_B_CPU1_SB_DQS_DN(9)   I236 @T6G_MB_LIB.T6G(SCH_1):PAGE98
   201 M_B_CPU1_SA_DQS_DP<9> @T6G_MB_LIB.T6G(SCH_1):M_B_CPU1_SA_DQS_DP(9)   I236 @T6G_MB_LIB.T6G(SCH_1):PAGE98
   200 M_B_CPU1_SA_DQS_DN<9> @T6G_MB_LIB.T6G(SCH_1):M_B_CPU1_SA_DQS_DN(9)   I236 @T6G_MB_LIB.T6G(SCH_1):PAGE98
   190 M_B_CPU1_SA_DQS_DP<8> @T6G_MB_LIB.T6G(SCH_1):M_B_CPU1_SA_DQS_DP(8)   I236 @T6G_MB_LIB.T6G(SCH_1):PAGE98
   189 M_B_CPU1_SA_DQS_DN<8> @T6G_MB_LIB.T6G(SCH_1):M_B_CPU1_SA_DQS_DN(8)   I236 @T6G_MB_LIB.T6G(SCH_1):PAGE98
   271 M_B_CPU1_SB_DQS_DN<7> @T6G_MB_LIB.T6G(SCH_1):M_B_CPU1_SB_DQS_DN(7)   I236 @T6G_MB_LIB.T6G(SCH_1):PAGE98
   179 M_B_CPU1_SA_DQS_DP<7> @T6G_MB_LIB.T6G(SCH_1):M_B_CPU1_SA_DQS_DP(7)   I236 @T6G_MB_LIB.T6G(SCH_1):PAGE98
   261 M_B_CPU1_SB_DQS_DP<6> @T6G_MB_LIB.T6G(SCH_1):M_B_CPU1_SB_DQS_DP(6)   I236 @T6G_MB_LIB.T6G(SCH_1):PAGE98
   260 M_B_CPU1_SB_DQS_DN<6> @T6G_MB_LIB.T6G(SCH_1):M_B_CPU1_SB_DQS_DN(6)   I236 @T6G_MB_LIB.T6G(SCH_1):PAGE98
   167 M_B_CPU1_SA_DQS_DN<6> @T6G_MB_LIB.T6G(SCH_1):M_B_CPU1_SA_DQS_DN(6)   I236 @T6G_MB_LIB.T6G(SCH_1):PAGE98
   250 M_B_CPU1_SB_DQS_DP<5> @T6G_MB_LIB.T6G(SCH_1):M_B_CPU1_SB_DQS_DP(5)   I236 @T6G_MB_LIB.T6G(SCH_1):PAGE98
   249 M_B_CPU1_SB_DQS_DN<5> @T6G_MB_LIB.T6G(SCH_1):M_B_CPU1_SB_DQS_DN(5)   I236 @T6G_MB_LIB.T6G(SCH_1):PAGE98
   157 M_B_CPU1_SA_DQS_DP<5> @T6G_MB_LIB.T6G(SCH_1):M_B_CPU1_SA_DQS_DP(5)   I236 @T6G_MB_LIB.T6G(SCH_1):PAGE98
   156 M_B_CPU1_SA_DQS_DN<5> @T6G_MB_LIB.T6G(SCH_1):M_B_CPU1_SA_DQS_DN(5)   I236 @T6G_MB_LIB.T6G(SCH_1):PAGE98
   239 M_B_CPU1_SB_DQS_DP<4> @T6G_MB_LIB.T6G(SCH_1):M_B_CPU1_SB_DQS_DP(4)   I236 @T6G_MB_LIB.T6G(SCH_1):PAGE98
   238 M_B_CPU1_SB_DQS_DN<4> @T6G_MB_LIB.T6G(SCH_1):M_B_CPU1_SB_DQS_DN(4)   I236 @T6G_MB_LIB.T6G(SCH_1):PAGE98
    55 M_B_CPU1_SA_DQS_DP<4> @T6G_MB_LIB.T6G(SCH_1):M_B_CPU1_SA_DQS_DP(4)   I236 @T6G_MB_LIB.T6G(SCH_1):PAGE98
    56 M_B_CPU1_SA_DQS_DN<4> @T6G_MB_LIB.T6G(SCH_1):M_B_CPU1_SA_DQS_DN(4)   I236 @T6G_MB_LIB.T6G(SCH_1):PAGE98
   137 M_B_CPU1_SB_DQS_DP<3> @T6G_MB_LIB.T6G(SCH_1):M_B_CPU1_SB_DQS_DP(3)   I236 @T6G_MB_LIB.T6G(SCH_1):PAGE98
   138 M_B_CPU1_SB_DQS_DN<3> @T6G_MB_LIB.T6G(SCH_1):M_B_CPU1_SB_DQS_DN(3)   I236 @T6G_MB_LIB.T6G(SCH_1):PAGE98
    44 M_B_CPU1_SA_DQS_DP<3> @T6G_MB_LIB.T6G(SCH_1):M_B_CPU1_SA_DQS_DP(3)   I236 @T6G_MB_LIB.T6G(SCH_1):PAGE98
    45 M_B_CPU1_SA_DQS_DN<3> @T6G_MB_LIB.T6G(SCH_1):M_B_CPU1_SA_DQS_DN(3)   I236 @T6G_MB_LIB.T6G(SCH_1):PAGE98
   126 M_B_CPU1_SB_DQS_DP<2> @T6G_MB_LIB.T6G(SCH_1):M_B_CPU1_SB_DQS_DP(2)   I236 @T6G_MB_LIB.T6G(SCH_1):PAGE98
   127 M_B_CPU1_SB_DQS_DN<2> @T6G_MB_LIB.T6G(SCH_1):M_B_CPU1_SB_DQS_DN(2)   I236 @T6G_MB_LIB.T6G(SCH_1):PAGE98
    33 M_B_CPU1_SA_DQS_DP<2> @T6G_MB_LIB.T6G(SCH_1):M_B_CPU1_SA_DQS_DP(2)   I236 @T6G_MB_LIB.T6G(SCH_1):PAGE98
    34 M_B_CPU1_SA_DQS_DN<2> @T6G_MB_LIB.T6G(SCH_1):M_B_CPU1_SA_DQS_DN(2)   I236 @T6G_MB_LIB.T6G(SCH_1):PAGE98
   115 M_B_CPU1_SB_DQS_DP<1> @T6G_MB_LIB.T6G(SCH_1):M_B_CPU1_SB_DQS_DP(1)   I236 @T6G_MB_LIB.T6G(SCH_1):PAGE98
   116 M_B_CPU1_SB_DQS_DN<1> @T6G_MB_LIB.T6G(SCH_1):M_B_CPU1_SB_DQS_DN(1)   I236 @T6G_MB_LIB.T6G(SCH_1):PAGE98
    22 M_B_CPU1_SA_DQS_DP<1> @T6G_MB_LIB.T6G(SCH_1):M_B_CPU1_SA_DQS_DP(1)   I236 @T6G_MB_LIB.T6G(SCH_1):PAGE98
    23 M_B_CPU1_SA_DQS_DN<1> @T6G_MB_LIB.T6G(SCH_1):M_B_CPU1_SA_DQS_DN(1)   I236 @T6G_MB_LIB.T6G(SCH_1):PAGE98
   104 M_B_CPU1_SB_DQS_DP<0> @T6G_MB_LIB.T6G(SCH_1):M_B_CPU1_SB_DQS_DP(0)   I236 @T6G_MB_LIB.T6G(SCH_1):PAGE98
   105 M_B_CPU1_SB_DQS_DN<0> @T6G_MB_LIB.T6G(SCH_1):M_B_CPU1_SB_DQS_DN(0)   I236 @T6G_MB_LIB.T6G(SCH_1):PAGE98
    11 M_B_CPU1_SA_DQS_DP<0> @T6G_MB_LIB.T6G(SCH_1):M_B_CPU1_SA_DQS_DP(0)   I236 @T6G_MB_LIB.T6G(SCH_1):PAGE98
    12 M_B_CPU1_SA_DQS_DN<0> @T6G_MB_LIB.T6G(SCH_1):M_B_CPU1_SA_DQS_DN(0)   I236 @T6G_MB_LIB.T6G(SCH_1):PAGE98
   272 M_B_CPU1_SB_DQS_DP<7> @T6G_MB_LIB.T6G(SCH_1):M_B_CPU1_SB_DQS_DP(7)   I236 @T6G_MB_LIB.T6G(SCH_1):PAGE98
   282 M_B_CPU1_SB_DQS_DN<8> @T6G_MB_LIB.T6G(SCH_1):M_B_CPU1_SB_DQS_DN(8)   I236 @T6G_MB_LIB.T6G(SCH_1):PAGE98
   283 M_B_CPU1_SB_DQS_DP<8> @T6G_MB_LIB.T6G(SCH_1):M_B_CPU1_SB_DQS_DP(8)   I236 @T6G_MB_LIB.T6G(SCH_1):PAGE98
   168 M_B_CPU1_SA_DQS_DP<6> @T6G_MB_LIB.T6G(SCH_1):M_B_CPU1_SA_DQS_DP(6)   I236 @T6G_MB_LIB.T6G(SCH_1):PAGE98
   178 M_B_CPU1_SA_DQS_DN<7> @T6G_MB_LIB.T6G(SCH_1):M_B_CPU1_SA_DQS_DN(7)   I236 @T6G_MB_LIB.T6G(SCH_1):PAGE98
     6    GND @T6G_MB_LIB.T6G(SCH_1):GND   I160 @T6G_MB_LIB.T6G(SCH_1):PAGE98
     8    GND @T6G_MB_LIB.T6G(SCH_1):GND   I160 @T6G_MB_LIB.T6G(SCH_1):PAGE98
    10    GND @T6G_MB_LIB.T6G(SCH_1):GND   I160 @T6G_MB_LIB.T6G(SCH_1):PAGE98
    13    GND @T6G_MB_LIB.T6G(SCH_1):GND   I160 @T6G_MB_LIB.T6G(SCH_1):PAGE98
    15    GND @T6G_MB_LIB.T6G(SCH_1):GND   I160 @T6G_MB_LIB.T6G(SCH_1):PAGE98
    17    GND @T6G_MB_LIB.T6G(SCH_1):GND   I160 @T6G_MB_LIB.T6G(SCH_1):PAGE98
    19    GND @T6G_MB_LIB.T6G(SCH_1):GND   I160 @T6G_MB_LIB.T6G(SCH_1):PAGE98
    21    GND @T6G_MB_LIB.T6G(SCH_1):GND   I160 @T6G_MB_LIB.T6G(SCH_1):PAGE98
    24    GND @T6G_MB_LIB.T6G(SCH_1):GND   I160 @T6G_MB_LIB.T6G(SCH_1):PAGE98
    26    GND @T6G_MB_LIB.T6G(SCH_1):GND   I160 @T6G_MB_LIB.T6G(SCH_1):PAGE98
    28    GND @T6G_MB_LIB.T6G(SCH_1):GND   I160 @T6G_MB_LIB.T6G(SCH_1):PAGE98
    30    GND @T6G_MB_LIB.T6G(SCH_1):GND   I160 @T6G_MB_LIB.T6G(SCH_1):PAGE98
    32    GND @T6G_MB_LIB.T6G(SCH_1):GND   I160 @T6G_MB_LIB.T6G(SCH_1):PAGE98
    35    GND @T6G_MB_LIB.T6G(SCH_1):GND   I160 @T6G_MB_LIB.T6G(SCH_1):PAGE98
    37    GND @T6G_MB_LIB.T6G(SCH_1):GND   I160 @T6G_MB_LIB.T6G(SCH_1):PAGE98
    39    GND @T6G_MB_LIB.T6G(SCH_1):GND   I160 @T6G_MB_LIB.T6G(SCH_1):PAGE98
    41    GND @T6G_MB_LIB.T6G(SCH_1):GND   I160 @T6G_MB_LIB.T6G(SCH_1):PAGE98
    43    GND @T6G_MB_LIB.T6G(SCH_1):GND   I160 @T6G_MB_LIB.T6G(SCH_1):PAGE98
    46    GND @T6G_MB_LIB.T6G(SCH_1):GND   I160 @T6G_MB_LIB.T6G(SCH_1):PAGE98
    48    GND @T6G_MB_LIB.T6G(SCH_1):GND   I160 @T6G_MB_LIB.T6G(SCH_1):PAGE98
    50    GND @T6G_MB_LIB.T6G(SCH_1):GND   I160 @T6G_MB_LIB.T6G(SCH_1):PAGE98
    52    GND @T6G_MB_LIB.T6G(SCH_1):GND   I160 @T6G_MB_LIB.T6G(SCH_1):PAGE98
    54    GND @T6G_MB_LIB.T6G(SCH_1):GND   I160 @T6G_MB_LIB.T6G(SCH_1):PAGE98
    57    GND @T6G_MB_LIB.T6G(SCH_1):GND   I160 @T6G_MB_LIB.T6G(SCH_1):PAGE98
    59    GND @T6G_MB_LIB.T6G(SCH_1):GND   I160 @T6G_MB_LIB.T6G(SCH_1):PAGE98
    61    GND @T6G_MB_LIB.T6G(SCH_1):GND   I160 @T6G_MB_LIB.T6G(SCH_1):PAGE98
    63    GND @T6G_MB_LIB.T6G(SCH_1):GND   I160 @T6G_MB_LIB.T6G(SCH_1):PAGE98
    65    GND @T6G_MB_LIB.T6G(SCH_1):GND   I160 @T6G_MB_LIB.T6G(SCH_1):PAGE98
    67    GND @T6G_MB_LIB.T6G(SCH_1):GND   I160 @T6G_MB_LIB.T6G(SCH_1):PAGE98
    69    GND @T6G_MB_LIB.T6G(SCH_1):GND   I160 @T6G_MB_LIB.T6G(SCH_1):PAGE98
    71    GND @T6G_MB_LIB.T6G(SCH_1):GND   I160 @T6G_MB_LIB.T6G(SCH_1):PAGE98
    73    GND @T6G_MB_LIB.T6G(SCH_1):GND   I160 @T6G_MB_LIB.T6G(SCH_1):PAGE98
    75    GND @T6G_MB_LIB.T6G(SCH_1):GND   I160 @T6G_MB_LIB.T6G(SCH_1):PAGE98
    77    GND @T6G_MB_LIB.T6G(SCH_1):GND   I160 @T6G_MB_LIB.T6G(SCH_1):PAGE98
    79    GND @T6G_MB_LIB.T6G(SCH_1):GND   I160 @T6G_MB_LIB.T6G(SCH_1):PAGE98
    81    GND @T6G_MB_LIB.T6G(SCH_1):GND   I160 @T6G_MB_LIB.T6G(SCH_1):PAGE98
    83    GND @T6G_MB_LIB.T6G(SCH_1):GND   I160 @T6G_MB_LIB.T6G(SCH_1):PAGE98
    85    GND @T6G_MB_LIB.T6G(SCH_1):GND   I160 @T6G_MB_LIB.T6G(SCH_1):PAGE98
    88    GND @T6G_MB_LIB.T6G(SCH_1):GND   I160 @T6G_MB_LIB.T6G(SCH_1):PAGE98
    90    GND @T6G_MB_LIB.T6G(SCH_1):GND   I160 @T6G_MB_LIB.T6G(SCH_1):PAGE98
    92    GND @T6G_MB_LIB.T6G(SCH_1):GND   I160 @T6G_MB_LIB.T6G(SCH_1):PAGE98
    95    GND @T6G_MB_LIB.T6G(SCH_1):GND   I160 @T6G_MB_LIB.T6G(SCH_1):PAGE98
    97    GND @T6G_MB_LIB.T6G(SCH_1):GND   I160 @T6G_MB_LIB.T6G(SCH_1):PAGE98
    99    GND @T6G_MB_LIB.T6G(SCH_1):GND   I160 @T6G_MB_LIB.T6G(SCH_1):PAGE98
   101    GND @T6G_MB_LIB.T6G(SCH_1):GND   I160 @T6G_MB_LIB.T6G(SCH_1):PAGE98
   103    GND @T6G_MB_LIB.T6G(SCH_1):GND   I160 @T6G_MB_LIB.T6G(SCH_1):PAGE98
   106    GND @T6G_MB_LIB.T6G(SCH_1):GND   I160 @T6G_MB_LIB.T6G(SCH_1):PAGE98
   108    GND @T6G_MB_LIB.T6G(SCH_1):GND   I160 @T6G_MB_LIB.T6G(SCH_1):PAGE98
   110    GND @T6G_MB_LIB.T6G(SCH_1):GND   I160 @T6G_MB_LIB.T6G(SCH_1):PAGE98
   112    GND @T6G_MB_LIB.T6G(SCH_1):GND   I160 @T6G_MB_LIB.T6G(SCH_1):PAGE98
   114    GND @T6G_MB_LIB.T6G(SCH_1):GND   I160 @T6G_MB_LIB.T6G(SCH_1):PAGE98
   117    GND @T6G_MB_LIB.T6G(SCH_1):GND   I160 @T6G_MB_LIB.T6G(SCH_1):PAGE98
   119    GND @T6G_MB_LIB.T6G(SCH_1):GND   I160 @T6G_MB_LIB.T6G(SCH_1):PAGE98
   121    GND @T6G_MB_LIB.T6G(SCH_1):GND   I160 @T6G_MB_LIB.T6G(SCH_1):PAGE98
   123    GND @T6G_MB_LIB.T6G(SCH_1):GND   I160 @T6G_MB_LIB.T6G(SCH_1):PAGE98
   125    GND @T6G_MB_LIB.T6G(SCH_1):GND   I160 @T6G_MB_LIB.T6G(SCH_1):PAGE98
   128    GND @T6G_MB_LIB.T6G(SCH_1):GND   I160 @T6G_MB_LIB.T6G(SCH_1):PAGE98
   130    GND @T6G_MB_LIB.T6G(SCH_1):GND   I160 @T6G_MB_LIB.T6G(SCH_1):PAGE98
   134    GND @T6G_MB_LIB.T6G(SCH_1):GND   I160 @T6G_MB_LIB.T6G(SCH_1):PAGE98
   143    GND @T6G_MB_LIB.T6G(SCH_1):GND   I160 @T6G_MB_LIB.T6G(SCH_1):PAGE98
   151    GND @T6G_MB_LIB.T6G(SCH_1):GND   I160 @T6G_MB_LIB.T6G(SCH_1):PAGE98
   153    GND @T6G_MB_LIB.T6G(SCH_1):GND   I160 @T6G_MB_LIB.T6G(SCH_1):PAGE98
   155    GND @T6G_MB_LIB.T6G(SCH_1):GND   I160 @T6G_MB_LIB.T6G(SCH_1):PAGE98
   158    GND @T6G_MB_LIB.T6G(SCH_1):GND   I160 @T6G_MB_LIB.T6G(SCH_1):PAGE98
   160    GND @T6G_MB_LIB.T6G(SCH_1):GND   I160 @T6G_MB_LIB.T6G(SCH_1):PAGE98
   162    GND @T6G_MB_LIB.T6G(SCH_1):GND   I160 @T6G_MB_LIB.T6G(SCH_1):PAGE98
   164    GND @T6G_MB_LIB.T6G(SCH_1):GND   I160 @T6G_MB_LIB.T6G(SCH_1):PAGE98
   166    GND @T6G_MB_LIB.T6G(SCH_1):GND   I160 @T6G_MB_LIB.T6G(SCH_1):PAGE98
   169    GND @T6G_MB_LIB.T6G(SCH_1):GND   I160 @T6G_MB_LIB.T6G(SCH_1):PAGE98
   171    GND @T6G_MB_LIB.T6G(SCH_1):GND   I160 @T6G_MB_LIB.T6G(SCH_1):PAGE98
   173    GND @T6G_MB_LIB.T6G(SCH_1):GND   I160 @T6G_MB_LIB.T6G(SCH_1):PAGE98
   175    GND @T6G_MB_LIB.T6G(SCH_1):GND   I160 @T6G_MB_LIB.T6G(SCH_1):PAGE98
   177    GND @T6G_MB_LIB.T6G(SCH_1):GND   I160 @T6G_MB_LIB.T6G(SCH_1):PAGE98
   180    GND @T6G_MB_LIB.T6G(SCH_1):GND   I160 @T6G_MB_LIB.T6G(SCH_1):PAGE98
   182    GND @T6G_MB_LIB.T6G(SCH_1):GND   I160 @T6G_MB_LIB.T6G(SCH_1):PAGE98
   184    GND @T6G_MB_LIB.T6G(SCH_1):GND   I160 @T6G_MB_LIB.T6G(SCH_1):PAGE98
   186    GND @T6G_MB_LIB.T6G(SCH_1):GND   I160 @T6G_MB_LIB.T6G(SCH_1):PAGE98
   188    GND @T6G_MB_LIB.T6G(SCH_1):GND   I160 @T6G_MB_LIB.T6G(SCH_1):PAGE98
   191    GND @T6G_MB_LIB.T6G(SCH_1):GND   I160 @T6G_MB_LIB.T6G(SCH_1):PAGE98
   193    GND @T6G_MB_LIB.T6G(SCH_1):GND   I160 @T6G_MB_LIB.T6G(SCH_1):PAGE98
   195    GND @T6G_MB_LIB.T6G(SCH_1):GND   I160 @T6G_MB_LIB.T6G(SCH_1):PAGE98
   197    GND @T6G_MB_LIB.T6G(SCH_1):GND   I160 @T6G_MB_LIB.T6G(SCH_1):PAGE98
   199    GND @T6G_MB_LIB.T6G(SCH_1):GND   I160 @T6G_MB_LIB.T6G(SCH_1):PAGE98
   202    GND @T6G_MB_LIB.T6G(SCH_1):GND   I160 @T6G_MB_LIB.T6G(SCH_1):PAGE98
   204    GND @T6G_MB_LIB.T6G(SCH_1):GND   I160 @T6G_MB_LIB.T6G(SCH_1):PAGE98
   206    GND @T6G_MB_LIB.T6G(SCH_1):GND   I160 @T6G_MB_LIB.T6G(SCH_1):PAGE98
   208    GND @T6G_MB_LIB.T6G(SCH_1):GND   I160 @T6G_MB_LIB.T6G(SCH_1):PAGE98
   210    GND @T6G_MB_LIB.T6G(SCH_1):GND   I160 @T6G_MB_LIB.T6G(SCH_1):PAGE98
   212    GND @T6G_MB_LIB.T6G(SCH_1):GND   I160 @T6G_MB_LIB.T6G(SCH_1):PAGE98
   214    GND @T6G_MB_LIB.T6G(SCH_1):GND   I160 @T6G_MB_LIB.T6G(SCH_1):PAGE98
   216    GND @T6G_MB_LIB.T6G(SCH_1):GND   I160 @T6G_MB_LIB.T6G(SCH_1):PAGE98
   219    GND @T6G_MB_LIB.T6G(SCH_1):GND   I160 @T6G_MB_LIB.T6G(SCH_1):PAGE98
   222    GND @T6G_MB_LIB.T6G(SCH_1):GND   I160 @T6G_MB_LIB.T6G(SCH_1):PAGE98
   224    GND @T6G_MB_LIB.T6G(SCH_1):GND   I160 @T6G_MB_LIB.T6G(SCH_1):PAGE98
   226    GND @T6G_MB_LIB.T6G(SCH_1):GND   I160 @T6G_MB_LIB.T6G(SCH_1):PAGE98
   228    GND @T6G_MB_LIB.T6G(SCH_1):GND   I160 @T6G_MB_LIB.T6G(SCH_1):PAGE98
   233    GND @T6G_MB_LIB.T6G(SCH_1):GND   I160 @T6G_MB_LIB.T6G(SCH_1):PAGE98
   237    GND @T6G_MB_LIB.T6G(SCH_1):GND   I160 @T6G_MB_LIB.T6G(SCH_1):PAGE98
   242    GND @T6G_MB_LIB.T6G(SCH_1):GND   I160 @T6G_MB_LIB.T6G(SCH_1):PAGE98
   244    GND @T6G_MB_LIB.T6G(SCH_1):GND   I160 @T6G_MB_LIB.T6G(SCH_1):PAGE98
   246    GND @T6G_MB_LIB.T6G(SCH_1):GND   I160 @T6G_MB_LIB.T6G(SCH_1):PAGE98
   248    GND @T6G_MB_LIB.T6G(SCH_1):GND   I160 @T6G_MB_LIB.T6G(SCH_1):PAGE98
   251    GND @T6G_MB_LIB.T6G(SCH_1):GND   I160 @T6G_MB_LIB.T6G(SCH_1):PAGE98
   253    GND @T6G_MB_LIB.T6G(SCH_1):GND   I160 @T6G_MB_LIB.T6G(SCH_1):PAGE98
   255    GND @T6G_MB_LIB.T6G(SCH_1):GND   I160 @T6G_MB_LIB.T6G(SCH_1):PAGE98
   257    GND @T6G_MB_LIB.T6G(SCH_1):GND   I160 @T6G_MB_LIB.T6G(SCH_1):PAGE98
   259    GND @T6G_MB_LIB.T6G(SCH_1):GND   I160 @T6G_MB_LIB.T6G(SCH_1):PAGE98
   262    GND @T6G_MB_LIB.T6G(SCH_1):GND   I160 @T6G_MB_LIB.T6G(SCH_1):PAGE98
   264    GND @T6G_MB_LIB.T6G(SCH_1):GND   I160 @T6G_MB_LIB.T6G(SCH_1):PAGE98
   266    GND @T6G_MB_LIB.T6G(SCH_1):GND   I160 @T6G_MB_LIB.T6G(SCH_1):PAGE98
   268    GND @T6G_MB_LIB.T6G(SCH_1):GND   I160 @T6G_MB_LIB.T6G(SCH_1):PAGE98
   270    GND @T6G_MB_LIB.T6G(SCH_1):GND   I160 @T6G_MB_LIB.T6G(SCH_1):PAGE98
   273    GND @T6G_MB_LIB.T6G(SCH_1):GND   I160 @T6G_MB_LIB.T6G(SCH_1):PAGE98
   275    GND @T6G_MB_LIB.T6G(SCH_1):GND   I160 @T6G_MB_LIB.T6G(SCH_1):PAGE98
   277    GND @T6G_MB_LIB.T6G(SCH_1):GND   I160 @T6G_MB_LIB.T6G(SCH_1):PAGE98
   279    GND @T6G_MB_LIB.T6G(SCH_1):GND   I160 @T6G_MB_LIB.T6G(SCH_1):PAGE98
   281    GND @T6G_MB_LIB.T6G(SCH_1):GND   I160 @T6G_MB_LIB.T6G(SCH_1):PAGE98
   284    GND @T6G_MB_LIB.T6G(SCH_1):GND   I160 @T6G_MB_LIB.T6G(SCH_1):PAGE98
   286    GND @T6G_MB_LIB.T6G(SCH_1):GND   I160 @T6G_MB_LIB.T6G(SCH_1):PAGE98
   288    GND @T6G_MB_LIB.T6G(SCH_1):GND   I160 @T6G_MB_LIB.T6G(SCH_1):PAGE98
     1 P12V_MEM_CPU1 @T6G_MB_LIB.T6G(SCH_1):P12V_MEM_CPU1   I160 @T6G_MB_LIB.T6G(SCH_1):PAGE98
   145 P12V_MEM_CPU1 @T6G_MB_LIB.T6G(SCH_1):P12V_MEM_CPU1   I160 @T6G_MB_LIB.T6G(SCH_1):PAGE98
   146 P12V_MEM_CPU1 @T6G_MB_LIB.T6G(SCH_1):P12V_MEM_CPU1   I160 @T6G_MB_LIB.T6G(SCH_1):PAGE98
   230    GND @T6G_MB_LIB.T6G(SCH_1):GND   I160 @T6G_MB_LIB.T6G(SCH_1):PAGE98
   235    GND @T6G_MB_LIB.T6G(SCH_1):GND   I160 @T6G_MB_LIB.T6G(SCH_1):PAGE98
   240    GND @T6G_MB_LIB.T6G(SCH_1):GND   I160 @T6G_MB_LIB.T6G(SCH_1):PAGE98
   132    GND @T6G_MB_LIB.T6G(SCH_1):GND   I160 @T6G_MB_LIB.T6G(SCH_1):PAGE98
   136    GND @T6G_MB_LIB.T6G(SCH_1):GND   I160 @T6G_MB_LIB.T6G(SCH_1):PAGE98
   139    GND @T6G_MB_LIB.T6G(SCH_1):GND   I160 @T6G_MB_LIB.T6G(SCH_1):PAGE98
   141    GND @T6G_MB_LIB.T6G(SCH_1):GND   I160 @T6G_MB_LIB.T6G(SCH_1):PAGE98
    G1    GND @T6G_MB_LIB.T6G(SCH_1):GND   I160 @T6G_MB_LIB.T6G(SCH_1):PAGE98
    G2    GND @T6G_MB_LIB.T6G(SCH_1):GND   I160 @T6G_MB_LIB.T6G(SCH_1):PAGE98
    G3    GND @T6G_MB_LIB.T6G(SCH_1):GND   I160 @T6G_MB_LIB.T6G(SCH_1):PAGE98

 J27 SCONN288_DDR506112002KQ-SCONN288_DDR506112002KQ,SMA
     3 P3V3_AUX @T6G_MB_LIB.T6G(SCH_1):P3V3_AUX    I22 @T6G_MB_LIB.T6G(SCH_1):PAGE104
     2     NC     NC    I22 @T6G_MB_LIB.T6G(SCH_1):PAGE104
   144     NC     NC    I22 @T6G_MB_LIB.T6G(SCH_1):PAGE104
   149     NC     NC    I22 @T6G_MB_LIB.T6G(SCH_1):PAGE104
   150     NC     NC    I22 @T6G_MB_LIB.T6G(SCH_1):PAGE104
   220     NC     NC    I22 @T6G_MB_LIB.T6G(SCH_1):PAGE104
   231     NC     NC    I22 @T6G_MB_LIB.T6G(SCH_1):PAGE104
   232     NC     NC    I22 @T6G_MB_LIB.T6G(SCH_1):PAGE104
   207 M_H_CPU1_RESET_N @T6G_MB_LIB.T6G(SCH_1):M_H_CPU1_RESET_N    I22 @T6G_MB_LIB.T6G(SCH_1):PAGE104
   147 PWRGD_CHH_CPU1_DIMM @T6G_MB_LIB.T6G(SCH_1):PWRGD_CHH_CPU1_DIMM    I22 @T6G_MB_LIB.T6G(SCH_1):PAGE104
   227 M_H_CPU1_SB_PAR @T6G_MB_LIB.T6G(SCH_1):M_H_CPU1_SB_PAR    I22 @T6G_MB_LIB.T6G(SCH_1):PAGE104
    74 M_H_CPU1_SA_PAR @T6G_MB_LIB.T6G(SCH_1):M_H_CPU1_SA_PAR    I22 @T6G_MB_LIB.T6G(SCH_1):PAGE104
    87 M_H_CPU1_SB_RSP<0> @T6G_MB_LIB.T6G(SCH_1):M_H_CPU1_SB_RSP(0)    I22 @T6G_MB_LIB.T6G(SCH_1):PAGE104
    86 M_H_CPU1_SA_RSP<0> @T6G_MB_LIB.T6G(SCH_1):M_H_CPU1_SA_RSP(0)    I22 @T6G_MB_LIB.T6G(SCH_1):PAGE104
     5 I3C_SPD_DDRH_CPU1_SDA @T6G_MB_LIB.T6G(SCH_1):I3C_SPD_DDRH_CPU1_SDA    I22 @T6G_MB_LIB.T6G(SCH_1):PAGE104
     4 I3C_SPD_DDRH_CPU1_SCL @T6G_MB_LIB.T6G(SCH_1):I3C_SPD_DDRH_CPU1_SCL    I22 @T6G_MB_LIB.T6G(SCH_1):PAGE104
   148 PD_CHH_CPU1_DIMM_SAA @T6G_MB_LIB.T6G(SCH_1):PD_CHH_CPU1_DIMM_SAA    I22 @T6G_MB_LIB.T6G(SCH_1):PAGE104
   100 M_H_CPU1_SB_DQ<0> @T6G_MB_LIB.T6G(SCH_1):M_H_CPU1_SB_DQ(0)    I22 @T6G_MB_LIB.T6G(SCH_1):PAGE104
   102 M_H_CPU1_SB_DQ<1> @T6G_MB_LIB.T6G(SCH_1):M_H_CPU1_SB_DQ(1)    I22 @T6G_MB_LIB.T6G(SCH_1):PAGE104
   245 M_H_CPU1_SB_DQ<2> @T6G_MB_LIB.T6G(SCH_1):M_H_CPU1_SB_DQ(2)    I22 @T6G_MB_LIB.T6G(SCH_1):PAGE104
   247 M_H_CPU1_SB_DQ<3> @T6G_MB_LIB.T6G(SCH_1):M_H_CPU1_SB_DQ(3)    I22 @T6G_MB_LIB.T6G(SCH_1):PAGE104
   107 M_H_CPU1_SB_DQ<4> @T6G_MB_LIB.T6G(SCH_1):M_H_CPU1_SB_DQ(4)    I22 @T6G_MB_LIB.T6G(SCH_1):PAGE104
   109 M_H_CPU1_SB_DQ<5> @T6G_MB_LIB.T6G(SCH_1):M_H_CPU1_SB_DQ(5)    I22 @T6G_MB_LIB.T6G(SCH_1):PAGE104
   252 M_H_CPU1_SB_DQ<6> @T6G_MB_LIB.T6G(SCH_1):M_H_CPU1_SB_DQ(6)    I22 @T6G_MB_LIB.T6G(SCH_1):PAGE104
   254 M_H_CPU1_SB_DQ<7> @T6G_MB_LIB.T6G(SCH_1):M_H_CPU1_SB_DQ(7)    I22 @T6G_MB_LIB.T6G(SCH_1):PAGE104
   111 M_H_CPU1_SB_DQ<8> @T6G_MB_LIB.T6G(SCH_1):M_H_CPU1_SB_DQ(8)    I22 @T6G_MB_LIB.T6G(SCH_1):PAGE104
   113 M_H_CPU1_SB_DQ<9> @T6G_MB_LIB.T6G(SCH_1):M_H_CPU1_SB_DQ(9)    I22 @T6G_MB_LIB.T6G(SCH_1):PAGE104
   256 M_H_CPU1_SB_DQ<10> @T6G_MB_LIB.T6G(SCH_1):M_H_CPU1_SB_DQ(10)    I22 @T6G_MB_LIB.T6G(SCH_1):PAGE104
   258 M_H_CPU1_SB_DQ<11> @T6G_MB_LIB.T6G(SCH_1):M_H_CPU1_SB_DQ(11)    I22 @T6G_MB_LIB.T6G(SCH_1):PAGE104
   118 M_H_CPU1_SB_DQ<12> @T6G_MB_LIB.T6G(SCH_1):M_H_CPU1_SB_DQ(12)    I22 @T6G_MB_LIB.T6G(SCH_1):PAGE104
   120 M_H_CPU1_SB_DQ<13> @T6G_MB_LIB.T6G(SCH_1):M_H_CPU1_SB_DQ(13)    I22 @T6G_MB_LIB.T6G(SCH_1):PAGE104
   263 M_H_CPU1_SB_DQ<14> @T6G_MB_LIB.T6G(SCH_1):M_H_CPU1_SB_DQ(14)    I22 @T6G_MB_LIB.T6G(SCH_1):PAGE104
   265 M_H_CPU1_SB_DQ<15> @T6G_MB_LIB.T6G(SCH_1):M_H_CPU1_SB_DQ(15)    I22 @T6G_MB_LIB.T6G(SCH_1):PAGE104
   122 M_H_CPU1_SB_DQ<16> @T6G_MB_LIB.T6G(SCH_1):M_H_CPU1_SB_DQ(16)    I22 @T6G_MB_LIB.T6G(SCH_1):PAGE104
   124 M_H_CPU1_SB_DQ<17> @T6G_MB_LIB.T6G(SCH_1):M_H_CPU1_SB_DQ(17)    I22 @T6G_MB_LIB.T6G(SCH_1):PAGE104
   267 M_H_CPU1_SB_DQ<18> @T6G_MB_LIB.T6G(SCH_1):M_H_CPU1_SB_DQ(18)    I22 @T6G_MB_LIB.T6G(SCH_1):PAGE104
   269 M_H_CPU1_SB_DQ<19> @T6G_MB_LIB.T6G(SCH_1):M_H_CPU1_SB_DQ(19)    I22 @T6G_MB_LIB.T6G(SCH_1):PAGE104
   129 M_H_CPU1_SB_DQ<20> @T6G_MB_LIB.T6G(SCH_1):M_H_CPU1_SB_DQ(20)    I22 @T6G_MB_LIB.T6G(SCH_1):PAGE104
   131 M_H_CPU1_SB_DQ<21> @T6G_MB_LIB.T6G(SCH_1):M_H_CPU1_SB_DQ(21)    I22 @T6G_MB_LIB.T6G(SCH_1):PAGE104
   274 M_H_CPU1_SB_DQ<22> @T6G_MB_LIB.T6G(SCH_1):M_H_CPU1_SB_DQ(22)    I22 @T6G_MB_LIB.T6G(SCH_1):PAGE104
   276 M_H_CPU1_SB_DQ<23> @T6G_MB_LIB.T6G(SCH_1):M_H_CPU1_SB_DQ(23)    I22 @T6G_MB_LIB.T6G(SCH_1):PAGE104
   133 M_H_CPU1_SB_DQ<24> @T6G_MB_LIB.T6G(SCH_1):M_H_CPU1_SB_DQ(24)    I22 @T6G_MB_LIB.T6G(SCH_1):PAGE104
   135 M_H_CPU1_SB_DQ<25> @T6G_MB_LIB.T6G(SCH_1):M_H_CPU1_SB_DQ(25)    I22 @T6G_MB_LIB.T6G(SCH_1):PAGE104
   278 M_H_CPU1_SB_DQ<26> @T6G_MB_LIB.T6G(SCH_1):M_H_CPU1_SB_DQ(26)    I22 @T6G_MB_LIB.T6G(SCH_1):PAGE104
   280 M_H_CPU1_SB_DQ<27> @T6G_MB_LIB.T6G(SCH_1):M_H_CPU1_SB_DQ(27)    I22 @T6G_MB_LIB.T6G(SCH_1):PAGE104
   140 M_H_CPU1_SB_DQ<28> @T6G_MB_LIB.T6G(SCH_1):M_H_CPU1_SB_DQ(28)    I22 @T6G_MB_LIB.T6G(SCH_1):PAGE104
   142 M_H_CPU1_SB_DQ<29> @T6G_MB_LIB.T6G(SCH_1):M_H_CPU1_SB_DQ(29)    I22 @T6G_MB_LIB.T6G(SCH_1):PAGE104
   285 M_H_CPU1_SB_DQ<30> @T6G_MB_LIB.T6G(SCH_1):M_H_CPU1_SB_DQ(30)    I22 @T6G_MB_LIB.T6G(SCH_1):PAGE104
   287 M_H_CPU1_SB_DQ<31> @T6G_MB_LIB.T6G(SCH_1):M_H_CPU1_SB_DQ(31)    I22 @T6G_MB_LIB.T6G(SCH_1):PAGE104
     7 M_H_CPU1_SA_DQ<0> @T6G_MB_LIB.T6G(SCH_1):M_H_CPU1_SA_DQ(0)    I22 @T6G_MB_LIB.T6G(SCH_1):PAGE104
     9 M_H_CPU1_SA_DQ<1> @T6G_MB_LIB.T6G(SCH_1):M_H_CPU1_SA_DQ(1)    I22 @T6G_MB_LIB.T6G(SCH_1):PAGE104
   152 M_H_CPU1_SA_DQ<2> @T6G_MB_LIB.T6G(SCH_1):M_H_CPU1_SA_DQ(2)    I22 @T6G_MB_LIB.T6G(SCH_1):PAGE104
   154 M_H_CPU1_SA_DQ<3> @T6G_MB_LIB.T6G(SCH_1):M_H_CPU1_SA_DQ(3)    I22 @T6G_MB_LIB.T6G(SCH_1):PAGE104
    14 M_H_CPU1_SA_DQ<4> @T6G_MB_LIB.T6G(SCH_1):M_H_CPU1_SA_DQ(4)    I22 @T6G_MB_LIB.T6G(SCH_1):PAGE104
    16 M_H_CPU1_SA_DQ<5> @T6G_MB_LIB.T6G(SCH_1):M_H_CPU1_SA_DQ(5)    I22 @T6G_MB_LIB.T6G(SCH_1):PAGE104
   159 M_H_CPU1_SA_DQ<6> @T6G_MB_LIB.T6G(SCH_1):M_H_CPU1_SA_DQ(6)    I22 @T6G_MB_LIB.T6G(SCH_1):PAGE104
   161 M_H_CPU1_SA_DQ<7> @T6G_MB_LIB.T6G(SCH_1):M_H_CPU1_SA_DQ(7)    I22 @T6G_MB_LIB.T6G(SCH_1):PAGE104
    18 M_H_CPU1_SA_DQ<8> @T6G_MB_LIB.T6G(SCH_1):M_H_CPU1_SA_DQ(8)    I22 @T6G_MB_LIB.T6G(SCH_1):PAGE104
    20 M_H_CPU1_SA_DQ<9> @T6G_MB_LIB.T6G(SCH_1):M_H_CPU1_SA_DQ(9)    I22 @T6G_MB_LIB.T6G(SCH_1):PAGE104
   163 M_H_CPU1_SA_DQ<10> @T6G_MB_LIB.T6G(SCH_1):M_H_CPU1_SA_DQ(10)    I22 @T6G_MB_LIB.T6G(SCH_1):PAGE104
   165 M_H_CPU1_SA_DQ<11> @T6G_MB_LIB.T6G(SCH_1):M_H_CPU1_SA_DQ(11)    I22 @T6G_MB_LIB.T6G(SCH_1):PAGE104
    25 M_H_CPU1_SA_DQ<12> @T6G_MB_LIB.T6G(SCH_1):M_H_CPU1_SA_DQ(12)    I22 @T6G_MB_LIB.T6G(SCH_1):PAGE104
    27 M_H_CPU1_SA_DQ<13> @T6G_MB_LIB.T6G(SCH_1):M_H_CPU1_SA_DQ(13)    I22 @T6G_MB_LIB.T6G(SCH_1):PAGE104
   170 M_H_CPU1_SA_DQ<14> @T6G_MB_LIB.T6G(SCH_1):M_H_CPU1_SA_DQ(14)    I22 @T6G_MB_LIB.T6G(SCH_1):PAGE104
   172 M_H_CPU1_SA_DQ<15> @T6G_MB_LIB.T6G(SCH_1):M_H_CPU1_SA_DQ(15)    I22 @T6G_MB_LIB.T6G(SCH_1):PAGE104
    29 M_H_CPU1_SA_DQ<16> @T6G_MB_LIB.T6G(SCH_1):M_H_CPU1_SA_DQ(16)    I22 @T6G_MB_LIB.T6G(SCH_1):PAGE104
    31 M_H_CPU1_SA_DQ<17> @T6G_MB_LIB.T6G(SCH_1):M_H_CPU1_SA_DQ(17)    I22 @T6G_MB_LIB.T6G(SCH_1):PAGE104
   174 M_H_CPU1_SA_DQ<18> @T6G_MB_LIB.T6G(SCH_1):M_H_CPU1_SA_DQ(18)    I22 @T6G_MB_LIB.T6G(SCH_1):PAGE104
   176 M_H_CPU1_SA_DQ<19> @T6G_MB_LIB.T6G(SCH_1):M_H_CPU1_SA_DQ(19)    I22 @T6G_MB_LIB.T6G(SCH_1):PAGE104
    36 M_H_CPU1_SA_DQ<20> @T6G_MB_LIB.T6G(SCH_1):M_H_CPU1_SA_DQ(20)    I22 @T6G_MB_LIB.T6G(SCH_1):PAGE104
    38 M_H_CPU1_SA_DQ<21> @T6G_MB_LIB.T6G(SCH_1):M_H_CPU1_SA_DQ(21)    I22 @T6G_MB_LIB.T6G(SCH_1):PAGE104
   181 M_H_CPU1_SA_DQ<22> @T6G_MB_LIB.T6G(SCH_1):M_H_CPU1_SA_DQ(22)    I22 @T6G_MB_LIB.T6G(SCH_1):PAGE104
   183 M_H_CPU1_SA_DQ<23> @T6G_MB_LIB.T6G(SCH_1):M_H_CPU1_SA_DQ(23)    I22 @T6G_MB_LIB.T6G(SCH_1):PAGE104
    40 M_H_CPU1_SA_DQ<24> @T6G_MB_LIB.T6G(SCH_1):M_H_CPU1_SA_DQ(24)    I22 @T6G_MB_LIB.T6G(SCH_1):PAGE104
    42 M_H_CPU1_SA_DQ<25> @T6G_MB_LIB.T6G(SCH_1):M_H_CPU1_SA_DQ(25)    I22 @T6G_MB_LIB.T6G(SCH_1):PAGE104
   185 M_H_CPU1_SA_DQ<26> @T6G_MB_LIB.T6G(SCH_1):M_H_CPU1_SA_DQ(26)    I22 @T6G_MB_LIB.T6G(SCH_1):PAGE104
   187 M_H_CPU1_SA_DQ<27> @T6G_MB_LIB.T6G(SCH_1):M_H_CPU1_SA_DQ(27)    I22 @T6G_MB_LIB.T6G(SCH_1):PAGE104
    47 M_H_CPU1_SA_DQ<28> @T6G_MB_LIB.T6G(SCH_1):M_H_CPU1_SA_DQ(28)    I22 @T6G_MB_LIB.T6G(SCH_1):PAGE104
    49 M_H_CPU1_SA_DQ<29> @T6G_MB_LIB.T6G(SCH_1):M_H_CPU1_SA_DQ(29)    I22 @T6G_MB_LIB.T6G(SCH_1):PAGE104
   192 M_H_CPU1_SA_DQ<30> @T6G_MB_LIB.T6G(SCH_1):M_H_CPU1_SA_DQ(30)    I22 @T6G_MB_LIB.T6G(SCH_1):PAGE104
   229 M_H_CPU1_SB_CS_N<1> @T6G_MB_LIB.T6G(SCH_1):M_H_CPU1_SB_CS_N(1)    I22 @T6G_MB_LIB.T6G(SCH_1):PAGE104
   209 M_H_CPU1_SA_CS_N<1> @T6G_MB_LIB.T6G(SCH_1):M_H_CPU1_SA_CS_N(1)    I22 @T6G_MB_LIB.T6G(SCH_1):PAGE104
    84 M_H_CPU1_SB_CS_N<0> @T6G_MB_LIB.T6G(SCH_1):M_H_CPU1_SB_CS_N(0)    I22 @T6G_MB_LIB.T6G(SCH_1):PAGE104
    64 M_H_CPU1_SA_CS_N<0> @T6G_MB_LIB.T6G(SCH_1):M_H_CPU1_SA_CS_N(0)    I22 @T6G_MB_LIB.T6G(SCH_1):PAGE104
   217 M_H_CPU1_CLK_DP<0> @T6G_MB_LIB.T6G(SCH_1):M_H_CPU1_CLK_DP(0)    I22 @T6G_MB_LIB.T6G(SCH_1):PAGE104
   218 M_H_CPU1_CLK_DN<0> @T6G_MB_LIB.T6G(SCH_1):M_H_CPU1_CLK_DN(0)    I22 @T6G_MB_LIB.T6G(SCH_1):PAGE104
    96 M_H_CPU1_SB_CB<0> @T6G_MB_LIB.T6G(SCH_1):M_H_CPU1_SB_CB(0)    I22 @T6G_MB_LIB.T6G(SCH_1):PAGE104
    98 M_H_CPU1_SB_CB<1> @T6G_MB_LIB.T6G(SCH_1):M_H_CPU1_SB_CB(1)    I22 @T6G_MB_LIB.T6G(SCH_1):PAGE104
   241 M_H_CPU1_SB_CB<2> @T6G_MB_LIB.T6G(SCH_1):M_H_CPU1_SB_CB(2)    I22 @T6G_MB_LIB.T6G(SCH_1):PAGE104
   243 M_H_CPU1_SB_CB<3> @T6G_MB_LIB.T6G(SCH_1):M_H_CPU1_SB_CB(3)    I22 @T6G_MB_LIB.T6G(SCH_1):PAGE104
    89 M_H_CPU1_SB_CB<4> @T6G_MB_LIB.T6G(SCH_1):M_H_CPU1_SB_CB(4)    I22 @T6G_MB_LIB.T6G(SCH_1):PAGE104
    91 M_H_CPU1_SB_CB<5> @T6G_MB_LIB.T6G(SCH_1):M_H_CPU1_SB_CB(5)    I22 @T6G_MB_LIB.T6G(SCH_1):PAGE104
   234 M_H_CPU1_SB_CB<6> @T6G_MB_LIB.T6G(SCH_1):M_H_CPU1_SB_CB(6)    I22 @T6G_MB_LIB.T6G(SCH_1):PAGE104
    51 M_H_CPU1_SA_CB<0> @T6G_MB_LIB.T6G(SCH_1):M_H_CPU1_SA_CB(0)    I22 @T6G_MB_LIB.T6G(SCH_1):PAGE104
   196 M_H_CPU1_SA_CB<2> @T6G_MB_LIB.T6G(SCH_1):M_H_CPU1_SA_CB(2)    I22 @T6G_MB_LIB.T6G(SCH_1):PAGE104
   198 M_H_CPU1_SA_CB<3> @T6G_MB_LIB.T6G(SCH_1):M_H_CPU1_SA_CB(3)    I22 @T6G_MB_LIB.T6G(SCH_1):PAGE104
    60 M_H_CPU1_SA_CB<5> @T6G_MB_LIB.T6G(SCH_1):M_H_CPU1_SA_CB(5)    I22 @T6G_MB_LIB.T6G(SCH_1):PAGE104
   203 M_H_CPU1_SA_CB<6> @T6G_MB_LIB.T6G(SCH_1):M_H_CPU1_SA_CB(6)    I22 @T6G_MB_LIB.T6G(SCH_1):PAGE104
    82 M_H_CPU1_SB_CA<6> @T6G_MB_LIB.T6G(SCH_1):M_H_CPU1_SB_CA(6)    I22 @T6G_MB_LIB.T6G(SCH_1):PAGE104
    72 M_H_CPU1_SA_CA<6> @T6G_MB_LIB.T6G(SCH_1):M_H_CPU1_SA_CA(6)    I22 @T6G_MB_LIB.T6G(SCH_1):PAGE104
   225 M_H_CPU1_SB_CA<5> @T6G_MB_LIB.T6G(SCH_1):M_H_CPU1_SB_CA(5)    I22 @T6G_MB_LIB.T6G(SCH_1):PAGE104
   215 M_H_CPU1_SA_CA<5> @T6G_MB_LIB.T6G(SCH_1):M_H_CPU1_SA_CA(5)    I22 @T6G_MB_LIB.T6G(SCH_1):PAGE104
    80 M_H_CPU1_SB_CA<4> @T6G_MB_LIB.T6G(SCH_1):M_H_CPU1_SB_CA(4)    I22 @T6G_MB_LIB.T6G(SCH_1):PAGE104
    70 M_H_CPU1_SA_CA<4> @T6G_MB_LIB.T6G(SCH_1):M_H_CPU1_SA_CA(4)    I22 @T6G_MB_LIB.T6G(SCH_1):PAGE104
   223 M_H_CPU1_SB_CA<3> @T6G_MB_LIB.T6G(SCH_1):M_H_CPU1_SB_CA(3)    I22 @T6G_MB_LIB.T6G(SCH_1):PAGE104
   213 M_H_CPU1_SA_CA<3> @T6G_MB_LIB.T6G(SCH_1):M_H_CPU1_SA_CA(3)    I22 @T6G_MB_LIB.T6G(SCH_1):PAGE104
    78 M_H_CPU1_SB_CA<2> @T6G_MB_LIB.T6G(SCH_1):M_H_CPU1_SB_CA(2)    I22 @T6G_MB_LIB.T6G(SCH_1):PAGE104
    68 M_H_CPU1_SA_CA<2> @T6G_MB_LIB.T6G(SCH_1):M_H_CPU1_SA_CA(2)    I22 @T6G_MB_LIB.T6G(SCH_1):PAGE104
   221 M_H_CPU1_SB_CA<1> @T6G_MB_LIB.T6G(SCH_1):M_H_CPU1_SB_CA(1)    I22 @T6G_MB_LIB.T6G(SCH_1):PAGE104
   211 M_H_CPU1_SA_CA<1> @T6G_MB_LIB.T6G(SCH_1):M_H_CPU1_SA_CA(1)    I22 @T6G_MB_LIB.T6G(SCH_1):PAGE104
    76 M_H_CPU1_SB_CA<0> @T6G_MB_LIB.T6G(SCH_1):M_H_CPU1_SB_CA(0)    I22 @T6G_MB_LIB.T6G(SCH_1):PAGE104
    66 M_H_CPU1_SA_CA<0> @T6G_MB_LIB.T6G(SCH_1):M_H_CPU1_SA_CA(0)    I22 @T6G_MB_LIB.T6G(SCH_1):PAGE104
    62 M_H_CPU1_ALERT_N @T6G_MB_LIB.T6G(SCH_1):M_H_CPU1_ALERT_N    I22 @T6G_MB_LIB.T6G(SCH_1):PAGE104
   236 M_H_CPU1_SB_CB<7> @T6G_MB_LIB.T6G(SCH_1):M_H_CPU1_SB_CB(7)    I22 @T6G_MB_LIB.T6G(SCH_1):PAGE104
    53 M_H_CPU1_SA_CB<1> @T6G_MB_LIB.T6G(SCH_1):M_H_CPU1_SA_CB(1)    I22 @T6G_MB_LIB.T6G(SCH_1):PAGE104
    58 M_H_CPU1_SA_CB<4> @T6G_MB_LIB.T6G(SCH_1):M_H_CPU1_SA_CB(4)    I22 @T6G_MB_LIB.T6G(SCH_1):PAGE104
   205 M_H_CPU1_SA_CB<7> @T6G_MB_LIB.T6G(SCH_1):M_H_CPU1_SA_CB(7)    I22 @T6G_MB_LIB.T6G(SCH_1):PAGE104
   194 M_H_CPU1_SA_DQ<31> @T6G_MB_LIB.T6G(SCH_1):M_H_CPU1_SA_DQ(31)    I22 @T6G_MB_LIB.T6G(SCH_1):PAGE104
    93 M_H_CPU1_SB_DQS_DP<9> @T6G_MB_LIB.T6G(SCH_1):M_H_CPU1_SB_DQS_DP(9)   I238 @T6G_MB_LIB.T6G(SCH_1):PAGE104
    94 M_H_CPU1_SB_DQS_DN<9> @T6G_MB_LIB.T6G(SCH_1):M_H_CPU1_SB_DQS_DN(9)   I238 @T6G_MB_LIB.T6G(SCH_1):PAGE104
   201 M_H_CPU1_SA_DQS_DP<9> @T6G_MB_LIB.T6G(SCH_1):M_H_CPU1_SA_DQS_DP(9)   I238 @T6G_MB_LIB.T6G(SCH_1):PAGE104
   200 M_H_CPU1_SA_DQS_DN<9> @T6G_MB_LIB.T6G(SCH_1):M_H_CPU1_SA_DQS_DN(9)   I238 @T6G_MB_LIB.T6G(SCH_1):PAGE104
   190 M_H_CPU1_SA_DQS_DP<8> @T6G_MB_LIB.T6G(SCH_1):M_H_CPU1_SA_DQS_DP(8)   I238 @T6G_MB_LIB.T6G(SCH_1):PAGE104
   189 M_H_CPU1_SA_DQS_DN<8> @T6G_MB_LIB.T6G(SCH_1):M_H_CPU1_SA_DQS_DN(8)   I238 @T6G_MB_LIB.T6G(SCH_1):PAGE104
   271 M_H_CPU1_SB_DQS_DN<7> @T6G_MB_LIB.T6G(SCH_1):M_H_CPU1_SB_DQS_DN(7)   I238 @T6G_MB_LIB.T6G(SCH_1):PAGE104
   179 M_H_CPU1_SA_DQS_DP<7> @T6G_MB_LIB.T6G(SCH_1):M_H_CPU1_SA_DQS_DP(7)   I238 @T6G_MB_LIB.T6G(SCH_1):PAGE104
   261 M_H_CPU1_SB_DQS_DP<6> @T6G_MB_LIB.T6G(SCH_1):M_H_CPU1_SB_DQS_DP(6)   I238 @T6G_MB_LIB.T6G(SCH_1):PAGE104
   260 M_H_CPU1_SB_DQS_DN<6> @T6G_MB_LIB.T6G(SCH_1):M_H_CPU1_SB_DQS_DN(6)   I238 @T6G_MB_LIB.T6G(SCH_1):PAGE104
   167 M_H_CPU1_SA_DQS_DN<6> @T6G_MB_LIB.T6G(SCH_1):M_H_CPU1_SA_DQS_DN(6)   I238 @T6G_MB_LIB.T6G(SCH_1):PAGE104
   250 M_H_CPU1_SB_DQS_DP<5> @T6G_MB_LIB.T6G(SCH_1):M_H_CPU1_SB_DQS_DP(5)   I238 @T6G_MB_LIB.T6G(SCH_1):PAGE104
   249 M_H_CPU1_SB_DQS_DN<5> @T6G_MB_LIB.T6G(SCH_1):M_H_CPU1_SB_DQS_DN(5)   I238 @T6G_MB_LIB.T6G(SCH_1):PAGE104
   157 M_H_CPU1_SA_DQS_DP<5> @T6G_MB_LIB.T6G(SCH_1):M_H_CPU1_SA_DQS_DP(5)   I238 @T6G_MB_LIB.T6G(SCH_1):PAGE104
   156 M_H_CPU1_SA_DQS_DN<5> @T6G_MB_LIB.T6G(SCH_1):M_H_CPU1_SA_DQS_DN(5)   I238 @T6G_MB_LIB.T6G(SCH_1):PAGE104
   239 M_H_CPU1_SB_DQS_DP<4> @T6G_MB_LIB.T6G(SCH_1):M_H_CPU1_SB_DQS_DP(4)   I238 @T6G_MB_LIB.T6G(SCH_1):PAGE104
   238 M_H_CPU1_SB_DQS_DN<4> @T6G_MB_LIB.T6G(SCH_1):M_H_CPU1_SB_DQS_DN(4)   I238 @T6G_MB_LIB.T6G(SCH_1):PAGE104
    55 M_H_CPU1_SA_DQS_DP<4> @T6G_MB_LIB.T6G(SCH_1):M_H_CPU1_SA_DQS_DP(4)   I238 @T6G_MB_LIB.T6G(SCH_1):PAGE104
    56 M_H_CPU1_SA_DQS_DN<4> @T6G_MB_LIB.T6G(SCH_1):M_H_CPU1_SA_DQS_DN(4)   I238 @T6G_MB_LIB.T6G(SCH_1):PAGE104
   137 M_H_CPU1_SB_DQS_DP<3> @T6G_MB_LIB.T6G(SCH_1):M_H_CPU1_SB_DQS_DP(3)   I238 @T6G_MB_LIB.T6G(SCH_1):PAGE104
   138 M_H_CPU1_SB_DQS_DN<3> @T6G_MB_LIB.T6G(SCH_1):M_H_CPU1_SB_DQS_DN(3)   I238 @T6G_MB_LIB.T6G(SCH_1):PAGE104
    44 M_H_CPU1_SA_DQS_DP<3> @T6G_MB_LIB.T6G(SCH_1):M_H_CPU1_SA_DQS_DP(3)   I238 @T6G_MB_LIB.T6G(SCH_1):PAGE104
    45 M_H_CPU1_SA_DQS_DN<3> @T6G_MB_LIB.T6G(SCH_1):M_H_CPU1_SA_DQS_DN(3)   I238 @T6G_MB_LIB.T6G(SCH_1):PAGE104
   126 M_H_CPU1_SB_DQS_DP<2> @T6G_MB_LIB.T6G(SCH_1):M_H_CPU1_SB_DQS_DP(2)   I238 @T6G_MB_LIB.T6G(SCH_1):PAGE104
   127 M_H_CPU1_SB_DQS_DN<2> @T6G_MB_LIB.T6G(SCH_1):M_H_CPU1_SB_DQS_DN(2)   I238 @T6G_MB_LIB.T6G(SCH_1):PAGE104
    33 M_H_CPU1_SA_DQS_DP<2> @T6G_MB_LIB.T6G(SCH_1):M_H_CPU1_SA_DQS_DP(2)   I238 @T6G_MB_LIB.T6G(SCH_1):PAGE104
    34 M_H_CPU1_SA_DQS_DN<2> @T6G_MB_LIB.T6G(SCH_1):M_H_CPU1_SA_DQS_DN(2)   I238 @T6G_MB_LIB.T6G(SCH_1):PAGE104
   115 M_H_CPU1_SB_DQS_DP<1> @T6G_MB_LIB.T6G(SCH_1):M_H_CPU1_SB_DQS_DP(1)   I238 @T6G_MB_LIB.T6G(SCH_1):PAGE104
   116 M_H_CPU1_SB_DQS_DN<1> @T6G_MB_LIB.T6G(SCH_1):M_H_CPU1_SB_DQS_DN(1)   I238 @T6G_MB_LIB.T6G(SCH_1):PAGE104
    22 M_H_CPU1_SA_DQS_DP<1> @T6G_MB_LIB.T6G(SCH_1):M_H_CPU1_SA_DQS_DP(1)   I238 @T6G_MB_LIB.T6G(SCH_1):PAGE104
    23 M_H_CPU1_SA_DQS_DN<1> @T6G_MB_LIB.T6G(SCH_1):M_H_CPU1_SA_DQS_DN(1)   I238 @T6G_MB_LIB.T6G(SCH_1):PAGE104
   104 M_H_CPU1_SB_DQS_DP<0> @T6G_MB_LIB.T6G(SCH_1):M_H_CPU1_SB_DQS_DP(0)   I238 @T6G_MB_LIB.T6G(SCH_1):PAGE104
   105 M_H_CPU1_SB_DQS_DN<0> @T6G_MB_LIB.T6G(SCH_1):M_H_CPU1_SB_DQS_DN(0)   I238 @T6G_MB_LIB.T6G(SCH_1):PAGE104
    11 M_H_CPU1_SA_DQS_DP<0> @T6G_MB_LIB.T6G(SCH_1):M_H_CPU1_SA_DQS_DP(0)   I238 @T6G_MB_LIB.T6G(SCH_1):PAGE104
    12 M_H_CPU1_SA_DQS_DN<0> @T6G_MB_LIB.T6G(SCH_1):M_H_CPU1_SA_DQS_DN(0)   I238 @T6G_MB_LIB.T6G(SCH_1):PAGE104
   272 M_H_CPU1_SB_DQS_DP<7> @T6G_MB_LIB.T6G(SCH_1):M_H_CPU1_SB_DQS_DP(7)   I238 @T6G_MB_LIB.T6G(SCH_1):PAGE104
   282 M_H_CPU1_SB_DQS_DN<8> @T6G_MB_LIB.T6G(SCH_1):M_H_CPU1_SB_DQS_DN(8)   I238 @T6G_MB_LIB.T6G(SCH_1):PAGE104
   283 M_H_CPU1_SB_DQS_DP<8> @T6G_MB_LIB.T6G(SCH_1):M_H_CPU1_SB_DQS_DP(8)   I238 @T6G_MB_LIB.T6G(SCH_1):PAGE104
   168 M_H_CPU1_SA_DQS_DP<6> @T6G_MB_LIB.T6G(SCH_1):M_H_CPU1_SA_DQS_DP(6)   I238 @T6G_MB_LIB.T6G(SCH_1):PAGE104
   178 M_H_CPU1_SA_DQS_DN<7> @T6G_MB_LIB.T6G(SCH_1):M_H_CPU1_SA_DQS_DN(7)   I238 @T6G_MB_LIB.T6G(SCH_1):PAGE104
     6    GND @T6G_MB_LIB.T6G(SCH_1):GND   I174 @T6G_MB_LIB.T6G(SCH_1):PAGE104
     8    GND @T6G_MB_LIB.T6G(SCH_1):GND   I174 @T6G_MB_LIB.T6G(SCH_1):PAGE104
    10    GND @T6G_MB_LIB.T6G(SCH_1):GND   I174 @T6G_MB_LIB.T6G(SCH_1):PAGE104
    13    GND @T6G_MB_LIB.T6G(SCH_1):GND   I174 @T6G_MB_LIB.T6G(SCH_1):PAGE104
    15    GND @T6G_MB_LIB.T6G(SCH_1):GND   I174 @T6G_MB_LIB.T6G(SCH_1):PAGE104
    17    GND @T6G_MB_LIB.T6G(SCH_1):GND   I174 @T6G_MB_LIB.T6G(SCH_1):PAGE104
    19    GND @T6G_MB_LIB.T6G(SCH_1):GND   I174 @T6G_MB_LIB.T6G(SCH_1):PAGE104
    21    GND @T6G_MB_LIB.T6G(SCH_1):GND   I174 @T6G_MB_LIB.T6G(SCH_1):PAGE104
    24    GND @T6G_MB_LIB.T6G(SCH_1):GND   I174 @T6G_MB_LIB.T6G(SCH_1):PAGE104
    26    GND @T6G_MB_LIB.T6G(SCH_1):GND   I174 @T6G_MB_LIB.T6G(SCH_1):PAGE104
    28    GND @T6G_MB_LIB.T6G(SCH_1):GND   I174 @T6G_MB_LIB.T6G(SCH_1):PAGE104
    30    GND @T6G_MB_LIB.T6G(SCH_1):GND   I174 @T6G_MB_LIB.T6G(SCH_1):PAGE104
    32    GND @T6G_MB_LIB.T6G(SCH_1):GND   I174 @T6G_MB_LIB.T6G(SCH_1):PAGE104
    35    GND @T6G_MB_LIB.T6G(SCH_1):GND   I174 @T6G_MB_LIB.T6G(SCH_1):PAGE104
    37    GND @T6G_MB_LIB.T6G(SCH_1):GND   I174 @T6G_MB_LIB.T6G(SCH_1):PAGE104
    39    GND @T6G_MB_LIB.T6G(SCH_1):GND   I174 @T6G_MB_LIB.T6G(SCH_1):PAGE104
    41    GND @T6G_MB_LIB.T6G(SCH_1):GND   I174 @T6G_MB_LIB.T6G(SCH_1):PAGE104
    43    GND @T6G_MB_LIB.T6G(SCH_1):GND   I174 @T6G_MB_LIB.T6G(SCH_1):PAGE104
    46    GND @T6G_MB_LIB.T6G(SCH_1):GND   I174 @T6G_MB_LIB.T6G(SCH_1):PAGE104
    48    GND @T6G_MB_LIB.T6G(SCH_1):GND   I174 @T6G_MB_LIB.T6G(SCH_1):PAGE104
    50    GND @T6G_MB_LIB.T6G(SCH_1):GND   I174 @T6G_MB_LIB.T6G(SCH_1):PAGE104
    52    GND @T6G_MB_LIB.T6G(SCH_1):GND   I174 @T6G_MB_LIB.T6G(SCH_1):PAGE104
    54    GND @T6G_MB_LIB.T6G(SCH_1):GND   I174 @T6G_MB_LIB.T6G(SCH_1):PAGE104
    57    GND @T6G_MB_LIB.T6G(SCH_1):GND   I174 @T6G_MB_LIB.T6G(SCH_1):PAGE104
    59    GND @T6G_MB_LIB.T6G(SCH_1):GND   I174 @T6G_MB_LIB.T6G(SCH_1):PAGE104
    61    GND @T6G_MB_LIB.T6G(SCH_1):GND   I174 @T6G_MB_LIB.T6G(SCH_1):PAGE104
    63    GND @T6G_MB_LIB.T6G(SCH_1):GND   I174 @T6G_MB_LIB.T6G(SCH_1):PAGE104
    65    GND @T6G_MB_LIB.T6G(SCH_1):GND   I174 @T6G_MB_LIB.T6G(SCH_1):PAGE104
    67    GND @T6G_MB_LIB.T6G(SCH_1):GND   I174 @T6G_MB_LIB.T6G(SCH_1):PAGE104
    69    GND @T6G_MB_LIB.T6G(SCH_1):GND   I174 @T6G_MB_LIB.T6G(SCH_1):PAGE104
    71    GND @T6G_MB_LIB.T6G(SCH_1):GND   I174 @T6G_MB_LIB.T6G(SCH_1):PAGE104
    73    GND @T6G_MB_LIB.T6G(SCH_1):GND   I174 @T6G_MB_LIB.T6G(SCH_1):PAGE104
    75    GND @T6G_MB_LIB.T6G(SCH_1):GND   I174 @T6G_MB_LIB.T6G(SCH_1):PAGE104
    77    GND @T6G_MB_LIB.T6G(SCH_1):GND   I174 @T6G_MB_LIB.T6G(SCH_1):PAGE104
    79    GND @T6G_MB_LIB.T6G(SCH_1):GND   I174 @T6G_MB_LIB.T6G(SCH_1):PAGE104
    81    GND @T6G_MB_LIB.T6G(SCH_1):GND   I174 @T6G_MB_LIB.T6G(SCH_1):PAGE104
    83    GND @T6G_MB_LIB.T6G(SCH_1):GND   I174 @T6G_MB_LIB.T6G(SCH_1):PAGE104
    85    GND @T6G_MB_LIB.T6G(SCH_1):GND   I174 @T6G_MB_LIB.T6G(SCH_1):PAGE104
    88    GND @T6G_MB_LIB.T6G(SCH_1):GND   I174 @T6G_MB_LIB.T6G(SCH_1):PAGE104
    90    GND @T6G_MB_LIB.T6G(SCH_1):GND   I174 @T6G_MB_LIB.T6G(SCH_1):PAGE104
    92    GND @T6G_MB_LIB.T6G(SCH_1):GND   I174 @T6G_MB_LIB.T6G(SCH_1):PAGE104
    95    GND @T6G_MB_LIB.T6G(SCH_1):GND   I174 @T6G_MB_LIB.T6G(SCH_1):PAGE104
    97    GND @T6G_MB_LIB.T6G(SCH_1):GND   I174 @T6G_MB_LIB.T6G(SCH_1):PAGE104
    99    GND @T6G_MB_LIB.T6G(SCH_1):GND   I174 @T6G_MB_LIB.T6G(SCH_1):PAGE104
   101    GND @T6G_MB_LIB.T6G(SCH_1):GND   I174 @T6G_MB_LIB.T6G(SCH_1):PAGE104
   103    GND @T6G_MB_LIB.T6G(SCH_1):GND   I174 @T6G_MB_LIB.T6G(SCH_1):PAGE104
   106    GND @T6G_MB_LIB.T6G(SCH_1):GND   I174 @T6G_MB_LIB.T6G(SCH_1):PAGE104
   108    GND @T6G_MB_LIB.T6G(SCH_1):GND   I174 @T6G_MB_LIB.T6G(SCH_1):PAGE104
   110    GND @T6G_MB_LIB.T6G(SCH_1):GND   I174 @T6G_MB_LIB.T6G(SCH_1):PAGE104
   112    GND @T6G_MB_LIB.T6G(SCH_1):GND   I174 @T6G_MB_LIB.T6G(SCH_1):PAGE104
   114    GND @T6G_MB_LIB.T6G(SCH_1):GND   I174 @T6G_MB_LIB.T6G(SCH_1):PAGE104
   117    GND @T6G_MB_LIB.T6G(SCH_1):GND   I174 @T6G_MB_LIB.T6G(SCH_1):PAGE104
   119    GND @T6G_MB_LIB.T6G(SCH_1):GND   I174 @T6G_MB_LIB.T6G(SCH_1):PAGE104
   121    GND @T6G_MB_LIB.T6G(SCH_1):GND   I174 @T6G_MB_LIB.T6G(SCH_1):PAGE104
   123    GND @T6G_MB_LIB.T6G(SCH_1):GND   I174 @T6G_MB_LIB.T6G(SCH_1):PAGE104
   125    GND @T6G_MB_LIB.T6G(SCH_1):GND   I174 @T6G_MB_LIB.T6G(SCH_1):PAGE104
   128    GND @T6G_MB_LIB.T6G(SCH_1):GND   I174 @T6G_MB_LIB.T6G(SCH_1):PAGE104
   130    GND @T6G_MB_LIB.T6G(SCH_1):GND   I174 @T6G_MB_LIB.T6G(SCH_1):PAGE104
   134    GND @T6G_MB_LIB.T6G(SCH_1):GND   I174 @T6G_MB_LIB.T6G(SCH_1):PAGE104
   143    GND @T6G_MB_LIB.T6G(SCH_1):GND   I174 @T6G_MB_LIB.T6G(SCH_1):PAGE104
   151    GND @T6G_MB_LIB.T6G(SCH_1):GND   I174 @T6G_MB_LIB.T6G(SCH_1):PAGE104
   153    GND @T6G_MB_LIB.T6G(SCH_1):GND   I174 @T6G_MB_LIB.T6G(SCH_1):PAGE104
   155    GND @T6G_MB_LIB.T6G(SCH_1):GND   I174 @T6G_MB_LIB.T6G(SCH_1):PAGE104
   158    GND @T6G_MB_LIB.T6G(SCH_1):GND   I174 @T6G_MB_LIB.T6G(SCH_1):PAGE104
   160    GND @T6G_MB_LIB.T6G(SCH_1):GND   I174 @T6G_MB_LIB.T6G(SCH_1):PAGE104
   162    GND @T6G_MB_LIB.T6G(SCH_1):GND   I174 @T6G_MB_LIB.T6G(SCH_1):PAGE104
   164    GND @T6G_MB_LIB.T6G(SCH_1):GND   I174 @T6G_MB_LIB.T6G(SCH_1):PAGE104
   166    GND @T6G_MB_LIB.T6G(SCH_1):GND   I174 @T6G_MB_LIB.T6G(SCH_1):PAGE104
   169    GND @T6G_MB_LIB.T6G(SCH_1):GND   I174 @T6G_MB_LIB.T6G(SCH_1):PAGE104
   171    GND @T6G_MB_LIB.T6G(SCH_1):GND   I174 @T6G_MB_LIB.T6G(SCH_1):PAGE104
   173    GND @T6G_MB_LIB.T6G(SCH_1):GND   I174 @T6G_MB_LIB.T6G(SCH_1):PAGE104
   175    GND @T6G_MB_LIB.T6G(SCH_1):GND   I174 @T6G_MB_LIB.T6G(SCH_1):PAGE104
   177    GND @T6G_MB_LIB.T6G(SCH_1):GND   I174 @T6G_MB_LIB.T6G(SCH_1):PAGE104
   180    GND @T6G_MB_LIB.T6G(SCH_1):GND   I174 @T6G_MB_LIB.T6G(SCH_1):PAGE104
   182    GND @T6G_MB_LIB.T6G(SCH_1):GND   I174 @T6G_MB_LIB.T6G(SCH_1):PAGE104
   184    GND @T6G_MB_LIB.T6G(SCH_1):GND   I174 @T6G_MB_LIB.T6G(SCH_1):PAGE104
   186    GND @T6G_MB_LIB.T6G(SCH_1):GND   I174 @T6G_MB_LIB.T6G(SCH_1):PAGE104
   188    GND @T6G_MB_LIB.T6G(SCH_1):GND   I174 @T6G_MB_LIB.T6G(SCH_1):PAGE104
   191    GND @T6G_MB_LIB.T6G(SCH_1):GND   I174 @T6G_MB_LIB.T6G(SCH_1):PAGE104
   193    GND @T6G_MB_LIB.T6G(SCH_1):GND   I174 @T6G_MB_LIB.T6G(SCH_1):PAGE104
   195    GND @T6G_MB_LIB.T6G(SCH_1):GND   I174 @T6G_MB_LIB.T6G(SCH_1):PAGE104
   197    GND @T6G_MB_LIB.T6G(SCH_1):GND   I174 @T6G_MB_LIB.T6G(SCH_1):PAGE104
   199    GND @T6G_MB_LIB.T6G(SCH_1):GND   I174 @T6G_MB_LIB.T6G(SCH_1):PAGE104
   202    GND @T6G_MB_LIB.T6G(SCH_1):GND   I174 @T6G_MB_LIB.T6G(SCH_1):PAGE104
   204    GND @T6G_MB_LIB.T6G(SCH_1):GND   I174 @T6G_MB_LIB.T6G(SCH_1):PAGE104
   206    GND @T6G_MB_LIB.T6G(SCH_1):GND   I174 @T6G_MB_LIB.T6G(SCH_1):PAGE104
   208    GND @T6G_MB_LIB.T6G(SCH_1):GND   I174 @T6G_MB_LIB.T6G(SCH_1):PAGE104
   210    GND @T6G_MB_LIB.T6G(SCH_1):GND   I174 @T6G_MB_LIB.T6G(SCH_1):PAGE104
   212    GND @T6G_MB_LIB.T6G(SCH_1):GND   I174 @T6G_MB_LIB.T6G(SCH_1):PAGE104
   214    GND @T6G_MB_LIB.T6G(SCH_1):GND   I174 @T6G_MB_LIB.T6G(SCH_1):PAGE104
   216    GND @T6G_MB_LIB.T6G(SCH_1):GND   I174 @T6G_MB_LIB.T6G(SCH_1):PAGE104
   219    GND @T6G_MB_LIB.T6G(SCH_1):GND   I174 @T6G_MB_LIB.T6G(SCH_1):PAGE104
   222    GND @T6G_MB_LIB.T6G(SCH_1):GND   I174 @T6G_MB_LIB.T6G(SCH_1):PAGE104
   224    GND @T6G_MB_LIB.T6G(SCH_1):GND   I174 @T6G_MB_LIB.T6G(SCH_1):PAGE104
   226    GND @T6G_MB_LIB.T6G(SCH_1):GND   I174 @T6G_MB_LIB.T6G(SCH_1):PAGE104
   228    GND @T6G_MB_LIB.T6G(SCH_1):GND   I174 @T6G_MB_LIB.T6G(SCH_1):PAGE104
   233    GND @T6G_MB_LIB.T6G(SCH_1):GND   I174 @T6G_MB_LIB.T6G(SCH_1):PAGE104
   237    GND @T6G_MB_LIB.T6G(SCH_1):GND   I174 @T6G_MB_LIB.T6G(SCH_1):PAGE104
   242    GND @T6G_MB_LIB.T6G(SCH_1):GND   I174 @T6G_MB_LIB.T6G(SCH_1):PAGE104
   244    GND @T6G_MB_LIB.T6G(SCH_1):GND   I174 @T6G_MB_LIB.T6G(SCH_1):PAGE104
   246    GND @T6G_MB_LIB.T6G(SCH_1):GND   I174 @T6G_MB_LIB.T6G(SCH_1):PAGE104
   248    GND @T6G_MB_LIB.T6G(SCH_1):GND   I174 @T6G_MB_LIB.T6G(SCH_1):PAGE104
   251    GND @T6G_MB_LIB.T6G(SCH_1):GND   I174 @T6G_MB_LIB.T6G(SCH_1):PAGE104
   253    GND @T6G_MB_LIB.T6G(SCH_1):GND   I174 @T6G_MB_LIB.T6G(SCH_1):PAGE104
   255    GND @T6G_MB_LIB.T6G(SCH_1):GND   I174 @T6G_MB_LIB.T6G(SCH_1):PAGE104
   257    GND @T6G_MB_LIB.T6G(SCH_1):GND   I174 @T6G_MB_LIB.T6G(SCH_1):PAGE104
   259    GND @T6G_MB_LIB.T6G(SCH_1):GND   I174 @T6G_MB_LIB.T6G(SCH_1):PAGE104
   262    GND @T6G_MB_LIB.T6G(SCH_1):GND   I174 @T6G_MB_LIB.T6G(SCH_1):PAGE104
   264    GND @T6G_MB_LIB.T6G(SCH_1):GND   I174 @T6G_MB_LIB.T6G(SCH_1):PAGE104
   266    GND @T6G_MB_LIB.T6G(SCH_1):GND   I174 @T6G_MB_LIB.T6G(SCH_1):PAGE104
   268    GND @T6G_MB_LIB.T6G(SCH_1):GND   I174 @T6G_MB_LIB.T6G(SCH_1):PAGE104
   270    GND @T6G_MB_LIB.T6G(SCH_1):GND   I174 @T6G_MB_LIB.T6G(SCH_1):PAGE104
   273    GND @T6G_MB_LIB.T6G(SCH_1):GND   I174 @T6G_MB_LIB.T6G(SCH_1):PAGE104
   275    GND @T6G_MB_LIB.T6G(SCH_1):GND   I174 @T6G_MB_LIB.T6G(SCH_1):PAGE104
   277    GND @T6G_MB_LIB.T6G(SCH_1):GND   I174 @T6G_MB_LIB.T6G(SCH_1):PAGE104
   279    GND @T6G_MB_LIB.T6G(SCH_1):GND   I174 @T6G_MB_LIB.T6G(SCH_1):PAGE104
   281    GND @T6G_MB_LIB.T6G(SCH_1):GND   I174 @T6G_MB_LIB.T6G(SCH_1):PAGE104
   284    GND @T6G_MB_LIB.T6G(SCH_1):GND   I174 @T6G_MB_LIB.T6G(SCH_1):PAGE104
   286    GND @T6G_MB_LIB.T6G(SCH_1):GND   I174 @T6G_MB_LIB.T6G(SCH_1):PAGE104
   288    GND @T6G_MB_LIB.T6G(SCH_1):GND   I174 @T6G_MB_LIB.T6G(SCH_1):PAGE104
     1 P12V_MEM_CPU1 @T6G_MB_LIB.T6G(SCH_1):P12V_MEM_CPU1   I174 @T6G_MB_LIB.T6G(SCH_1):PAGE104
   145 P12V_MEM_CPU1 @T6G_MB_LIB.T6G(SCH_1):P12V_MEM_CPU1   I174 @T6G_MB_LIB.T6G(SCH_1):PAGE104
   146 P12V_MEM_CPU1 @T6G_MB_LIB.T6G(SCH_1):P12V_MEM_CPU1   I174 @T6G_MB_LIB.T6G(SCH_1):PAGE104
   230    GND @T6G_MB_LIB.T6G(SCH_1):GND   I174 @T6G_MB_LIB.T6G(SCH_1):PAGE104
   235    GND @T6G_MB_LIB.T6G(SCH_1):GND   I174 @T6G_MB_LIB.T6G(SCH_1):PAGE104
   240    GND @T6G_MB_LIB.T6G(SCH_1):GND   I174 @T6G_MB_LIB.T6G(SCH_1):PAGE104
   132    GND @T6G_MB_LIB.T6G(SCH_1):GND   I174 @T6G_MB_LIB.T6G(SCH_1):PAGE104
   136    GND @T6G_MB_LIB.T6G(SCH_1):GND   I174 @T6G_MB_LIB.T6G(SCH_1):PAGE104
   139    GND @T6G_MB_LIB.T6G(SCH_1):GND   I174 @T6G_MB_LIB.T6G(SCH_1):PAGE104
   141    GND @T6G_MB_LIB.T6G(SCH_1):GND   I174 @T6G_MB_LIB.T6G(SCH_1):PAGE104
    G1    GND @T6G_MB_LIB.T6G(SCH_1):GND   I174 @T6G_MB_LIB.T6G(SCH_1):PAGE104
    G2    GND @T6G_MB_LIB.T6G(SCH_1):GND   I174 @T6G_MB_LIB.T6G(SCH_1):PAGE104
    G3    GND @T6G_MB_LIB.T6G(SCH_1):GND   I174 @T6G_MB_LIB.T6G(SCH_1):PAGE104

 J28 SCONN288_DDR506112002KQ-SCONN288_DDR506112002KQ,SMA
     3 P3V3_AUX @T6G_MB_LIB.T6G(SCH_1):P3V3_AUX    I22 @T6G_MB_LIB.T6G(SCH_1):PAGE99
     2     NC     NC    I22 @T6G_MB_LIB.T6G(SCH_1):PAGE99
   144     NC     NC    I22 @T6G_MB_LIB.T6G(SCH_1):PAGE99
   149     NC     NC    I22 @T6G_MB_LIB.T6G(SCH_1):PAGE99
   150     NC     NC    I22 @T6G_MB_LIB.T6G(SCH_1):PAGE99
   220     NC     NC    I22 @T6G_MB_LIB.T6G(SCH_1):PAGE99
   231     NC     NC    I22 @T6G_MB_LIB.T6G(SCH_1):PAGE99
   232     NC     NC    I22 @T6G_MB_LIB.T6G(SCH_1):PAGE99
   207 M_C_CPU1_RESET_N @T6G_MB_LIB.T6G(SCH_1):M_C_CPU1_RESET_N    I22 @T6G_MB_LIB.T6G(SCH_1):PAGE99
   147 PWRGD_CHC_CPU1_DIMM @T6G_MB_LIB.T6G(SCH_1):PWRGD_CHC_CPU1_DIMM    I22 @T6G_MB_LIB.T6G(SCH_1):PAGE99
   227 M_C_CPU1_SB_PAR @T6G_MB_LIB.T6G(SCH_1):M_C_CPU1_SB_PAR    I22 @T6G_MB_LIB.T6G(SCH_1):PAGE99
    74 M_C_CPU1_SA_PAR @T6G_MB_LIB.T6G(SCH_1):M_C_CPU1_SA_PAR    I22 @T6G_MB_LIB.T6G(SCH_1):PAGE99
    87 M_C_CPU1_SB_RSP<0> @T6G_MB_LIB.T6G(SCH_1):M_C_CPU1_SB_RSP(0)    I22 @T6G_MB_LIB.T6G(SCH_1):PAGE99
    86 M_C_CPU1_SA_RSP<0> @T6G_MB_LIB.T6G(SCH_1):M_C_CPU1_SA_RSP(0)    I22 @T6G_MB_LIB.T6G(SCH_1):PAGE99
     5 I3C_SPD_DDRC_CPU1_SDA @T6G_MB_LIB.T6G(SCH_1):I3C_SPD_DDRC_CPU1_SDA    I22 @T6G_MB_LIB.T6G(SCH_1):PAGE99
     4 I3C_SPD_DDRC_CPU1_SCL @T6G_MB_LIB.T6G(SCH_1):I3C_SPD_DDRC_CPU1_SCL    I22 @T6G_MB_LIB.T6G(SCH_1):PAGE99
   148 PD_CHC_CPU1_DIMM_SAA @T6G_MB_LIB.T6G(SCH_1):PD_CHC_CPU1_DIMM_SAA    I22 @T6G_MB_LIB.T6G(SCH_1):PAGE99
   100 M_C_CPU1_SB_DQ<0> @T6G_MB_LIB.T6G(SCH_1):M_C_CPU1_SB_DQ(0)    I22 @T6G_MB_LIB.T6G(SCH_1):PAGE99
   102 M_C_CPU1_SB_DQ<1> @T6G_MB_LIB.T6G(SCH_1):M_C_CPU1_SB_DQ(1)    I22 @T6G_MB_LIB.T6G(SCH_1):PAGE99
   245 M_C_CPU1_SB_DQ<2> @T6G_MB_LIB.T6G(SCH_1):M_C_CPU1_SB_DQ(2)    I22 @T6G_MB_LIB.T6G(SCH_1):PAGE99
   247 M_C_CPU1_SB_DQ<3> @T6G_MB_LIB.T6G(SCH_1):M_C_CPU1_SB_DQ(3)    I22 @T6G_MB_LIB.T6G(SCH_1):PAGE99
   107 M_C_CPU1_SB_DQ<4> @T6G_MB_LIB.T6G(SCH_1):M_C_CPU1_SB_DQ(4)    I22 @T6G_MB_LIB.T6G(SCH_1):PAGE99
   109 M_C_CPU1_SB_DQ<5> @T6G_MB_LIB.T6G(SCH_1):M_C_CPU1_SB_DQ(5)    I22 @T6G_MB_LIB.T6G(SCH_1):PAGE99
   252 M_C_CPU1_SB_DQ<6> @T6G_MB_LIB.T6G(SCH_1):M_C_CPU1_SB_DQ(6)    I22 @T6G_MB_LIB.T6G(SCH_1):PAGE99
   254 M_C_CPU1_SB_DQ<7> @T6G_MB_LIB.T6G(SCH_1):M_C_CPU1_SB_DQ(7)    I22 @T6G_MB_LIB.T6G(SCH_1):PAGE99
   111 M_C_CPU1_SB_DQ<8> @T6G_MB_LIB.T6G(SCH_1):M_C_CPU1_SB_DQ(8)    I22 @T6G_MB_LIB.T6G(SCH_1):PAGE99
   113 M_C_CPU1_SB_DQ<9> @T6G_MB_LIB.T6G(SCH_1):M_C_CPU1_SB_DQ(9)    I22 @T6G_MB_LIB.T6G(SCH_1):PAGE99
   256 M_C_CPU1_SB_DQ<10> @T6G_MB_LIB.T6G(SCH_1):M_C_CPU1_SB_DQ(10)    I22 @T6G_MB_LIB.T6G(SCH_1):PAGE99
   258 M_C_CPU1_SB_DQ<11> @T6G_MB_LIB.T6G(SCH_1):M_C_CPU1_SB_DQ(11)    I22 @T6G_MB_LIB.T6G(SCH_1):PAGE99
   118 M_C_CPU1_SB_DQ<12> @T6G_MB_LIB.T6G(SCH_1):M_C_CPU1_SB_DQ(12)    I22 @T6G_MB_LIB.T6G(SCH_1):PAGE99
   120 M_C_CPU1_SB_DQ<13> @T6G_MB_LIB.T6G(SCH_1):M_C_CPU1_SB_DQ(13)    I22 @T6G_MB_LIB.T6G(SCH_1):PAGE99
   263 M_C_CPU1_SB_DQ<14> @T6G_MB_LIB.T6G(SCH_1):M_C_CPU1_SB_DQ(14)    I22 @T6G_MB_LIB.T6G(SCH_1):PAGE99
   265 M_C_CPU1_SB_DQ<15> @T6G_MB_LIB.T6G(SCH_1):M_C_CPU1_SB_DQ(15)    I22 @T6G_MB_LIB.T6G(SCH_1):PAGE99
   122 M_C_CPU1_SB_DQ<16> @T6G_MB_LIB.T6G(SCH_1):M_C_CPU1_SB_DQ(16)    I22 @T6G_MB_LIB.T6G(SCH_1):PAGE99
   124 M_C_CPU1_SB_DQ<17> @T6G_MB_LIB.T6G(SCH_1):M_C_CPU1_SB_DQ(17)    I22 @T6G_MB_LIB.T6G(SCH_1):PAGE99
   267 M_C_CPU1_SB_DQ<18> @T6G_MB_LIB.T6G(SCH_1):M_C_CPU1_SB_DQ(18)    I22 @T6G_MB_LIB.T6G(SCH_1):PAGE99
   269 M_C_CPU1_SB_DQ<19> @T6G_MB_LIB.T6G(SCH_1):M_C_CPU1_SB_DQ(19)    I22 @T6G_MB_LIB.T6G(SCH_1):PAGE99
   129 M_C_CPU1_SB_DQ<20> @T6G_MB_LIB.T6G(SCH_1):M_C_CPU1_SB_DQ(20)    I22 @T6G_MB_LIB.T6G(SCH_1):PAGE99
   131 M_C_CPU1_SB_DQ<21> @T6G_MB_LIB.T6G(SCH_1):M_C_CPU1_SB_DQ(21)    I22 @T6G_MB_LIB.T6G(SCH_1):PAGE99
   274 M_C_CPU1_SB_DQ<22> @T6G_MB_LIB.T6G(SCH_1):M_C_CPU1_SB_DQ(22)    I22 @T6G_MB_LIB.T6G(SCH_1):PAGE99
   276 M_C_CPU1_SB_DQ<23> @T6G_MB_LIB.T6G(SCH_1):M_C_CPU1_SB_DQ(23)    I22 @T6G_MB_LIB.T6G(SCH_1):PAGE99
   133 M_C_CPU1_SB_DQ<24> @T6G_MB_LIB.T6G(SCH_1):M_C_CPU1_SB_DQ(24)    I22 @T6G_MB_LIB.T6G(SCH_1):PAGE99
   135 M_C_CPU1_SB_DQ<25> @T6G_MB_LIB.T6G(SCH_1):M_C_CPU1_SB_DQ(25)    I22 @T6G_MB_LIB.T6G(SCH_1):PAGE99
   278 M_C_CPU1_SB_DQ<26> @T6G_MB_LIB.T6G(SCH_1):M_C_CPU1_SB_DQ(26)    I22 @T6G_MB_LIB.T6G(SCH_1):PAGE99
   280 M_C_CPU1_SB_DQ<27> @T6G_MB_LIB.T6G(SCH_1):M_C_CPU1_SB_DQ(27)    I22 @T6G_MB_LIB.T6G(SCH_1):PAGE99
   140 M_C_CPU1_SB_DQ<28> @T6G_MB_LIB.T6G(SCH_1):M_C_CPU1_SB_DQ(28)    I22 @T6G_MB_LIB.T6G(SCH_1):PAGE99
   142 M_C_CPU1_SB_DQ<29> @T6G_MB_LIB.T6G(SCH_1):M_C_CPU1_SB_DQ(29)    I22 @T6G_MB_LIB.T6G(SCH_1):PAGE99
   285 M_C_CPU1_SB_DQ<30> @T6G_MB_LIB.T6G(SCH_1):M_C_CPU1_SB_DQ(30)    I22 @T6G_MB_LIB.T6G(SCH_1):PAGE99
   287 M_C_CPU1_SB_DQ<31> @T6G_MB_LIB.T6G(SCH_1):M_C_CPU1_SB_DQ(31)    I22 @T6G_MB_LIB.T6G(SCH_1):PAGE99
     7 M_C_CPU1_SA_DQ<0> @T6G_MB_LIB.T6G(SCH_1):M_C_CPU1_SA_DQ(0)    I22 @T6G_MB_LIB.T6G(SCH_1):PAGE99
     9 M_C_CPU1_SA_DQ<1> @T6G_MB_LIB.T6G(SCH_1):M_C_CPU1_SA_DQ(1)    I22 @T6G_MB_LIB.T6G(SCH_1):PAGE99
   152 M_C_CPU1_SA_DQ<2> @T6G_MB_LIB.T6G(SCH_1):M_C_CPU1_SA_DQ(2)    I22 @T6G_MB_LIB.T6G(SCH_1):PAGE99
   154 M_C_CPU1_SA_DQ<3> @T6G_MB_LIB.T6G(SCH_1):M_C_CPU1_SA_DQ(3)    I22 @T6G_MB_LIB.T6G(SCH_1):PAGE99
    14 M_C_CPU1_SA_DQ<4> @T6G_MB_LIB.T6G(SCH_1):M_C_CPU1_SA_DQ(4)    I22 @T6G_MB_LIB.T6G(SCH_1):PAGE99
    16 M_C_CPU1_SA_DQ<5> @T6G_MB_LIB.T6G(SCH_1):M_C_CPU1_SA_DQ(5)    I22 @T6G_MB_LIB.T6G(SCH_1):PAGE99
   159 M_C_CPU1_SA_DQ<6> @T6G_MB_LIB.T6G(SCH_1):M_C_CPU1_SA_DQ(6)    I22 @T6G_MB_LIB.T6G(SCH_1):PAGE99
   161 M_C_CPU1_SA_DQ<7> @T6G_MB_LIB.T6G(SCH_1):M_C_CPU1_SA_DQ(7)    I22 @T6G_MB_LIB.T6G(SCH_1):PAGE99
    18 M_C_CPU1_SA_DQ<8> @T6G_MB_LIB.T6G(SCH_1):M_C_CPU1_SA_DQ(8)    I22 @T6G_MB_LIB.T6G(SCH_1):PAGE99
    20 M_C_CPU1_SA_DQ<9> @T6G_MB_LIB.T6G(SCH_1):M_C_CPU1_SA_DQ(9)    I22 @T6G_MB_LIB.T6G(SCH_1):PAGE99
   163 M_C_CPU1_SA_DQ<10> @T6G_MB_LIB.T6G(SCH_1):M_C_CPU1_SA_DQ(10)    I22 @T6G_MB_LIB.T6G(SCH_1):PAGE99
   165 M_C_CPU1_SA_DQ<11> @T6G_MB_LIB.T6G(SCH_1):M_C_CPU1_SA_DQ(11)    I22 @T6G_MB_LIB.T6G(SCH_1):PAGE99
    25 M_C_CPU1_SA_DQ<12> @T6G_MB_LIB.T6G(SCH_1):M_C_CPU1_SA_DQ(12)    I22 @T6G_MB_LIB.T6G(SCH_1):PAGE99
    27 M_C_CPU1_SA_DQ<13> @T6G_MB_LIB.T6G(SCH_1):M_C_CPU1_SA_DQ(13)    I22 @T6G_MB_LIB.T6G(SCH_1):PAGE99
   170 M_C_CPU1_SA_DQ<14> @T6G_MB_LIB.T6G(SCH_1):M_C_CPU1_SA_DQ(14)    I22 @T6G_MB_LIB.T6G(SCH_1):PAGE99
   172 M_C_CPU1_SA_DQ<15> @T6G_MB_LIB.T6G(SCH_1):M_C_CPU1_SA_DQ(15)    I22 @T6G_MB_LIB.T6G(SCH_1):PAGE99
    29 M_C_CPU1_SA_DQ<16> @T6G_MB_LIB.T6G(SCH_1):M_C_CPU1_SA_DQ(16)    I22 @T6G_MB_LIB.T6G(SCH_1):PAGE99
    31 M_C_CPU1_SA_DQ<17> @T6G_MB_LIB.T6G(SCH_1):M_C_CPU1_SA_DQ(17)    I22 @T6G_MB_LIB.T6G(SCH_1):PAGE99
   174 M_C_CPU1_SA_DQ<18> @T6G_MB_LIB.T6G(SCH_1):M_C_CPU1_SA_DQ(18)    I22 @T6G_MB_LIB.T6G(SCH_1):PAGE99
   176 M_C_CPU1_SA_DQ<19> @T6G_MB_LIB.T6G(SCH_1):M_C_CPU1_SA_DQ(19)    I22 @T6G_MB_LIB.T6G(SCH_1):PAGE99
    36 M_C_CPU1_SA_DQ<20> @T6G_MB_LIB.T6G(SCH_1):M_C_CPU1_SA_DQ(20)    I22 @T6G_MB_LIB.T6G(SCH_1):PAGE99
    38 M_C_CPU1_SA_DQ<21> @T6G_MB_LIB.T6G(SCH_1):M_C_CPU1_SA_DQ(21)    I22 @T6G_MB_LIB.T6G(SCH_1):PAGE99
   181 M_C_CPU1_SA_DQ<22> @T6G_MB_LIB.T6G(SCH_1):M_C_CPU1_SA_DQ(22)    I22 @T6G_MB_LIB.T6G(SCH_1):PAGE99
   183 M_C_CPU1_SA_DQ<23> @T6G_MB_LIB.T6G(SCH_1):M_C_CPU1_SA_DQ(23)    I22 @T6G_MB_LIB.T6G(SCH_1):PAGE99
    40 M_C_CPU1_SA_DQ<24> @T6G_MB_LIB.T6G(SCH_1):M_C_CPU1_SA_DQ(24)    I22 @T6G_MB_LIB.T6G(SCH_1):PAGE99
    42 M_C_CPU1_SA_DQ<25> @T6G_MB_LIB.T6G(SCH_1):M_C_CPU1_SA_DQ(25)    I22 @T6G_MB_LIB.T6G(SCH_1):PAGE99
   185 M_C_CPU1_SA_DQ<26> @T6G_MB_LIB.T6G(SCH_1):M_C_CPU1_SA_DQ(26)    I22 @T6G_MB_LIB.T6G(SCH_1):PAGE99
   187 M_C_CPU1_SA_DQ<27> @T6G_MB_LIB.T6G(SCH_1):M_C_CPU1_SA_DQ(27)    I22 @T6G_MB_LIB.T6G(SCH_1):PAGE99
    47 M_C_CPU1_SA_DQ<28> @T6G_MB_LIB.T6G(SCH_1):M_C_CPU1_SA_DQ(28)    I22 @T6G_MB_LIB.T6G(SCH_1):PAGE99
    49 M_C_CPU1_SA_DQ<29> @T6G_MB_LIB.T6G(SCH_1):M_C_CPU1_SA_DQ(29)    I22 @T6G_MB_LIB.T6G(SCH_1):PAGE99
   192 M_C_CPU1_SA_DQ<30> @T6G_MB_LIB.T6G(SCH_1):M_C_CPU1_SA_DQ(30)    I22 @T6G_MB_LIB.T6G(SCH_1):PAGE99
   229 M_C_CPU1_SB_CS_N<1> @T6G_MB_LIB.T6G(SCH_1):M_C_CPU1_SB_CS_N(1)    I22 @T6G_MB_LIB.T6G(SCH_1):PAGE99
   209 M_C_CPU1_SA_CS_N<1> @T6G_MB_LIB.T6G(SCH_1):M_C_CPU1_SA_CS_N(1)    I22 @T6G_MB_LIB.T6G(SCH_1):PAGE99
    84 M_C_CPU1_SB_CS_N<0> @T6G_MB_LIB.T6G(SCH_1):M_C_CPU1_SB_CS_N(0)    I22 @T6G_MB_LIB.T6G(SCH_1):PAGE99
    64 M_C_CPU1_SA_CS_N<0> @T6G_MB_LIB.T6G(SCH_1):M_C_CPU1_SA_CS_N(0)    I22 @T6G_MB_LIB.T6G(SCH_1):PAGE99
   217 M_C_CPU1_CLK_DP<0> @T6G_MB_LIB.T6G(SCH_1):M_C_CPU1_CLK_DP(0)    I22 @T6G_MB_LIB.T6G(SCH_1):PAGE99
   218 M_C_CPU1_CLK_DN<0> @T6G_MB_LIB.T6G(SCH_1):M_C_CPU1_CLK_DN(0)    I22 @T6G_MB_LIB.T6G(SCH_1):PAGE99
    96 M_C_CPU1_SB_CB<0> @T6G_MB_LIB.T6G(SCH_1):M_C_CPU1_SB_CB(0)    I22 @T6G_MB_LIB.T6G(SCH_1):PAGE99
    98 M_C_CPU1_SB_CB<1> @T6G_MB_LIB.T6G(SCH_1):M_C_CPU1_SB_CB(1)    I22 @T6G_MB_LIB.T6G(SCH_1):PAGE99
   241 M_C_CPU1_SB_CB<2> @T6G_MB_LIB.T6G(SCH_1):M_C_CPU1_SB_CB(2)    I22 @T6G_MB_LIB.T6G(SCH_1):PAGE99
   243 M_C_CPU1_SB_CB<3> @T6G_MB_LIB.T6G(SCH_1):M_C_CPU1_SB_CB(3)    I22 @T6G_MB_LIB.T6G(SCH_1):PAGE99
    89 M_C_CPU1_SB_CB<4> @T6G_MB_LIB.T6G(SCH_1):M_C_CPU1_SB_CB(4)    I22 @T6G_MB_LIB.T6G(SCH_1):PAGE99
    91 M_C_CPU1_SB_CB<5> @T6G_MB_LIB.T6G(SCH_1):M_C_CPU1_SB_CB(5)    I22 @T6G_MB_LIB.T6G(SCH_1):PAGE99
   234 M_C_CPU1_SB_CB<6> @T6G_MB_LIB.T6G(SCH_1):M_C_CPU1_SB_CB(6)    I22 @T6G_MB_LIB.T6G(SCH_1):PAGE99
    51 M_C_CPU1_SA_CB<0> @T6G_MB_LIB.T6G(SCH_1):M_C_CPU1_SA_CB(0)    I22 @T6G_MB_LIB.T6G(SCH_1):PAGE99
   196 M_C_CPU1_SA_CB<2> @T6G_MB_LIB.T6G(SCH_1):M_C_CPU1_SA_CB(2)    I22 @T6G_MB_LIB.T6G(SCH_1):PAGE99
   198 M_C_CPU1_SA_CB<3> @T6G_MB_LIB.T6G(SCH_1):M_C_CPU1_SA_CB(3)    I22 @T6G_MB_LIB.T6G(SCH_1):PAGE99
    60 M_C_CPU1_SA_CB<5> @T6G_MB_LIB.T6G(SCH_1):M_C_CPU1_SA_CB(5)    I22 @T6G_MB_LIB.T6G(SCH_1):PAGE99
   203 M_C_CPU1_SA_CB<6> @T6G_MB_LIB.T6G(SCH_1):M_C_CPU1_SA_CB(6)    I22 @T6G_MB_LIB.T6G(SCH_1):PAGE99
    82 M_C_CPU1_SB_CA<6> @T6G_MB_LIB.T6G(SCH_1):M_C_CPU1_SB_CA(6)    I22 @T6G_MB_LIB.T6G(SCH_1):PAGE99
    72 M_C_CPU1_SA_CA<6> @T6G_MB_LIB.T6G(SCH_1):M_C_CPU1_SA_CA(6)    I22 @T6G_MB_LIB.T6G(SCH_1):PAGE99
   225 M_C_CPU1_SB_CA<5> @T6G_MB_LIB.T6G(SCH_1):M_C_CPU1_SB_CA(5)    I22 @T6G_MB_LIB.T6G(SCH_1):PAGE99
   215 M_C_CPU1_SA_CA<5> @T6G_MB_LIB.T6G(SCH_1):M_C_CPU1_SA_CA(5)    I22 @T6G_MB_LIB.T6G(SCH_1):PAGE99
    80 M_C_CPU1_SB_CA<4> @T6G_MB_LIB.T6G(SCH_1):M_C_CPU1_SB_CA(4)    I22 @T6G_MB_LIB.T6G(SCH_1):PAGE99
    70 M_C_CPU1_SA_CA<4> @T6G_MB_LIB.T6G(SCH_1):M_C_CPU1_SA_CA(4)    I22 @T6G_MB_LIB.T6G(SCH_1):PAGE99
   223 M_C_CPU1_SB_CA<3> @T6G_MB_LIB.T6G(SCH_1):M_C_CPU1_SB_CA(3)    I22 @T6G_MB_LIB.T6G(SCH_1):PAGE99
   213 M_C_CPU1_SA_CA<3> @T6G_MB_LIB.T6G(SCH_1):M_C_CPU1_SA_CA(3)    I22 @T6G_MB_LIB.T6G(SCH_1):PAGE99
    78 M_C_CPU1_SB_CA<2> @T6G_MB_LIB.T6G(SCH_1):M_C_CPU1_SB_CA(2)    I22 @T6G_MB_LIB.T6G(SCH_1):PAGE99
    68 M_C_CPU1_SA_CA<2> @T6G_MB_LIB.T6G(SCH_1):M_C_CPU1_SA_CA(2)    I22 @T6G_MB_LIB.T6G(SCH_1):PAGE99
   221 M_C_CPU1_SB_CA<1> @T6G_MB_LIB.T6G(SCH_1):M_C_CPU1_SB_CA(1)    I22 @T6G_MB_LIB.T6G(SCH_1):PAGE99
   211 M_C_CPU1_SA_CA<1> @T6G_MB_LIB.T6G(SCH_1):M_C_CPU1_SA_CA(1)    I22 @T6G_MB_LIB.T6G(SCH_1):PAGE99
    76 M_C_CPU1_SB_CA<0> @T6G_MB_LIB.T6G(SCH_1):M_C_CPU1_SB_CA(0)    I22 @T6G_MB_LIB.T6G(SCH_1):PAGE99
    66 M_C_CPU1_SA_CA<0> @T6G_MB_LIB.T6G(SCH_1):M_C_CPU1_SA_CA(0)    I22 @T6G_MB_LIB.T6G(SCH_1):PAGE99
    62 M_C_CPU1_ALERT_N @T6G_MB_LIB.T6G(SCH_1):M_C_CPU1_ALERT_N    I22 @T6G_MB_LIB.T6G(SCH_1):PAGE99
   236 M_C_CPU1_SB_CB<7> @T6G_MB_LIB.T6G(SCH_1):M_C_CPU1_SB_CB(7)    I22 @T6G_MB_LIB.T6G(SCH_1):PAGE99
    53 M_C_CPU1_SA_CB<1> @T6G_MB_LIB.T6G(SCH_1):M_C_CPU1_SA_CB(1)    I22 @T6G_MB_LIB.T6G(SCH_1):PAGE99
    58 M_C_CPU1_SA_CB<4> @T6G_MB_LIB.T6G(SCH_1):M_C_CPU1_SA_CB(4)    I22 @T6G_MB_LIB.T6G(SCH_1):PAGE99
   205 M_C_CPU1_SA_CB<7> @T6G_MB_LIB.T6G(SCH_1):M_C_CPU1_SA_CB(7)    I22 @T6G_MB_LIB.T6G(SCH_1):PAGE99
   194 M_C_CPU1_SA_DQ<31> @T6G_MB_LIB.T6G(SCH_1):M_C_CPU1_SA_DQ(31)    I22 @T6G_MB_LIB.T6G(SCH_1):PAGE99
    93 M_C_CPU1_SB_DQS_DP<9> @T6G_MB_LIB.T6G(SCH_1):M_C_CPU1_SB_DQS_DP(9)   I236 @T6G_MB_LIB.T6G(SCH_1):PAGE99
    94 M_C_CPU1_SB_DQS_DN<9> @T6G_MB_LIB.T6G(SCH_1):M_C_CPU1_SB_DQS_DN(9)   I236 @T6G_MB_LIB.T6G(SCH_1):PAGE99
   201 M_C_CPU1_SA_DQS_DP<9> @T6G_MB_LIB.T6G(SCH_1):M_C_CPU1_SA_DQS_DP(9)   I236 @T6G_MB_LIB.T6G(SCH_1):PAGE99
   200 M_C_CPU1_SA_DQS_DN<9> @T6G_MB_LIB.T6G(SCH_1):M_C_CPU1_SA_DQS_DN(9)   I236 @T6G_MB_LIB.T6G(SCH_1):PAGE99
   190 M_C_CPU1_SA_DQS_DP<8> @T6G_MB_LIB.T6G(SCH_1):M_C_CPU1_SA_DQS_DP(8)   I236 @T6G_MB_LIB.T6G(SCH_1):PAGE99
   189 M_C_CPU1_SA_DQS_DN<8> @T6G_MB_LIB.T6G(SCH_1):M_C_CPU1_SA_DQS_DN(8)   I236 @T6G_MB_LIB.T6G(SCH_1):PAGE99
   271 M_C_CPU1_SB_DQS_DN<7> @T6G_MB_LIB.T6G(SCH_1):M_C_CPU1_SB_DQS_DN(7)   I236 @T6G_MB_LIB.T6G(SCH_1):PAGE99
   179 M_C_CPU1_SA_DQS_DP<7> @T6G_MB_LIB.T6G(SCH_1):M_C_CPU1_SA_DQS_DP(7)   I236 @T6G_MB_LIB.T6G(SCH_1):PAGE99
   261 M_C_CPU1_SB_DQS_DP<6> @T6G_MB_LIB.T6G(SCH_1):M_C_CPU1_SB_DQS_DP(6)   I236 @T6G_MB_LIB.T6G(SCH_1):PAGE99
   260 M_C_CPU1_SB_DQS_DN<6> @T6G_MB_LIB.T6G(SCH_1):M_C_CPU1_SB_DQS_DN(6)   I236 @T6G_MB_LIB.T6G(SCH_1):PAGE99
   167 M_C_CPU1_SA_DQS_DN<6> @T6G_MB_LIB.T6G(SCH_1):M_C_CPU1_SA_DQS_DN(6)   I236 @T6G_MB_LIB.T6G(SCH_1):PAGE99
   250 M_C_CPU1_SB_DQS_DP<5> @T6G_MB_LIB.T6G(SCH_1):M_C_CPU1_SB_DQS_DP(5)   I236 @T6G_MB_LIB.T6G(SCH_1):PAGE99
   249 M_C_CPU1_SB_DQS_DN<5> @T6G_MB_LIB.T6G(SCH_1):M_C_CPU1_SB_DQS_DN(5)   I236 @T6G_MB_LIB.T6G(SCH_1):PAGE99
   157 M_C_CPU1_SA_DQS_DP<5> @T6G_MB_LIB.T6G(SCH_1):M_C_CPU1_SA_DQS_DP(5)   I236 @T6G_MB_LIB.T6G(SCH_1):PAGE99
   156 M_C_CPU1_SA_DQS_DN<5> @T6G_MB_LIB.T6G(SCH_1):M_C_CPU1_SA_DQS_DN(5)   I236 @T6G_MB_LIB.T6G(SCH_1):PAGE99
   239 M_C_CPU1_SB_DQS_DP<4> @T6G_MB_LIB.T6G(SCH_1):M_C_CPU1_SB_DQS_DP(4)   I236 @T6G_MB_LIB.T6G(SCH_1):PAGE99
   238 M_C_CPU1_SB_DQS_DN<4> @T6G_MB_LIB.T6G(SCH_1):M_C_CPU1_SB_DQS_DN(4)   I236 @T6G_MB_LIB.T6G(SCH_1):PAGE99
    55 M_C_CPU1_SA_DQS_DP<4> @T6G_MB_LIB.T6G(SCH_1):M_C_CPU1_SA_DQS_DP(4)   I236 @T6G_MB_LIB.T6G(SCH_1):PAGE99
    56 M_C_CPU1_SA_DQS_DN<4> @T6G_MB_LIB.T6G(SCH_1):M_C_CPU1_SA_DQS_DN(4)   I236 @T6G_MB_LIB.T6G(SCH_1):PAGE99
   137 M_C_CPU1_SB_DQS_DP<3> @T6G_MB_LIB.T6G(SCH_1):M_C_CPU1_SB_DQS_DP(3)   I236 @T6G_MB_LIB.T6G(SCH_1):PAGE99
   138 M_C_CPU1_SB_DQS_DN<3> @T6G_MB_LIB.T6G(SCH_1):M_C_CPU1_SB_DQS_DN(3)   I236 @T6G_MB_LIB.T6G(SCH_1):PAGE99
    44 M_C_CPU1_SA_DQS_DP<3> @T6G_MB_LIB.T6G(SCH_1):M_C_CPU1_SA_DQS_DP(3)   I236 @T6G_MB_LIB.T6G(SCH_1):PAGE99
    45 M_C_CPU1_SA_DQS_DN<3> @T6G_MB_LIB.T6G(SCH_1):M_C_CPU1_SA_DQS_DN(3)   I236 @T6G_MB_LIB.T6G(SCH_1):PAGE99
   126 M_C_CPU1_SB_DQS_DP<2> @T6G_MB_LIB.T6G(SCH_1):M_C_CPU1_SB_DQS_DP(2)   I236 @T6G_MB_LIB.T6G(SCH_1):PAGE99
   127 M_C_CPU1_SB_DQS_DN<2> @T6G_MB_LIB.T6G(SCH_1):M_C_CPU1_SB_DQS_DN(2)   I236 @T6G_MB_LIB.T6G(SCH_1):PAGE99
    33 M_C_CPU1_SA_DQS_DP<2> @T6G_MB_LIB.T6G(SCH_1):M_C_CPU1_SA_DQS_DP(2)   I236 @T6G_MB_LIB.T6G(SCH_1):PAGE99
    34 M_C_CPU1_SA_DQS_DN<2> @T6G_MB_LIB.T6G(SCH_1):M_C_CPU1_SA_DQS_DN(2)   I236 @T6G_MB_LIB.T6G(SCH_1):PAGE99
   115 M_C_CPU1_SB_DQS_DP<1> @T6G_MB_LIB.T6G(SCH_1):M_C_CPU1_SB_DQS_DP(1)   I236 @T6G_MB_LIB.T6G(SCH_1):PAGE99
   116 M_C_CPU1_SB_DQS_DN<1> @T6G_MB_LIB.T6G(SCH_1):M_C_CPU1_SB_DQS_DN(1)   I236 @T6G_MB_LIB.T6G(SCH_1):PAGE99
    22 M_C_CPU1_SA_DQS_DP<1> @T6G_MB_LIB.T6G(SCH_1):M_C_CPU1_SA_DQS_DP(1)   I236 @T6G_MB_LIB.T6G(SCH_1):PAGE99
    23 M_C_CPU1_SA_DQS_DN<1> @T6G_MB_LIB.T6G(SCH_1):M_C_CPU1_SA_DQS_DN(1)   I236 @T6G_MB_LIB.T6G(SCH_1):PAGE99
   104 M_C_CPU1_SB_DQS_DP<0> @T6G_MB_LIB.T6G(SCH_1):M_C_CPU1_SB_DQS_DP(0)   I236 @T6G_MB_LIB.T6G(SCH_1):PAGE99
   105 M_C_CPU1_SB_DQS_DN<0> @T6G_MB_LIB.T6G(SCH_1):M_C_CPU1_SB_DQS_DN(0)   I236 @T6G_MB_LIB.T6G(SCH_1):PAGE99
    11 M_C_CPU1_SA_DQS_DP<0> @T6G_MB_LIB.T6G(SCH_1):M_C_CPU1_SA_DQS_DP(0)   I236 @T6G_MB_LIB.T6G(SCH_1):PAGE99
    12 M_C_CPU1_SA_DQS_DN<0> @T6G_MB_LIB.T6G(SCH_1):M_C_CPU1_SA_DQS_DN(0)   I236 @T6G_MB_LIB.T6G(SCH_1):PAGE99
   272 M_C_CPU1_SB_DQS_DP<7> @T6G_MB_LIB.T6G(SCH_1):M_C_CPU1_SB_DQS_DP(7)   I236 @T6G_MB_LIB.T6G(SCH_1):PAGE99
   282 M_C_CPU1_SB_DQS_DN<8> @T6G_MB_LIB.T6G(SCH_1):M_C_CPU1_SB_DQS_DN(8)   I236 @T6G_MB_LIB.T6G(SCH_1):PAGE99
   283 M_C_CPU1_SB_DQS_DP<8> @T6G_MB_LIB.T6G(SCH_1):M_C_CPU1_SB_DQS_DP(8)   I236 @T6G_MB_LIB.T6G(SCH_1):PAGE99
   168 M_C_CPU1_SA_DQS_DP<6> @T6G_MB_LIB.T6G(SCH_1):M_C_CPU1_SA_DQS_DP(6)   I236 @T6G_MB_LIB.T6G(SCH_1):PAGE99
   178 M_C_CPU1_SA_DQS_DN<7> @T6G_MB_LIB.T6G(SCH_1):M_C_CPU1_SA_DQS_DN(7)   I236 @T6G_MB_LIB.T6G(SCH_1):PAGE99
     6    GND @T6G_MB_LIB.T6G(SCH_1):GND   I155 @T6G_MB_LIB.T6G(SCH_1):PAGE99
     8    GND @T6G_MB_LIB.T6G(SCH_1):GND   I155 @T6G_MB_LIB.T6G(SCH_1):PAGE99
    10    GND @T6G_MB_LIB.T6G(SCH_1):GND   I155 @T6G_MB_LIB.T6G(SCH_1):PAGE99
    13    GND @T6G_MB_LIB.T6G(SCH_1):GND   I155 @T6G_MB_LIB.T6G(SCH_1):PAGE99
    15    GND @T6G_MB_LIB.T6G(SCH_1):GND   I155 @T6G_MB_LIB.T6G(SCH_1):PAGE99
    17    GND @T6G_MB_LIB.T6G(SCH_1):GND   I155 @T6G_MB_LIB.T6G(SCH_1):PAGE99
    19    GND @T6G_MB_LIB.T6G(SCH_1):GND   I155 @T6G_MB_LIB.T6G(SCH_1):PAGE99
    21    GND @T6G_MB_LIB.T6G(SCH_1):GND   I155 @T6G_MB_LIB.T6G(SCH_1):PAGE99
    24    GND @T6G_MB_LIB.T6G(SCH_1):GND   I155 @T6G_MB_LIB.T6G(SCH_1):PAGE99
    26    GND @T6G_MB_LIB.T6G(SCH_1):GND   I155 @T6G_MB_LIB.T6G(SCH_1):PAGE99
    28    GND @T6G_MB_LIB.T6G(SCH_1):GND   I155 @T6G_MB_LIB.T6G(SCH_1):PAGE99
    30    GND @T6G_MB_LIB.T6G(SCH_1):GND   I155 @T6G_MB_LIB.T6G(SCH_1):PAGE99
    32    GND @T6G_MB_LIB.T6G(SCH_1):GND   I155 @T6G_MB_LIB.T6G(SCH_1):PAGE99
    35    GND @T6G_MB_LIB.T6G(SCH_1):GND   I155 @T6G_MB_LIB.T6G(SCH_1):PAGE99
    37    GND @T6G_MB_LIB.T6G(SCH_1):GND   I155 @T6G_MB_LIB.T6G(SCH_1):PAGE99
    39    GND @T6G_MB_LIB.T6G(SCH_1):GND   I155 @T6G_MB_LIB.T6G(SCH_1):PAGE99
    41    GND @T6G_MB_LIB.T6G(SCH_1):GND   I155 @T6G_MB_LIB.T6G(SCH_1):PAGE99
    43    GND @T6G_MB_LIB.T6G(SCH_1):GND   I155 @T6G_MB_LIB.T6G(SCH_1):PAGE99
    46    GND @T6G_MB_LIB.T6G(SCH_1):GND   I155 @T6G_MB_LIB.T6G(SCH_1):PAGE99
    48    GND @T6G_MB_LIB.T6G(SCH_1):GND   I155 @T6G_MB_LIB.T6G(SCH_1):PAGE99
    50    GND @T6G_MB_LIB.T6G(SCH_1):GND   I155 @T6G_MB_LIB.T6G(SCH_1):PAGE99
    52    GND @T6G_MB_LIB.T6G(SCH_1):GND   I155 @T6G_MB_LIB.T6G(SCH_1):PAGE99
    54    GND @T6G_MB_LIB.T6G(SCH_1):GND   I155 @T6G_MB_LIB.T6G(SCH_1):PAGE99
    57    GND @T6G_MB_LIB.T6G(SCH_1):GND   I155 @T6G_MB_LIB.T6G(SCH_1):PAGE99
    59    GND @T6G_MB_LIB.T6G(SCH_1):GND   I155 @T6G_MB_LIB.T6G(SCH_1):PAGE99
    61    GND @T6G_MB_LIB.T6G(SCH_1):GND   I155 @T6G_MB_LIB.T6G(SCH_1):PAGE99
    63    GND @T6G_MB_LIB.T6G(SCH_1):GND   I155 @T6G_MB_LIB.T6G(SCH_1):PAGE99
    65    GND @T6G_MB_LIB.T6G(SCH_1):GND   I155 @T6G_MB_LIB.T6G(SCH_1):PAGE99
    67    GND @T6G_MB_LIB.T6G(SCH_1):GND   I155 @T6G_MB_LIB.T6G(SCH_1):PAGE99
    69    GND @T6G_MB_LIB.T6G(SCH_1):GND   I155 @T6G_MB_LIB.T6G(SCH_1):PAGE99
    71    GND @T6G_MB_LIB.T6G(SCH_1):GND   I155 @T6G_MB_LIB.T6G(SCH_1):PAGE99
    73    GND @T6G_MB_LIB.T6G(SCH_1):GND   I155 @T6G_MB_LIB.T6G(SCH_1):PAGE99
    75    GND @T6G_MB_LIB.T6G(SCH_1):GND   I155 @T6G_MB_LIB.T6G(SCH_1):PAGE99
    77    GND @T6G_MB_LIB.T6G(SCH_1):GND   I155 @T6G_MB_LIB.T6G(SCH_1):PAGE99
    79    GND @T6G_MB_LIB.T6G(SCH_1):GND   I155 @T6G_MB_LIB.T6G(SCH_1):PAGE99
    81    GND @T6G_MB_LIB.T6G(SCH_1):GND   I155 @T6G_MB_LIB.T6G(SCH_1):PAGE99
    83    GND @T6G_MB_LIB.T6G(SCH_1):GND   I155 @T6G_MB_LIB.T6G(SCH_1):PAGE99
    85    GND @T6G_MB_LIB.T6G(SCH_1):GND   I155 @T6G_MB_LIB.T6G(SCH_1):PAGE99
    88    GND @T6G_MB_LIB.T6G(SCH_1):GND   I155 @T6G_MB_LIB.T6G(SCH_1):PAGE99
    90    GND @T6G_MB_LIB.T6G(SCH_1):GND   I155 @T6G_MB_LIB.T6G(SCH_1):PAGE99
    92    GND @T6G_MB_LIB.T6G(SCH_1):GND   I155 @T6G_MB_LIB.T6G(SCH_1):PAGE99
    95    GND @T6G_MB_LIB.T6G(SCH_1):GND   I155 @T6G_MB_LIB.T6G(SCH_1):PAGE99
    97    GND @T6G_MB_LIB.T6G(SCH_1):GND   I155 @T6G_MB_LIB.T6G(SCH_1):PAGE99
    99    GND @T6G_MB_LIB.T6G(SCH_1):GND   I155 @T6G_MB_LIB.T6G(SCH_1):PAGE99
   101    GND @T6G_MB_LIB.T6G(SCH_1):GND   I155 @T6G_MB_LIB.T6G(SCH_1):PAGE99
   103    GND @T6G_MB_LIB.T6G(SCH_1):GND   I155 @T6G_MB_LIB.T6G(SCH_1):PAGE99
   106    GND @T6G_MB_LIB.T6G(SCH_1):GND   I155 @T6G_MB_LIB.T6G(SCH_1):PAGE99
   108    GND @T6G_MB_LIB.T6G(SCH_1):GND   I155 @T6G_MB_LIB.T6G(SCH_1):PAGE99
   110    GND @T6G_MB_LIB.T6G(SCH_1):GND   I155 @T6G_MB_LIB.T6G(SCH_1):PAGE99
   112    GND @T6G_MB_LIB.T6G(SCH_1):GND   I155 @T6G_MB_LIB.T6G(SCH_1):PAGE99
   114    GND @T6G_MB_LIB.T6G(SCH_1):GND   I155 @T6G_MB_LIB.T6G(SCH_1):PAGE99
   117    GND @T6G_MB_LIB.T6G(SCH_1):GND   I155 @T6G_MB_LIB.T6G(SCH_1):PAGE99
   119    GND @T6G_MB_LIB.T6G(SCH_1):GND   I155 @T6G_MB_LIB.T6G(SCH_1):PAGE99
   121    GND @T6G_MB_LIB.T6G(SCH_1):GND   I155 @T6G_MB_LIB.T6G(SCH_1):PAGE99
   123    GND @T6G_MB_LIB.T6G(SCH_1):GND   I155 @T6G_MB_LIB.T6G(SCH_1):PAGE99
   125    GND @T6G_MB_LIB.T6G(SCH_1):GND   I155 @T6G_MB_LIB.T6G(SCH_1):PAGE99
   128    GND @T6G_MB_LIB.T6G(SCH_1):GND   I155 @T6G_MB_LIB.T6G(SCH_1):PAGE99
   130    GND @T6G_MB_LIB.T6G(SCH_1):GND   I155 @T6G_MB_LIB.T6G(SCH_1):PAGE99
   134    GND @T6G_MB_LIB.T6G(SCH_1):GND   I155 @T6G_MB_LIB.T6G(SCH_1):PAGE99
   143    GND @T6G_MB_LIB.T6G(SCH_1):GND   I155 @T6G_MB_LIB.T6G(SCH_1):PAGE99
   151    GND @T6G_MB_LIB.T6G(SCH_1):GND   I155 @T6G_MB_LIB.T6G(SCH_1):PAGE99
   153    GND @T6G_MB_LIB.T6G(SCH_1):GND   I155 @T6G_MB_LIB.T6G(SCH_1):PAGE99
   155    GND @T6G_MB_LIB.T6G(SCH_1):GND   I155 @T6G_MB_LIB.T6G(SCH_1):PAGE99
   158    GND @T6G_MB_LIB.T6G(SCH_1):GND   I155 @T6G_MB_LIB.T6G(SCH_1):PAGE99
   160    GND @T6G_MB_LIB.T6G(SCH_1):GND   I155 @T6G_MB_LIB.T6G(SCH_1):PAGE99
   162    GND @T6G_MB_LIB.T6G(SCH_1):GND   I155 @T6G_MB_LIB.T6G(SCH_1):PAGE99
   164    GND @T6G_MB_LIB.T6G(SCH_1):GND   I155 @T6G_MB_LIB.T6G(SCH_1):PAGE99
   166    GND @T6G_MB_LIB.T6G(SCH_1):GND   I155 @T6G_MB_LIB.T6G(SCH_1):PAGE99
   169    GND @T6G_MB_LIB.T6G(SCH_1):GND   I155 @T6G_MB_LIB.T6G(SCH_1):PAGE99
   171    GND @T6G_MB_LIB.T6G(SCH_1):GND   I155 @T6G_MB_LIB.T6G(SCH_1):PAGE99
   173    GND @T6G_MB_LIB.T6G(SCH_1):GND   I155 @T6G_MB_LIB.T6G(SCH_1):PAGE99
   175    GND @T6G_MB_LIB.T6G(SCH_1):GND   I155 @T6G_MB_LIB.T6G(SCH_1):PAGE99
   177    GND @T6G_MB_LIB.T6G(SCH_1):GND   I155 @T6G_MB_LIB.T6G(SCH_1):PAGE99
   180    GND @T6G_MB_LIB.T6G(SCH_1):GND   I155 @T6G_MB_LIB.T6G(SCH_1):PAGE99
   182    GND @T6G_MB_LIB.T6G(SCH_1):GND   I155 @T6G_MB_LIB.T6G(SCH_1):PAGE99
   184    GND @T6G_MB_LIB.T6G(SCH_1):GND   I155 @T6G_MB_LIB.T6G(SCH_1):PAGE99
   186    GND @T6G_MB_LIB.T6G(SCH_1):GND   I155 @T6G_MB_LIB.T6G(SCH_1):PAGE99
   188    GND @T6G_MB_LIB.T6G(SCH_1):GND   I155 @T6G_MB_LIB.T6G(SCH_1):PAGE99
   191    GND @T6G_MB_LIB.T6G(SCH_1):GND   I155 @T6G_MB_LIB.T6G(SCH_1):PAGE99
   193    GND @T6G_MB_LIB.T6G(SCH_1):GND   I155 @T6G_MB_LIB.T6G(SCH_1):PAGE99
   195    GND @T6G_MB_LIB.T6G(SCH_1):GND   I155 @T6G_MB_LIB.T6G(SCH_1):PAGE99
   197    GND @T6G_MB_LIB.T6G(SCH_1):GND   I155 @T6G_MB_LIB.T6G(SCH_1):PAGE99
   199    GND @T6G_MB_LIB.T6G(SCH_1):GND   I155 @T6G_MB_LIB.T6G(SCH_1):PAGE99
   202    GND @T6G_MB_LIB.T6G(SCH_1):GND   I155 @T6G_MB_LIB.T6G(SCH_1):PAGE99
   204    GND @T6G_MB_LIB.T6G(SCH_1):GND   I155 @T6G_MB_LIB.T6G(SCH_1):PAGE99
   206    GND @T6G_MB_LIB.T6G(SCH_1):GND   I155 @T6G_MB_LIB.T6G(SCH_1):PAGE99
   208    GND @T6G_MB_LIB.T6G(SCH_1):GND   I155 @T6G_MB_LIB.T6G(SCH_1):PAGE99
   210    GND @T6G_MB_LIB.T6G(SCH_1):GND   I155 @T6G_MB_LIB.T6G(SCH_1):PAGE99
   212    GND @T6G_MB_LIB.T6G(SCH_1):GND   I155 @T6G_MB_LIB.T6G(SCH_1):PAGE99
   214    GND @T6G_MB_LIB.T6G(SCH_1):GND   I155 @T6G_MB_LIB.T6G(SCH_1):PAGE99
   216    GND @T6G_MB_LIB.T6G(SCH_1):GND   I155 @T6G_MB_LIB.T6G(SCH_1):PAGE99
   219    GND @T6G_MB_LIB.T6G(SCH_1):GND   I155 @T6G_MB_LIB.T6G(SCH_1):PAGE99
   222    GND @T6G_MB_LIB.T6G(SCH_1):GND   I155 @T6G_MB_LIB.T6G(SCH_1):PAGE99
   224    GND @T6G_MB_LIB.T6G(SCH_1):GND   I155 @T6G_MB_LIB.T6G(SCH_1):PAGE99
   226    GND @T6G_MB_LIB.T6G(SCH_1):GND   I155 @T6G_MB_LIB.T6G(SCH_1):PAGE99
   228    GND @T6G_MB_LIB.T6G(SCH_1):GND   I155 @T6G_MB_LIB.T6G(SCH_1):PAGE99
   233    GND @T6G_MB_LIB.T6G(SCH_1):GND   I155 @T6G_MB_LIB.T6G(SCH_1):PAGE99
   237    GND @T6G_MB_LIB.T6G(SCH_1):GND   I155 @T6G_MB_LIB.T6G(SCH_1):PAGE99
   242    GND @T6G_MB_LIB.T6G(SCH_1):GND   I155 @T6G_MB_LIB.T6G(SCH_1):PAGE99
   244    GND @T6G_MB_LIB.T6G(SCH_1):GND   I155 @T6G_MB_LIB.T6G(SCH_1):PAGE99
   246    GND @T6G_MB_LIB.T6G(SCH_1):GND   I155 @T6G_MB_LIB.T6G(SCH_1):PAGE99
   248    GND @T6G_MB_LIB.T6G(SCH_1):GND   I155 @T6G_MB_LIB.T6G(SCH_1):PAGE99
   251    GND @T6G_MB_LIB.T6G(SCH_1):GND   I155 @T6G_MB_LIB.T6G(SCH_1):PAGE99
   253    GND @T6G_MB_LIB.T6G(SCH_1):GND   I155 @T6G_MB_LIB.T6G(SCH_1):PAGE99
   255    GND @T6G_MB_LIB.T6G(SCH_1):GND   I155 @T6G_MB_LIB.T6G(SCH_1):PAGE99
   257    GND @T6G_MB_LIB.T6G(SCH_1):GND   I155 @T6G_MB_LIB.T6G(SCH_1):PAGE99
   259    GND @T6G_MB_LIB.T6G(SCH_1):GND   I155 @T6G_MB_LIB.T6G(SCH_1):PAGE99
   262    GND @T6G_MB_LIB.T6G(SCH_1):GND   I155 @T6G_MB_LIB.T6G(SCH_1):PAGE99
   264    GND @T6G_MB_LIB.T6G(SCH_1):GND   I155 @T6G_MB_LIB.T6G(SCH_1):PAGE99
   266    GND @T6G_MB_LIB.T6G(SCH_1):GND   I155 @T6G_MB_LIB.T6G(SCH_1):PAGE99
   268    GND @T6G_MB_LIB.T6G(SCH_1):GND   I155 @T6G_MB_LIB.T6G(SCH_1):PAGE99
   270    GND @T6G_MB_LIB.T6G(SCH_1):GND   I155 @T6G_MB_LIB.T6G(SCH_1):PAGE99
   273    GND @T6G_MB_LIB.T6G(SCH_1):GND   I155 @T6G_MB_LIB.T6G(SCH_1):PAGE99
   275    GND @T6G_MB_LIB.T6G(SCH_1):GND   I155 @T6G_MB_LIB.T6G(SCH_1):PAGE99
   277    GND @T6G_MB_LIB.T6G(SCH_1):GND   I155 @T6G_MB_LIB.T6G(SCH_1):PAGE99
   279    GND @T6G_MB_LIB.T6G(SCH_1):GND   I155 @T6G_MB_LIB.T6G(SCH_1):PAGE99
   281    GND @T6G_MB_LIB.T6G(SCH_1):GND   I155 @T6G_MB_LIB.T6G(SCH_1):PAGE99
   284    GND @T6G_MB_LIB.T6G(SCH_1):GND   I155 @T6G_MB_LIB.T6G(SCH_1):PAGE99
   286    GND @T6G_MB_LIB.T6G(SCH_1):GND   I155 @T6G_MB_LIB.T6G(SCH_1):PAGE99
   288    GND @T6G_MB_LIB.T6G(SCH_1):GND   I155 @T6G_MB_LIB.T6G(SCH_1):PAGE99
     1 P12V_MEM_CPU1 @T6G_MB_LIB.T6G(SCH_1):P12V_MEM_CPU1   I155 @T6G_MB_LIB.T6G(SCH_1):PAGE99
   145 P12V_MEM_CPU1 @T6G_MB_LIB.T6G(SCH_1):P12V_MEM_CPU1   I155 @T6G_MB_LIB.T6G(SCH_1):PAGE99
   146 P12V_MEM_CPU1 @T6G_MB_LIB.T6G(SCH_1):P12V_MEM_CPU1   I155 @T6G_MB_LIB.T6G(SCH_1):PAGE99
   230    GND @T6G_MB_LIB.T6G(SCH_1):GND   I155 @T6G_MB_LIB.T6G(SCH_1):PAGE99
   235    GND @T6G_MB_LIB.T6G(SCH_1):GND   I155 @T6G_MB_LIB.T6G(SCH_1):PAGE99
   240    GND @T6G_MB_LIB.T6G(SCH_1):GND   I155 @T6G_MB_LIB.T6G(SCH_1):PAGE99
   132    GND @T6G_MB_LIB.T6G(SCH_1):GND   I155 @T6G_MB_LIB.T6G(SCH_1):PAGE99
   136    GND @T6G_MB_LIB.T6G(SCH_1):GND   I155 @T6G_MB_LIB.T6G(SCH_1):PAGE99
   139    GND @T6G_MB_LIB.T6G(SCH_1):GND   I155 @T6G_MB_LIB.T6G(SCH_1):PAGE99
   141    GND @T6G_MB_LIB.T6G(SCH_1):GND   I155 @T6G_MB_LIB.T6G(SCH_1):PAGE99
    G1    GND @T6G_MB_LIB.T6G(SCH_1):GND   I155 @T6G_MB_LIB.T6G(SCH_1):PAGE99
    G2    GND @T6G_MB_LIB.T6G(SCH_1):GND   I155 @T6G_MB_LIB.T6G(SCH_1):PAGE99
    G3    GND @T6G_MB_LIB.T6G(SCH_1):GND   I155 @T6G_MB_LIB.T6G(SCH_1):PAGE99

 J29 SCONN288_DDR506112002KQ-SCONN288_DDR506112002KQ,SMA
     3 P3V3_AUX @T6G_MB_LIB.T6G(SCH_1):P3V3_AUX    I22 @T6G_MB_LIB.T6G(SCH_1):PAGE106
     2     NC     NC    I22 @T6G_MB_LIB.T6G(SCH_1):PAGE106
   144     NC     NC    I22 @T6G_MB_LIB.T6G(SCH_1):PAGE106
   149     NC     NC    I22 @T6G_MB_LIB.T6G(SCH_1):PAGE106
   150     NC     NC    I22 @T6G_MB_LIB.T6G(SCH_1):PAGE106
   220     NC     NC    I22 @T6G_MB_LIB.T6G(SCH_1):PAGE106
   231     NC     NC    I22 @T6G_MB_LIB.T6G(SCH_1):PAGE106
   232     NC     NC    I22 @T6G_MB_LIB.T6G(SCH_1):PAGE106
   207 M_J_CPU1_RESET_N @T6G_MB_LIB.T6G(SCH_1):M_J_CPU1_RESET_N    I22 @T6G_MB_LIB.T6G(SCH_1):PAGE106
   147 PWRGD_CHJ_CPU1_DIMM @T6G_MB_LIB.T6G(SCH_1):PWRGD_CHJ_CPU1_DIMM    I22 @T6G_MB_LIB.T6G(SCH_1):PAGE106
   227 M_J_CPU1_SB_PAR @T6G_MB_LIB.T6G(SCH_1):M_J_CPU1_SB_PAR    I22 @T6G_MB_LIB.T6G(SCH_1):PAGE106
    74 M_J_CPU1_SA_PAR @T6G_MB_LIB.T6G(SCH_1):M_J_CPU1_SA_PAR    I22 @T6G_MB_LIB.T6G(SCH_1):PAGE106
    87 M_J_CPU1_SB_RSP<0> @T6G_MB_LIB.T6G(SCH_1):M_J_CPU1_SB_RSP(0)    I22 @T6G_MB_LIB.T6G(SCH_1):PAGE106
    86 M_J_CPU1_SA_RSP<0> @T6G_MB_LIB.T6G(SCH_1):M_J_CPU1_SA_RSP(0)    I22 @T6G_MB_LIB.T6G(SCH_1):PAGE106
     5 I3C_SPD_DDRJ_CPU1_SDA @T6G_MB_LIB.T6G(SCH_1):I3C_SPD_DDRJ_CPU1_SDA    I22 @T6G_MB_LIB.T6G(SCH_1):PAGE106
     4 I3C_SPD_DDRJ_CPU1_SCL @T6G_MB_LIB.T6G(SCH_1):I3C_SPD_DDRJ_CPU1_SCL    I22 @T6G_MB_LIB.T6G(SCH_1):PAGE106
   148 PD_CHJ_CPU1_DIMM_SAA @T6G_MB_LIB.T6G(SCH_1):PD_CHJ_CPU1_DIMM_SAA    I22 @T6G_MB_LIB.T6G(SCH_1):PAGE106
   100 M_J_CPU1_SB_DQ<0> @T6G_MB_LIB.T6G(SCH_1):M_J_CPU1_SB_DQ(0)    I22 @T6G_MB_LIB.T6G(SCH_1):PAGE106
   102 M_J_CPU1_SB_DQ<1> @T6G_MB_LIB.T6G(SCH_1):M_J_CPU1_SB_DQ(1)    I22 @T6G_MB_LIB.T6G(SCH_1):PAGE106
   245 M_J_CPU1_SB_DQ<2> @T6G_MB_LIB.T6G(SCH_1):M_J_CPU1_SB_DQ(2)    I22 @T6G_MB_LIB.T6G(SCH_1):PAGE106
   247 M_J_CPU1_SB_DQ<3> @T6G_MB_LIB.T6G(SCH_1):M_J_CPU1_SB_DQ(3)    I22 @T6G_MB_LIB.T6G(SCH_1):PAGE106
   107 M_J_CPU1_SB_DQ<4> @T6G_MB_LIB.T6G(SCH_1):M_J_CPU1_SB_DQ(4)    I22 @T6G_MB_LIB.T6G(SCH_1):PAGE106
   109 M_J_CPU1_SB_DQ<5> @T6G_MB_LIB.T6G(SCH_1):M_J_CPU1_SB_DQ(5)    I22 @T6G_MB_LIB.T6G(SCH_1):PAGE106
   252 M_J_CPU1_SB_DQ<6> @T6G_MB_LIB.T6G(SCH_1):M_J_CPU1_SB_DQ(6)    I22 @T6G_MB_LIB.T6G(SCH_1):PAGE106
   254 M_J_CPU1_SB_DQ<7> @T6G_MB_LIB.T6G(SCH_1):M_J_CPU1_SB_DQ(7)    I22 @T6G_MB_LIB.T6G(SCH_1):PAGE106
   111 M_J_CPU1_SB_DQ<8> @T6G_MB_LIB.T6G(SCH_1):M_J_CPU1_SB_DQ(8)    I22 @T6G_MB_LIB.T6G(SCH_1):PAGE106
   113 M_J_CPU1_SB_DQ<9> @T6G_MB_LIB.T6G(SCH_1):M_J_CPU1_SB_DQ(9)    I22 @T6G_MB_LIB.T6G(SCH_1):PAGE106
   256 M_J_CPU1_SB_DQ<10> @T6G_MB_LIB.T6G(SCH_1):M_J_CPU1_SB_DQ(10)    I22 @T6G_MB_LIB.T6G(SCH_1):PAGE106
   258 M_J_CPU1_SB_DQ<11> @T6G_MB_LIB.T6G(SCH_1):M_J_CPU1_SB_DQ(11)    I22 @T6G_MB_LIB.T6G(SCH_1):PAGE106
   118 M_J_CPU1_SB_DQ<12> @T6G_MB_LIB.T6G(SCH_1):M_J_CPU1_SB_DQ(12)    I22 @T6G_MB_LIB.T6G(SCH_1):PAGE106
   120 M_J_CPU1_SB_DQ<13> @T6G_MB_LIB.T6G(SCH_1):M_J_CPU1_SB_DQ(13)    I22 @T6G_MB_LIB.T6G(SCH_1):PAGE106
   263 M_J_CPU1_SB_DQ<14> @T6G_MB_LIB.T6G(SCH_1):M_J_CPU1_SB_DQ(14)    I22 @T6G_MB_LIB.T6G(SCH_1):PAGE106
   265 M_J_CPU1_SB_DQ<15> @T6G_MB_LIB.T6G(SCH_1):M_J_CPU1_SB_DQ(15)    I22 @T6G_MB_LIB.T6G(SCH_1):PAGE106
   122 M_J_CPU1_SB_DQ<16> @T6G_MB_LIB.T6G(SCH_1):M_J_CPU1_SB_DQ(16)    I22 @T6G_MB_LIB.T6G(SCH_1):PAGE106
   124 M_J_CPU1_SB_DQ<17> @T6G_MB_LIB.T6G(SCH_1):M_J_CPU1_SB_DQ(17)    I22 @T6G_MB_LIB.T6G(SCH_1):PAGE106
   267 M_J_CPU1_SB_DQ<18> @T6G_MB_LIB.T6G(SCH_1):M_J_CPU1_SB_DQ(18)    I22 @T6G_MB_LIB.T6G(SCH_1):PAGE106
   269 M_J_CPU1_SB_DQ<19> @T6G_MB_LIB.T6G(SCH_1):M_J_CPU1_SB_DQ(19)    I22 @T6G_MB_LIB.T6G(SCH_1):PAGE106
   129 M_J_CPU1_SB_DQ<20> @T6G_MB_LIB.T6G(SCH_1):M_J_CPU1_SB_DQ(20)    I22 @T6G_MB_LIB.T6G(SCH_1):PAGE106
   131 M_J_CPU1_SB_DQ<21> @T6G_MB_LIB.T6G(SCH_1):M_J_CPU1_SB_DQ(21)    I22 @T6G_MB_LIB.T6G(SCH_1):PAGE106
   274 M_J_CPU1_SB_DQ<22> @T6G_MB_LIB.T6G(SCH_1):M_J_CPU1_SB_DQ(22)    I22 @T6G_MB_LIB.T6G(SCH_1):PAGE106
   276 M_J_CPU1_SB_DQ<23> @T6G_MB_LIB.T6G(SCH_1):M_J_CPU1_SB_DQ(23)    I22 @T6G_MB_LIB.T6G(SCH_1):PAGE106
   133 M_J_CPU1_SB_DQ<24> @T6G_MB_LIB.T6G(SCH_1):M_J_CPU1_SB_DQ(24)    I22 @T6G_MB_LIB.T6G(SCH_1):PAGE106
   135 M_J_CPU1_SB_DQ<25> @T6G_MB_LIB.T6G(SCH_1):M_J_CPU1_SB_DQ(25)    I22 @T6G_MB_LIB.T6G(SCH_1):PAGE106
   278 M_J_CPU1_SB_DQ<26> @T6G_MB_LIB.T6G(SCH_1):M_J_CPU1_SB_DQ(26)    I22 @T6G_MB_LIB.T6G(SCH_1):PAGE106
   280 M_J_CPU1_SB_DQ<27> @T6G_MB_LIB.T6G(SCH_1):M_J_CPU1_SB_DQ(27)    I22 @T6G_MB_LIB.T6G(SCH_1):PAGE106
   140 M_J_CPU1_SB_DQ<28> @T6G_MB_LIB.T6G(SCH_1):M_J_CPU1_SB_DQ(28)    I22 @T6G_MB_LIB.T6G(SCH_1):PAGE106
   142 M_J_CPU1_SB_DQ<29> @T6G_MB_LIB.T6G(SCH_1):M_J_CPU1_SB_DQ(29)    I22 @T6G_MB_LIB.T6G(SCH_1):PAGE106
   285 M_J_CPU1_SB_DQ<30> @T6G_MB_LIB.T6G(SCH_1):M_J_CPU1_SB_DQ(30)    I22 @T6G_MB_LIB.T6G(SCH_1):PAGE106
   287 M_J_CPU1_SB_DQ<31> @T6G_MB_LIB.T6G(SCH_1):M_J_CPU1_SB_DQ(31)    I22 @T6G_MB_LIB.T6G(SCH_1):PAGE106
     7 M_J_CPU1_SA_DQ<0> @T6G_MB_LIB.T6G(SCH_1):M_J_CPU1_SA_DQ(0)    I22 @T6G_MB_LIB.T6G(SCH_1):PAGE106
     9 M_J_CPU1_SA_DQ<1> @T6G_MB_LIB.T6G(SCH_1):M_J_CPU1_SA_DQ(1)    I22 @T6G_MB_LIB.T6G(SCH_1):PAGE106
   152 M_J_CPU1_SA_DQ<2> @T6G_MB_LIB.T6G(SCH_1):M_J_CPU1_SA_DQ(2)    I22 @T6G_MB_LIB.T6G(SCH_1):PAGE106
   154 M_J_CPU1_SA_DQ<3> @T6G_MB_LIB.T6G(SCH_1):M_J_CPU1_SA_DQ(3)    I22 @T6G_MB_LIB.T6G(SCH_1):PAGE106
    14 M_J_CPU1_SA_DQ<4> @T6G_MB_LIB.T6G(SCH_1):M_J_CPU1_SA_DQ(4)    I22 @T6G_MB_LIB.T6G(SCH_1):PAGE106
    16 M_J_CPU1_SA_DQ<5> @T6G_MB_LIB.T6G(SCH_1):M_J_CPU1_SA_DQ(5)    I22 @T6G_MB_LIB.T6G(SCH_1):PAGE106
   159 M_J_CPU1_SA_DQ<6> @T6G_MB_LIB.T6G(SCH_1):M_J_CPU1_SA_DQ(6)    I22 @T6G_MB_LIB.T6G(SCH_1):PAGE106
   161 M_J_CPU1_SA_DQ<7> @T6G_MB_LIB.T6G(SCH_1):M_J_CPU1_SA_DQ(7)    I22 @T6G_MB_LIB.T6G(SCH_1):PAGE106
    18 M_J_CPU1_SA_DQ<8> @T6G_MB_LIB.T6G(SCH_1):M_J_CPU1_SA_DQ(8)    I22 @T6G_MB_LIB.T6G(SCH_1):PAGE106
    20 M_J_CPU1_SA_DQ<9> @T6G_MB_LIB.T6G(SCH_1):M_J_CPU1_SA_DQ(9)    I22 @T6G_MB_LIB.T6G(SCH_1):PAGE106
   163 M_J_CPU1_SA_DQ<10> @T6G_MB_LIB.T6G(SCH_1):M_J_CPU1_SA_DQ(10)    I22 @T6G_MB_LIB.T6G(SCH_1):PAGE106
   165 M_J_CPU1_SA_DQ<11> @T6G_MB_LIB.T6G(SCH_1):M_J_CPU1_SA_DQ(11)    I22 @T6G_MB_LIB.T6G(SCH_1):PAGE106
    25 M_J_CPU1_SA_DQ<12> @T6G_MB_LIB.T6G(SCH_1):M_J_CPU1_SA_DQ(12)    I22 @T6G_MB_LIB.T6G(SCH_1):PAGE106
    27 M_J_CPU1_SA_DQ<13> @T6G_MB_LIB.T6G(SCH_1):M_J_CPU1_SA_DQ(13)    I22 @T6G_MB_LIB.T6G(SCH_1):PAGE106
   170 M_J_CPU1_SA_DQ<14> @T6G_MB_LIB.T6G(SCH_1):M_J_CPU1_SA_DQ(14)    I22 @T6G_MB_LIB.T6G(SCH_1):PAGE106
   172 M_J_CPU1_SA_DQ<15> @T6G_MB_LIB.T6G(SCH_1):M_J_CPU1_SA_DQ(15)    I22 @T6G_MB_LIB.T6G(SCH_1):PAGE106
    29 M_J_CPU1_SA_DQ<16> @T6G_MB_LIB.T6G(SCH_1):M_J_CPU1_SA_DQ(16)    I22 @T6G_MB_LIB.T6G(SCH_1):PAGE106
    31 M_J_CPU1_SA_DQ<17> @T6G_MB_LIB.T6G(SCH_1):M_J_CPU1_SA_DQ(17)    I22 @T6G_MB_LIB.T6G(SCH_1):PAGE106
   174 M_J_CPU1_SA_DQ<18> @T6G_MB_LIB.T6G(SCH_1):M_J_CPU1_SA_DQ(18)    I22 @T6G_MB_LIB.T6G(SCH_1):PAGE106
   176 M_J_CPU1_SA_DQ<19> @T6G_MB_LIB.T6G(SCH_1):M_J_CPU1_SA_DQ(19)    I22 @T6G_MB_LIB.T6G(SCH_1):PAGE106
    36 M_J_CPU1_SA_DQ<20> @T6G_MB_LIB.T6G(SCH_1):M_J_CPU1_SA_DQ(20)    I22 @T6G_MB_LIB.T6G(SCH_1):PAGE106
    38 M_J_CPU1_SA_DQ<21> @T6G_MB_LIB.T6G(SCH_1):M_J_CPU1_SA_DQ(21)    I22 @T6G_MB_LIB.T6G(SCH_1):PAGE106
   181 M_J_CPU1_SA_DQ<22> @T6G_MB_LIB.T6G(SCH_1):M_J_CPU1_SA_DQ(22)    I22 @T6G_MB_LIB.T6G(SCH_1):PAGE106
   183 M_J_CPU1_SA_DQ<23> @T6G_MB_LIB.T6G(SCH_1):M_J_CPU1_SA_DQ(23)    I22 @T6G_MB_LIB.T6G(SCH_1):PAGE106
    40 M_J_CPU1_SA_DQ<24> @T6G_MB_LIB.T6G(SCH_1):M_J_CPU1_SA_DQ(24)    I22 @T6G_MB_LIB.T6G(SCH_1):PAGE106
    42 M_J_CPU1_SA_DQ<25> @T6G_MB_LIB.T6G(SCH_1):M_J_CPU1_SA_DQ(25)    I22 @T6G_MB_LIB.T6G(SCH_1):PAGE106
   185 M_J_CPU1_SA_DQ<26> @T6G_MB_LIB.T6G(SCH_1):M_J_CPU1_SA_DQ(26)    I22 @T6G_MB_LIB.T6G(SCH_1):PAGE106
   187 M_J_CPU1_SA_DQ<27> @T6G_MB_LIB.T6G(SCH_1):M_J_CPU1_SA_DQ(27)    I22 @T6G_MB_LIB.T6G(SCH_1):PAGE106
    47 M_J_CPU1_SA_DQ<28> @T6G_MB_LIB.T6G(SCH_1):M_J_CPU1_SA_DQ(28)    I22 @T6G_MB_LIB.T6G(SCH_1):PAGE106
    49 M_J_CPU1_SA_DQ<29> @T6G_MB_LIB.T6G(SCH_1):M_J_CPU1_SA_DQ(29)    I22 @T6G_MB_LIB.T6G(SCH_1):PAGE106
   192 M_J_CPU1_SA_DQ<30> @T6G_MB_LIB.T6G(SCH_1):M_J_CPU1_SA_DQ(30)    I22 @T6G_MB_LIB.T6G(SCH_1):PAGE106
   229 M_J_CPU1_SB_CS_N<1> @T6G_MB_LIB.T6G(SCH_1):M_J_CPU1_SB_CS_N(1)    I22 @T6G_MB_LIB.T6G(SCH_1):PAGE106
   209 M_J_CPU1_SA_CS_N<1> @T6G_MB_LIB.T6G(SCH_1):M_J_CPU1_SA_CS_N(1)    I22 @T6G_MB_LIB.T6G(SCH_1):PAGE106
    84 M_J_CPU1_SB_CS_N<0> @T6G_MB_LIB.T6G(SCH_1):M_J_CPU1_SB_CS_N(0)    I22 @T6G_MB_LIB.T6G(SCH_1):PAGE106
    64 M_J_CPU1_SA_CS_N<0> @T6G_MB_LIB.T6G(SCH_1):M_J_CPU1_SA_CS_N(0)    I22 @T6G_MB_LIB.T6G(SCH_1):PAGE106
   217 M_J_CPU1_CLK_DP<0> @T6G_MB_LIB.T6G(SCH_1):M_J_CPU1_CLK_DP(0)    I22 @T6G_MB_LIB.T6G(SCH_1):PAGE106
   218 M_J_CPU1_CLK_DN<0> @T6G_MB_LIB.T6G(SCH_1):M_J_CPU1_CLK_DN(0)    I22 @T6G_MB_LIB.T6G(SCH_1):PAGE106
    96 M_J_CPU1_SB_CB<0> @T6G_MB_LIB.T6G(SCH_1):M_J_CPU1_SB_CB(0)    I22 @T6G_MB_LIB.T6G(SCH_1):PAGE106
    98 M_J_CPU1_SB_CB<1> @T6G_MB_LIB.T6G(SCH_1):M_J_CPU1_SB_CB(1)    I22 @T6G_MB_LIB.T6G(SCH_1):PAGE106
   241 M_J_CPU1_SB_CB<2> @T6G_MB_LIB.T6G(SCH_1):M_J_CPU1_SB_CB(2)    I22 @T6G_MB_LIB.T6G(SCH_1):PAGE106
   243 M_J_CPU1_SB_CB<3> @T6G_MB_LIB.T6G(SCH_1):M_J_CPU1_SB_CB(3)    I22 @T6G_MB_LIB.T6G(SCH_1):PAGE106
    89 M_J_CPU1_SB_CB<4> @T6G_MB_LIB.T6G(SCH_1):M_J_CPU1_SB_CB(4)    I22 @T6G_MB_LIB.T6G(SCH_1):PAGE106
    91 M_J_CPU1_SB_CB<5> @T6G_MB_LIB.T6G(SCH_1):M_J_CPU1_SB_CB(5)    I22 @T6G_MB_LIB.T6G(SCH_1):PAGE106
   234 M_J_CPU1_SB_CB<6> @T6G_MB_LIB.T6G(SCH_1):M_J_CPU1_SB_CB(6)    I22 @T6G_MB_LIB.T6G(SCH_1):PAGE106
    51 M_J_CPU1_SA_CB<0> @T6G_MB_LIB.T6G(SCH_1):M_J_CPU1_SA_CB(0)    I22 @T6G_MB_LIB.T6G(SCH_1):PAGE106
   196 M_J_CPU1_SA_CB<2> @T6G_MB_LIB.T6G(SCH_1):M_J_CPU1_SA_CB(2)    I22 @T6G_MB_LIB.T6G(SCH_1):PAGE106
   198 M_J_CPU1_SA_CB<3> @T6G_MB_LIB.T6G(SCH_1):M_J_CPU1_SA_CB(3)    I22 @T6G_MB_LIB.T6G(SCH_1):PAGE106
    60 M_J_CPU1_SA_CB<5> @T6G_MB_LIB.T6G(SCH_1):M_J_CPU1_SA_CB(5)    I22 @T6G_MB_LIB.T6G(SCH_1):PAGE106
   203 M_J_CPU1_SA_CB<6> @T6G_MB_LIB.T6G(SCH_1):M_J_CPU1_SA_CB(6)    I22 @T6G_MB_LIB.T6G(SCH_1):PAGE106
    82 M_J_CPU1_SB_CA<6> @T6G_MB_LIB.T6G(SCH_1):M_J_CPU1_SB_CA(6)    I22 @T6G_MB_LIB.T6G(SCH_1):PAGE106
    72 M_J_CPU1_SA_CA<6> @T6G_MB_LIB.T6G(SCH_1):M_J_CPU1_SA_CA(6)    I22 @T6G_MB_LIB.T6G(SCH_1):PAGE106
   225 M_J_CPU1_SB_CA<5> @T6G_MB_LIB.T6G(SCH_1):M_J_CPU1_SB_CA(5)    I22 @T6G_MB_LIB.T6G(SCH_1):PAGE106
   215 M_J_CPU1_SA_CA<5> @T6G_MB_LIB.T6G(SCH_1):M_J_CPU1_SA_CA(5)    I22 @T6G_MB_LIB.T6G(SCH_1):PAGE106
    80 M_J_CPU1_SB_CA<4> @T6G_MB_LIB.T6G(SCH_1):M_J_CPU1_SB_CA(4)    I22 @T6G_MB_LIB.T6G(SCH_1):PAGE106
    70 M_J_CPU1_SA_CA<4> @T6G_MB_LIB.T6G(SCH_1):M_J_CPU1_SA_CA(4)    I22 @T6G_MB_LIB.T6G(SCH_1):PAGE106
   223 M_J_CPU1_SB_CA<3> @T6G_MB_LIB.T6G(SCH_1):M_J_CPU1_SB_CA(3)    I22 @T6G_MB_LIB.T6G(SCH_1):PAGE106
   213 M_J_CPU1_SA_CA<3> @T6G_MB_LIB.T6G(SCH_1):M_J_CPU1_SA_CA(3)    I22 @T6G_MB_LIB.T6G(SCH_1):PAGE106
    78 M_J_CPU1_SB_CA<2> @T6G_MB_LIB.T6G(SCH_1):M_J_CPU1_SB_CA(2)    I22 @T6G_MB_LIB.T6G(SCH_1):PAGE106
    68 M_J_CPU1_SA_CA<2> @T6G_MB_LIB.T6G(SCH_1):M_J_CPU1_SA_CA(2)    I22 @T6G_MB_LIB.T6G(SCH_1):PAGE106
   221 M_J_CPU1_SB_CA<1> @T6G_MB_LIB.T6G(SCH_1):M_J_CPU1_SB_CA(1)    I22 @T6G_MB_LIB.T6G(SCH_1):PAGE106
   211 M_J_CPU1_SA_CA<1> @T6G_MB_LIB.T6G(SCH_1):M_J_CPU1_SA_CA(1)    I22 @T6G_MB_LIB.T6G(SCH_1):PAGE106
    76 M_J_CPU1_SB_CA<0> @T6G_MB_LIB.T6G(SCH_1):M_J_CPU1_SB_CA(0)    I22 @T6G_MB_LIB.T6G(SCH_1):PAGE106
    66 M_J_CPU1_SA_CA<0> @T6G_MB_LIB.T6G(SCH_1):M_J_CPU1_SA_CA(0)    I22 @T6G_MB_LIB.T6G(SCH_1):PAGE106
    62 M_J_CPU1_ALERT_N @T6G_MB_LIB.T6G(SCH_1):M_J_CPU1_ALERT_N    I22 @T6G_MB_LIB.T6G(SCH_1):PAGE106
   236 M_J_CPU1_SB_CB<7> @T6G_MB_LIB.T6G(SCH_1):M_J_CPU1_SB_CB(7)    I22 @T6G_MB_LIB.T6G(SCH_1):PAGE106
    53 M_J_CPU1_SA_CB<1> @T6G_MB_LIB.T6G(SCH_1):M_J_CPU1_SA_CB(1)    I22 @T6G_MB_LIB.T6G(SCH_1):PAGE106
    58 M_J_CPU1_SA_CB<4> @T6G_MB_LIB.T6G(SCH_1):M_J_CPU1_SA_CB(4)    I22 @T6G_MB_LIB.T6G(SCH_1):PAGE106
   205 M_J_CPU1_SA_CB<7> @T6G_MB_LIB.T6G(SCH_1):M_J_CPU1_SA_CB(7)    I22 @T6G_MB_LIB.T6G(SCH_1):PAGE106
   194 M_J_CPU1_SA_DQ<31> @T6G_MB_LIB.T6G(SCH_1):M_J_CPU1_SA_DQ(31)    I22 @T6G_MB_LIB.T6G(SCH_1):PAGE106
    93 M_J_CPU1_SB_DQS_DP<9> @T6G_MB_LIB.T6G(SCH_1):M_J_CPU1_SB_DQS_DP(9)   I236 @T6G_MB_LIB.T6G(SCH_1):PAGE106
    94 M_J_CPU1_SB_DQS_DN<9> @T6G_MB_LIB.T6G(SCH_1):M_J_CPU1_SB_DQS_DN(9)   I236 @T6G_MB_LIB.T6G(SCH_1):PAGE106
   201 M_J_CPU1_SA_DQS_DP<9> @T6G_MB_LIB.T6G(SCH_1):M_J_CPU1_SA_DQS_DP(9)   I236 @T6G_MB_LIB.T6G(SCH_1):PAGE106
   200 M_J_CPU1_SA_DQS_DN<9> @T6G_MB_LIB.T6G(SCH_1):M_J_CPU1_SA_DQS_DN(9)   I236 @T6G_MB_LIB.T6G(SCH_1):PAGE106
   190 M_J_CPU1_SA_DQS_DP<8> @T6G_MB_LIB.T6G(SCH_1):M_J_CPU1_SA_DQS_DP(8)   I236 @T6G_MB_LIB.T6G(SCH_1):PAGE106
   189 M_J_CPU1_SA_DQS_DN<8> @T6G_MB_LIB.T6G(SCH_1):M_J_CPU1_SA_DQS_DN(8)   I236 @T6G_MB_LIB.T6G(SCH_1):PAGE106
   271 M_J_CPU1_SB_DQS_DN<7> @T6G_MB_LIB.T6G(SCH_1):M_J_CPU1_SB_DQS_DN(7)   I236 @T6G_MB_LIB.T6G(SCH_1):PAGE106
   179 M_J_CPU1_SA_DQS_DP<7> @T6G_MB_LIB.T6G(SCH_1):M_J_CPU1_SA_DQS_DP(7)   I236 @T6G_MB_LIB.T6G(SCH_1):PAGE106
   261 M_J_CPU1_SB_DQS_DP<6> @T6G_MB_LIB.T6G(SCH_1):M_J_CPU1_SB_DQS_DP(6)   I236 @T6G_MB_LIB.T6G(SCH_1):PAGE106
   260 M_J_CPU1_SB_DQS_DN<6> @T6G_MB_LIB.T6G(SCH_1):M_J_CPU1_SB_DQS_DN(6)   I236 @T6G_MB_LIB.T6G(SCH_1):PAGE106
   167 M_J_CPU1_SA_DQS_DN<6> @T6G_MB_LIB.T6G(SCH_1):M_J_CPU1_SA_DQS_DN(6)   I236 @T6G_MB_LIB.T6G(SCH_1):PAGE106
   250 M_J_CPU1_SB_DQS_DP<5> @T6G_MB_LIB.T6G(SCH_1):M_J_CPU1_SB_DQS_DP(5)   I236 @T6G_MB_LIB.T6G(SCH_1):PAGE106
   249 M_J_CPU1_SB_DQS_DN<5> @T6G_MB_LIB.T6G(SCH_1):M_J_CPU1_SB_DQS_DN(5)   I236 @T6G_MB_LIB.T6G(SCH_1):PAGE106
   157 M_J_CPU1_SA_DQS_DP<5> @T6G_MB_LIB.T6G(SCH_1):M_J_CPU1_SA_DQS_DP(5)   I236 @T6G_MB_LIB.T6G(SCH_1):PAGE106
   156 M_J_CPU1_SA_DQS_DN<5> @T6G_MB_LIB.T6G(SCH_1):M_J_CPU1_SA_DQS_DN(5)   I236 @T6G_MB_LIB.T6G(SCH_1):PAGE106
   239 M_J_CPU1_SB_DQS_DP<4> @T6G_MB_LIB.T6G(SCH_1):M_J_CPU1_SB_DQS_DP(4)   I236 @T6G_MB_LIB.T6G(SCH_1):PAGE106
   238 M_J_CPU1_SB_DQS_DN<4> @T6G_MB_LIB.T6G(SCH_1):M_J_CPU1_SB_DQS_DN(4)   I236 @T6G_MB_LIB.T6G(SCH_1):PAGE106
    55 M_J_CPU1_SA_DQS_DP<4> @T6G_MB_LIB.T6G(SCH_1):M_J_CPU1_SA_DQS_DP(4)   I236 @T6G_MB_LIB.T6G(SCH_1):PAGE106
    56 M_J_CPU1_SA_DQS_DN<4> @T6G_MB_LIB.T6G(SCH_1):M_J_CPU1_SA_DQS_DN(4)   I236 @T6G_MB_LIB.T6G(SCH_1):PAGE106
   137 M_J_CPU1_SB_DQS_DP<3> @T6G_MB_LIB.T6G(SCH_1):M_J_CPU1_SB_DQS_DP(3)   I236 @T6G_MB_LIB.T6G(SCH_1):PAGE106
   138 M_J_CPU1_SB_DQS_DN<3> @T6G_MB_LIB.T6G(SCH_1):M_J_CPU1_SB_DQS_DN(3)   I236 @T6G_MB_LIB.T6G(SCH_1):PAGE106
    44 M_J_CPU1_SA_DQS_DP<3> @T6G_MB_LIB.T6G(SCH_1):M_J_CPU1_SA_DQS_DP(3)   I236 @T6G_MB_LIB.T6G(SCH_1):PAGE106
    45 M_J_CPU1_SA_DQS_DN<3> @T6G_MB_LIB.T6G(SCH_1):M_J_CPU1_SA_DQS_DN(3)   I236 @T6G_MB_LIB.T6G(SCH_1):PAGE106
   126 M_J_CPU1_SB_DQS_DP<2> @T6G_MB_LIB.T6G(SCH_1):M_J_CPU1_SB_DQS_DP(2)   I236 @T6G_MB_LIB.T6G(SCH_1):PAGE106
   127 M_J_CPU1_SB_DQS_DN<2> @T6G_MB_LIB.T6G(SCH_1):M_J_CPU1_SB_DQS_DN(2)   I236 @T6G_MB_LIB.T6G(SCH_1):PAGE106
    33 M_J_CPU1_SA_DQS_DP<2> @T6G_MB_LIB.T6G(SCH_1):M_J_CPU1_SA_DQS_DP(2)   I236 @T6G_MB_LIB.T6G(SCH_1):PAGE106
    34 M_J_CPU1_SA_DQS_DN<2> @T6G_MB_LIB.T6G(SCH_1):M_J_CPU1_SA_DQS_DN(2)   I236 @T6G_MB_LIB.T6G(SCH_1):PAGE106
   115 M_J_CPU1_SB_DQS_DP<1> @T6G_MB_LIB.T6G(SCH_1):M_J_CPU1_SB_DQS_DP(1)   I236 @T6G_MB_LIB.T6G(SCH_1):PAGE106
   116 M_J_CPU1_SB_DQS_DN<1> @T6G_MB_LIB.T6G(SCH_1):M_J_CPU1_SB_DQS_DN(1)   I236 @T6G_MB_LIB.T6G(SCH_1):PAGE106
    22 M_J_CPU1_SA_DQS_DP<1> @T6G_MB_LIB.T6G(SCH_1):M_J_CPU1_SA_DQS_DP(1)   I236 @T6G_MB_LIB.T6G(SCH_1):PAGE106
    23 M_J_CPU1_SA_DQS_DN<1> @T6G_MB_LIB.T6G(SCH_1):M_J_CPU1_SA_DQS_DN(1)   I236 @T6G_MB_LIB.T6G(SCH_1):PAGE106
   104 M_J_CPU1_SB_DQS_DP<0> @T6G_MB_LIB.T6G(SCH_1):M_J_CPU1_SB_DQS_DP(0)   I236 @T6G_MB_LIB.T6G(SCH_1):PAGE106
   105 M_J_CPU1_SB_DQS_DN<0> @T6G_MB_LIB.T6G(SCH_1):M_J_CPU1_SB_DQS_DN(0)   I236 @T6G_MB_LIB.T6G(SCH_1):PAGE106
    11 M_J_CPU1_SA_DQS_DP<0> @T6G_MB_LIB.T6G(SCH_1):M_J_CPU1_SA_DQS_DP(0)   I236 @T6G_MB_LIB.T6G(SCH_1):PAGE106
    12 M_J_CPU1_SA_DQS_DN<0> @T6G_MB_LIB.T6G(SCH_1):M_J_CPU1_SA_DQS_DN(0)   I236 @T6G_MB_LIB.T6G(SCH_1):PAGE106
   272 M_J_CPU1_SB_DQS_DP<7> @T6G_MB_LIB.T6G(SCH_1):M_J_CPU1_SB_DQS_DP(7)   I236 @T6G_MB_LIB.T6G(SCH_1):PAGE106
   282 M_J_CPU1_SB_DQS_DN<8> @T6G_MB_LIB.T6G(SCH_1):M_J_CPU1_SB_DQS_DN(8)   I236 @T6G_MB_LIB.T6G(SCH_1):PAGE106
   283 M_J_CPU1_SB_DQS_DP<8> @T6G_MB_LIB.T6G(SCH_1):M_J_CPU1_SB_DQS_DP(8)   I236 @T6G_MB_LIB.T6G(SCH_1):PAGE106
   168 M_J_CPU1_SA_DQS_DP<6> @T6G_MB_LIB.T6G(SCH_1):M_J_CPU1_SA_DQS_DP(6)   I236 @T6G_MB_LIB.T6G(SCH_1):PAGE106
   178 M_J_CPU1_SA_DQS_DN<7> @T6G_MB_LIB.T6G(SCH_1):M_J_CPU1_SA_DQS_DN(7)   I236 @T6G_MB_LIB.T6G(SCH_1):PAGE106
     6    GND @T6G_MB_LIB.T6G(SCH_1):GND   I143 @T6G_MB_LIB.T6G(SCH_1):PAGE106
     8    GND @T6G_MB_LIB.T6G(SCH_1):GND   I143 @T6G_MB_LIB.T6G(SCH_1):PAGE106
    10    GND @T6G_MB_LIB.T6G(SCH_1):GND   I143 @T6G_MB_LIB.T6G(SCH_1):PAGE106
    13    GND @T6G_MB_LIB.T6G(SCH_1):GND   I143 @T6G_MB_LIB.T6G(SCH_1):PAGE106
    15    GND @T6G_MB_LIB.T6G(SCH_1):GND   I143 @T6G_MB_LIB.T6G(SCH_1):PAGE106
    17    GND @T6G_MB_LIB.T6G(SCH_1):GND   I143 @T6G_MB_LIB.T6G(SCH_1):PAGE106
    19    GND @T6G_MB_LIB.T6G(SCH_1):GND   I143 @T6G_MB_LIB.T6G(SCH_1):PAGE106
    21    GND @T6G_MB_LIB.T6G(SCH_1):GND   I143 @T6G_MB_LIB.T6G(SCH_1):PAGE106
    24    GND @T6G_MB_LIB.T6G(SCH_1):GND   I143 @T6G_MB_LIB.T6G(SCH_1):PAGE106
    26    GND @T6G_MB_LIB.T6G(SCH_1):GND   I143 @T6G_MB_LIB.T6G(SCH_1):PAGE106
    28    GND @T6G_MB_LIB.T6G(SCH_1):GND   I143 @T6G_MB_LIB.T6G(SCH_1):PAGE106
    30    GND @T6G_MB_LIB.T6G(SCH_1):GND   I143 @T6G_MB_LIB.T6G(SCH_1):PAGE106
    32    GND @T6G_MB_LIB.T6G(SCH_1):GND   I143 @T6G_MB_LIB.T6G(SCH_1):PAGE106
    35    GND @T6G_MB_LIB.T6G(SCH_1):GND   I143 @T6G_MB_LIB.T6G(SCH_1):PAGE106
    37    GND @T6G_MB_LIB.T6G(SCH_1):GND   I143 @T6G_MB_LIB.T6G(SCH_1):PAGE106
    39    GND @T6G_MB_LIB.T6G(SCH_1):GND   I143 @T6G_MB_LIB.T6G(SCH_1):PAGE106
    41    GND @T6G_MB_LIB.T6G(SCH_1):GND   I143 @T6G_MB_LIB.T6G(SCH_1):PAGE106
    43    GND @T6G_MB_LIB.T6G(SCH_1):GND   I143 @T6G_MB_LIB.T6G(SCH_1):PAGE106
    46    GND @T6G_MB_LIB.T6G(SCH_1):GND   I143 @T6G_MB_LIB.T6G(SCH_1):PAGE106
    48    GND @T6G_MB_LIB.T6G(SCH_1):GND   I143 @T6G_MB_LIB.T6G(SCH_1):PAGE106
    50    GND @T6G_MB_LIB.T6G(SCH_1):GND   I143 @T6G_MB_LIB.T6G(SCH_1):PAGE106
    52    GND @T6G_MB_LIB.T6G(SCH_1):GND   I143 @T6G_MB_LIB.T6G(SCH_1):PAGE106
    54    GND @T6G_MB_LIB.T6G(SCH_1):GND   I143 @T6G_MB_LIB.T6G(SCH_1):PAGE106
    57    GND @T6G_MB_LIB.T6G(SCH_1):GND   I143 @T6G_MB_LIB.T6G(SCH_1):PAGE106
    59    GND @T6G_MB_LIB.T6G(SCH_1):GND   I143 @T6G_MB_LIB.T6G(SCH_1):PAGE106
    61    GND @T6G_MB_LIB.T6G(SCH_1):GND   I143 @T6G_MB_LIB.T6G(SCH_1):PAGE106
    63    GND @T6G_MB_LIB.T6G(SCH_1):GND   I143 @T6G_MB_LIB.T6G(SCH_1):PAGE106
    65    GND @T6G_MB_LIB.T6G(SCH_1):GND   I143 @T6G_MB_LIB.T6G(SCH_1):PAGE106
    67    GND @T6G_MB_LIB.T6G(SCH_1):GND   I143 @T6G_MB_LIB.T6G(SCH_1):PAGE106
    69    GND @T6G_MB_LIB.T6G(SCH_1):GND   I143 @T6G_MB_LIB.T6G(SCH_1):PAGE106
    71    GND @T6G_MB_LIB.T6G(SCH_1):GND   I143 @T6G_MB_LIB.T6G(SCH_1):PAGE106
    73    GND @T6G_MB_LIB.T6G(SCH_1):GND   I143 @T6G_MB_LIB.T6G(SCH_1):PAGE106
    75    GND @T6G_MB_LIB.T6G(SCH_1):GND   I143 @T6G_MB_LIB.T6G(SCH_1):PAGE106
    77    GND @T6G_MB_LIB.T6G(SCH_1):GND   I143 @T6G_MB_LIB.T6G(SCH_1):PAGE106
    79    GND @T6G_MB_LIB.T6G(SCH_1):GND   I143 @T6G_MB_LIB.T6G(SCH_1):PAGE106
    81    GND @T6G_MB_LIB.T6G(SCH_1):GND   I143 @T6G_MB_LIB.T6G(SCH_1):PAGE106
    83    GND @T6G_MB_LIB.T6G(SCH_1):GND   I143 @T6G_MB_LIB.T6G(SCH_1):PAGE106
    85    GND @T6G_MB_LIB.T6G(SCH_1):GND   I143 @T6G_MB_LIB.T6G(SCH_1):PAGE106
    88    GND @T6G_MB_LIB.T6G(SCH_1):GND   I143 @T6G_MB_LIB.T6G(SCH_1):PAGE106
    90    GND @T6G_MB_LIB.T6G(SCH_1):GND   I143 @T6G_MB_LIB.T6G(SCH_1):PAGE106
    92    GND @T6G_MB_LIB.T6G(SCH_1):GND   I143 @T6G_MB_LIB.T6G(SCH_1):PAGE106
    95    GND @T6G_MB_LIB.T6G(SCH_1):GND   I143 @T6G_MB_LIB.T6G(SCH_1):PAGE106
    97    GND @T6G_MB_LIB.T6G(SCH_1):GND   I143 @T6G_MB_LIB.T6G(SCH_1):PAGE106
    99    GND @T6G_MB_LIB.T6G(SCH_1):GND   I143 @T6G_MB_LIB.T6G(SCH_1):PAGE106
   101    GND @T6G_MB_LIB.T6G(SCH_1):GND   I143 @T6G_MB_LIB.T6G(SCH_1):PAGE106
   103    GND @T6G_MB_LIB.T6G(SCH_1):GND   I143 @T6G_MB_LIB.T6G(SCH_1):PAGE106
   106    GND @T6G_MB_LIB.T6G(SCH_1):GND   I143 @T6G_MB_LIB.T6G(SCH_1):PAGE106
   108    GND @T6G_MB_LIB.T6G(SCH_1):GND   I143 @T6G_MB_LIB.T6G(SCH_1):PAGE106
   110    GND @T6G_MB_LIB.T6G(SCH_1):GND   I143 @T6G_MB_LIB.T6G(SCH_1):PAGE106
   112    GND @T6G_MB_LIB.T6G(SCH_1):GND   I143 @T6G_MB_LIB.T6G(SCH_1):PAGE106
   114    GND @T6G_MB_LIB.T6G(SCH_1):GND   I143 @T6G_MB_LIB.T6G(SCH_1):PAGE106
   117    GND @T6G_MB_LIB.T6G(SCH_1):GND   I143 @T6G_MB_LIB.T6G(SCH_1):PAGE106
   119    GND @T6G_MB_LIB.T6G(SCH_1):GND   I143 @T6G_MB_LIB.T6G(SCH_1):PAGE106
   121    GND @T6G_MB_LIB.T6G(SCH_1):GND   I143 @T6G_MB_LIB.T6G(SCH_1):PAGE106
   123    GND @T6G_MB_LIB.T6G(SCH_1):GND   I143 @T6G_MB_LIB.T6G(SCH_1):PAGE106
   125    GND @T6G_MB_LIB.T6G(SCH_1):GND   I143 @T6G_MB_LIB.T6G(SCH_1):PAGE106
   128    GND @T6G_MB_LIB.T6G(SCH_1):GND   I143 @T6G_MB_LIB.T6G(SCH_1):PAGE106
   130    GND @T6G_MB_LIB.T6G(SCH_1):GND   I143 @T6G_MB_LIB.T6G(SCH_1):PAGE106
   134    GND @T6G_MB_LIB.T6G(SCH_1):GND   I143 @T6G_MB_LIB.T6G(SCH_1):PAGE106
   143    GND @T6G_MB_LIB.T6G(SCH_1):GND   I143 @T6G_MB_LIB.T6G(SCH_1):PAGE106
   151    GND @T6G_MB_LIB.T6G(SCH_1):GND   I143 @T6G_MB_LIB.T6G(SCH_1):PAGE106
   153    GND @T6G_MB_LIB.T6G(SCH_1):GND   I143 @T6G_MB_LIB.T6G(SCH_1):PAGE106
   155    GND @T6G_MB_LIB.T6G(SCH_1):GND   I143 @T6G_MB_LIB.T6G(SCH_1):PAGE106
   158    GND @T6G_MB_LIB.T6G(SCH_1):GND   I143 @T6G_MB_LIB.T6G(SCH_1):PAGE106
   160    GND @T6G_MB_LIB.T6G(SCH_1):GND   I143 @T6G_MB_LIB.T6G(SCH_1):PAGE106
   162    GND @T6G_MB_LIB.T6G(SCH_1):GND   I143 @T6G_MB_LIB.T6G(SCH_1):PAGE106
   164    GND @T6G_MB_LIB.T6G(SCH_1):GND   I143 @T6G_MB_LIB.T6G(SCH_1):PAGE106
   166    GND @T6G_MB_LIB.T6G(SCH_1):GND   I143 @T6G_MB_LIB.T6G(SCH_1):PAGE106
   169    GND @T6G_MB_LIB.T6G(SCH_1):GND   I143 @T6G_MB_LIB.T6G(SCH_1):PAGE106
   171    GND @T6G_MB_LIB.T6G(SCH_1):GND   I143 @T6G_MB_LIB.T6G(SCH_1):PAGE106
   173    GND @T6G_MB_LIB.T6G(SCH_1):GND   I143 @T6G_MB_LIB.T6G(SCH_1):PAGE106
   175    GND @T6G_MB_LIB.T6G(SCH_1):GND   I143 @T6G_MB_LIB.T6G(SCH_1):PAGE106
   177    GND @T6G_MB_LIB.T6G(SCH_1):GND   I143 @T6G_MB_LIB.T6G(SCH_1):PAGE106
   180    GND @T6G_MB_LIB.T6G(SCH_1):GND   I143 @T6G_MB_LIB.T6G(SCH_1):PAGE106
   182    GND @T6G_MB_LIB.T6G(SCH_1):GND   I143 @T6G_MB_LIB.T6G(SCH_1):PAGE106
   184    GND @T6G_MB_LIB.T6G(SCH_1):GND   I143 @T6G_MB_LIB.T6G(SCH_1):PAGE106
   186    GND @T6G_MB_LIB.T6G(SCH_1):GND   I143 @T6G_MB_LIB.T6G(SCH_1):PAGE106
   188    GND @T6G_MB_LIB.T6G(SCH_1):GND   I143 @T6G_MB_LIB.T6G(SCH_1):PAGE106
   191    GND @T6G_MB_LIB.T6G(SCH_1):GND   I143 @T6G_MB_LIB.T6G(SCH_1):PAGE106
   193    GND @T6G_MB_LIB.T6G(SCH_1):GND   I143 @T6G_MB_LIB.T6G(SCH_1):PAGE106
   195    GND @T6G_MB_LIB.T6G(SCH_1):GND   I143 @T6G_MB_LIB.T6G(SCH_1):PAGE106
   197    GND @T6G_MB_LIB.T6G(SCH_1):GND   I143 @T6G_MB_LIB.T6G(SCH_1):PAGE106
   199    GND @T6G_MB_LIB.T6G(SCH_1):GND   I143 @T6G_MB_LIB.T6G(SCH_1):PAGE106
   202    GND @T6G_MB_LIB.T6G(SCH_1):GND   I143 @T6G_MB_LIB.T6G(SCH_1):PAGE106
   204    GND @T6G_MB_LIB.T6G(SCH_1):GND   I143 @T6G_MB_LIB.T6G(SCH_1):PAGE106
   206    GND @T6G_MB_LIB.T6G(SCH_1):GND   I143 @T6G_MB_LIB.T6G(SCH_1):PAGE106
   208    GND @T6G_MB_LIB.T6G(SCH_1):GND   I143 @T6G_MB_LIB.T6G(SCH_1):PAGE106
   210    GND @T6G_MB_LIB.T6G(SCH_1):GND   I143 @T6G_MB_LIB.T6G(SCH_1):PAGE106
   212    GND @T6G_MB_LIB.T6G(SCH_1):GND   I143 @T6G_MB_LIB.T6G(SCH_1):PAGE106
   214    GND @T6G_MB_LIB.T6G(SCH_1):GND   I143 @T6G_MB_LIB.T6G(SCH_1):PAGE106
   216    GND @T6G_MB_LIB.T6G(SCH_1):GND   I143 @T6G_MB_LIB.T6G(SCH_1):PAGE106
   219    GND @T6G_MB_LIB.T6G(SCH_1):GND   I143 @T6G_MB_LIB.T6G(SCH_1):PAGE106
   222    GND @T6G_MB_LIB.T6G(SCH_1):GND   I143 @T6G_MB_LIB.T6G(SCH_1):PAGE106
   224    GND @T6G_MB_LIB.T6G(SCH_1):GND   I143 @T6G_MB_LIB.T6G(SCH_1):PAGE106
   226    GND @T6G_MB_LIB.T6G(SCH_1):GND   I143 @T6G_MB_LIB.T6G(SCH_1):PAGE106
   228    GND @T6G_MB_LIB.T6G(SCH_1):GND   I143 @T6G_MB_LIB.T6G(SCH_1):PAGE106
   233    GND @T6G_MB_LIB.T6G(SCH_1):GND   I143 @T6G_MB_LIB.T6G(SCH_1):PAGE106
   237    GND @T6G_MB_LIB.T6G(SCH_1):GND   I143 @T6G_MB_LIB.T6G(SCH_1):PAGE106
   242    GND @T6G_MB_LIB.T6G(SCH_1):GND   I143 @T6G_MB_LIB.T6G(SCH_1):PAGE106
   244    GND @T6G_MB_LIB.T6G(SCH_1):GND   I143 @T6G_MB_LIB.T6G(SCH_1):PAGE106
   246    GND @T6G_MB_LIB.T6G(SCH_1):GND   I143 @T6G_MB_LIB.T6G(SCH_1):PAGE106
   248    GND @T6G_MB_LIB.T6G(SCH_1):GND   I143 @T6G_MB_LIB.T6G(SCH_1):PAGE106
   251    GND @T6G_MB_LIB.T6G(SCH_1):GND   I143 @T6G_MB_LIB.T6G(SCH_1):PAGE106
   253    GND @T6G_MB_LIB.T6G(SCH_1):GND   I143 @T6G_MB_LIB.T6G(SCH_1):PAGE106
   255    GND @T6G_MB_LIB.T6G(SCH_1):GND   I143 @T6G_MB_LIB.T6G(SCH_1):PAGE106
   257    GND @T6G_MB_LIB.T6G(SCH_1):GND   I143 @T6G_MB_LIB.T6G(SCH_1):PAGE106
   259    GND @T6G_MB_LIB.T6G(SCH_1):GND   I143 @T6G_MB_LIB.T6G(SCH_1):PAGE106
   262    GND @T6G_MB_LIB.T6G(SCH_1):GND   I143 @T6G_MB_LIB.T6G(SCH_1):PAGE106
   264    GND @T6G_MB_LIB.T6G(SCH_1):GND   I143 @T6G_MB_LIB.T6G(SCH_1):PAGE106
   266    GND @T6G_MB_LIB.T6G(SCH_1):GND   I143 @T6G_MB_LIB.T6G(SCH_1):PAGE106
   268    GND @T6G_MB_LIB.T6G(SCH_1):GND   I143 @T6G_MB_LIB.T6G(SCH_1):PAGE106
   270    GND @T6G_MB_LIB.T6G(SCH_1):GND   I143 @T6G_MB_LIB.T6G(SCH_1):PAGE106
   273    GND @T6G_MB_LIB.T6G(SCH_1):GND   I143 @T6G_MB_LIB.T6G(SCH_1):PAGE106
   275    GND @T6G_MB_LIB.T6G(SCH_1):GND   I143 @T6G_MB_LIB.T6G(SCH_1):PAGE106
   277    GND @T6G_MB_LIB.T6G(SCH_1):GND   I143 @T6G_MB_LIB.T6G(SCH_1):PAGE106
   279    GND @T6G_MB_LIB.T6G(SCH_1):GND   I143 @T6G_MB_LIB.T6G(SCH_1):PAGE106
   281    GND @T6G_MB_LIB.T6G(SCH_1):GND   I143 @T6G_MB_LIB.T6G(SCH_1):PAGE106
   284    GND @T6G_MB_LIB.T6G(SCH_1):GND   I143 @T6G_MB_LIB.T6G(SCH_1):PAGE106
   286    GND @T6G_MB_LIB.T6G(SCH_1):GND   I143 @T6G_MB_LIB.T6G(SCH_1):PAGE106
   288    GND @T6G_MB_LIB.T6G(SCH_1):GND   I143 @T6G_MB_LIB.T6G(SCH_1):PAGE106
     1 P12V_MEM_CPU1 @T6G_MB_LIB.T6G(SCH_1):P12V_MEM_CPU1   I143 @T6G_MB_LIB.T6G(SCH_1):PAGE106
   145 P12V_MEM_CPU1 @T6G_MB_LIB.T6G(SCH_1):P12V_MEM_CPU1   I143 @T6G_MB_LIB.T6G(SCH_1):PAGE106
   146 P12V_MEM_CPU1 @T6G_MB_LIB.T6G(SCH_1):P12V_MEM_CPU1   I143 @T6G_MB_LIB.T6G(SCH_1):PAGE106
   230    GND @T6G_MB_LIB.T6G(SCH_1):GND   I143 @T6G_MB_LIB.T6G(SCH_1):PAGE106
   235    GND @T6G_MB_LIB.T6G(SCH_1):GND   I143 @T6G_MB_LIB.T6G(SCH_1):PAGE106
   240    GND @T6G_MB_LIB.T6G(SCH_1):GND   I143 @T6G_MB_LIB.T6G(SCH_1):PAGE106
   132    GND @T6G_MB_LIB.T6G(SCH_1):GND   I143 @T6G_MB_LIB.T6G(SCH_1):PAGE106
   136    GND @T6G_MB_LIB.T6G(SCH_1):GND   I143 @T6G_MB_LIB.T6G(SCH_1):PAGE106
   139    GND @T6G_MB_LIB.T6G(SCH_1):GND   I143 @T6G_MB_LIB.T6G(SCH_1):PAGE106
   141    GND @T6G_MB_LIB.T6G(SCH_1):GND   I143 @T6G_MB_LIB.T6G(SCH_1):PAGE106
    G1    GND @T6G_MB_LIB.T6G(SCH_1):GND   I143 @T6G_MB_LIB.T6G(SCH_1):PAGE106
    G2    GND @T6G_MB_LIB.T6G(SCH_1):GND   I143 @T6G_MB_LIB.T6G(SCH_1):PAGE106
    G3    GND @T6G_MB_LIB.T6G(SCH_1):GND   I143 @T6G_MB_LIB.T6G(SCH_1):PAGE106

 J30 SCONN288_DDR506112002KQ-SCONN288_DDR506112002KQ,SMA
     3 P3V3_AUX @T6G_MB_LIB.T6G(SCH_1):P3V3_AUX    I52 @T6G_MB_LIB.T6G(SCH_1):PAGE100
     2     NC     NC    I52 @T6G_MB_LIB.T6G(SCH_1):PAGE100
   144     NC     NC    I52 @T6G_MB_LIB.T6G(SCH_1):PAGE100
   149     NC     NC    I52 @T6G_MB_LIB.T6G(SCH_1):PAGE100
   150     NC     NC    I52 @T6G_MB_LIB.T6G(SCH_1):PAGE100
   220     NC     NC    I52 @T6G_MB_LIB.T6G(SCH_1):PAGE100
   231     NC     NC    I52 @T6G_MB_LIB.T6G(SCH_1):PAGE100
   232     NC     NC    I52 @T6G_MB_LIB.T6G(SCH_1):PAGE100
   207 M_D_CPU1_RESET_N @T6G_MB_LIB.T6G(SCH_1):M_D_CPU1_RESET_N    I52 @T6G_MB_LIB.T6G(SCH_1):PAGE100
   147 PWRGD_CHD_CPU1_DIMM @T6G_MB_LIB.T6G(SCH_1):PWRGD_CHD_CPU1_DIMM    I52 @T6G_MB_LIB.T6G(SCH_1):PAGE100
   227 M_D_CPU1_SB_PAR @T6G_MB_LIB.T6G(SCH_1):M_D_CPU1_SB_PAR    I52 @T6G_MB_LIB.T6G(SCH_1):PAGE100
    74 M_D_CPU1_SA_PAR @T6G_MB_LIB.T6G(SCH_1):M_D_CPU1_SA_PAR    I52 @T6G_MB_LIB.T6G(SCH_1):PAGE100
    87 M_D_CPU1_SB_RSP<0> @T6G_MB_LIB.T6G(SCH_1):M_D_CPU1_SB_RSP(0)    I52 @T6G_MB_LIB.T6G(SCH_1):PAGE100
    86 M_D_CPU1_SA_RSP<0> @T6G_MB_LIB.T6G(SCH_1):M_D_CPU1_SA_RSP(0)    I52 @T6G_MB_LIB.T6G(SCH_1):PAGE100
     5 I3C_SPD_DDRD_CPU1_SDA @T6G_MB_LIB.T6G(SCH_1):I3C_SPD_DDRD_CPU1_SDA    I52 @T6G_MB_LIB.T6G(SCH_1):PAGE100
     4 I3C_SPD_DDRD_CPU1_SCL @T6G_MB_LIB.T6G(SCH_1):I3C_SPD_DDRD_CPU1_SCL    I52 @T6G_MB_LIB.T6G(SCH_1):PAGE100
   148 PD_CHD_CPU1_DIMM_SAA @T6G_MB_LIB.T6G(SCH_1):PD_CHD_CPU1_DIMM_SAA    I52 @T6G_MB_LIB.T6G(SCH_1):PAGE100
   100 M_D_CPU1_SB_DQ<0> @T6G_MB_LIB.T6G(SCH_1):M_D_CPU1_SB_DQ(0)    I52 @T6G_MB_LIB.T6G(SCH_1):PAGE100
   102 M_D_CPU1_SB_DQ<1> @T6G_MB_LIB.T6G(SCH_1):M_D_CPU1_SB_DQ(1)    I52 @T6G_MB_LIB.T6G(SCH_1):PAGE100
   245 M_D_CPU1_SB_DQ<2> @T6G_MB_LIB.T6G(SCH_1):M_D_CPU1_SB_DQ(2)    I52 @T6G_MB_LIB.T6G(SCH_1):PAGE100
   247 M_D_CPU1_SB_DQ<3> @T6G_MB_LIB.T6G(SCH_1):M_D_CPU1_SB_DQ(3)    I52 @T6G_MB_LIB.T6G(SCH_1):PAGE100
   107 M_D_CPU1_SB_DQ<4> @T6G_MB_LIB.T6G(SCH_1):M_D_CPU1_SB_DQ(4)    I52 @T6G_MB_LIB.T6G(SCH_1):PAGE100
   109 M_D_CPU1_SB_DQ<5> @T6G_MB_LIB.T6G(SCH_1):M_D_CPU1_SB_DQ(5)    I52 @T6G_MB_LIB.T6G(SCH_1):PAGE100
   252 M_D_CPU1_SB_DQ<6> @T6G_MB_LIB.T6G(SCH_1):M_D_CPU1_SB_DQ(6)    I52 @T6G_MB_LIB.T6G(SCH_1):PAGE100
   254 M_D_CPU1_SB_DQ<7> @T6G_MB_LIB.T6G(SCH_1):M_D_CPU1_SB_DQ(7)    I52 @T6G_MB_LIB.T6G(SCH_1):PAGE100
   111 M_D_CPU1_SB_DQ<8> @T6G_MB_LIB.T6G(SCH_1):M_D_CPU1_SB_DQ(8)    I52 @T6G_MB_LIB.T6G(SCH_1):PAGE100
   113 M_D_CPU1_SB_DQ<9> @T6G_MB_LIB.T6G(SCH_1):M_D_CPU1_SB_DQ(9)    I52 @T6G_MB_LIB.T6G(SCH_1):PAGE100
   256 M_D_CPU1_SB_DQ<10> @T6G_MB_LIB.T6G(SCH_1):M_D_CPU1_SB_DQ(10)    I52 @T6G_MB_LIB.T6G(SCH_1):PAGE100
   258 M_D_CPU1_SB_DQ<11> @T6G_MB_LIB.T6G(SCH_1):M_D_CPU1_SB_DQ(11)    I52 @T6G_MB_LIB.T6G(SCH_1):PAGE100
   118 M_D_CPU1_SB_DQ<12> @T6G_MB_LIB.T6G(SCH_1):M_D_CPU1_SB_DQ(12)    I52 @T6G_MB_LIB.T6G(SCH_1):PAGE100
   120 M_D_CPU1_SB_DQ<13> @T6G_MB_LIB.T6G(SCH_1):M_D_CPU1_SB_DQ(13)    I52 @T6G_MB_LIB.T6G(SCH_1):PAGE100
   263 M_D_CPU1_SB_DQ<14> @T6G_MB_LIB.T6G(SCH_1):M_D_CPU1_SB_DQ(14)    I52 @T6G_MB_LIB.T6G(SCH_1):PAGE100
   265 M_D_CPU1_SB_DQ<15> @T6G_MB_LIB.T6G(SCH_1):M_D_CPU1_SB_DQ(15)    I52 @T6G_MB_LIB.T6G(SCH_1):PAGE100
   122 M_D_CPU1_SB_DQ<16> @T6G_MB_LIB.T6G(SCH_1):M_D_CPU1_SB_DQ(16)    I52 @T6G_MB_LIB.T6G(SCH_1):PAGE100
   124 M_D_CPU1_SB_DQ<17> @T6G_MB_LIB.T6G(SCH_1):M_D_CPU1_SB_DQ(17)    I52 @T6G_MB_LIB.T6G(SCH_1):PAGE100
   267 M_D_CPU1_SB_DQ<18> @T6G_MB_LIB.T6G(SCH_1):M_D_CPU1_SB_DQ(18)    I52 @T6G_MB_LIB.T6G(SCH_1):PAGE100
   269 M_D_CPU1_SB_DQ<19> @T6G_MB_LIB.T6G(SCH_1):M_D_CPU1_SB_DQ(19)    I52 @T6G_MB_LIB.T6G(SCH_1):PAGE100
   129 M_D_CPU1_SB_DQ<20> @T6G_MB_LIB.T6G(SCH_1):M_D_CPU1_SB_DQ(20)    I52 @T6G_MB_LIB.T6G(SCH_1):PAGE100
   131 M_D_CPU1_SB_DQ<21> @T6G_MB_LIB.T6G(SCH_1):M_D_CPU1_SB_DQ(21)    I52 @T6G_MB_LIB.T6G(SCH_1):PAGE100
   274 M_D_CPU1_SB_DQ<22> @T6G_MB_LIB.T6G(SCH_1):M_D_CPU1_SB_DQ(22)    I52 @T6G_MB_LIB.T6G(SCH_1):PAGE100
   276 M_D_CPU1_SB_DQ<23> @T6G_MB_LIB.T6G(SCH_1):M_D_CPU1_SB_DQ(23)    I52 @T6G_MB_LIB.T6G(SCH_1):PAGE100
   133 M_D_CPU1_SB_DQ<24> @T6G_MB_LIB.T6G(SCH_1):M_D_CPU1_SB_DQ(24)    I52 @T6G_MB_LIB.T6G(SCH_1):PAGE100
   135 M_D_CPU1_SB_DQ<25> @T6G_MB_LIB.T6G(SCH_1):M_D_CPU1_SB_DQ(25)    I52 @T6G_MB_LIB.T6G(SCH_1):PAGE100
   278 M_D_CPU1_SB_DQ<26> @T6G_MB_LIB.T6G(SCH_1):M_D_CPU1_SB_DQ(26)    I52 @T6G_MB_LIB.T6G(SCH_1):PAGE100
   280 M_D_CPU1_SB_DQ<27> @T6G_MB_LIB.T6G(SCH_1):M_D_CPU1_SB_DQ(27)    I52 @T6G_MB_LIB.T6G(SCH_1):PAGE100
   140 M_D_CPU1_SB_DQ<28> @T6G_MB_LIB.T6G(SCH_1):M_D_CPU1_SB_DQ(28)    I52 @T6G_MB_LIB.T6G(SCH_1):PAGE100
   142 M_D_CPU1_SB_DQ<29> @T6G_MB_LIB.T6G(SCH_1):M_D_CPU1_SB_DQ(29)    I52 @T6G_MB_LIB.T6G(SCH_1):PAGE100
   285 M_D_CPU1_SB_DQ<30> @T6G_MB_LIB.T6G(SCH_1):M_D_CPU1_SB_DQ(30)    I52 @T6G_MB_LIB.T6G(SCH_1):PAGE100
   287 M_D_CPU1_SB_DQ<31> @T6G_MB_LIB.T6G(SCH_1):M_D_CPU1_SB_DQ(31)    I52 @T6G_MB_LIB.T6G(SCH_1):PAGE100
     7 M_D_CPU1_SA_DQ<0> @T6G_MB_LIB.T6G(SCH_1):M_D_CPU1_SA_DQ(0)    I52 @T6G_MB_LIB.T6G(SCH_1):PAGE100
     9 M_D_CPU1_SA_DQ<1> @T6G_MB_LIB.T6G(SCH_1):M_D_CPU1_SA_DQ(1)    I52 @T6G_MB_LIB.T6G(SCH_1):PAGE100
   152 M_D_CPU1_SA_DQ<2> @T6G_MB_LIB.T6G(SCH_1):M_D_CPU1_SA_DQ(2)    I52 @T6G_MB_LIB.T6G(SCH_1):PAGE100
   154 M_D_CPU1_SA_DQ<3> @T6G_MB_LIB.T6G(SCH_1):M_D_CPU1_SA_DQ(3)    I52 @T6G_MB_LIB.T6G(SCH_1):PAGE100
    14 M_D_CPU1_SA_DQ<4> @T6G_MB_LIB.T6G(SCH_1):M_D_CPU1_SA_DQ(4)    I52 @T6G_MB_LIB.T6G(SCH_1):PAGE100
    16 M_D_CPU1_SA_DQ<5> @T6G_MB_LIB.T6G(SCH_1):M_D_CPU1_SA_DQ(5)    I52 @T6G_MB_LIB.T6G(SCH_1):PAGE100
   159 M_D_CPU1_SA_DQ<6> @T6G_MB_LIB.T6G(SCH_1):M_D_CPU1_SA_DQ(6)    I52 @T6G_MB_LIB.T6G(SCH_1):PAGE100
   161 M_D_CPU1_SA_DQ<7> @T6G_MB_LIB.T6G(SCH_1):M_D_CPU1_SA_DQ(7)    I52 @T6G_MB_LIB.T6G(SCH_1):PAGE100
    18 M_D_CPU1_SA_DQ<8> @T6G_MB_LIB.T6G(SCH_1):M_D_CPU1_SA_DQ(8)    I52 @T6G_MB_LIB.T6G(SCH_1):PAGE100
    20 M_D_CPU1_SA_DQ<9> @T6G_MB_LIB.T6G(SCH_1):M_D_CPU1_SA_DQ(9)    I52 @T6G_MB_LIB.T6G(SCH_1):PAGE100
   163 M_D_CPU1_SA_DQ<10> @T6G_MB_LIB.T6G(SCH_1):M_D_CPU1_SA_DQ(10)    I52 @T6G_MB_LIB.T6G(SCH_1):PAGE100
   165 M_D_CPU1_SA_DQ<11> @T6G_MB_LIB.T6G(SCH_1):M_D_CPU1_SA_DQ(11)    I52 @T6G_MB_LIB.T6G(SCH_1):PAGE100
    25 M_D_CPU1_SA_DQ<12> @T6G_MB_LIB.T6G(SCH_1):M_D_CPU1_SA_DQ(12)    I52 @T6G_MB_LIB.T6G(SCH_1):PAGE100
    27 M_D_CPU1_SA_DQ<13> @T6G_MB_LIB.T6G(SCH_1):M_D_CPU1_SA_DQ(13)    I52 @T6G_MB_LIB.T6G(SCH_1):PAGE100
   170 M_D_CPU1_SA_DQ<14> @T6G_MB_LIB.T6G(SCH_1):M_D_CPU1_SA_DQ(14)    I52 @T6G_MB_LIB.T6G(SCH_1):PAGE100
   172 M_D_CPU1_SA_DQ<15> @T6G_MB_LIB.T6G(SCH_1):M_D_CPU1_SA_DQ(15)    I52 @T6G_MB_LIB.T6G(SCH_1):PAGE100
    29 M_D_CPU1_SA_DQ<16> @T6G_MB_LIB.T6G(SCH_1):M_D_CPU1_SA_DQ(16)    I52 @T6G_MB_LIB.T6G(SCH_1):PAGE100
    31 M_D_CPU1_SA_DQ<17> @T6G_MB_LIB.T6G(SCH_1):M_D_CPU1_SA_DQ(17)    I52 @T6G_MB_LIB.T6G(SCH_1):PAGE100
   174 M_D_CPU1_SA_DQ<18> @T6G_MB_LIB.T6G(SCH_1):M_D_CPU1_SA_DQ(18)    I52 @T6G_MB_LIB.T6G(SCH_1):PAGE100
   176 M_D_CPU1_SA_DQ<19> @T6G_MB_LIB.T6G(SCH_1):M_D_CPU1_SA_DQ(19)    I52 @T6G_MB_LIB.T6G(SCH_1):PAGE100
    36 M_D_CPU1_SA_DQ<20> @T6G_MB_LIB.T6G(SCH_1):M_D_CPU1_SA_DQ(20)    I52 @T6G_MB_LIB.T6G(SCH_1):PAGE100
    38 M_D_CPU1_SA_DQ<21> @T6G_MB_LIB.T6G(SCH_1):M_D_CPU1_SA_DQ(21)    I52 @T6G_MB_LIB.T6G(SCH_1):PAGE100
   181 M_D_CPU1_SA_DQ<22> @T6G_MB_LIB.T6G(SCH_1):M_D_CPU1_SA_DQ(22)    I52 @T6G_MB_LIB.T6G(SCH_1):PAGE100
   183 M_D_CPU1_SA_DQ<23> @T6G_MB_LIB.T6G(SCH_1):M_D_CPU1_SA_DQ(23)    I52 @T6G_MB_LIB.T6G(SCH_1):PAGE100
    40 M_D_CPU1_SA_DQ<24> @T6G_MB_LIB.T6G(SCH_1):M_D_CPU1_SA_DQ(24)    I52 @T6G_MB_LIB.T6G(SCH_1):PAGE100
    42 M_D_CPU1_SA_DQ<25> @T6G_MB_LIB.T6G(SCH_1):M_D_CPU1_SA_DQ(25)    I52 @T6G_MB_LIB.T6G(SCH_1):PAGE100
   185 M_D_CPU1_SA_DQ<26> @T6G_MB_LIB.T6G(SCH_1):M_D_CPU1_SA_DQ(26)    I52 @T6G_MB_LIB.T6G(SCH_1):PAGE100
   187 M_D_CPU1_SA_DQ<27> @T6G_MB_LIB.T6G(SCH_1):M_D_CPU1_SA_DQ(27)    I52 @T6G_MB_LIB.T6G(SCH_1):PAGE100
    47 M_D_CPU1_SA_DQ<28> @T6G_MB_LIB.T6G(SCH_1):M_D_CPU1_SA_DQ(28)    I52 @T6G_MB_LIB.T6G(SCH_1):PAGE100
    49 M_D_CPU1_SA_DQ<29> @T6G_MB_LIB.T6G(SCH_1):M_D_CPU1_SA_DQ(29)    I52 @T6G_MB_LIB.T6G(SCH_1):PAGE100
   192 M_D_CPU1_SA_DQ<30> @T6G_MB_LIB.T6G(SCH_1):M_D_CPU1_SA_DQ(30)    I52 @T6G_MB_LIB.T6G(SCH_1):PAGE100
   229 M_D_CPU1_SB_CS_N<1> @T6G_MB_LIB.T6G(SCH_1):M_D_CPU1_SB_CS_N(1)    I52 @T6G_MB_LIB.T6G(SCH_1):PAGE100
   209 M_D_CPU1_SA_CS_N<1> @T6G_MB_LIB.T6G(SCH_1):M_D_CPU1_SA_CS_N(1)    I52 @T6G_MB_LIB.T6G(SCH_1):PAGE100
    84 M_D_CPU1_SB_CS_N<0> @T6G_MB_LIB.T6G(SCH_1):M_D_CPU1_SB_CS_N(0)    I52 @T6G_MB_LIB.T6G(SCH_1):PAGE100
    64 M_D_CPU1_SA_CS_N<0> @T6G_MB_LIB.T6G(SCH_1):M_D_CPU1_SA_CS_N(0)    I52 @T6G_MB_LIB.T6G(SCH_1):PAGE100
   217 M_D_CPU1_CLK_DP<0> @T6G_MB_LIB.T6G(SCH_1):M_D_CPU1_CLK_DP(0)    I52 @T6G_MB_LIB.T6G(SCH_1):PAGE100
   218 M_D_CPU1_CLK_DN<0> @T6G_MB_LIB.T6G(SCH_1):M_D_CPU1_CLK_DN(0)    I52 @T6G_MB_LIB.T6G(SCH_1):PAGE100
    96 M_D_CPU1_SB_CB<0> @T6G_MB_LIB.T6G(SCH_1):M_D_CPU1_SB_CB(0)    I52 @T6G_MB_LIB.T6G(SCH_1):PAGE100
    98 M_D_CPU1_SB_CB<1> @T6G_MB_LIB.T6G(SCH_1):M_D_CPU1_SB_CB(1)    I52 @T6G_MB_LIB.T6G(SCH_1):PAGE100
   241 M_D_CPU1_SB_CB<2> @T6G_MB_LIB.T6G(SCH_1):M_D_CPU1_SB_CB(2)    I52 @T6G_MB_LIB.T6G(SCH_1):PAGE100
   243 M_D_CPU1_SB_CB<3> @T6G_MB_LIB.T6G(SCH_1):M_D_CPU1_SB_CB(3)    I52 @T6G_MB_LIB.T6G(SCH_1):PAGE100
    89 M_D_CPU1_SB_CB<4> @T6G_MB_LIB.T6G(SCH_1):M_D_CPU1_SB_CB(4)    I52 @T6G_MB_LIB.T6G(SCH_1):PAGE100
    91 M_D_CPU1_SB_CB<5> @T6G_MB_LIB.T6G(SCH_1):M_D_CPU1_SB_CB(5)    I52 @T6G_MB_LIB.T6G(SCH_1):PAGE100
   234 M_D_CPU1_SB_CB<6> @T6G_MB_LIB.T6G(SCH_1):M_D_CPU1_SB_CB(6)    I52 @T6G_MB_LIB.T6G(SCH_1):PAGE100
    51 M_D_CPU1_SA_CB<0> @T6G_MB_LIB.T6G(SCH_1):M_D_CPU1_SA_CB(0)    I52 @T6G_MB_LIB.T6G(SCH_1):PAGE100
   196 M_D_CPU1_SA_CB<2> @T6G_MB_LIB.T6G(SCH_1):M_D_CPU1_SA_CB(2)    I52 @T6G_MB_LIB.T6G(SCH_1):PAGE100
   198 M_D_CPU1_SA_CB<3> @T6G_MB_LIB.T6G(SCH_1):M_D_CPU1_SA_CB(3)    I52 @T6G_MB_LIB.T6G(SCH_1):PAGE100
    60 M_D_CPU1_SA_CB<5> @T6G_MB_LIB.T6G(SCH_1):M_D_CPU1_SA_CB(5)    I52 @T6G_MB_LIB.T6G(SCH_1):PAGE100
   203 M_D_CPU1_SA_CB<6> @T6G_MB_LIB.T6G(SCH_1):M_D_CPU1_SA_CB(6)    I52 @T6G_MB_LIB.T6G(SCH_1):PAGE100
    82 M_D_CPU1_SB_CA<6> @T6G_MB_LIB.T6G(SCH_1):M_D_CPU1_SB_CA(6)    I52 @T6G_MB_LIB.T6G(SCH_1):PAGE100
    72 M_D_CPU1_SA_CA<6> @T6G_MB_LIB.T6G(SCH_1):M_D_CPU1_SA_CA(6)    I52 @T6G_MB_LIB.T6G(SCH_1):PAGE100
   225 M_D_CPU1_SB_CA<5> @T6G_MB_LIB.T6G(SCH_1):M_D_CPU1_SB_CA(5)    I52 @T6G_MB_LIB.T6G(SCH_1):PAGE100
   215 M_D_CPU1_SA_CA<5> @T6G_MB_LIB.T6G(SCH_1):M_D_CPU1_SA_CA(5)    I52 @T6G_MB_LIB.T6G(SCH_1):PAGE100
    80 M_D_CPU1_SB_CA<4> @T6G_MB_LIB.T6G(SCH_1):M_D_CPU1_SB_CA(4)    I52 @T6G_MB_LIB.T6G(SCH_1):PAGE100
    70 M_D_CPU1_SA_CA<4> @T6G_MB_LIB.T6G(SCH_1):M_D_CPU1_SA_CA(4)    I52 @T6G_MB_LIB.T6G(SCH_1):PAGE100
   223 M_D_CPU1_SB_CA<3> @T6G_MB_LIB.T6G(SCH_1):M_D_CPU1_SB_CA(3)    I52 @T6G_MB_LIB.T6G(SCH_1):PAGE100
   213 M_D_CPU1_SA_CA<3> @T6G_MB_LIB.T6G(SCH_1):M_D_CPU1_SA_CA(3)    I52 @T6G_MB_LIB.T6G(SCH_1):PAGE100
    78 M_D_CPU1_SB_CA<2> @T6G_MB_LIB.T6G(SCH_1):M_D_CPU1_SB_CA(2)    I52 @T6G_MB_LIB.T6G(SCH_1):PAGE100
    68 M_D_CPU1_SA_CA<2> @T6G_MB_LIB.T6G(SCH_1):M_D_CPU1_SA_CA(2)    I52 @T6G_MB_LIB.T6G(SCH_1):PAGE100
   221 M_D_CPU1_SB_CA<1> @T6G_MB_LIB.T6G(SCH_1):M_D_CPU1_SB_CA(1)    I52 @T6G_MB_LIB.T6G(SCH_1):PAGE100
   211 M_D_CPU1_SA_CA<1> @T6G_MB_LIB.T6G(SCH_1):M_D_CPU1_SA_CA(1)    I52 @T6G_MB_LIB.T6G(SCH_1):PAGE100
    76 M_D_CPU1_SB_CA<0> @T6G_MB_LIB.T6G(SCH_1):M_D_CPU1_SB_CA(0)    I52 @T6G_MB_LIB.T6G(SCH_1):PAGE100
    66 M_D_CPU1_SA_CA<0> @T6G_MB_LIB.T6G(SCH_1):M_D_CPU1_SA_CA(0)    I52 @T6G_MB_LIB.T6G(SCH_1):PAGE100
    62 M_D_CPU1_ALERT_N @T6G_MB_LIB.T6G(SCH_1):M_D_CPU1_ALERT_N    I52 @T6G_MB_LIB.T6G(SCH_1):PAGE100
   236 M_D_CPU1_SB_CB<7> @T6G_MB_LIB.T6G(SCH_1):M_D_CPU1_SB_CB(7)    I52 @T6G_MB_LIB.T6G(SCH_1):PAGE100
    53 M_D_CPU1_SA_CB<1> @T6G_MB_LIB.T6G(SCH_1):M_D_CPU1_SA_CB(1)    I52 @T6G_MB_LIB.T6G(SCH_1):PAGE100
    58 M_D_CPU1_SA_CB<4> @T6G_MB_LIB.T6G(SCH_1):M_D_CPU1_SA_CB(4)    I52 @T6G_MB_LIB.T6G(SCH_1):PAGE100
   205 M_D_CPU1_SA_CB<7> @T6G_MB_LIB.T6G(SCH_1):M_D_CPU1_SA_CB(7)    I52 @T6G_MB_LIB.T6G(SCH_1):PAGE100
   194 M_D_CPU1_SA_DQ<31> @T6G_MB_LIB.T6G(SCH_1):M_D_CPU1_SA_DQ(31)    I52 @T6G_MB_LIB.T6G(SCH_1):PAGE100
    93 M_D_CPU1_SB_DQS_DP<9> @T6G_MB_LIB.T6G(SCH_1):M_D_CPU1_SB_DQS_DP(9)   I236 @T6G_MB_LIB.T6G(SCH_1):PAGE100
    94 M_D_CPU1_SB_DQS_DN<9> @T6G_MB_LIB.T6G(SCH_1):M_D_CPU1_SB_DQS_DN(9)   I236 @T6G_MB_LIB.T6G(SCH_1):PAGE100
   201 M_D_CPU1_SA_DQS_DP<9> @T6G_MB_LIB.T6G(SCH_1):M_D_CPU1_SA_DQS_DP(9)   I236 @T6G_MB_LIB.T6G(SCH_1):PAGE100
   200 M_D_CPU1_SA_DQS_DN<9> @T6G_MB_LIB.T6G(SCH_1):M_D_CPU1_SA_DQS_DN(9)   I236 @T6G_MB_LIB.T6G(SCH_1):PAGE100
   190 M_D_CPU1_SA_DQS_DP<8> @T6G_MB_LIB.T6G(SCH_1):M_D_CPU1_SA_DQS_DP(8)   I236 @T6G_MB_LIB.T6G(SCH_1):PAGE100
   189 M_D_CPU1_SA_DQS_DN<8> @T6G_MB_LIB.T6G(SCH_1):M_D_CPU1_SA_DQS_DN(8)   I236 @T6G_MB_LIB.T6G(SCH_1):PAGE100
   271 M_D_CPU1_SB_DQS_DN<7> @T6G_MB_LIB.T6G(SCH_1):M_D_CPU1_SB_DQS_DN(7)   I236 @T6G_MB_LIB.T6G(SCH_1):PAGE100
   179 M_D_CPU1_SA_DQS_DP<7> @T6G_MB_LIB.T6G(SCH_1):M_D_CPU1_SA_DQS_DP(7)   I236 @T6G_MB_LIB.T6G(SCH_1):PAGE100
   261 M_D_CPU1_SB_DQS_DP<6> @T6G_MB_LIB.T6G(SCH_1):M_D_CPU1_SB_DQS_DP(6)   I236 @T6G_MB_LIB.T6G(SCH_1):PAGE100
   260 M_D_CPU1_SB_DQS_DN<6> @T6G_MB_LIB.T6G(SCH_1):M_D_CPU1_SB_DQS_DN(6)   I236 @T6G_MB_LIB.T6G(SCH_1):PAGE100
   167 M_D_CPU1_SA_DQS_DN<6> @T6G_MB_LIB.T6G(SCH_1):M_D_CPU1_SA_DQS_DN(6)   I236 @T6G_MB_LIB.T6G(SCH_1):PAGE100
   250 M_D_CPU1_SB_DQS_DP<5> @T6G_MB_LIB.T6G(SCH_1):M_D_CPU1_SB_DQS_DP(5)   I236 @T6G_MB_LIB.T6G(SCH_1):PAGE100
   249 M_D_CPU1_SB_DQS_DN<5> @T6G_MB_LIB.T6G(SCH_1):M_D_CPU1_SB_DQS_DN(5)   I236 @T6G_MB_LIB.T6G(SCH_1):PAGE100
   157 M_D_CPU1_SA_DQS_DP<5> @T6G_MB_LIB.T6G(SCH_1):M_D_CPU1_SA_DQS_DP(5)   I236 @T6G_MB_LIB.T6G(SCH_1):PAGE100
   156 M_D_CPU1_SA_DQS_DN<5> @T6G_MB_LIB.T6G(SCH_1):M_D_CPU1_SA_DQS_DN(5)   I236 @T6G_MB_LIB.T6G(SCH_1):PAGE100
   239 M_D_CPU1_SB_DQS_DP<4> @T6G_MB_LIB.T6G(SCH_1):M_D_CPU1_SB_DQS_DP(4)   I236 @T6G_MB_LIB.T6G(SCH_1):PAGE100
   238 M_D_CPU1_SB_DQS_DN<4> @T6G_MB_LIB.T6G(SCH_1):M_D_CPU1_SB_DQS_DN(4)   I236 @T6G_MB_LIB.T6G(SCH_1):PAGE100
    55 M_D_CPU1_SA_DQS_DP<4> @T6G_MB_LIB.T6G(SCH_1):M_D_CPU1_SA_DQS_DP(4)   I236 @T6G_MB_LIB.T6G(SCH_1):PAGE100
    56 M_D_CPU1_SA_DQS_DN<4> @T6G_MB_LIB.T6G(SCH_1):M_D_CPU1_SA_DQS_DN(4)   I236 @T6G_MB_LIB.T6G(SCH_1):PAGE100
   137 M_D_CPU1_SB_DQS_DP<3> @T6G_MB_LIB.T6G(SCH_1):M_D_CPU1_SB_DQS_DP(3)   I236 @T6G_MB_LIB.T6G(SCH_1):PAGE100
   138 M_D_CPU1_SB_DQS_DN<3> @T6G_MB_LIB.T6G(SCH_1):M_D_CPU1_SB_DQS_DN(3)   I236 @T6G_MB_LIB.T6G(SCH_1):PAGE100
    44 M_D_CPU1_SA_DQS_DP<3> @T6G_MB_LIB.T6G(SCH_1):M_D_CPU1_SA_DQS_DP(3)   I236 @T6G_MB_LIB.T6G(SCH_1):PAGE100
    45 M_D_CPU1_SA_DQS_DN<3> @T6G_MB_LIB.T6G(SCH_1):M_D_CPU1_SA_DQS_DN(3)   I236 @T6G_MB_LIB.T6G(SCH_1):PAGE100
   126 M_D_CPU1_SB_DQS_DP<2> @T6G_MB_LIB.T6G(SCH_1):M_D_CPU1_SB_DQS_DP(2)   I236 @T6G_MB_LIB.T6G(SCH_1):PAGE100
   127 M_D_CPU1_SB_DQS_DN<2> @T6G_MB_LIB.T6G(SCH_1):M_D_CPU1_SB_DQS_DN(2)   I236 @T6G_MB_LIB.T6G(SCH_1):PAGE100
    33 M_D_CPU1_SA_DQS_DP<2> @T6G_MB_LIB.T6G(SCH_1):M_D_CPU1_SA_DQS_DP(2)   I236 @T6G_MB_LIB.T6G(SCH_1):PAGE100
    34 M_D_CPU1_SA_DQS_DN<2> @T6G_MB_LIB.T6G(SCH_1):M_D_CPU1_SA_DQS_DN(2)   I236 @T6G_MB_LIB.T6G(SCH_1):PAGE100
   115 M_D_CPU1_SB_DQS_DP<1> @T6G_MB_LIB.T6G(SCH_1):M_D_CPU1_SB_DQS_DP(1)   I236 @T6G_MB_LIB.T6G(SCH_1):PAGE100
   116 M_D_CPU1_SB_DQS_DN<1> @T6G_MB_LIB.T6G(SCH_1):M_D_CPU1_SB_DQS_DN(1)   I236 @T6G_MB_LIB.T6G(SCH_1):PAGE100
    22 M_D_CPU1_SA_DQS_DP<1> @T6G_MB_LIB.T6G(SCH_1):M_D_CPU1_SA_DQS_DP(1)   I236 @T6G_MB_LIB.T6G(SCH_1):PAGE100
    23 M_D_CPU1_SA_DQS_DN<1> @T6G_MB_LIB.T6G(SCH_1):M_D_CPU1_SA_DQS_DN(1)   I236 @T6G_MB_LIB.T6G(SCH_1):PAGE100
   104 M_D_CPU1_SB_DQS_DP<0> @T6G_MB_LIB.T6G(SCH_1):M_D_CPU1_SB_DQS_DP(0)   I236 @T6G_MB_LIB.T6G(SCH_1):PAGE100
   105 M_D_CPU1_SB_DQS_DN<0> @T6G_MB_LIB.T6G(SCH_1):M_D_CPU1_SB_DQS_DN(0)   I236 @T6G_MB_LIB.T6G(SCH_1):PAGE100
    11 M_D_CPU1_SA_DQS_DP<0> @T6G_MB_LIB.T6G(SCH_1):M_D_CPU1_SA_DQS_DP(0)   I236 @T6G_MB_LIB.T6G(SCH_1):PAGE100
    12 M_D_CPU1_SA_DQS_DN<0> @T6G_MB_LIB.T6G(SCH_1):M_D_CPU1_SA_DQS_DN(0)   I236 @T6G_MB_LIB.T6G(SCH_1):PAGE100
   272 M_D_CPU1_SB_DQS_DP<7> @T6G_MB_LIB.T6G(SCH_1):M_D_CPU1_SB_DQS_DP(7)   I236 @T6G_MB_LIB.T6G(SCH_1):PAGE100
   282 M_D_CPU1_SB_DQS_DN<8> @T6G_MB_LIB.T6G(SCH_1):M_D_CPU1_SB_DQS_DN(8)   I236 @T6G_MB_LIB.T6G(SCH_1):PAGE100
   283 M_D_CPU1_SB_DQS_DP<8> @T6G_MB_LIB.T6G(SCH_1):M_D_CPU1_SB_DQS_DP(8)   I236 @T6G_MB_LIB.T6G(SCH_1):PAGE100
   168 M_D_CPU1_SA_DQS_DP<6> @T6G_MB_LIB.T6G(SCH_1):M_D_CPU1_SA_DQS_DP(6)   I236 @T6G_MB_LIB.T6G(SCH_1):PAGE100
   178 M_D_CPU1_SA_DQS_DN<7> @T6G_MB_LIB.T6G(SCH_1):M_D_CPU1_SA_DQS_DN(7)   I236 @T6G_MB_LIB.T6G(SCH_1):PAGE100
     6    GND @T6G_MB_LIB.T6G(SCH_1):GND   I161 @T6G_MB_LIB.T6G(SCH_1):PAGE100
     8    GND @T6G_MB_LIB.T6G(SCH_1):GND   I161 @T6G_MB_LIB.T6G(SCH_1):PAGE100
    10    GND @T6G_MB_LIB.T6G(SCH_1):GND   I161 @T6G_MB_LIB.T6G(SCH_1):PAGE100
    13    GND @T6G_MB_LIB.T6G(SCH_1):GND   I161 @T6G_MB_LIB.T6G(SCH_1):PAGE100
    15    GND @T6G_MB_LIB.T6G(SCH_1):GND   I161 @T6G_MB_LIB.T6G(SCH_1):PAGE100
    17    GND @T6G_MB_LIB.T6G(SCH_1):GND   I161 @T6G_MB_LIB.T6G(SCH_1):PAGE100
    19    GND @T6G_MB_LIB.T6G(SCH_1):GND   I161 @T6G_MB_LIB.T6G(SCH_1):PAGE100
    21    GND @T6G_MB_LIB.T6G(SCH_1):GND   I161 @T6G_MB_LIB.T6G(SCH_1):PAGE100
    24    GND @T6G_MB_LIB.T6G(SCH_1):GND   I161 @T6G_MB_LIB.T6G(SCH_1):PAGE100
    26    GND @T6G_MB_LIB.T6G(SCH_1):GND   I161 @T6G_MB_LIB.T6G(SCH_1):PAGE100
    28    GND @T6G_MB_LIB.T6G(SCH_1):GND   I161 @T6G_MB_LIB.T6G(SCH_1):PAGE100
    30    GND @T6G_MB_LIB.T6G(SCH_1):GND   I161 @T6G_MB_LIB.T6G(SCH_1):PAGE100
    32    GND @T6G_MB_LIB.T6G(SCH_1):GND   I161 @T6G_MB_LIB.T6G(SCH_1):PAGE100
    35    GND @T6G_MB_LIB.T6G(SCH_1):GND   I161 @T6G_MB_LIB.T6G(SCH_1):PAGE100
    37    GND @T6G_MB_LIB.T6G(SCH_1):GND   I161 @T6G_MB_LIB.T6G(SCH_1):PAGE100
    39    GND @T6G_MB_LIB.T6G(SCH_1):GND   I161 @T6G_MB_LIB.T6G(SCH_1):PAGE100
    41    GND @T6G_MB_LIB.T6G(SCH_1):GND   I161 @T6G_MB_LIB.T6G(SCH_1):PAGE100
    43    GND @T6G_MB_LIB.T6G(SCH_1):GND   I161 @T6G_MB_LIB.T6G(SCH_1):PAGE100
    46    GND @T6G_MB_LIB.T6G(SCH_1):GND   I161 @T6G_MB_LIB.T6G(SCH_1):PAGE100
    48    GND @T6G_MB_LIB.T6G(SCH_1):GND   I161 @T6G_MB_LIB.T6G(SCH_1):PAGE100
    50    GND @T6G_MB_LIB.T6G(SCH_1):GND   I161 @T6G_MB_LIB.T6G(SCH_1):PAGE100
    52    GND @T6G_MB_LIB.T6G(SCH_1):GND   I161 @T6G_MB_LIB.T6G(SCH_1):PAGE100
    54    GND @T6G_MB_LIB.T6G(SCH_1):GND   I161 @T6G_MB_LIB.T6G(SCH_1):PAGE100
    57    GND @T6G_MB_LIB.T6G(SCH_1):GND   I161 @T6G_MB_LIB.T6G(SCH_1):PAGE100
    59    GND @T6G_MB_LIB.T6G(SCH_1):GND   I161 @T6G_MB_LIB.T6G(SCH_1):PAGE100
    61    GND @T6G_MB_LIB.T6G(SCH_1):GND   I161 @T6G_MB_LIB.T6G(SCH_1):PAGE100
    63    GND @T6G_MB_LIB.T6G(SCH_1):GND   I161 @T6G_MB_LIB.T6G(SCH_1):PAGE100
    65    GND @T6G_MB_LIB.T6G(SCH_1):GND   I161 @T6G_MB_LIB.T6G(SCH_1):PAGE100
    67    GND @T6G_MB_LIB.T6G(SCH_1):GND   I161 @T6G_MB_LIB.T6G(SCH_1):PAGE100
    69    GND @T6G_MB_LIB.T6G(SCH_1):GND   I161 @T6G_MB_LIB.T6G(SCH_1):PAGE100
    71    GND @T6G_MB_LIB.T6G(SCH_1):GND   I161 @T6G_MB_LIB.T6G(SCH_1):PAGE100
    73    GND @T6G_MB_LIB.T6G(SCH_1):GND   I161 @T6G_MB_LIB.T6G(SCH_1):PAGE100
    75    GND @T6G_MB_LIB.T6G(SCH_1):GND   I161 @T6G_MB_LIB.T6G(SCH_1):PAGE100
    77    GND @T6G_MB_LIB.T6G(SCH_1):GND   I161 @T6G_MB_LIB.T6G(SCH_1):PAGE100
    79    GND @T6G_MB_LIB.T6G(SCH_1):GND   I161 @T6G_MB_LIB.T6G(SCH_1):PAGE100
    81    GND @T6G_MB_LIB.T6G(SCH_1):GND   I161 @T6G_MB_LIB.T6G(SCH_1):PAGE100
    83    GND @T6G_MB_LIB.T6G(SCH_1):GND   I161 @T6G_MB_LIB.T6G(SCH_1):PAGE100
    85    GND @T6G_MB_LIB.T6G(SCH_1):GND   I161 @T6G_MB_LIB.T6G(SCH_1):PAGE100
    88    GND @T6G_MB_LIB.T6G(SCH_1):GND   I161 @T6G_MB_LIB.T6G(SCH_1):PAGE100
    90    GND @T6G_MB_LIB.T6G(SCH_1):GND   I161 @T6G_MB_LIB.T6G(SCH_1):PAGE100
    92    GND @T6G_MB_LIB.T6G(SCH_1):GND   I161 @T6G_MB_LIB.T6G(SCH_1):PAGE100
    95    GND @T6G_MB_LIB.T6G(SCH_1):GND   I161 @T6G_MB_LIB.T6G(SCH_1):PAGE100
    97    GND @T6G_MB_LIB.T6G(SCH_1):GND   I161 @T6G_MB_LIB.T6G(SCH_1):PAGE100
    99    GND @T6G_MB_LIB.T6G(SCH_1):GND   I161 @T6G_MB_LIB.T6G(SCH_1):PAGE100
   101    GND @T6G_MB_LIB.T6G(SCH_1):GND   I161 @T6G_MB_LIB.T6G(SCH_1):PAGE100
   103    GND @T6G_MB_LIB.T6G(SCH_1):GND   I161 @T6G_MB_LIB.T6G(SCH_1):PAGE100
   106    GND @T6G_MB_LIB.T6G(SCH_1):GND   I161 @T6G_MB_LIB.T6G(SCH_1):PAGE100
   108    GND @T6G_MB_LIB.T6G(SCH_1):GND   I161 @T6G_MB_LIB.T6G(SCH_1):PAGE100
   110    GND @T6G_MB_LIB.T6G(SCH_1):GND   I161 @T6G_MB_LIB.T6G(SCH_1):PAGE100
   112    GND @T6G_MB_LIB.T6G(SCH_1):GND   I161 @T6G_MB_LIB.T6G(SCH_1):PAGE100
   114    GND @T6G_MB_LIB.T6G(SCH_1):GND   I161 @T6G_MB_LIB.T6G(SCH_1):PAGE100
   117    GND @T6G_MB_LIB.T6G(SCH_1):GND   I161 @T6G_MB_LIB.T6G(SCH_1):PAGE100
   119    GND @T6G_MB_LIB.T6G(SCH_1):GND   I161 @T6G_MB_LIB.T6G(SCH_1):PAGE100
   121    GND @T6G_MB_LIB.T6G(SCH_1):GND   I161 @T6G_MB_LIB.T6G(SCH_1):PAGE100
   123    GND @T6G_MB_LIB.T6G(SCH_1):GND   I161 @T6G_MB_LIB.T6G(SCH_1):PAGE100
   125    GND @T6G_MB_LIB.T6G(SCH_1):GND   I161 @T6G_MB_LIB.T6G(SCH_1):PAGE100
   128    GND @T6G_MB_LIB.T6G(SCH_1):GND   I161 @T6G_MB_LIB.T6G(SCH_1):PAGE100
   130    GND @T6G_MB_LIB.T6G(SCH_1):GND   I161 @T6G_MB_LIB.T6G(SCH_1):PAGE100
   134    GND @T6G_MB_LIB.T6G(SCH_1):GND   I161 @T6G_MB_LIB.T6G(SCH_1):PAGE100
   143    GND @T6G_MB_LIB.T6G(SCH_1):GND   I161 @T6G_MB_LIB.T6G(SCH_1):PAGE100
   151    GND @T6G_MB_LIB.T6G(SCH_1):GND   I161 @T6G_MB_LIB.T6G(SCH_1):PAGE100
   153    GND @T6G_MB_LIB.T6G(SCH_1):GND   I161 @T6G_MB_LIB.T6G(SCH_1):PAGE100
   155    GND @T6G_MB_LIB.T6G(SCH_1):GND   I161 @T6G_MB_LIB.T6G(SCH_1):PAGE100
   158    GND @T6G_MB_LIB.T6G(SCH_1):GND   I161 @T6G_MB_LIB.T6G(SCH_1):PAGE100
   160    GND @T6G_MB_LIB.T6G(SCH_1):GND   I161 @T6G_MB_LIB.T6G(SCH_1):PAGE100
   162    GND @T6G_MB_LIB.T6G(SCH_1):GND   I161 @T6G_MB_LIB.T6G(SCH_1):PAGE100
   164    GND @T6G_MB_LIB.T6G(SCH_1):GND   I161 @T6G_MB_LIB.T6G(SCH_1):PAGE100
   166    GND @T6G_MB_LIB.T6G(SCH_1):GND   I161 @T6G_MB_LIB.T6G(SCH_1):PAGE100
   169    GND @T6G_MB_LIB.T6G(SCH_1):GND   I161 @T6G_MB_LIB.T6G(SCH_1):PAGE100
   171    GND @T6G_MB_LIB.T6G(SCH_1):GND   I161 @T6G_MB_LIB.T6G(SCH_1):PAGE100
   173    GND @T6G_MB_LIB.T6G(SCH_1):GND   I161 @T6G_MB_LIB.T6G(SCH_1):PAGE100
   175    GND @T6G_MB_LIB.T6G(SCH_1):GND   I161 @T6G_MB_LIB.T6G(SCH_1):PAGE100
   177    GND @T6G_MB_LIB.T6G(SCH_1):GND   I161 @T6G_MB_LIB.T6G(SCH_1):PAGE100
   180    GND @T6G_MB_LIB.T6G(SCH_1):GND   I161 @T6G_MB_LIB.T6G(SCH_1):PAGE100
   182    GND @T6G_MB_LIB.T6G(SCH_1):GND   I161 @T6G_MB_LIB.T6G(SCH_1):PAGE100
   184    GND @T6G_MB_LIB.T6G(SCH_1):GND   I161 @T6G_MB_LIB.T6G(SCH_1):PAGE100
   186    GND @T6G_MB_LIB.T6G(SCH_1):GND   I161 @T6G_MB_LIB.T6G(SCH_1):PAGE100
   188    GND @T6G_MB_LIB.T6G(SCH_1):GND   I161 @T6G_MB_LIB.T6G(SCH_1):PAGE100
   191    GND @T6G_MB_LIB.T6G(SCH_1):GND   I161 @T6G_MB_LIB.T6G(SCH_1):PAGE100
   193    GND @T6G_MB_LIB.T6G(SCH_1):GND   I161 @T6G_MB_LIB.T6G(SCH_1):PAGE100
   195    GND @T6G_MB_LIB.T6G(SCH_1):GND   I161 @T6G_MB_LIB.T6G(SCH_1):PAGE100
   197    GND @T6G_MB_LIB.T6G(SCH_1):GND   I161 @T6G_MB_LIB.T6G(SCH_1):PAGE100
   199    GND @T6G_MB_LIB.T6G(SCH_1):GND   I161 @T6G_MB_LIB.T6G(SCH_1):PAGE100
   202    GND @T6G_MB_LIB.T6G(SCH_1):GND   I161 @T6G_MB_LIB.T6G(SCH_1):PAGE100
   204    GND @T6G_MB_LIB.T6G(SCH_1):GND   I161 @T6G_MB_LIB.T6G(SCH_1):PAGE100
   206    GND @T6G_MB_LIB.T6G(SCH_1):GND   I161 @T6G_MB_LIB.T6G(SCH_1):PAGE100
   208    GND @T6G_MB_LIB.T6G(SCH_1):GND   I161 @T6G_MB_LIB.T6G(SCH_1):PAGE100
   210    GND @T6G_MB_LIB.T6G(SCH_1):GND   I161 @T6G_MB_LIB.T6G(SCH_1):PAGE100
   212    GND @T6G_MB_LIB.T6G(SCH_1):GND   I161 @T6G_MB_LIB.T6G(SCH_1):PAGE100
   214    GND @T6G_MB_LIB.T6G(SCH_1):GND   I161 @T6G_MB_LIB.T6G(SCH_1):PAGE100
   216    GND @T6G_MB_LIB.T6G(SCH_1):GND   I161 @T6G_MB_LIB.T6G(SCH_1):PAGE100
   219    GND @T6G_MB_LIB.T6G(SCH_1):GND   I161 @T6G_MB_LIB.T6G(SCH_1):PAGE100
   222    GND @T6G_MB_LIB.T6G(SCH_1):GND   I161 @T6G_MB_LIB.T6G(SCH_1):PAGE100
   224    GND @T6G_MB_LIB.T6G(SCH_1):GND   I161 @T6G_MB_LIB.T6G(SCH_1):PAGE100
   226    GND @T6G_MB_LIB.T6G(SCH_1):GND   I161 @T6G_MB_LIB.T6G(SCH_1):PAGE100
   228    GND @T6G_MB_LIB.T6G(SCH_1):GND   I161 @T6G_MB_LIB.T6G(SCH_1):PAGE100
   233    GND @T6G_MB_LIB.T6G(SCH_1):GND   I161 @T6G_MB_LIB.T6G(SCH_1):PAGE100
   237    GND @T6G_MB_LIB.T6G(SCH_1):GND   I161 @T6G_MB_LIB.T6G(SCH_1):PAGE100
   242    GND @T6G_MB_LIB.T6G(SCH_1):GND   I161 @T6G_MB_LIB.T6G(SCH_1):PAGE100
   244    GND @T6G_MB_LIB.T6G(SCH_1):GND   I161 @T6G_MB_LIB.T6G(SCH_1):PAGE100
   246    GND @T6G_MB_LIB.T6G(SCH_1):GND   I161 @T6G_MB_LIB.T6G(SCH_1):PAGE100
   248    GND @T6G_MB_LIB.T6G(SCH_1):GND   I161 @T6G_MB_LIB.T6G(SCH_1):PAGE100
   251    GND @T6G_MB_LIB.T6G(SCH_1):GND   I161 @T6G_MB_LIB.T6G(SCH_1):PAGE100
   253    GND @T6G_MB_LIB.T6G(SCH_1):GND   I161 @T6G_MB_LIB.T6G(SCH_1):PAGE100
   255    GND @T6G_MB_LIB.T6G(SCH_1):GND   I161 @T6G_MB_LIB.T6G(SCH_1):PAGE100
   257    GND @T6G_MB_LIB.T6G(SCH_1):GND   I161 @T6G_MB_LIB.T6G(SCH_1):PAGE100
   259    GND @T6G_MB_LIB.T6G(SCH_1):GND   I161 @T6G_MB_LIB.T6G(SCH_1):PAGE100
   262    GND @T6G_MB_LIB.T6G(SCH_1):GND   I161 @T6G_MB_LIB.T6G(SCH_1):PAGE100
   264    GND @T6G_MB_LIB.T6G(SCH_1):GND   I161 @T6G_MB_LIB.T6G(SCH_1):PAGE100
   266    GND @T6G_MB_LIB.T6G(SCH_1):GND   I161 @T6G_MB_LIB.T6G(SCH_1):PAGE100
   268    GND @T6G_MB_LIB.T6G(SCH_1):GND   I161 @T6G_MB_LIB.T6G(SCH_1):PAGE100
   270    GND @T6G_MB_LIB.T6G(SCH_1):GND   I161 @T6G_MB_LIB.T6G(SCH_1):PAGE100
   273    GND @T6G_MB_LIB.T6G(SCH_1):GND   I161 @T6G_MB_LIB.T6G(SCH_1):PAGE100
   275    GND @T6G_MB_LIB.T6G(SCH_1):GND   I161 @T6G_MB_LIB.T6G(SCH_1):PAGE100
   277    GND @T6G_MB_LIB.T6G(SCH_1):GND   I161 @T6G_MB_LIB.T6G(SCH_1):PAGE100
   279    GND @T6G_MB_LIB.T6G(SCH_1):GND   I161 @T6G_MB_LIB.T6G(SCH_1):PAGE100
   281    GND @T6G_MB_LIB.T6G(SCH_1):GND   I161 @T6G_MB_LIB.T6G(SCH_1):PAGE100
   284    GND @T6G_MB_LIB.T6G(SCH_1):GND   I161 @T6G_MB_LIB.T6G(SCH_1):PAGE100
   286    GND @T6G_MB_LIB.T6G(SCH_1):GND   I161 @T6G_MB_LIB.T6G(SCH_1):PAGE100
   288    GND @T6G_MB_LIB.T6G(SCH_1):GND   I161 @T6G_MB_LIB.T6G(SCH_1):PAGE100
     1 P12V_MEM_CPU1 @T6G_MB_LIB.T6G(SCH_1):P12V_MEM_CPU1   I161 @T6G_MB_LIB.T6G(SCH_1):PAGE100
   145 P12V_MEM_CPU1 @T6G_MB_LIB.T6G(SCH_1):P12V_MEM_CPU1   I161 @T6G_MB_LIB.T6G(SCH_1):PAGE100
   146 P12V_MEM_CPU1 @T6G_MB_LIB.T6G(SCH_1):P12V_MEM_CPU1   I161 @T6G_MB_LIB.T6G(SCH_1):PAGE100
   230    GND @T6G_MB_LIB.T6G(SCH_1):GND   I161 @T6G_MB_LIB.T6G(SCH_1):PAGE100
   235    GND @T6G_MB_LIB.T6G(SCH_1):GND   I161 @T6G_MB_LIB.T6G(SCH_1):PAGE100
   240    GND @T6G_MB_LIB.T6G(SCH_1):GND   I161 @T6G_MB_LIB.T6G(SCH_1):PAGE100
   132    GND @T6G_MB_LIB.T6G(SCH_1):GND   I161 @T6G_MB_LIB.T6G(SCH_1):PAGE100
   136    GND @T6G_MB_LIB.T6G(SCH_1):GND   I161 @T6G_MB_LIB.T6G(SCH_1):PAGE100
   139    GND @T6G_MB_LIB.T6G(SCH_1):GND   I161 @T6G_MB_LIB.T6G(SCH_1):PAGE100
   141    GND @T6G_MB_LIB.T6G(SCH_1):GND   I161 @T6G_MB_LIB.T6G(SCH_1):PAGE100
    G1    GND @T6G_MB_LIB.T6G(SCH_1):GND   I161 @T6G_MB_LIB.T6G(SCH_1):PAGE100
    G2    GND @T6G_MB_LIB.T6G(SCH_1):GND   I161 @T6G_MB_LIB.T6G(SCH_1):PAGE100
    G3    GND @T6G_MB_LIB.T6G(SCH_1):GND   I161 @T6G_MB_LIB.T6G(SCH_1):PAGE100

 J32 SCONN288_DDR506112002KQ-SCONN288_DDR506112002KQ,SMA
     3 P3V3_AUX @T6G_MB_LIB.T6G(SCH_1):P3V3_AUX    I52 @T6G_MB_LIB.T6G(SCH_1):PAGE101
     2     NC     NC    I52 @T6G_MB_LIB.T6G(SCH_1):PAGE101
   144     NC     NC    I52 @T6G_MB_LIB.T6G(SCH_1):PAGE101
   149     NC     NC    I52 @T6G_MB_LIB.T6G(SCH_1):PAGE101
   150     NC     NC    I52 @T6G_MB_LIB.T6G(SCH_1):PAGE101
   220     NC     NC    I52 @T6G_MB_LIB.T6G(SCH_1):PAGE101
   231     NC     NC    I52 @T6G_MB_LIB.T6G(SCH_1):PAGE101
   232     NC     NC    I52 @T6G_MB_LIB.T6G(SCH_1):PAGE101
   207 M_E_CPU1_RESET_N @T6G_MB_LIB.T6G(SCH_1):M_E_CPU1_RESET_N    I52 @T6G_MB_LIB.T6G(SCH_1):PAGE101
   147 PWRGD_CHE_CPU1_DIMM @T6G_MB_LIB.T6G(SCH_1):PWRGD_CHE_CPU1_DIMM    I52 @T6G_MB_LIB.T6G(SCH_1):PAGE101
   227 M_E_CPU1_SB_PAR @T6G_MB_LIB.T6G(SCH_1):M_E_CPU1_SB_PAR    I52 @T6G_MB_LIB.T6G(SCH_1):PAGE101
    74 M_E_CPU1_SA_PAR @T6G_MB_LIB.T6G(SCH_1):M_E_CPU1_SA_PAR    I52 @T6G_MB_LIB.T6G(SCH_1):PAGE101
    87 M_E_CPU1_SB_RSP<0> @T6G_MB_LIB.T6G(SCH_1):M_E_CPU1_SB_RSP(0)    I52 @T6G_MB_LIB.T6G(SCH_1):PAGE101
    86 M_E_CPU1_SA_RSP<0> @T6G_MB_LIB.T6G(SCH_1):M_E_CPU1_SA_RSP(0)    I52 @T6G_MB_LIB.T6G(SCH_1):PAGE101
     5 I3C_SPD_DDRE_CPU1_SDA @T6G_MB_LIB.T6G(SCH_1):I3C_SPD_DDRE_CPU1_SDA    I52 @T6G_MB_LIB.T6G(SCH_1):PAGE101
     4 I3C_SPD_DDRE_CPU1_SCL @T6G_MB_LIB.T6G(SCH_1):I3C_SPD_DDRE_CPU1_SCL    I52 @T6G_MB_LIB.T6G(SCH_1):PAGE101
   148 PD_CHE_CPU1_DIMM_SAA @T6G_MB_LIB.T6G(SCH_1):PD_CHE_CPU1_DIMM_SAA    I52 @T6G_MB_LIB.T6G(SCH_1):PAGE101
   100 M_E_CPU1_SB_DQ<0> @T6G_MB_LIB.T6G(SCH_1):M_E_CPU1_SB_DQ(0)    I52 @T6G_MB_LIB.T6G(SCH_1):PAGE101
   102 M_E_CPU1_SB_DQ<1> @T6G_MB_LIB.T6G(SCH_1):M_E_CPU1_SB_DQ(1)    I52 @T6G_MB_LIB.T6G(SCH_1):PAGE101
   245 M_E_CPU1_SB_DQ<2> @T6G_MB_LIB.T6G(SCH_1):M_E_CPU1_SB_DQ(2)    I52 @T6G_MB_LIB.T6G(SCH_1):PAGE101
   247 M_E_CPU1_SB_DQ<3> @T6G_MB_LIB.T6G(SCH_1):M_E_CPU1_SB_DQ(3)    I52 @T6G_MB_LIB.T6G(SCH_1):PAGE101
   107 M_E_CPU1_SB_DQ<4> @T6G_MB_LIB.T6G(SCH_1):M_E_CPU1_SB_DQ(4)    I52 @T6G_MB_LIB.T6G(SCH_1):PAGE101
   109 M_E_CPU1_SB_DQ<5> @T6G_MB_LIB.T6G(SCH_1):M_E_CPU1_SB_DQ(5)    I52 @T6G_MB_LIB.T6G(SCH_1):PAGE101
   252 M_E_CPU1_SB_DQ<6> @T6G_MB_LIB.T6G(SCH_1):M_E_CPU1_SB_DQ(6)    I52 @T6G_MB_LIB.T6G(SCH_1):PAGE101
   254 M_E_CPU1_SB_DQ<7> @T6G_MB_LIB.T6G(SCH_1):M_E_CPU1_SB_DQ(7)    I52 @T6G_MB_LIB.T6G(SCH_1):PAGE101
   111 M_E_CPU1_SB_DQ<8> @T6G_MB_LIB.T6G(SCH_1):M_E_CPU1_SB_DQ(8)    I52 @T6G_MB_LIB.T6G(SCH_1):PAGE101
   113 M_E_CPU1_SB_DQ<9> @T6G_MB_LIB.T6G(SCH_1):M_E_CPU1_SB_DQ(9)    I52 @T6G_MB_LIB.T6G(SCH_1):PAGE101
   256 M_E_CPU1_SB_DQ<10> @T6G_MB_LIB.T6G(SCH_1):M_E_CPU1_SB_DQ(10)    I52 @T6G_MB_LIB.T6G(SCH_1):PAGE101
   258 M_E_CPU1_SB_DQ<11> @T6G_MB_LIB.T6G(SCH_1):M_E_CPU1_SB_DQ(11)    I52 @T6G_MB_LIB.T6G(SCH_1):PAGE101
   118 M_E_CPU1_SB_DQ<12> @T6G_MB_LIB.T6G(SCH_1):M_E_CPU1_SB_DQ(12)    I52 @T6G_MB_LIB.T6G(SCH_1):PAGE101
   120 M_E_CPU1_SB_DQ<13> @T6G_MB_LIB.T6G(SCH_1):M_E_CPU1_SB_DQ(13)    I52 @T6G_MB_LIB.T6G(SCH_1):PAGE101
   263 M_E_CPU1_SB_DQ<14> @T6G_MB_LIB.T6G(SCH_1):M_E_CPU1_SB_DQ(14)    I52 @T6G_MB_LIB.T6G(SCH_1):PAGE101
   265 M_E_CPU1_SB_DQ<15> @T6G_MB_LIB.T6G(SCH_1):M_E_CPU1_SB_DQ(15)    I52 @T6G_MB_LIB.T6G(SCH_1):PAGE101
   122 M_E_CPU1_SB_DQ<16> @T6G_MB_LIB.T6G(SCH_1):M_E_CPU1_SB_DQ(16)    I52 @T6G_MB_LIB.T6G(SCH_1):PAGE101
   124 M_E_CPU1_SB_DQ<17> @T6G_MB_LIB.T6G(SCH_1):M_E_CPU1_SB_DQ(17)    I52 @T6G_MB_LIB.T6G(SCH_1):PAGE101
   267 M_E_CPU1_SB_DQ<18> @T6G_MB_LIB.T6G(SCH_1):M_E_CPU1_SB_DQ(18)    I52 @T6G_MB_LIB.T6G(SCH_1):PAGE101
   269 M_E_CPU1_SB_DQ<19> @T6G_MB_LIB.T6G(SCH_1):M_E_CPU1_SB_DQ(19)    I52 @T6G_MB_LIB.T6G(SCH_1):PAGE101
   129 M_E_CPU1_SB_DQ<20> @T6G_MB_LIB.T6G(SCH_1):M_E_CPU1_SB_DQ(20)    I52 @T6G_MB_LIB.T6G(SCH_1):PAGE101
   131 M_E_CPU1_SB_DQ<21> @T6G_MB_LIB.T6G(SCH_1):M_E_CPU1_SB_DQ(21)    I52 @T6G_MB_LIB.T6G(SCH_1):PAGE101
   274 M_E_CPU1_SB_DQ<22> @T6G_MB_LIB.T6G(SCH_1):M_E_CPU1_SB_DQ(22)    I52 @T6G_MB_LIB.T6G(SCH_1):PAGE101
   276 M_E_CPU1_SB_DQ<23> @T6G_MB_LIB.T6G(SCH_1):M_E_CPU1_SB_DQ(23)    I52 @T6G_MB_LIB.T6G(SCH_1):PAGE101
   133 M_E_CPU1_SB_DQ<24> @T6G_MB_LIB.T6G(SCH_1):M_E_CPU1_SB_DQ(24)    I52 @T6G_MB_LIB.T6G(SCH_1):PAGE101
   135 M_E_CPU1_SB_DQ<25> @T6G_MB_LIB.T6G(SCH_1):M_E_CPU1_SB_DQ(25)    I52 @T6G_MB_LIB.T6G(SCH_1):PAGE101
   278 M_E_CPU1_SB_DQ<26> @T6G_MB_LIB.T6G(SCH_1):M_E_CPU1_SB_DQ(26)    I52 @T6G_MB_LIB.T6G(SCH_1):PAGE101
   280 M_E_CPU1_SB_DQ<27> @T6G_MB_LIB.T6G(SCH_1):M_E_CPU1_SB_DQ(27)    I52 @T6G_MB_LIB.T6G(SCH_1):PAGE101
   140 M_E_CPU1_SB_DQ<28> @T6G_MB_LIB.T6G(SCH_1):M_E_CPU1_SB_DQ(28)    I52 @T6G_MB_LIB.T6G(SCH_1):PAGE101
   142 M_E_CPU1_SB_DQ<29> @T6G_MB_LIB.T6G(SCH_1):M_E_CPU1_SB_DQ(29)    I52 @T6G_MB_LIB.T6G(SCH_1):PAGE101
   285 M_E_CPU1_SB_DQ<30> @T6G_MB_LIB.T6G(SCH_1):M_E_CPU1_SB_DQ(30)    I52 @T6G_MB_LIB.T6G(SCH_1):PAGE101
   287 M_E_CPU1_SB_DQ<31> @T6G_MB_LIB.T6G(SCH_1):M_E_CPU1_SB_DQ(31)    I52 @T6G_MB_LIB.T6G(SCH_1):PAGE101
     7 M_E_CPU1_SA_DQ<0> @T6G_MB_LIB.T6G(SCH_1):M_E_CPU1_SA_DQ(0)    I52 @T6G_MB_LIB.T6G(SCH_1):PAGE101
     9 M_E_CPU1_SA_DQ<1> @T6G_MB_LIB.T6G(SCH_1):M_E_CPU1_SA_DQ(1)    I52 @T6G_MB_LIB.T6G(SCH_1):PAGE101
   152 M_E_CPU1_SA_DQ<2> @T6G_MB_LIB.T6G(SCH_1):M_E_CPU1_SA_DQ(2)    I52 @T6G_MB_LIB.T6G(SCH_1):PAGE101
   154 M_E_CPU1_SA_DQ<3> @T6G_MB_LIB.T6G(SCH_1):M_E_CPU1_SA_DQ(3)    I52 @T6G_MB_LIB.T6G(SCH_1):PAGE101
    14 M_E_CPU1_SA_DQ<4> @T6G_MB_LIB.T6G(SCH_1):M_E_CPU1_SA_DQ(4)    I52 @T6G_MB_LIB.T6G(SCH_1):PAGE101
    16 M_E_CPU1_SA_DQ<5> @T6G_MB_LIB.T6G(SCH_1):M_E_CPU1_SA_DQ(5)    I52 @T6G_MB_LIB.T6G(SCH_1):PAGE101
   159 M_E_CPU1_SA_DQ<6> @T6G_MB_LIB.T6G(SCH_1):M_E_CPU1_SA_DQ(6)    I52 @T6G_MB_LIB.T6G(SCH_1):PAGE101
   161 M_E_CPU1_SA_DQ<7> @T6G_MB_LIB.T6G(SCH_1):M_E_CPU1_SA_DQ(7)    I52 @T6G_MB_LIB.T6G(SCH_1):PAGE101
    18 M_E_CPU1_SA_DQ<8> @T6G_MB_LIB.T6G(SCH_1):M_E_CPU1_SA_DQ(8)    I52 @T6G_MB_LIB.T6G(SCH_1):PAGE101
    20 M_E_CPU1_SA_DQ<9> @T6G_MB_LIB.T6G(SCH_1):M_E_CPU1_SA_DQ(9)    I52 @T6G_MB_LIB.T6G(SCH_1):PAGE101
   163 M_E_CPU1_SA_DQ<10> @T6G_MB_LIB.T6G(SCH_1):M_E_CPU1_SA_DQ(10)    I52 @T6G_MB_LIB.T6G(SCH_1):PAGE101
   165 M_E_CPU1_SA_DQ<11> @T6G_MB_LIB.T6G(SCH_1):M_E_CPU1_SA_DQ(11)    I52 @T6G_MB_LIB.T6G(SCH_1):PAGE101
    25 M_E_CPU1_SA_DQ<12> @T6G_MB_LIB.T6G(SCH_1):M_E_CPU1_SA_DQ(12)    I52 @T6G_MB_LIB.T6G(SCH_1):PAGE101
    27 M_E_CPU1_SA_DQ<13> @T6G_MB_LIB.T6G(SCH_1):M_E_CPU1_SA_DQ(13)    I52 @T6G_MB_LIB.T6G(SCH_1):PAGE101
   170 M_E_CPU1_SA_DQ<14> @T6G_MB_LIB.T6G(SCH_1):M_E_CPU1_SA_DQ(14)    I52 @T6G_MB_LIB.T6G(SCH_1):PAGE101
   172 M_E_CPU1_SA_DQ<15> @T6G_MB_LIB.T6G(SCH_1):M_E_CPU1_SA_DQ(15)    I52 @T6G_MB_LIB.T6G(SCH_1):PAGE101
    29 M_E_CPU1_SA_DQ<16> @T6G_MB_LIB.T6G(SCH_1):M_E_CPU1_SA_DQ(16)    I52 @T6G_MB_LIB.T6G(SCH_1):PAGE101
    31 M_E_CPU1_SA_DQ<17> @T6G_MB_LIB.T6G(SCH_1):M_E_CPU1_SA_DQ(17)    I52 @T6G_MB_LIB.T6G(SCH_1):PAGE101
   174 M_E_CPU1_SA_DQ<18> @T6G_MB_LIB.T6G(SCH_1):M_E_CPU1_SA_DQ(18)    I52 @T6G_MB_LIB.T6G(SCH_1):PAGE101
   176 M_E_CPU1_SA_DQ<19> @T6G_MB_LIB.T6G(SCH_1):M_E_CPU1_SA_DQ(19)    I52 @T6G_MB_LIB.T6G(SCH_1):PAGE101
    36 M_E_CPU1_SA_DQ<20> @T6G_MB_LIB.T6G(SCH_1):M_E_CPU1_SA_DQ(20)    I52 @T6G_MB_LIB.T6G(SCH_1):PAGE101
    38 M_E_CPU1_SA_DQ<21> @T6G_MB_LIB.T6G(SCH_1):M_E_CPU1_SA_DQ(21)    I52 @T6G_MB_LIB.T6G(SCH_1):PAGE101
   181 M_E_CPU1_SA_DQ<22> @T6G_MB_LIB.T6G(SCH_1):M_E_CPU1_SA_DQ(22)    I52 @T6G_MB_LIB.T6G(SCH_1):PAGE101
   183 M_E_CPU1_SA_DQ<23> @T6G_MB_LIB.T6G(SCH_1):M_E_CPU1_SA_DQ(23)    I52 @T6G_MB_LIB.T6G(SCH_1):PAGE101
    40 M_E_CPU1_SA_DQ<24> @T6G_MB_LIB.T6G(SCH_1):M_E_CPU1_SA_DQ(24)    I52 @T6G_MB_LIB.T6G(SCH_1):PAGE101
    42 M_E_CPU1_SA_DQ<25> @T6G_MB_LIB.T6G(SCH_1):M_E_CPU1_SA_DQ(25)    I52 @T6G_MB_LIB.T6G(SCH_1):PAGE101
   185 M_E_CPU1_SA_DQ<26> @T6G_MB_LIB.T6G(SCH_1):M_E_CPU1_SA_DQ(26)    I52 @T6G_MB_LIB.T6G(SCH_1):PAGE101
   187 M_E_CPU1_SA_DQ<27> @T6G_MB_LIB.T6G(SCH_1):M_E_CPU1_SA_DQ(27)    I52 @T6G_MB_LIB.T6G(SCH_1):PAGE101
    47 M_E_CPU1_SA_DQ<28> @T6G_MB_LIB.T6G(SCH_1):M_E_CPU1_SA_DQ(28)    I52 @T6G_MB_LIB.T6G(SCH_1):PAGE101
    49 M_E_CPU1_SA_DQ<29> @T6G_MB_LIB.T6G(SCH_1):M_E_CPU1_SA_DQ(29)    I52 @T6G_MB_LIB.T6G(SCH_1):PAGE101
   192 M_E_CPU1_SA_DQ<30> @T6G_MB_LIB.T6G(SCH_1):M_E_CPU1_SA_DQ(30)    I52 @T6G_MB_LIB.T6G(SCH_1):PAGE101
   229 M_E_CPU1_SB_CS_N<1> @T6G_MB_LIB.T6G(SCH_1):M_E_CPU1_SB_CS_N(1)    I52 @T6G_MB_LIB.T6G(SCH_1):PAGE101
   209 M_E_CPU1_SA_CS_N<1> @T6G_MB_LIB.T6G(SCH_1):M_E_CPU1_SA_CS_N(1)    I52 @T6G_MB_LIB.T6G(SCH_1):PAGE101
    84 M_E_CPU1_SB_CS_N<0> @T6G_MB_LIB.T6G(SCH_1):M_E_CPU1_SB_CS_N(0)    I52 @T6G_MB_LIB.T6G(SCH_1):PAGE101
    64 M_E_CPU1_SA_CS_N<0> @T6G_MB_LIB.T6G(SCH_1):M_E_CPU1_SA_CS_N(0)    I52 @T6G_MB_LIB.T6G(SCH_1):PAGE101
   217 M_E_CPU1_CLK_DP<0> @T6G_MB_LIB.T6G(SCH_1):M_E_CPU1_CLK_DP(0)    I52 @T6G_MB_LIB.T6G(SCH_1):PAGE101
   218 M_E_CPU1_CLK_DN<0> @T6G_MB_LIB.T6G(SCH_1):M_E_CPU1_CLK_DN(0)    I52 @T6G_MB_LIB.T6G(SCH_1):PAGE101
    96 M_E_CPU1_SB_CB<0> @T6G_MB_LIB.T6G(SCH_1):M_E_CPU1_SB_CB(0)    I52 @T6G_MB_LIB.T6G(SCH_1):PAGE101
    98 M_E_CPU1_SB_CB<1> @T6G_MB_LIB.T6G(SCH_1):M_E_CPU1_SB_CB(1)    I52 @T6G_MB_LIB.T6G(SCH_1):PAGE101
   241 M_E_CPU1_SB_CB<2> @T6G_MB_LIB.T6G(SCH_1):M_E_CPU1_SB_CB(2)    I52 @T6G_MB_LIB.T6G(SCH_1):PAGE101
   243 M_E_CPU1_SB_CB<3> @T6G_MB_LIB.T6G(SCH_1):M_E_CPU1_SB_CB(3)    I52 @T6G_MB_LIB.T6G(SCH_1):PAGE101
    89 M_E_CPU1_SB_CB<4> @T6G_MB_LIB.T6G(SCH_1):M_E_CPU1_SB_CB(4)    I52 @T6G_MB_LIB.T6G(SCH_1):PAGE101
    91 M_E_CPU1_SB_CB<5> @T6G_MB_LIB.T6G(SCH_1):M_E_CPU1_SB_CB(5)    I52 @T6G_MB_LIB.T6G(SCH_1):PAGE101
   234 M_E_CPU1_SB_CB<6> @T6G_MB_LIB.T6G(SCH_1):M_E_CPU1_SB_CB(6)    I52 @T6G_MB_LIB.T6G(SCH_1):PAGE101
    51 M_E_CPU1_SA_CB<0> @T6G_MB_LIB.T6G(SCH_1):M_E_CPU1_SA_CB(0)    I52 @T6G_MB_LIB.T6G(SCH_1):PAGE101
   196 M_E_CPU1_SA_CB<2> @T6G_MB_LIB.T6G(SCH_1):M_E_CPU1_SA_CB(2)    I52 @T6G_MB_LIB.T6G(SCH_1):PAGE101
   198 M_E_CPU1_SA_CB<3> @T6G_MB_LIB.T6G(SCH_1):M_E_CPU1_SA_CB(3)    I52 @T6G_MB_LIB.T6G(SCH_1):PAGE101
    60 M_E_CPU1_SA_CB<5> @T6G_MB_LIB.T6G(SCH_1):M_E_CPU1_SA_CB(5)    I52 @T6G_MB_LIB.T6G(SCH_1):PAGE101
   203 M_E_CPU1_SA_CB<6> @T6G_MB_LIB.T6G(SCH_1):M_E_CPU1_SA_CB(6)    I52 @T6G_MB_LIB.T6G(SCH_1):PAGE101
    82 M_E_CPU1_SB_CA<6> @T6G_MB_LIB.T6G(SCH_1):M_E_CPU1_SB_CA(6)    I52 @T6G_MB_LIB.T6G(SCH_1):PAGE101
    72 M_E_CPU1_SA_CA<6> @T6G_MB_LIB.T6G(SCH_1):M_E_CPU1_SA_CA(6)    I52 @T6G_MB_LIB.T6G(SCH_1):PAGE101
   225 M_E_CPU1_SB_CA<5> @T6G_MB_LIB.T6G(SCH_1):M_E_CPU1_SB_CA(5)    I52 @T6G_MB_LIB.T6G(SCH_1):PAGE101
   215 M_E_CPU1_SA_CA<5> @T6G_MB_LIB.T6G(SCH_1):M_E_CPU1_SA_CA(5)    I52 @T6G_MB_LIB.T6G(SCH_1):PAGE101
    80 M_E_CPU1_SB_CA<4> @T6G_MB_LIB.T6G(SCH_1):M_E_CPU1_SB_CA(4)    I52 @T6G_MB_LIB.T6G(SCH_1):PAGE101
    70 M_E_CPU1_SA_CA<4> @T6G_MB_LIB.T6G(SCH_1):M_E_CPU1_SA_CA(4)    I52 @T6G_MB_LIB.T6G(SCH_1):PAGE101
   223 M_E_CPU1_SB_CA<3> @T6G_MB_LIB.T6G(SCH_1):M_E_CPU1_SB_CA(3)    I52 @T6G_MB_LIB.T6G(SCH_1):PAGE101
   213 M_E_CPU1_SA_CA<3> @T6G_MB_LIB.T6G(SCH_1):M_E_CPU1_SA_CA(3)    I52 @T6G_MB_LIB.T6G(SCH_1):PAGE101
    78 M_E_CPU1_SB_CA<2> @T6G_MB_LIB.T6G(SCH_1):M_E_CPU1_SB_CA(2)    I52 @T6G_MB_LIB.T6G(SCH_1):PAGE101
    68 M_E_CPU1_SA_CA<2> @T6G_MB_LIB.T6G(SCH_1):M_E_CPU1_SA_CA(2)    I52 @T6G_MB_LIB.T6G(SCH_1):PAGE101
   221 M_E_CPU1_SB_CA<1> @T6G_MB_LIB.T6G(SCH_1):M_E_CPU1_SB_CA(1)    I52 @T6G_MB_LIB.T6G(SCH_1):PAGE101
   211 M_E_CPU1_SA_CA<1> @T6G_MB_LIB.T6G(SCH_1):M_E_CPU1_SA_CA(1)    I52 @T6G_MB_LIB.T6G(SCH_1):PAGE101
    76 M_E_CPU1_SB_CA<0> @T6G_MB_LIB.T6G(SCH_1):M_E_CPU1_SB_CA(0)    I52 @T6G_MB_LIB.T6G(SCH_1):PAGE101
    66 M_E_CPU1_SA_CA<0> @T6G_MB_LIB.T6G(SCH_1):M_E_CPU1_SA_CA(0)    I52 @T6G_MB_LIB.T6G(SCH_1):PAGE101
    62 M_E_CPU1_ALERT_N @T6G_MB_LIB.T6G(SCH_1):M_E_CPU1_ALERT_N    I52 @T6G_MB_LIB.T6G(SCH_1):PAGE101
   236 M_E_CPU1_SB_CB<7> @T6G_MB_LIB.T6G(SCH_1):M_E_CPU1_SB_CB(7)    I52 @T6G_MB_LIB.T6G(SCH_1):PAGE101
    53 M_E_CPU1_SA_CB<1> @T6G_MB_LIB.T6G(SCH_1):M_E_CPU1_SA_CB(1)    I52 @T6G_MB_LIB.T6G(SCH_1):PAGE101
    58 M_E_CPU1_SA_CB<4> @T6G_MB_LIB.T6G(SCH_1):M_E_CPU1_SA_CB(4)    I52 @T6G_MB_LIB.T6G(SCH_1):PAGE101
   205 M_E_CPU1_SA_CB<7> @T6G_MB_LIB.T6G(SCH_1):M_E_CPU1_SA_CB(7)    I52 @T6G_MB_LIB.T6G(SCH_1):PAGE101
   194 M_E_CPU1_SA_DQ<31> @T6G_MB_LIB.T6G(SCH_1):M_E_CPU1_SA_DQ(31)    I52 @T6G_MB_LIB.T6G(SCH_1):PAGE101
    93 M_E_CPU1_SB_DQS_DP<9> @T6G_MB_LIB.T6G(SCH_1):M_E_CPU1_SB_DQS_DP(9)   I236 @T6G_MB_LIB.T6G(SCH_1):PAGE101
    94 M_E_CPU1_SB_DQS_DN<9> @T6G_MB_LIB.T6G(SCH_1):M_E_CPU1_SB_DQS_DN(9)   I236 @T6G_MB_LIB.T6G(SCH_1):PAGE101
   201 M_E_CPU1_SA_DQS_DP<9> @T6G_MB_LIB.T6G(SCH_1):M_E_CPU1_SA_DQS_DP(9)   I236 @T6G_MB_LIB.T6G(SCH_1):PAGE101
   200 M_E_CPU1_SA_DQS_DN<9> @T6G_MB_LIB.T6G(SCH_1):M_E_CPU1_SA_DQS_DN(9)   I236 @T6G_MB_LIB.T6G(SCH_1):PAGE101
   190 M_E_CPU1_SA_DQS_DP<8> @T6G_MB_LIB.T6G(SCH_1):M_E_CPU1_SA_DQS_DP(8)   I236 @T6G_MB_LIB.T6G(SCH_1):PAGE101
   189 M_E_CPU1_SA_DQS_DN<8> @T6G_MB_LIB.T6G(SCH_1):M_E_CPU1_SA_DQS_DN(8)   I236 @T6G_MB_LIB.T6G(SCH_1):PAGE101
   271 M_E_CPU1_SB_DQS_DN<7> @T6G_MB_LIB.T6G(SCH_1):M_E_CPU1_SB_DQS_DN(7)   I236 @T6G_MB_LIB.T6G(SCH_1):PAGE101
   179 M_E_CPU1_SA_DQS_DP<7> @T6G_MB_LIB.T6G(SCH_1):M_E_CPU1_SA_DQS_DP(7)   I236 @T6G_MB_LIB.T6G(SCH_1):PAGE101
   261 M_E_CPU1_SB_DQS_DP<6> @T6G_MB_LIB.T6G(SCH_1):M_E_CPU1_SB_DQS_DP(6)   I236 @T6G_MB_LIB.T6G(SCH_1):PAGE101
   260 M_E_CPU1_SB_DQS_DN<6> @T6G_MB_LIB.T6G(SCH_1):M_E_CPU1_SB_DQS_DN(6)   I236 @T6G_MB_LIB.T6G(SCH_1):PAGE101
   167 M_E_CPU1_SA_DQS_DN<6> @T6G_MB_LIB.T6G(SCH_1):M_E_CPU1_SA_DQS_DN(6)   I236 @T6G_MB_LIB.T6G(SCH_1):PAGE101
   250 M_E_CPU1_SB_DQS_DP<5> @T6G_MB_LIB.T6G(SCH_1):M_E_CPU1_SB_DQS_DP(5)   I236 @T6G_MB_LIB.T6G(SCH_1):PAGE101
   249 M_E_CPU1_SB_DQS_DN<5> @T6G_MB_LIB.T6G(SCH_1):M_E_CPU1_SB_DQS_DN(5)   I236 @T6G_MB_LIB.T6G(SCH_1):PAGE101
   157 M_E_CPU1_SA_DQS_DP<5> @T6G_MB_LIB.T6G(SCH_1):M_E_CPU1_SA_DQS_DP(5)   I236 @T6G_MB_LIB.T6G(SCH_1):PAGE101
   156 M_E_CPU1_SA_DQS_DN<5> @T6G_MB_LIB.T6G(SCH_1):M_E_CPU1_SA_DQS_DN(5)   I236 @T6G_MB_LIB.T6G(SCH_1):PAGE101
   239 M_E_CPU1_SB_DQS_DP<4> @T6G_MB_LIB.T6G(SCH_1):M_E_CPU1_SB_DQS_DP(4)   I236 @T6G_MB_LIB.T6G(SCH_1):PAGE101
   238 M_E_CPU1_SB_DQS_DN<4> @T6G_MB_LIB.T6G(SCH_1):M_E_CPU1_SB_DQS_DN(4)   I236 @T6G_MB_LIB.T6G(SCH_1):PAGE101
    55 M_E_CPU1_SA_DQS_DP<4> @T6G_MB_LIB.T6G(SCH_1):M_E_CPU1_SA_DQS_DP(4)   I236 @T6G_MB_LIB.T6G(SCH_1):PAGE101
    56 M_E_CPU1_SA_DQS_DN<4> @T6G_MB_LIB.T6G(SCH_1):M_E_CPU1_SA_DQS_DN(4)   I236 @T6G_MB_LIB.T6G(SCH_1):PAGE101
   137 M_E_CPU1_SB_DQS_DP<3> @T6G_MB_LIB.T6G(SCH_1):M_E_CPU1_SB_DQS_DP(3)   I236 @T6G_MB_LIB.T6G(SCH_1):PAGE101
   138 M_E_CPU1_SB_DQS_DN<3> @T6G_MB_LIB.T6G(SCH_1):M_E_CPU1_SB_DQS_DN(3)   I236 @T6G_MB_LIB.T6G(SCH_1):PAGE101
    44 M_E_CPU1_SA_DQS_DP<3> @T6G_MB_LIB.T6G(SCH_1):M_E_CPU1_SA_DQS_DP(3)   I236 @T6G_MB_LIB.T6G(SCH_1):PAGE101
    45 M_E_CPU1_SA_DQS_DN<3> @T6G_MB_LIB.T6G(SCH_1):M_E_CPU1_SA_DQS_DN(3)   I236 @T6G_MB_LIB.T6G(SCH_1):PAGE101
   126 M_E_CPU1_SB_DQS_DP<2> @T6G_MB_LIB.T6G(SCH_1):M_E_CPU1_SB_DQS_DP(2)   I236 @T6G_MB_LIB.T6G(SCH_1):PAGE101
   127 M_E_CPU1_SB_DQS_DN<2> @T6G_MB_LIB.T6G(SCH_1):M_E_CPU1_SB_DQS_DN(2)   I236 @T6G_MB_LIB.T6G(SCH_1):PAGE101
    33 M_E_CPU1_SA_DQS_DP<2> @T6G_MB_LIB.T6G(SCH_1):M_E_CPU1_SA_DQS_DP(2)   I236 @T6G_MB_LIB.T6G(SCH_1):PAGE101
    34 M_E_CPU1_SA_DQS_DN<2> @T6G_MB_LIB.T6G(SCH_1):M_E_CPU1_SA_DQS_DN(2)   I236 @T6G_MB_LIB.T6G(SCH_1):PAGE101
   115 M_E_CPU1_SB_DQS_DP<1> @T6G_MB_LIB.T6G(SCH_1):M_E_CPU1_SB_DQS_DP(1)   I236 @T6G_MB_LIB.T6G(SCH_1):PAGE101
   116 M_E_CPU1_SB_DQS_DN<1> @T6G_MB_LIB.T6G(SCH_1):M_E_CPU1_SB_DQS_DN(1)   I236 @T6G_MB_LIB.T6G(SCH_1):PAGE101
    22 M_E_CPU1_SA_DQS_DP<1> @T6G_MB_LIB.T6G(SCH_1):M_E_CPU1_SA_DQS_DP(1)   I236 @T6G_MB_LIB.T6G(SCH_1):PAGE101
    23 M_E_CPU1_SA_DQS_DN<1> @T6G_MB_LIB.T6G(SCH_1):M_E_CPU1_SA_DQS_DN(1)   I236 @T6G_MB_LIB.T6G(SCH_1):PAGE101
   104 M_E_CPU1_SB_DQS_DP<0> @T6G_MB_LIB.T6G(SCH_1):M_E_CPU1_SB_DQS_DP(0)   I236 @T6G_MB_LIB.T6G(SCH_1):PAGE101
   105 M_E_CPU1_SB_DQS_DN<0> @T6G_MB_LIB.T6G(SCH_1):M_E_CPU1_SB_DQS_DN(0)   I236 @T6G_MB_LIB.T6G(SCH_1):PAGE101
    11 M_E_CPU1_SA_DQS_DP<0> @T6G_MB_LIB.T6G(SCH_1):M_E_CPU1_SA_DQS_DP(0)   I236 @T6G_MB_LIB.T6G(SCH_1):PAGE101
    12 M_E_CPU1_SA_DQS_DN<0> @T6G_MB_LIB.T6G(SCH_1):M_E_CPU1_SA_DQS_DN(0)   I236 @T6G_MB_LIB.T6G(SCH_1):PAGE101
   272 M_E_CPU1_SB_DQS_DP<7> @T6G_MB_LIB.T6G(SCH_1):M_E_CPU1_SB_DQS_DP(7)   I236 @T6G_MB_LIB.T6G(SCH_1):PAGE101
   282 M_E_CPU1_SB_DQS_DN<8> @T6G_MB_LIB.T6G(SCH_1):M_E_CPU1_SB_DQS_DN(8)   I236 @T6G_MB_LIB.T6G(SCH_1):PAGE101
   283 M_E_CPU1_SB_DQS_DP<8> @T6G_MB_LIB.T6G(SCH_1):M_E_CPU1_SB_DQS_DP(8)   I236 @T6G_MB_LIB.T6G(SCH_1):PAGE101
   168 M_E_CPU1_SA_DQS_DP<6> @T6G_MB_LIB.T6G(SCH_1):M_E_CPU1_SA_DQS_DP(6)   I236 @T6G_MB_LIB.T6G(SCH_1):PAGE101
   178 M_E_CPU1_SA_DQS_DN<7> @T6G_MB_LIB.T6G(SCH_1):M_E_CPU1_SA_DQS_DN(7)   I236 @T6G_MB_LIB.T6G(SCH_1):PAGE101
     6    GND @T6G_MB_LIB.T6G(SCH_1):GND   I175 @T6G_MB_LIB.T6G(SCH_1):PAGE101
     8    GND @T6G_MB_LIB.T6G(SCH_1):GND   I175 @T6G_MB_LIB.T6G(SCH_1):PAGE101
    10    GND @T6G_MB_LIB.T6G(SCH_1):GND   I175 @T6G_MB_LIB.T6G(SCH_1):PAGE101
    13    GND @T6G_MB_LIB.T6G(SCH_1):GND   I175 @T6G_MB_LIB.T6G(SCH_1):PAGE101
    15    GND @T6G_MB_LIB.T6G(SCH_1):GND   I175 @T6G_MB_LIB.T6G(SCH_1):PAGE101
    17    GND @T6G_MB_LIB.T6G(SCH_1):GND   I175 @T6G_MB_LIB.T6G(SCH_1):PAGE101
    19    GND @T6G_MB_LIB.T6G(SCH_1):GND   I175 @T6G_MB_LIB.T6G(SCH_1):PAGE101
    21    GND @T6G_MB_LIB.T6G(SCH_1):GND   I175 @T6G_MB_LIB.T6G(SCH_1):PAGE101
    24    GND @T6G_MB_LIB.T6G(SCH_1):GND   I175 @T6G_MB_LIB.T6G(SCH_1):PAGE101
    26    GND @T6G_MB_LIB.T6G(SCH_1):GND   I175 @T6G_MB_LIB.T6G(SCH_1):PAGE101
    28    GND @T6G_MB_LIB.T6G(SCH_1):GND   I175 @T6G_MB_LIB.T6G(SCH_1):PAGE101
    30    GND @T6G_MB_LIB.T6G(SCH_1):GND   I175 @T6G_MB_LIB.T6G(SCH_1):PAGE101
    32    GND @T6G_MB_LIB.T6G(SCH_1):GND   I175 @T6G_MB_LIB.T6G(SCH_1):PAGE101
    35    GND @T6G_MB_LIB.T6G(SCH_1):GND   I175 @T6G_MB_LIB.T6G(SCH_1):PAGE101
    37    GND @T6G_MB_LIB.T6G(SCH_1):GND   I175 @T6G_MB_LIB.T6G(SCH_1):PAGE101
    39    GND @T6G_MB_LIB.T6G(SCH_1):GND   I175 @T6G_MB_LIB.T6G(SCH_1):PAGE101
    41    GND @T6G_MB_LIB.T6G(SCH_1):GND   I175 @T6G_MB_LIB.T6G(SCH_1):PAGE101
    43    GND @T6G_MB_LIB.T6G(SCH_1):GND   I175 @T6G_MB_LIB.T6G(SCH_1):PAGE101
    46    GND @T6G_MB_LIB.T6G(SCH_1):GND   I175 @T6G_MB_LIB.T6G(SCH_1):PAGE101
    48    GND @T6G_MB_LIB.T6G(SCH_1):GND   I175 @T6G_MB_LIB.T6G(SCH_1):PAGE101
    50    GND @T6G_MB_LIB.T6G(SCH_1):GND   I175 @T6G_MB_LIB.T6G(SCH_1):PAGE101
    52    GND @T6G_MB_LIB.T6G(SCH_1):GND   I175 @T6G_MB_LIB.T6G(SCH_1):PAGE101
    54    GND @T6G_MB_LIB.T6G(SCH_1):GND   I175 @T6G_MB_LIB.T6G(SCH_1):PAGE101
    57    GND @T6G_MB_LIB.T6G(SCH_1):GND   I175 @T6G_MB_LIB.T6G(SCH_1):PAGE101
    59    GND @T6G_MB_LIB.T6G(SCH_1):GND   I175 @T6G_MB_LIB.T6G(SCH_1):PAGE101
    61    GND @T6G_MB_LIB.T6G(SCH_1):GND   I175 @T6G_MB_LIB.T6G(SCH_1):PAGE101
    63    GND @T6G_MB_LIB.T6G(SCH_1):GND   I175 @T6G_MB_LIB.T6G(SCH_1):PAGE101
    65    GND @T6G_MB_LIB.T6G(SCH_1):GND   I175 @T6G_MB_LIB.T6G(SCH_1):PAGE101
    67    GND @T6G_MB_LIB.T6G(SCH_1):GND   I175 @T6G_MB_LIB.T6G(SCH_1):PAGE101
    69    GND @T6G_MB_LIB.T6G(SCH_1):GND   I175 @T6G_MB_LIB.T6G(SCH_1):PAGE101
    71    GND @T6G_MB_LIB.T6G(SCH_1):GND   I175 @T6G_MB_LIB.T6G(SCH_1):PAGE101
    73    GND @T6G_MB_LIB.T6G(SCH_1):GND   I175 @T6G_MB_LIB.T6G(SCH_1):PAGE101
    75    GND @T6G_MB_LIB.T6G(SCH_1):GND   I175 @T6G_MB_LIB.T6G(SCH_1):PAGE101
    77    GND @T6G_MB_LIB.T6G(SCH_1):GND   I175 @T6G_MB_LIB.T6G(SCH_1):PAGE101
    79    GND @T6G_MB_LIB.T6G(SCH_1):GND   I175 @T6G_MB_LIB.T6G(SCH_1):PAGE101
    81    GND @T6G_MB_LIB.T6G(SCH_1):GND   I175 @T6G_MB_LIB.T6G(SCH_1):PAGE101
    83    GND @T6G_MB_LIB.T6G(SCH_1):GND   I175 @T6G_MB_LIB.T6G(SCH_1):PAGE101
    85    GND @T6G_MB_LIB.T6G(SCH_1):GND   I175 @T6G_MB_LIB.T6G(SCH_1):PAGE101
    88    GND @T6G_MB_LIB.T6G(SCH_1):GND   I175 @T6G_MB_LIB.T6G(SCH_1):PAGE101
    90    GND @T6G_MB_LIB.T6G(SCH_1):GND   I175 @T6G_MB_LIB.T6G(SCH_1):PAGE101
    92    GND @T6G_MB_LIB.T6G(SCH_1):GND   I175 @T6G_MB_LIB.T6G(SCH_1):PAGE101
    95    GND @T6G_MB_LIB.T6G(SCH_1):GND   I175 @T6G_MB_LIB.T6G(SCH_1):PAGE101
    97    GND @T6G_MB_LIB.T6G(SCH_1):GND   I175 @T6G_MB_LIB.T6G(SCH_1):PAGE101
    99    GND @T6G_MB_LIB.T6G(SCH_1):GND   I175 @T6G_MB_LIB.T6G(SCH_1):PAGE101
   101    GND @T6G_MB_LIB.T6G(SCH_1):GND   I175 @T6G_MB_LIB.T6G(SCH_1):PAGE101
   103    GND @T6G_MB_LIB.T6G(SCH_1):GND   I175 @T6G_MB_LIB.T6G(SCH_1):PAGE101
   106    GND @T6G_MB_LIB.T6G(SCH_1):GND   I175 @T6G_MB_LIB.T6G(SCH_1):PAGE101
   108    GND @T6G_MB_LIB.T6G(SCH_1):GND   I175 @T6G_MB_LIB.T6G(SCH_1):PAGE101
   110    GND @T6G_MB_LIB.T6G(SCH_1):GND   I175 @T6G_MB_LIB.T6G(SCH_1):PAGE101
   112    GND @T6G_MB_LIB.T6G(SCH_1):GND   I175 @T6G_MB_LIB.T6G(SCH_1):PAGE101
   114    GND @T6G_MB_LIB.T6G(SCH_1):GND   I175 @T6G_MB_LIB.T6G(SCH_1):PAGE101
   117    GND @T6G_MB_LIB.T6G(SCH_1):GND   I175 @T6G_MB_LIB.T6G(SCH_1):PAGE101
   119    GND @T6G_MB_LIB.T6G(SCH_1):GND   I175 @T6G_MB_LIB.T6G(SCH_1):PAGE101
   121    GND @T6G_MB_LIB.T6G(SCH_1):GND   I175 @T6G_MB_LIB.T6G(SCH_1):PAGE101
   123    GND @T6G_MB_LIB.T6G(SCH_1):GND   I175 @T6G_MB_LIB.T6G(SCH_1):PAGE101
   125    GND @T6G_MB_LIB.T6G(SCH_1):GND   I175 @T6G_MB_LIB.T6G(SCH_1):PAGE101
   128    GND @T6G_MB_LIB.T6G(SCH_1):GND   I175 @T6G_MB_LIB.T6G(SCH_1):PAGE101
   130    GND @T6G_MB_LIB.T6G(SCH_1):GND   I175 @T6G_MB_LIB.T6G(SCH_1):PAGE101
   134    GND @T6G_MB_LIB.T6G(SCH_1):GND   I175 @T6G_MB_LIB.T6G(SCH_1):PAGE101
   143    GND @T6G_MB_LIB.T6G(SCH_1):GND   I175 @T6G_MB_LIB.T6G(SCH_1):PAGE101
   151    GND @T6G_MB_LIB.T6G(SCH_1):GND   I175 @T6G_MB_LIB.T6G(SCH_1):PAGE101
   153    GND @T6G_MB_LIB.T6G(SCH_1):GND   I175 @T6G_MB_LIB.T6G(SCH_1):PAGE101
   155    GND @T6G_MB_LIB.T6G(SCH_1):GND   I175 @T6G_MB_LIB.T6G(SCH_1):PAGE101
   158    GND @T6G_MB_LIB.T6G(SCH_1):GND   I175 @T6G_MB_LIB.T6G(SCH_1):PAGE101
   160    GND @T6G_MB_LIB.T6G(SCH_1):GND   I175 @T6G_MB_LIB.T6G(SCH_1):PAGE101
   162    GND @T6G_MB_LIB.T6G(SCH_1):GND   I175 @T6G_MB_LIB.T6G(SCH_1):PAGE101
   164    GND @T6G_MB_LIB.T6G(SCH_1):GND   I175 @T6G_MB_LIB.T6G(SCH_1):PAGE101
   166    GND @T6G_MB_LIB.T6G(SCH_1):GND   I175 @T6G_MB_LIB.T6G(SCH_1):PAGE101
   169    GND @T6G_MB_LIB.T6G(SCH_1):GND   I175 @T6G_MB_LIB.T6G(SCH_1):PAGE101
   171    GND @T6G_MB_LIB.T6G(SCH_1):GND   I175 @T6G_MB_LIB.T6G(SCH_1):PAGE101
   173    GND @T6G_MB_LIB.T6G(SCH_1):GND   I175 @T6G_MB_LIB.T6G(SCH_1):PAGE101
   175    GND @T6G_MB_LIB.T6G(SCH_1):GND   I175 @T6G_MB_LIB.T6G(SCH_1):PAGE101
   177    GND @T6G_MB_LIB.T6G(SCH_1):GND   I175 @T6G_MB_LIB.T6G(SCH_1):PAGE101
   180    GND @T6G_MB_LIB.T6G(SCH_1):GND   I175 @T6G_MB_LIB.T6G(SCH_1):PAGE101
   182    GND @T6G_MB_LIB.T6G(SCH_1):GND   I175 @T6G_MB_LIB.T6G(SCH_1):PAGE101
   184    GND @T6G_MB_LIB.T6G(SCH_1):GND   I175 @T6G_MB_LIB.T6G(SCH_1):PAGE101
   186    GND @T6G_MB_LIB.T6G(SCH_1):GND   I175 @T6G_MB_LIB.T6G(SCH_1):PAGE101
   188    GND @T6G_MB_LIB.T6G(SCH_1):GND   I175 @T6G_MB_LIB.T6G(SCH_1):PAGE101
   191    GND @T6G_MB_LIB.T6G(SCH_1):GND   I175 @T6G_MB_LIB.T6G(SCH_1):PAGE101
   193    GND @T6G_MB_LIB.T6G(SCH_1):GND   I175 @T6G_MB_LIB.T6G(SCH_1):PAGE101
   195    GND @T6G_MB_LIB.T6G(SCH_1):GND   I175 @T6G_MB_LIB.T6G(SCH_1):PAGE101
   197    GND @T6G_MB_LIB.T6G(SCH_1):GND   I175 @T6G_MB_LIB.T6G(SCH_1):PAGE101
   199    GND @T6G_MB_LIB.T6G(SCH_1):GND   I175 @T6G_MB_LIB.T6G(SCH_1):PAGE101
   202    GND @T6G_MB_LIB.T6G(SCH_1):GND   I175 @T6G_MB_LIB.T6G(SCH_1):PAGE101
   204    GND @T6G_MB_LIB.T6G(SCH_1):GND   I175 @T6G_MB_LIB.T6G(SCH_1):PAGE101
   206    GND @T6G_MB_LIB.T6G(SCH_1):GND   I175 @T6G_MB_LIB.T6G(SCH_1):PAGE101
   208    GND @T6G_MB_LIB.T6G(SCH_1):GND   I175 @T6G_MB_LIB.T6G(SCH_1):PAGE101
   210    GND @T6G_MB_LIB.T6G(SCH_1):GND   I175 @T6G_MB_LIB.T6G(SCH_1):PAGE101
   212    GND @T6G_MB_LIB.T6G(SCH_1):GND   I175 @T6G_MB_LIB.T6G(SCH_1):PAGE101
   214    GND @T6G_MB_LIB.T6G(SCH_1):GND   I175 @T6G_MB_LIB.T6G(SCH_1):PAGE101
   216    GND @T6G_MB_LIB.T6G(SCH_1):GND   I175 @T6G_MB_LIB.T6G(SCH_1):PAGE101
   219    GND @T6G_MB_LIB.T6G(SCH_1):GND   I175 @T6G_MB_LIB.T6G(SCH_1):PAGE101
   222    GND @T6G_MB_LIB.T6G(SCH_1):GND   I175 @T6G_MB_LIB.T6G(SCH_1):PAGE101
   224    GND @T6G_MB_LIB.T6G(SCH_1):GND   I175 @T6G_MB_LIB.T6G(SCH_1):PAGE101
   226    GND @T6G_MB_LIB.T6G(SCH_1):GND   I175 @T6G_MB_LIB.T6G(SCH_1):PAGE101
   228    GND @T6G_MB_LIB.T6G(SCH_1):GND   I175 @T6G_MB_LIB.T6G(SCH_1):PAGE101
   233    GND @T6G_MB_LIB.T6G(SCH_1):GND   I175 @T6G_MB_LIB.T6G(SCH_1):PAGE101
   237    GND @T6G_MB_LIB.T6G(SCH_1):GND   I175 @T6G_MB_LIB.T6G(SCH_1):PAGE101
   242    GND @T6G_MB_LIB.T6G(SCH_1):GND   I175 @T6G_MB_LIB.T6G(SCH_1):PAGE101
   244    GND @T6G_MB_LIB.T6G(SCH_1):GND   I175 @T6G_MB_LIB.T6G(SCH_1):PAGE101
   246    GND @T6G_MB_LIB.T6G(SCH_1):GND   I175 @T6G_MB_LIB.T6G(SCH_1):PAGE101
   248    GND @T6G_MB_LIB.T6G(SCH_1):GND   I175 @T6G_MB_LIB.T6G(SCH_1):PAGE101
   251    GND @T6G_MB_LIB.T6G(SCH_1):GND   I175 @T6G_MB_LIB.T6G(SCH_1):PAGE101
   253    GND @T6G_MB_LIB.T6G(SCH_1):GND   I175 @T6G_MB_LIB.T6G(SCH_1):PAGE101
   255    GND @T6G_MB_LIB.T6G(SCH_1):GND   I175 @T6G_MB_LIB.T6G(SCH_1):PAGE101
   257    GND @T6G_MB_LIB.T6G(SCH_1):GND   I175 @T6G_MB_LIB.T6G(SCH_1):PAGE101
   259    GND @T6G_MB_LIB.T6G(SCH_1):GND   I175 @T6G_MB_LIB.T6G(SCH_1):PAGE101
   262    GND @T6G_MB_LIB.T6G(SCH_1):GND   I175 @T6G_MB_LIB.T6G(SCH_1):PAGE101
   264    GND @T6G_MB_LIB.T6G(SCH_1):GND   I175 @T6G_MB_LIB.T6G(SCH_1):PAGE101
   266    GND @T6G_MB_LIB.T6G(SCH_1):GND   I175 @T6G_MB_LIB.T6G(SCH_1):PAGE101
   268    GND @T6G_MB_LIB.T6G(SCH_1):GND   I175 @T6G_MB_LIB.T6G(SCH_1):PAGE101
   270    GND @T6G_MB_LIB.T6G(SCH_1):GND   I175 @T6G_MB_LIB.T6G(SCH_1):PAGE101
   273    GND @T6G_MB_LIB.T6G(SCH_1):GND   I175 @T6G_MB_LIB.T6G(SCH_1):PAGE101
   275    GND @T6G_MB_LIB.T6G(SCH_1):GND   I175 @T6G_MB_LIB.T6G(SCH_1):PAGE101
   277    GND @T6G_MB_LIB.T6G(SCH_1):GND   I175 @T6G_MB_LIB.T6G(SCH_1):PAGE101
   279    GND @T6G_MB_LIB.T6G(SCH_1):GND   I175 @T6G_MB_LIB.T6G(SCH_1):PAGE101
   281    GND @T6G_MB_LIB.T6G(SCH_1):GND   I175 @T6G_MB_LIB.T6G(SCH_1):PAGE101
   284    GND @T6G_MB_LIB.T6G(SCH_1):GND   I175 @T6G_MB_LIB.T6G(SCH_1):PAGE101
   286    GND @T6G_MB_LIB.T6G(SCH_1):GND   I175 @T6G_MB_LIB.T6G(SCH_1):PAGE101
   288    GND @T6G_MB_LIB.T6G(SCH_1):GND   I175 @T6G_MB_LIB.T6G(SCH_1):PAGE101
     1 P12V_MEM_CPU1 @T6G_MB_LIB.T6G(SCH_1):P12V_MEM_CPU1   I175 @T6G_MB_LIB.T6G(SCH_1):PAGE101
   145 P12V_MEM_CPU1 @T6G_MB_LIB.T6G(SCH_1):P12V_MEM_CPU1   I175 @T6G_MB_LIB.T6G(SCH_1):PAGE101
   146 P12V_MEM_CPU1 @T6G_MB_LIB.T6G(SCH_1):P12V_MEM_CPU1   I175 @T6G_MB_LIB.T6G(SCH_1):PAGE101
   230    GND @T6G_MB_LIB.T6G(SCH_1):GND   I175 @T6G_MB_LIB.T6G(SCH_1):PAGE101
   235    GND @T6G_MB_LIB.T6G(SCH_1):GND   I175 @T6G_MB_LIB.T6G(SCH_1):PAGE101
   240    GND @T6G_MB_LIB.T6G(SCH_1):GND   I175 @T6G_MB_LIB.T6G(SCH_1):PAGE101
   132    GND @T6G_MB_LIB.T6G(SCH_1):GND   I175 @T6G_MB_LIB.T6G(SCH_1):PAGE101
   136    GND @T6G_MB_LIB.T6G(SCH_1):GND   I175 @T6G_MB_LIB.T6G(SCH_1):PAGE101
   139    GND @T6G_MB_LIB.T6G(SCH_1):GND   I175 @T6G_MB_LIB.T6G(SCH_1):PAGE101
   141    GND @T6G_MB_LIB.T6G(SCH_1):GND   I175 @T6G_MB_LIB.T6G(SCH_1):PAGE101
    G1    GND @T6G_MB_LIB.T6G(SCH_1):GND   I175 @T6G_MB_LIB.T6G(SCH_1):PAGE101
    G2    GND @T6G_MB_LIB.T6G(SCH_1):GND   I175 @T6G_MB_LIB.T6G(SCH_1):PAGE101
    G3    GND @T6G_MB_LIB.T6G(SCH_1):GND   I175 @T6G_MB_LIB.T6G(SCH_1):PAGE101

 J33 SCONN288_DDR506112002KQ-SCONN288_DDR506112002KQ,SMA
     3 P3V3_AUX @T6G_MB_LIB.T6G(SCH_1):P3V3_AUX    I22 @T6G_MB_LIB.T6G(SCH_1):PAGE102
     2     NC     NC    I22 @T6G_MB_LIB.T6G(SCH_1):PAGE102
   144     NC     NC    I22 @T6G_MB_LIB.T6G(SCH_1):PAGE102
   149     NC     NC    I22 @T6G_MB_LIB.T6G(SCH_1):PAGE102
   150     NC     NC    I22 @T6G_MB_LIB.T6G(SCH_1):PAGE102
   220     NC     NC    I22 @T6G_MB_LIB.T6G(SCH_1):PAGE102
   231     NC     NC    I22 @T6G_MB_LIB.T6G(SCH_1):PAGE102
   232     NC     NC    I22 @T6G_MB_LIB.T6G(SCH_1):PAGE102
   207 M_F_CPU1_RESET_N @T6G_MB_LIB.T6G(SCH_1):M_F_CPU1_RESET_N    I22 @T6G_MB_LIB.T6G(SCH_1):PAGE102
   147 PWRGD_CHF_CPU1_DIMM @T6G_MB_LIB.T6G(SCH_1):PWRGD_CHF_CPU1_DIMM    I22 @T6G_MB_LIB.T6G(SCH_1):PAGE102
   227 M_F_CPU1_SB_PAR @T6G_MB_LIB.T6G(SCH_1):M_F_CPU1_SB_PAR    I22 @T6G_MB_LIB.T6G(SCH_1):PAGE102
    74 M_F_CPU1_SA_PAR @T6G_MB_LIB.T6G(SCH_1):M_F_CPU1_SA_PAR    I22 @T6G_MB_LIB.T6G(SCH_1):PAGE102
    87 M_F_CPU1_SB_RSP<0> @T6G_MB_LIB.T6G(SCH_1):M_F_CPU1_SB_RSP(0)    I22 @T6G_MB_LIB.T6G(SCH_1):PAGE102
    86 M_F_CPU1_SA_RSP<0> @T6G_MB_LIB.T6G(SCH_1):M_F_CPU1_SA_RSP(0)    I22 @T6G_MB_LIB.T6G(SCH_1):PAGE102
     5 I3C_SPD_DDRF_CPU1_SDA @T6G_MB_LIB.T6G(SCH_1):I3C_SPD_DDRF_CPU1_SDA    I22 @T6G_MB_LIB.T6G(SCH_1):PAGE102
     4 I3C_SPD_DDRF_CPU1_SCL @T6G_MB_LIB.T6G(SCH_1):I3C_SPD_DDRF_CPU1_SCL    I22 @T6G_MB_LIB.T6G(SCH_1):PAGE102
   148 PD_CHF_CPU1_DIMM_SAA @T6G_MB_LIB.T6G(SCH_1):PD_CHF_CPU1_DIMM_SAA    I22 @T6G_MB_LIB.T6G(SCH_1):PAGE102
   100 M_F_CPU1_SB_DQ<0> @T6G_MB_LIB.T6G(SCH_1):M_F_CPU1_SB_DQ(0)    I22 @T6G_MB_LIB.T6G(SCH_1):PAGE102
   102 M_F_CPU1_SB_DQ<1> @T6G_MB_LIB.T6G(SCH_1):M_F_CPU1_SB_DQ(1)    I22 @T6G_MB_LIB.T6G(SCH_1):PAGE102
   245 M_F_CPU1_SB_DQ<2> @T6G_MB_LIB.T6G(SCH_1):M_F_CPU1_SB_DQ(2)    I22 @T6G_MB_LIB.T6G(SCH_1):PAGE102
   247 M_F_CPU1_SB_DQ<3> @T6G_MB_LIB.T6G(SCH_1):M_F_CPU1_SB_DQ(3)    I22 @T6G_MB_LIB.T6G(SCH_1):PAGE102
   107 M_F_CPU1_SB_DQ<4> @T6G_MB_LIB.T6G(SCH_1):M_F_CPU1_SB_DQ(4)    I22 @T6G_MB_LIB.T6G(SCH_1):PAGE102
   109 M_F_CPU1_SB_DQ<5> @T6G_MB_LIB.T6G(SCH_1):M_F_CPU1_SB_DQ(5)    I22 @T6G_MB_LIB.T6G(SCH_1):PAGE102
   252 M_F_CPU1_SB_DQ<6> @T6G_MB_LIB.T6G(SCH_1):M_F_CPU1_SB_DQ(6)    I22 @T6G_MB_LIB.T6G(SCH_1):PAGE102
   254 M_F_CPU1_SB_DQ<7> @T6G_MB_LIB.T6G(SCH_1):M_F_CPU1_SB_DQ(7)    I22 @T6G_MB_LIB.T6G(SCH_1):PAGE102
   111 M_F_CPU1_SB_DQ<8> @T6G_MB_LIB.T6G(SCH_1):M_F_CPU1_SB_DQ(8)    I22 @T6G_MB_LIB.T6G(SCH_1):PAGE102
   113 M_F_CPU1_SB_DQ<9> @T6G_MB_LIB.T6G(SCH_1):M_F_CPU1_SB_DQ(9)    I22 @T6G_MB_LIB.T6G(SCH_1):PAGE102
   256 M_F_CPU1_SB_DQ<10> @T6G_MB_LIB.T6G(SCH_1):M_F_CPU1_SB_DQ(10)    I22 @T6G_MB_LIB.T6G(SCH_1):PAGE102
   258 M_F_CPU1_SB_DQ<11> @T6G_MB_LIB.T6G(SCH_1):M_F_CPU1_SB_DQ(11)    I22 @T6G_MB_LIB.T6G(SCH_1):PAGE102
   118 M_F_CPU1_SB_DQ<12> @T6G_MB_LIB.T6G(SCH_1):M_F_CPU1_SB_DQ(12)    I22 @T6G_MB_LIB.T6G(SCH_1):PAGE102
   120 M_F_CPU1_SB_DQ<13> @T6G_MB_LIB.T6G(SCH_1):M_F_CPU1_SB_DQ(13)    I22 @T6G_MB_LIB.T6G(SCH_1):PAGE102
   263 M_F_CPU1_SB_DQ<14> @T6G_MB_LIB.T6G(SCH_1):M_F_CPU1_SB_DQ(14)    I22 @T6G_MB_LIB.T6G(SCH_1):PAGE102
   265 M_F_CPU1_SB_DQ<15> @T6G_MB_LIB.T6G(SCH_1):M_F_CPU1_SB_DQ(15)    I22 @T6G_MB_LIB.T6G(SCH_1):PAGE102
   122 M_F_CPU1_SB_DQ<16> @T6G_MB_LIB.T6G(SCH_1):M_F_CPU1_SB_DQ(16)    I22 @T6G_MB_LIB.T6G(SCH_1):PAGE102
   124 M_F_CPU1_SB_DQ<17> @T6G_MB_LIB.T6G(SCH_1):M_F_CPU1_SB_DQ(17)    I22 @T6G_MB_LIB.T6G(SCH_1):PAGE102
   267 M_F_CPU1_SB_DQ<18> @T6G_MB_LIB.T6G(SCH_1):M_F_CPU1_SB_DQ(18)    I22 @T6G_MB_LIB.T6G(SCH_1):PAGE102
   269 M_F_CPU1_SB_DQ<19> @T6G_MB_LIB.T6G(SCH_1):M_F_CPU1_SB_DQ(19)    I22 @T6G_MB_LIB.T6G(SCH_1):PAGE102
   129 M_F_CPU1_SB_DQ<20> @T6G_MB_LIB.T6G(SCH_1):M_F_CPU1_SB_DQ(20)    I22 @T6G_MB_LIB.T6G(SCH_1):PAGE102
   131 M_F_CPU1_SB_DQ<21> @T6G_MB_LIB.T6G(SCH_1):M_F_CPU1_SB_DQ(21)    I22 @T6G_MB_LIB.T6G(SCH_1):PAGE102
   274 M_F_CPU1_SB_DQ<22> @T6G_MB_LIB.T6G(SCH_1):M_F_CPU1_SB_DQ(22)    I22 @T6G_MB_LIB.T6G(SCH_1):PAGE102
   276 M_F_CPU1_SB_DQ<23> @T6G_MB_LIB.T6G(SCH_1):M_F_CPU1_SB_DQ(23)    I22 @T6G_MB_LIB.T6G(SCH_1):PAGE102
   133 M_F_CPU1_SB_DQ<24> @T6G_MB_LIB.T6G(SCH_1):M_F_CPU1_SB_DQ(24)    I22 @T6G_MB_LIB.T6G(SCH_1):PAGE102
   135 M_F_CPU1_SB_DQ<25> @T6G_MB_LIB.T6G(SCH_1):M_F_CPU1_SB_DQ(25)    I22 @T6G_MB_LIB.T6G(SCH_1):PAGE102
   278 M_F_CPU1_SB_DQ<26> @T6G_MB_LIB.T6G(SCH_1):M_F_CPU1_SB_DQ(26)    I22 @T6G_MB_LIB.T6G(SCH_1):PAGE102
   280 M_F_CPU1_SB_DQ<27> @T6G_MB_LIB.T6G(SCH_1):M_F_CPU1_SB_DQ(27)    I22 @T6G_MB_LIB.T6G(SCH_1):PAGE102
   140 M_F_CPU1_SB_DQ<28> @T6G_MB_LIB.T6G(SCH_1):M_F_CPU1_SB_DQ(28)    I22 @T6G_MB_LIB.T6G(SCH_1):PAGE102
   142 M_F_CPU1_SB_DQ<29> @T6G_MB_LIB.T6G(SCH_1):M_F_CPU1_SB_DQ(29)    I22 @T6G_MB_LIB.T6G(SCH_1):PAGE102
   285 M_F_CPU1_SB_DQ<30> @T6G_MB_LIB.T6G(SCH_1):M_F_CPU1_SB_DQ(30)    I22 @T6G_MB_LIB.T6G(SCH_1):PAGE102
   287 M_F_CPU1_SB_DQ<31> @T6G_MB_LIB.T6G(SCH_1):M_F_CPU1_SB_DQ(31)    I22 @T6G_MB_LIB.T6G(SCH_1):PAGE102
     7 M_F_CPU1_SA_DQ<0> @T6G_MB_LIB.T6G(SCH_1):M_F_CPU1_SA_DQ(0)    I22 @T6G_MB_LIB.T6G(SCH_1):PAGE102
     9 M_F_CPU1_SA_DQ<1> @T6G_MB_LIB.T6G(SCH_1):M_F_CPU1_SA_DQ(1)    I22 @T6G_MB_LIB.T6G(SCH_1):PAGE102
   152 M_F_CPU1_SA_DQ<2> @T6G_MB_LIB.T6G(SCH_1):M_F_CPU1_SA_DQ(2)    I22 @T6G_MB_LIB.T6G(SCH_1):PAGE102
   154 M_F_CPU1_SA_DQ<3> @T6G_MB_LIB.T6G(SCH_1):M_F_CPU1_SA_DQ(3)    I22 @T6G_MB_LIB.T6G(SCH_1):PAGE102
    14 M_F_CPU1_SA_DQ<4> @T6G_MB_LIB.T6G(SCH_1):M_F_CPU1_SA_DQ(4)    I22 @T6G_MB_LIB.T6G(SCH_1):PAGE102
    16 M_F_CPU1_SA_DQ<5> @T6G_MB_LIB.T6G(SCH_1):M_F_CPU1_SA_DQ(5)    I22 @T6G_MB_LIB.T6G(SCH_1):PAGE102
   159 M_F_CPU1_SA_DQ<6> @T6G_MB_LIB.T6G(SCH_1):M_F_CPU1_SA_DQ(6)    I22 @T6G_MB_LIB.T6G(SCH_1):PAGE102
   161 M_F_CPU1_SA_DQ<7> @T6G_MB_LIB.T6G(SCH_1):M_F_CPU1_SA_DQ(7)    I22 @T6G_MB_LIB.T6G(SCH_1):PAGE102
    18 M_F_CPU1_SA_DQ<8> @T6G_MB_LIB.T6G(SCH_1):M_F_CPU1_SA_DQ(8)    I22 @T6G_MB_LIB.T6G(SCH_1):PAGE102
    20 M_F_CPU1_SA_DQ<9> @T6G_MB_LIB.T6G(SCH_1):M_F_CPU1_SA_DQ(9)    I22 @T6G_MB_LIB.T6G(SCH_1):PAGE102
   163 M_F_CPU1_SA_DQ<10> @T6G_MB_LIB.T6G(SCH_1):M_F_CPU1_SA_DQ(10)    I22 @T6G_MB_LIB.T6G(SCH_1):PAGE102
   165 M_F_CPU1_SA_DQ<11> @T6G_MB_LIB.T6G(SCH_1):M_F_CPU1_SA_DQ(11)    I22 @T6G_MB_LIB.T6G(SCH_1):PAGE102
    25 M_F_CPU1_SA_DQ<12> @T6G_MB_LIB.T6G(SCH_1):M_F_CPU1_SA_DQ(12)    I22 @T6G_MB_LIB.T6G(SCH_1):PAGE102
    27 M_F_CPU1_SA_DQ<13> @T6G_MB_LIB.T6G(SCH_1):M_F_CPU1_SA_DQ(13)    I22 @T6G_MB_LIB.T6G(SCH_1):PAGE102
   170 M_F_CPU1_SA_DQ<14> @T6G_MB_LIB.T6G(SCH_1):M_F_CPU1_SA_DQ(14)    I22 @T6G_MB_LIB.T6G(SCH_1):PAGE102
   172 M_F_CPU1_SA_DQ<15> @T6G_MB_LIB.T6G(SCH_1):M_F_CPU1_SA_DQ(15)    I22 @T6G_MB_LIB.T6G(SCH_1):PAGE102
    29 M_F_CPU1_SA_DQ<16> @T6G_MB_LIB.T6G(SCH_1):M_F_CPU1_SA_DQ(16)    I22 @T6G_MB_LIB.T6G(SCH_1):PAGE102
    31 M_F_CPU1_SA_DQ<17> @T6G_MB_LIB.T6G(SCH_1):M_F_CPU1_SA_DQ(17)    I22 @T6G_MB_LIB.T6G(SCH_1):PAGE102
   174 M_F_CPU1_SA_DQ<18> @T6G_MB_LIB.T6G(SCH_1):M_F_CPU1_SA_DQ(18)    I22 @T6G_MB_LIB.T6G(SCH_1):PAGE102
   176 M_F_CPU1_SA_DQ<19> @T6G_MB_LIB.T6G(SCH_1):M_F_CPU1_SA_DQ(19)    I22 @T6G_MB_LIB.T6G(SCH_1):PAGE102
    36 M_F_CPU1_SA_DQ<20> @T6G_MB_LIB.T6G(SCH_1):M_F_CPU1_SA_DQ(20)    I22 @T6G_MB_LIB.T6G(SCH_1):PAGE102
    38 M_F_CPU1_SA_DQ<21> @T6G_MB_LIB.T6G(SCH_1):M_F_CPU1_SA_DQ(21)    I22 @T6G_MB_LIB.T6G(SCH_1):PAGE102
   181 M_F_CPU1_SA_DQ<22> @T6G_MB_LIB.T6G(SCH_1):M_F_CPU1_SA_DQ(22)    I22 @T6G_MB_LIB.T6G(SCH_1):PAGE102
   183 M_F_CPU1_SA_DQ<23> @T6G_MB_LIB.T6G(SCH_1):M_F_CPU1_SA_DQ(23)    I22 @T6G_MB_LIB.T6G(SCH_1):PAGE102
    40 M_F_CPU1_SA_DQ<24> @T6G_MB_LIB.T6G(SCH_1):M_F_CPU1_SA_DQ(24)    I22 @T6G_MB_LIB.T6G(SCH_1):PAGE102
    42 M_F_CPU1_SA_DQ<25> @T6G_MB_LIB.T6G(SCH_1):M_F_CPU1_SA_DQ(25)    I22 @T6G_MB_LIB.T6G(SCH_1):PAGE102
   185 M_F_CPU1_SA_DQ<26> @T6G_MB_LIB.T6G(SCH_1):M_F_CPU1_SA_DQ(26)    I22 @T6G_MB_LIB.T6G(SCH_1):PAGE102
   187 M_F_CPU1_SA_DQ<27> @T6G_MB_LIB.T6G(SCH_1):M_F_CPU1_SA_DQ(27)    I22 @T6G_MB_LIB.T6G(SCH_1):PAGE102
    47 M_F_CPU1_SA_DQ<28> @T6G_MB_LIB.T6G(SCH_1):M_F_CPU1_SA_DQ(28)    I22 @T6G_MB_LIB.T6G(SCH_1):PAGE102
    49 M_F_CPU1_SA_DQ<29> @T6G_MB_LIB.T6G(SCH_1):M_F_CPU1_SA_DQ(29)    I22 @T6G_MB_LIB.T6G(SCH_1):PAGE102
   192 M_F_CPU1_SA_DQ<30> @T6G_MB_LIB.T6G(SCH_1):M_F_CPU1_SA_DQ(30)    I22 @T6G_MB_LIB.T6G(SCH_1):PAGE102
   229 M_F_CPU1_SB_CS_N<1> @T6G_MB_LIB.T6G(SCH_1):M_F_CPU1_SB_CS_N(1)    I22 @T6G_MB_LIB.T6G(SCH_1):PAGE102
   209 M_F_CPU1_SA_CS_N<1> @T6G_MB_LIB.T6G(SCH_1):M_F_CPU1_SA_CS_N(1)    I22 @T6G_MB_LIB.T6G(SCH_1):PAGE102
    84 M_F_CPU1_SB_CS_N<0> @T6G_MB_LIB.T6G(SCH_1):M_F_CPU1_SB_CS_N(0)    I22 @T6G_MB_LIB.T6G(SCH_1):PAGE102
    64 M_F_CPU1_SA_CS_N<0> @T6G_MB_LIB.T6G(SCH_1):M_F_CPU1_SA_CS_N(0)    I22 @T6G_MB_LIB.T6G(SCH_1):PAGE102
   217 M_F_CPU1_CLK_DP<0> @T6G_MB_LIB.T6G(SCH_1):M_F_CPU1_CLK_DP(0)    I22 @T6G_MB_LIB.T6G(SCH_1):PAGE102
   218 M_F_CPU1_CLK_DN<0> @T6G_MB_LIB.T6G(SCH_1):M_F_CPU1_CLK_DN(0)    I22 @T6G_MB_LIB.T6G(SCH_1):PAGE102
    96 M_F_CPU1_SB_CB<0> @T6G_MB_LIB.T6G(SCH_1):M_F_CPU1_SB_CB(0)    I22 @T6G_MB_LIB.T6G(SCH_1):PAGE102
    98 M_F_CPU1_SB_CB<1> @T6G_MB_LIB.T6G(SCH_1):M_F_CPU1_SB_CB(1)    I22 @T6G_MB_LIB.T6G(SCH_1):PAGE102
   241 M_F_CPU1_SB_CB<2> @T6G_MB_LIB.T6G(SCH_1):M_F_CPU1_SB_CB(2)    I22 @T6G_MB_LIB.T6G(SCH_1):PAGE102
   243 M_F_CPU1_SB_CB<3> @T6G_MB_LIB.T6G(SCH_1):M_F_CPU1_SB_CB(3)    I22 @T6G_MB_LIB.T6G(SCH_1):PAGE102
    89 M_F_CPU1_SB_CB<4> @T6G_MB_LIB.T6G(SCH_1):M_F_CPU1_SB_CB(4)    I22 @T6G_MB_LIB.T6G(SCH_1):PAGE102
    91 M_F_CPU1_SB_CB<5> @T6G_MB_LIB.T6G(SCH_1):M_F_CPU1_SB_CB(5)    I22 @T6G_MB_LIB.T6G(SCH_1):PAGE102
   234 M_F_CPU1_SB_CB<6> @T6G_MB_LIB.T6G(SCH_1):M_F_CPU1_SB_CB(6)    I22 @T6G_MB_LIB.T6G(SCH_1):PAGE102
    51 M_F_CPU1_SA_CB<0> @T6G_MB_LIB.T6G(SCH_1):M_F_CPU1_SA_CB(0)    I22 @T6G_MB_LIB.T6G(SCH_1):PAGE102
   196 M_F_CPU1_SA_CB<2> @T6G_MB_LIB.T6G(SCH_1):M_F_CPU1_SA_CB(2)    I22 @T6G_MB_LIB.T6G(SCH_1):PAGE102
   198 M_F_CPU1_SA_CB<3> @T6G_MB_LIB.T6G(SCH_1):M_F_CPU1_SA_CB(3)    I22 @T6G_MB_LIB.T6G(SCH_1):PAGE102
    60 M_F_CPU1_SA_CB<5> @T6G_MB_LIB.T6G(SCH_1):M_F_CPU1_SA_CB(5)    I22 @T6G_MB_LIB.T6G(SCH_1):PAGE102
   203 M_F_CPU1_SA_CB<6> @T6G_MB_LIB.T6G(SCH_1):M_F_CPU1_SA_CB(6)    I22 @T6G_MB_LIB.T6G(SCH_1):PAGE102
    82 M_F_CPU1_SB_CA<6> @T6G_MB_LIB.T6G(SCH_1):M_F_CPU1_SB_CA(6)    I22 @T6G_MB_LIB.T6G(SCH_1):PAGE102
    72 M_F_CPU1_SA_CA<6> @T6G_MB_LIB.T6G(SCH_1):M_F_CPU1_SA_CA(6)    I22 @T6G_MB_LIB.T6G(SCH_1):PAGE102
   225 M_F_CPU1_SB_CA<5> @T6G_MB_LIB.T6G(SCH_1):M_F_CPU1_SB_CA(5)    I22 @T6G_MB_LIB.T6G(SCH_1):PAGE102
   215 M_F_CPU1_SA_CA<5> @T6G_MB_LIB.T6G(SCH_1):M_F_CPU1_SA_CA(5)    I22 @T6G_MB_LIB.T6G(SCH_1):PAGE102
    80 M_F_CPU1_SB_CA<4> @T6G_MB_LIB.T6G(SCH_1):M_F_CPU1_SB_CA(4)    I22 @T6G_MB_LIB.T6G(SCH_1):PAGE102
    70 M_F_CPU1_SA_CA<4> @T6G_MB_LIB.T6G(SCH_1):M_F_CPU1_SA_CA(4)    I22 @T6G_MB_LIB.T6G(SCH_1):PAGE102
   223 M_F_CPU1_SB_CA<3> @T6G_MB_LIB.T6G(SCH_1):M_F_CPU1_SB_CA(3)    I22 @T6G_MB_LIB.T6G(SCH_1):PAGE102
   213 M_F_CPU1_SA_CA<3> @T6G_MB_LIB.T6G(SCH_1):M_F_CPU1_SA_CA(3)    I22 @T6G_MB_LIB.T6G(SCH_1):PAGE102
    78 M_F_CPU1_SB_CA<2> @T6G_MB_LIB.T6G(SCH_1):M_F_CPU1_SB_CA(2)    I22 @T6G_MB_LIB.T6G(SCH_1):PAGE102
    68 M_F_CPU1_SA_CA<2> @T6G_MB_LIB.T6G(SCH_1):M_F_CPU1_SA_CA(2)    I22 @T6G_MB_LIB.T6G(SCH_1):PAGE102
   221 M_F_CPU1_SB_CA<1> @T6G_MB_LIB.T6G(SCH_1):M_F_CPU1_SB_CA(1)    I22 @T6G_MB_LIB.T6G(SCH_1):PAGE102
   211 M_F_CPU1_SA_CA<1> @T6G_MB_LIB.T6G(SCH_1):M_F_CPU1_SA_CA(1)    I22 @T6G_MB_LIB.T6G(SCH_1):PAGE102
    76 M_F_CPU1_SB_CA<0> @T6G_MB_LIB.T6G(SCH_1):M_F_CPU1_SB_CA(0)    I22 @T6G_MB_LIB.T6G(SCH_1):PAGE102
    66 M_F_CPU1_SA_CA<0> @T6G_MB_LIB.T6G(SCH_1):M_F_CPU1_SA_CA(0)    I22 @T6G_MB_LIB.T6G(SCH_1):PAGE102
    62 M_F_CPU1_ALERT_N @T6G_MB_LIB.T6G(SCH_1):M_F_CPU1_ALERT_N    I22 @T6G_MB_LIB.T6G(SCH_1):PAGE102
   236 M_F_CPU1_SB_CB<7> @T6G_MB_LIB.T6G(SCH_1):M_F_CPU1_SB_CB(7)    I22 @T6G_MB_LIB.T6G(SCH_1):PAGE102
    53 M_F_CPU1_SA_CB<1> @T6G_MB_LIB.T6G(SCH_1):M_F_CPU1_SA_CB(1)    I22 @T6G_MB_LIB.T6G(SCH_1):PAGE102
    58 M_F_CPU1_SA_CB<4> @T6G_MB_LIB.T6G(SCH_1):M_F_CPU1_SA_CB(4)    I22 @T6G_MB_LIB.T6G(SCH_1):PAGE102
   205 M_F_CPU1_SA_CB<7> @T6G_MB_LIB.T6G(SCH_1):M_F_CPU1_SA_CB(7)    I22 @T6G_MB_LIB.T6G(SCH_1):PAGE102
   194 M_F_CPU1_SA_DQ<31> @T6G_MB_LIB.T6G(SCH_1):M_F_CPU1_SA_DQ(31)    I22 @T6G_MB_LIB.T6G(SCH_1):PAGE102
    93 M_F_CPU1_SB_DQS_DP<9> @T6G_MB_LIB.T6G(SCH_1):M_F_CPU1_SB_DQS_DP(9)   I236 @T6G_MB_LIB.T6G(SCH_1):PAGE102
    94 M_F_CPU1_SB_DQS_DN<9> @T6G_MB_LIB.T6G(SCH_1):M_F_CPU1_SB_DQS_DN(9)   I236 @T6G_MB_LIB.T6G(SCH_1):PAGE102
   201 M_F_CPU1_SA_DQS_DP<9> @T6G_MB_LIB.T6G(SCH_1):M_F_CPU1_SA_DQS_DP(9)   I236 @T6G_MB_LIB.T6G(SCH_1):PAGE102
   200 M_F_CPU1_SA_DQS_DN<9> @T6G_MB_LIB.T6G(SCH_1):M_F_CPU1_SA_DQS_DN(9)   I236 @T6G_MB_LIB.T6G(SCH_1):PAGE102
   190 M_F_CPU1_SA_DQS_DP<8> @T6G_MB_LIB.T6G(SCH_1):M_F_CPU1_SA_DQS_DP(8)   I236 @T6G_MB_LIB.T6G(SCH_1):PAGE102
   189 M_F_CPU1_SA_DQS_DN<8> @T6G_MB_LIB.T6G(SCH_1):M_F_CPU1_SA_DQS_DN(8)   I236 @T6G_MB_LIB.T6G(SCH_1):PAGE102
   271 M_F_CPU1_SB_DQS_DN<7> @T6G_MB_LIB.T6G(SCH_1):M_F_CPU1_SB_DQS_DN(7)   I236 @T6G_MB_LIB.T6G(SCH_1):PAGE102
   179 M_F_CPU1_SA_DQS_DP<7> @T6G_MB_LIB.T6G(SCH_1):M_F_CPU1_SA_DQS_DP(7)   I236 @T6G_MB_LIB.T6G(SCH_1):PAGE102
   261 M_F_CPU1_SB_DQS_DP<6> @T6G_MB_LIB.T6G(SCH_1):M_F_CPU1_SB_DQS_DP(6)   I236 @T6G_MB_LIB.T6G(SCH_1):PAGE102
   260 M_F_CPU1_SB_DQS_DN<6> @T6G_MB_LIB.T6G(SCH_1):M_F_CPU1_SB_DQS_DN(6)   I236 @T6G_MB_LIB.T6G(SCH_1):PAGE102
   167 M_F_CPU1_SA_DQS_DN<6> @T6G_MB_LIB.T6G(SCH_1):M_F_CPU1_SA_DQS_DN(6)   I236 @T6G_MB_LIB.T6G(SCH_1):PAGE102
   250 M_F_CPU1_SB_DQS_DP<5> @T6G_MB_LIB.T6G(SCH_1):M_F_CPU1_SB_DQS_DP(5)   I236 @T6G_MB_LIB.T6G(SCH_1):PAGE102
   249 M_F_CPU1_SB_DQS_DN<5> @T6G_MB_LIB.T6G(SCH_1):M_F_CPU1_SB_DQS_DN(5)   I236 @T6G_MB_LIB.T6G(SCH_1):PAGE102
   157 M_F_CPU1_SA_DQS_DP<5> @T6G_MB_LIB.T6G(SCH_1):M_F_CPU1_SA_DQS_DP(5)   I236 @T6G_MB_LIB.T6G(SCH_1):PAGE102
   156 M_F_CPU1_SA_DQS_DN<5> @T6G_MB_LIB.T6G(SCH_1):M_F_CPU1_SA_DQS_DN(5)   I236 @T6G_MB_LIB.T6G(SCH_1):PAGE102
   239 M_F_CPU1_SB_DQS_DP<4> @T6G_MB_LIB.T6G(SCH_1):M_F_CPU1_SB_DQS_DP(4)   I236 @T6G_MB_LIB.T6G(SCH_1):PAGE102
   238 M_F_CPU1_SB_DQS_DN<4> @T6G_MB_LIB.T6G(SCH_1):M_F_CPU1_SB_DQS_DN(4)   I236 @T6G_MB_LIB.T6G(SCH_1):PAGE102
    55 M_F_CPU1_SA_DQS_DP<4> @T6G_MB_LIB.T6G(SCH_1):M_F_CPU1_SA_DQS_DP(4)   I236 @T6G_MB_LIB.T6G(SCH_1):PAGE102
    56 M_F_CPU1_SA_DQS_DN<4> @T6G_MB_LIB.T6G(SCH_1):M_F_CPU1_SA_DQS_DN(4)   I236 @T6G_MB_LIB.T6G(SCH_1):PAGE102
   137 M_F_CPU1_SB_DQS_DP<3> @T6G_MB_LIB.T6G(SCH_1):M_F_CPU1_SB_DQS_DP(3)   I236 @T6G_MB_LIB.T6G(SCH_1):PAGE102
   138 M_F_CPU1_SB_DQS_DN<3> @T6G_MB_LIB.T6G(SCH_1):M_F_CPU1_SB_DQS_DN(3)   I236 @T6G_MB_LIB.T6G(SCH_1):PAGE102
    44 M_F_CPU1_SA_DQS_DP<3> @T6G_MB_LIB.T6G(SCH_1):M_F_CPU1_SA_DQS_DP(3)   I236 @T6G_MB_LIB.T6G(SCH_1):PAGE102
    45 M_F_CPU1_SA_DQS_DN<3> @T6G_MB_LIB.T6G(SCH_1):M_F_CPU1_SA_DQS_DN(3)   I236 @T6G_MB_LIB.T6G(SCH_1):PAGE102
   126 M_F_CPU1_SB_DQS_DP<2> @T6G_MB_LIB.T6G(SCH_1):M_F_CPU1_SB_DQS_DP(2)   I236 @T6G_MB_LIB.T6G(SCH_1):PAGE102
   127 M_F_CPU1_SB_DQS_DN<2> @T6G_MB_LIB.T6G(SCH_1):M_F_CPU1_SB_DQS_DN(2)   I236 @T6G_MB_LIB.T6G(SCH_1):PAGE102
    33 M_F_CPU1_SA_DQS_DP<2> @T6G_MB_LIB.T6G(SCH_1):M_F_CPU1_SA_DQS_DP(2)   I236 @T6G_MB_LIB.T6G(SCH_1):PAGE102
    34 M_F_CPU1_SA_DQS_DN<2> @T6G_MB_LIB.T6G(SCH_1):M_F_CPU1_SA_DQS_DN(2)   I236 @T6G_MB_LIB.T6G(SCH_1):PAGE102
   115 M_F_CPU1_SB_DQS_DP<1> @T6G_MB_LIB.T6G(SCH_1):M_F_CPU1_SB_DQS_DP(1)   I236 @T6G_MB_LIB.T6G(SCH_1):PAGE102
   116 M_F_CPU1_SB_DQS_DN<1> @T6G_MB_LIB.T6G(SCH_1):M_F_CPU1_SB_DQS_DN(1)   I236 @T6G_MB_LIB.T6G(SCH_1):PAGE102
    22 M_F_CPU1_SA_DQS_DP<1> @T6G_MB_LIB.T6G(SCH_1):M_F_CPU1_SA_DQS_DP(1)   I236 @T6G_MB_LIB.T6G(SCH_1):PAGE102
    23 M_F_CPU1_SA_DQS_DN<1> @T6G_MB_LIB.T6G(SCH_1):M_F_CPU1_SA_DQS_DN(1)   I236 @T6G_MB_LIB.T6G(SCH_1):PAGE102
   104 M_F_CPU1_SB_DQS_DP<0> @T6G_MB_LIB.T6G(SCH_1):M_F_CPU1_SB_DQS_DP(0)   I236 @T6G_MB_LIB.T6G(SCH_1):PAGE102
   105 M_F_CPU1_SB_DQS_DN<0> @T6G_MB_LIB.T6G(SCH_1):M_F_CPU1_SB_DQS_DN(0)   I236 @T6G_MB_LIB.T6G(SCH_1):PAGE102
    11 M_F_CPU1_SA_DQS_DP<0> @T6G_MB_LIB.T6G(SCH_1):M_F_CPU1_SA_DQS_DP(0)   I236 @T6G_MB_LIB.T6G(SCH_1):PAGE102
    12 M_F_CPU1_SA_DQS_DN<0> @T6G_MB_LIB.T6G(SCH_1):M_F_CPU1_SA_DQS_DN(0)   I236 @T6G_MB_LIB.T6G(SCH_1):PAGE102
   272 M_F_CPU1_SB_DQS_DP<7> @T6G_MB_LIB.T6G(SCH_1):M_F_CPU1_SB_DQS_DP(7)   I236 @T6G_MB_LIB.T6G(SCH_1):PAGE102
   282 M_F_CPU1_SB_DQS_DN<8> @T6G_MB_LIB.T6G(SCH_1):M_F_CPU1_SB_DQS_DN(8)   I236 @T6G_MB_LIB.T6G(SCH_1):PAGE102
   283 M_F_CPU1_SB_DQS_DP<8> @T6G_MB_LIB.T6G(SCH_1):M_F_CPU1_SB_DQS_DP(8)   I236 @T6G_MB_LIB.T6G(SCH_1):PAGE102
   168 M_F_CPU1_SA_DQS_DP<6> @T6G_MB_LIB.T6G(SCH_1):M_F_CPU1_SA_DQS_DP(6)   I236 @T6G_MB_LIB.T6G(SCH_1):PAGE102
   178 M_F_CPU1_SA_DQS_DN<7> @T6G_MB_LIB.T6G(SCH_1):M_F_CPU1_SA_DQS_DN(7)   I236 @T6G_MB_LIB.T6G(SCH_1):PAGE102
     6    GND @T6G_MB_LIB.T6G(SCH_1):GND   I142 @T6G_MB_LIB.T6G(SCH_1):PAGE102
     8    GND @T6G_MB_LIB.T6G(SCH_1):GND   I142 @T6G_MB_LIB.T6G(SCH_1):PAGE102
    10    GND @T6G_MB_LIB.T6G(SCH_1):GND   I142 @T6G_MB_LIB.T6G(SCH_1):PAGE102
    13    GND @T6G_MB_LIB.T6G(SCH_1):GND   I142 @T6G_MB_LIB.T6G(SCH_1):PAGE102
    15    GND @T6G_MB_LIB.T6G(SCH_1):GND   I142 @T6G_MB_LIB.T6G(SCH_1):PAGE102
    17    GND @T6G_MB_LIB.T6G(SCH_1):GND   I142 @T6G_MB_LIB.T6G(SCH_1):PAGE102
    19    GND @T6G_MB_LIB.T6G(SCH_1):GND   I142 @T6G_MB_LIB.T6G(SCH_1):PAGE102
    21    GND @T6G_MB_LIB.T6G(SCH_1):GND   I142 @T6G_MB_LIB.T6G(SCH_1):PAGE102
    24    GND @T6G_MB_LIB.T6G(SCH_1):GND   I142 @T6G_MB_LIB.T6G(SCH_1):PAGE102
    26    GND @T6G_MB_LIB.T6G(SCH_1):GND   I142 @T6G_MB_LIB.T6G(SCH_1):PAGE102
    28    GND @T6G_MB_LIB.T6G(SCH_1):GND   I142 @T6G_MB_LIB.T6G(SCH_1):PAGE102
    30    GND @T6G_MB_LIB.T6G(SCH_1):GND   I142 @T6G_MB_LIB.T6G(SCH_1):PAGE102
    32    GND @T6G_MB_LIB.T6G(SCH_1):GND   I142 @T6G_MB_LIB.T6G(SCH_1):PAGE102
    35    GND @T6G_MB_LIB.T6G(SCH_1):GND   I142 @T6G_MB_LIB.T6G(SCH_1):PAGE102
    37    GND @T6G_MB_LIB.T6G(SCH_1):GND   I142 @T6G_MB_LIB.T6G(SCH_1):PAGE102
    39    GND @T6G_MB_LIB.T6G(SCH_1):GND   I142 @T6G_MB_LIB.T6G(SCH_1):PAGE102
    41    GND @T6G_MB_LIB.T6G(SCH_1):GND   I142 @T6G_MB_LIB.T6G(SCH_1):PAGE102
    43    GND @T6G_MB_LIB.T6G(SCH_1):GND   I142 @T6G_MB_LIB.T6G(SCH_1):PAGE102
    46    GND @T6G_MB_LIB.T6G(SCH_1):GND   I142 @T6G_MB_LIB.T6G(SCH_1):PAGE102
    48    GND @T6G_MB_LIB.T6G(SCH_1):GND   I142 @T6G_MB_LIB.T6G(SCH_1):PAGE102
    50    GND @T6G_MB_LIB.T6G(SCH_1):GND   I142 @T6G_MB_LIB.T6G(SCH_1):PAGE102
    52    GND @T6G_MB_LIB.T6G(SCH_1):GND   I142 @T6G_MB_LIB.T6G(SCH_1):PAGE102
    54    GND @T6G_MB_LIB.T6G(SCH_1):GND   I142 @T6G_MB_LIB.T6G(SCH_1):PAGE102
    57    GND @T6G_MB_LIB.T6G(SCH_1):GND   I142 @T6G_MB_LIB.T6G(SCH_1):PAGE102
    59    GND @T6G_MB_LIB.T6G(SCH_1):GND   I142 @T6G_MB_LIB.T6G(SCH_1):PAGE102
    61    GND @T6G_MB_LIB.T6G(SCH_1):GND   I142 @T6G_MB_LIB.T6G(SCH_1):PAGE102
    63    GND @T6G_MB_LIB.T6G(SCH_1):GND   I142 @T6G_MB_LIB.T6G(SCH_1):PAGE102
    65    GND @T6G_MB_LIB.T6G(SCH_1):GND   I142 @T6G_MB_LIB.T6G(SCH_1):PAGE102
    67    GND @T6G_MB_LIB.T6G(SCH_1):GND   I142 @T6G_MB_LIB.T6G(SCH_1):PAGE102
    69    GND @T6G_MB_LIB.T6G(SCH_1):GND   I142 @T6G_MB_LIB.T6G(SCH_1):PAGE102
    71    GND @T6G_MB_LIB.T6G(SCH_1):GND   I142 @T6G_MB_LIB.T6G(SCH_1):PAGE102
    73    GND @T6G_MB_LIB.T6G(SCH_1):GND   I142 @T6G_MB_LIB.T6G(SCH_1):PAGE102
    75    GND @T6G_MB_LIB.T6G(SCH_1):GND   I142 @T6G_MB_LIB.T6G(SCH_1):PAGE102
    77    GND @T6G_MB_LIB.T6G(SCH_1):GND   I142 @T6G_MB_LIB.T6G(SCH_1):PAGE102
    79    GND @T6G_MB_LIB.T6G(SCH_1):GND   I142 @T6G_MB_LIB.T6G(SCH_1):PAGE102
    81    GND @T6G_MB_LIB.T6G(SCH_1):GND   I142 @T6G_MB_LIB.T6G(SCH_1):PAGE102
    83    GND @T6G_MB_LIB.T6G(SCH_1):GND   I142 @T6G_MB_LIB.T6G(SCH_1):PAGE102
    85    GND @T6G_MB_LIB.T6G(SCH_1):GND   I142 @T6G_MB_LIB.T6G(SCH_1):PAGE102
    88    GND @T6G_MB_LIB.T6G(SCH_1):GND   I142 @T6G_MB_LIB.T6G(SCH_1):PAGE102
    90    GND @T6G_MB_LIB.T6G(SCH_1):GND   I142 @T6G_MB_LIB.T6G(SCH_1):PAGE102
    92    GND @T6G_MB_LIB.T6G(SCH_1):GND   I142 @T6G_MB_LIB.T6G(SCH_1):PAGE102
    95    GND @T6G_MB_LIB.T6G(SCH_1):GND   I142 @T6G_MB_LIB.T6G(SCH_1):PAGE102
    97    GND @T6G_MB_LIB.T6G(SCH_1):GND   I142 @T6G_MB_LIB.T6G(SCH_1):PAGE102
    99    GND @T6G_MB_LIB.T6G(SCH_1):GND   I142 @T6G_MB_LIB.T6G(SCH_1):PAGE102
   101    GND @T6G_MB_LIB.T6G(SCH_1):GND   I142 @T6G_MB_LIB.T6G(SCH_1):PAGE102
   103    GND @T6G_MB_LIB.T6G(SCH_1):GND   I142 @T6G_MB_LIB.T6G(SCH_1):PAGE102
   106    GND @T6G_MB_LIB.T6G(SCH_1):GND   I142 @T6G_MB_LIB.T6G(SCH_1):PAGE102
   108    GND @T6G_MB_LIB.T6G(SCH_1):GND   I142 @T6G_MB_LIB.T6G(SCH_1):PAGE102
   110    GND @T6G_MB_LIB.T6G(SCH_1):GND   I142 @T6G_MB_LIB.T6G(SCH_1):PAGE102
   112    GND @T6G_MB_LIB.T6G(SCH_1):GND   I142 @T6G_MB_LIB.T6G(SCH_1):PAGE102
   114    GND @T6G_MB_LIB.T6G(SCH_1):GND   I142 @T6G_MB_LIB.T6G(SCH_1):PAGE102
   117    GND @T6G_MB_LIB.T6G(SCH_1):GND   I142 @T6G_MB_LIB.T6G(SCH_1):PAGE102
   119    GND @T6G_MB_LIB.T6G(SCH_1):GND   I142 @T6G_MB_LIB.T6G(SCH_1):PAGE102
   121    GND @T6G_MB_LIB.T6G(SCH_1):GND   I142 @T6G_MB_LIB.T6G(SCH_1):PAGE102
   123    GND @T6G_MB_LIB.T6G(SCH_1):GND   I142 @T6G_MB_LIB.T6G(SCH_1):PAGE102
   125    GND @T6G_MB_LIB.T6G(SCH_1):GND   I142 @T6G_MB_LIB.T6G(SCH_1):PAGE102
   128    GND @T6G_MB_LIB.T6G(SCH_1):GND   I142 @T6G_MB_LIB.T6G(SCH_1):PAGE102
   130    GND @T6G_MB_LIB.T6G(SCH_1):GND   I142 @T6G_MB_LIB.T6G(SCH_1):PAGE102
   134    GND @T6G_MB_LIB.T6G(SCH_1):GND   I142 @T6G_MB_LIB.T6G(SCH_1):PAGE102
   143    GND @T6G_MB_LIB.T6G(SCH_1):GND   I142 @T6G_MB_LIB.T6G(SCH_1):PAGE102
   151    GND @T6G_MB_LIB.T6G(SCH_1):GND   I142 @T6G_MB_LIB.T6G(SCH_1):PAGE102
   153    GND @T6G_MB_LIB.T6G(SCH_1):GND   I142 @T6G_MB_LIB.T6G(SCH_1):PAGE102
   155    GND @T6G_MB_LIB.T6G(SCH_1):GND   I142 @T6G_MB_LIB.T6G(SCH_1):PAGE102
   158    GND @T6G_MB_LIB.T6G(SCH_1):GND   I142 @T6G_MB_LIB.T6G(SCH_1):PAGE102
   160    GND @T6G_MB_LIB.T6G(SCH_1):GND   I142 @T6G_MB_LIB.T6G(SCH_1):PAGE102
   162    GND @T6G_MB_LIB.T6G(SCH_1):GND   I142 @T6G_MB_LIB.T6G(SCH_1):PAGE102
   164    GND @T6G_MB_LIB.T6G(SCH_1):GND   I142 @T6G_MB_LIB.T6G(SCH_1):PAGE102
   166    GND @T6G_MB_LIB.T6G(SCH_1):GND   I142 @T6G_MB_LIB.T6G(SCH_1):PAGE102
   169    GND @T6G_MB_LIB.T6G(SCH_1):GND   I142 @T6G_MB_LIB.T6G(SCH_1):PAGE102
   171    GND @T6G_MB_LIB.T6G(SCH_1):GND   I142 @T6G_MB_LIB.T6G(SCH_1):PAGE102
   173    GND @T6G_MB_LIB.T6G(SCH_1):GND   I142 @T6G_MB_LIB.T6G(SCH_1):PAGE102
   175    GND @T6G_MB_LIB.T6G(SCH_1):GND   I142 @T6G_MB_LIB.T6G(SCH_1):PAGE102
   177    GND @T6G_MB_LIB.T6G(SCH_1):GND   I142 @T6G_MB_LIB.T6G(SCH_1):PAGE102
   180    GND @T6G_MB_LIB.T6G(SCH_1):GND   I142 @T6G_MB_LIB.T6G(SCH_1):PAGE102
   182    GND @T6G_MB_LIB.T6G(SCH_1):GND   I142 @T6G_MB_LIB.T6G(SCH_1):PAGE102
   184    GND @T6G_MB_LIB.T6G(SCH_1):GND   I142 @T6G_MB_LIB.T6G(SCH_1):PAGE102
   186    GND @T6G_MB_LIB.T6G(SCH_1):GND   I142 @T6G_MB_LIB.T6G(SCH_1):PAGE102
   188    GND @T6G_MB_LIB.T6G(SCH_1):GND   I142 @T6G_MB_LIB.T6G(SCH_1):PAGE102
   191    GND @T6G_MB_LIB.T6G(SCH_1):GND   I142 @T6G_MB_LIB.T6G(SCH_1):PAGE102
   193    GND @T6G_MB_LIB.T6G(SCH_1):GND   I142 @T6G_MB_LIB.T6G(SCH_1):PAGE102
   195    GND @T6G_MB_LIB.T6G(SCH_1):GND   I142 @T6G_MB_LIB.T6G(SCH_1):PAGE102
   197    GND @T6G_MB_LIB.T6G(SCH_1):GND   I142 @T6G_MB_LIB.T6G(SCH_1):PAGE102
   199    GND @T6G_MB_LIB.T6G(SCH_1):GND   I142 @T6G_MB_LIB.T6G(SCH_1):PAGE102
   202    GND @T6G_MB_LIB.T6G(SCH_1):GND   I142 @T6G_MB_LIB.T6G(SCH_1):PAGE102
   204    GND @T6G_MB_LIB.T6G(SCH_1):GND   I142 @T6G_MB_LIB.T6G(SCH_1):PAGE102
   206    GND @T6G_MB_LIB.T6G(SCH_1):GND   I142 @T6G_MB_LIB.T6G(SCH_1):PAGE102
   208    GND @T6G_MB_LIB.T6G(SCH_1):GND   I142 @T6G_MB_LIB.T6G(SCH_1):PAGE102
   210    GND @T6G_MB_LIB.T6G(SCH_1):GND   I142 @T6G_MB_LIB.T6G(SCH_1):PAGE102
   212    GND @T6G_MB_LIB.T6G(SCH_1):GND   I142 @T6G_MB_LIB.T6G(SCH_1):PAGE102
   214    GND @T6G_MB_LIB.T6G(SCH_1):GND   I142 @T6G_MB_LIB.T6G(SCH_1):PAGE102
   216    GND @T6G_MB_LIB.T6G(SCH_1):GND   I142 @T6G_MB_LIB.T6G(SCH_1):PAGE102
   219    GND @T6G_MB_LIB.T6G(SCH_1):GND   I142 @T6G_MB_LIB.T6G(SCH_1):PAGE102
   222    GND @T6G_MB_LIB.T6G(SCH_1):GND   I142 @T6G_MB_LIB.T6G(SCH_1):PAGE102
   224    GND @T6G_MB_LIB.T6G(SCH_1):GND   I142 @T6G_MB_LIB.T6G(SCH_1):PAGE102
   226    GND @T6G_MB_LIB.T6G(SCH_1):GND   I142 @T6G_MB_LIB.T6G(SCH_1):PAGE102
   228    GND @T6G_MB_LIB.T6G(SCH_1):GND   I142 @T6G_MB_LIB.T6G(SCH_1):PAGE102
   233    GND @T6G_MB_LIB.T6G(SCH_1):GND   I142 @T6G_MB_LIB.T6G(SCH_1):PAGE102
   237    GND @T6G_MB_LIB.T6G(SCH_1):GND   I142 @T6G_MB_LIB.T6G(SCH_1):PAGE102
   242    GND @T6G_MB_LIB.T6G(SCH_1):GND   I142 @T6G_MB_LIB.T6G(SCH_1):PAGE102
   244    GND @T6G_MB_LIB.T6G(SCH_1):GND   I142 @T6G_MB_LIB.T6G(SCH_1):PAGE102
   246    GND @T6G_MB_LIB.T6G(SCH_1):GND   I142 @T6G_MB_LIB.T6G(SCH_1):PAGE102
   248    GND @T6G_MB_LIB.T6G(SCH_1):GND   I142 @T6G_MB_LIB.T6G(SCH_1):PAGE102
   251    GND @T6G_MB_LIB.T6G(SCH_1):GND   I142 @T6G_MB_LIB.T6G(SCH_1):PAGE102
   253    GND @T6G_MB_LIB.T6G(SCH_1):GND   I142 @T6G_MB_LIB.T6G(SCH_1):PAGE102
   255    GND @T6G_MB_LIB.T6G(SCH_1):GND   I142 @T6G_MB_LIB.T6G(SCH_1):PAGE102
   257    GND @T6G_MB_LIB.T6G(SCH_1):GND   I142 @T6G_MB_LIB.T6G(SCH_1):PAGE102
   259    GND @T6G_MB_LIB.T6G(SCH_1):GND   I142 @T6G_MB_LIB.T6G(SCH_1):PAGE102
   262    GND @T6G_MB_LIB.T6G(SCH_1):GND   I142 @T6G_MB_LIB.T6G(SCH_1):PAGE102
   264    GND @T6G_MB_LIB.T6G(SCH_1):GND   I142 @T6G_MB_LIB.T6G(SCH_1):PAGE102
   266    GND @T6G_MB_LIB.T6G(SCH_1):GND   I142 @T6G_MB_LIB.T6G(SCH_1):PAGE102
   268    GND @T6G_MB_LIB.T6G(SCH_1):GND   I142 @T6G_MB_LIB.T6G(SCH_1):PAGE102
   270    GND @T6G_MB_LIB.T6G(SCH_1):GND   I142 @T6G_MB_LIB.T6G(SCH_1):PAGE102
   273    GND @T6G_MB_LIB.T6G(SCH_1):GND   I142 @T6G_MB_LIB.T6G(SCH_1):PAGE102
   275    GND @T6G_MB_LIB.T6G(SCH_1):GND   I142 @T6G_MB_LIB.T6G(SCH_1):PAGE102
   277    GND @T6G_MB_LIB.T6G(SCH_1):GND   I142 @T6G_MB_LIB.T6G(SCH_1):PAGE102
   279    GND @T6G_MB_LIB.T6G(SCH_1):GND   I142 @T6G_MB_LIB.T6G(SCH_1):PAGE102
   281    GND @T6G_MB_LIB.T6G(SCH_1):GND   I142 @T6G_MB_LIB.T6G(SCH_1):PAGE102
   284    GND @T6G_MB_LIB.T6G(SCH_1):GND   I142 @T6G_MB_LIB.T6G(SCH_1):PAGE102
   286    GND @T6G_MB_LIB.T6G(SCH_1):GND   I142 @T6G_MB_LIB.T6G(SCH_1):PAGE102
   288    GND @T6G_MB_LIB.T6G(SCH_1):GND   I142 @T6G_MB_LIB.T6G(SCH_1):PAGE102
     1 P12V_MEM_CPU1 @T6G_MB_LIB.T6G(SCH_1):P12V_MEM_CPU1   I142 @T6G_MB_LIB.T6G(SCH_1):PAGE102
   145 P12V_MEM_CPU1 @T6G_MB_LIB.T6G(SCH_1):P12V_MEM_CPU1   I142 @T6G_MB_LIB.T6G(SCH_1):PAGE102
   146 P12V_MEM_CPU1 @T6G_MB_LIB.T6G(SCH_1):P12V_MEM_CPU1   I142 @T6G_MB_LIB.T6G(SCH_1):PAGE102
   230    GND @T6G_MB_LIB.T6G(SCH_1):GND   I142 @T6G_MB_LIB.T6G(SCH_1):PAGE102
   235    GND @T6G_MB_LIB.T6G(SCH_1):GND   I142 @T6G_MB_LIB.T6G(SCH_1):PAGE102
   240    GND @T6G_MB_LIB.T6G(SCH_1):GND   I142 @T6G_MB_LIB.T6G(SCH_1):PAGE102
   132    GND @T6G_MB_LIB.T6G(SCH_1):GND   I142 @T6G_MB_LIB.T6G(SCH_1):PAGE102
   136    GND @T6G_MB_LIB.T6G(SCH_1):GND   I142 @T6G_MB_LIB.T6G(SCH_1):PAGE102
   139    GND @T6G_MB_LIB.T6G(SCH_1):GND   I142 @T6G_MB_LIB.T6G(SCH_1):PAGE102
   141    GND @T6G_MB_LIB.T6G(SCH_1):GND   I142 @T6G_MB_LIB.T6G(SCH_1):PAGE102
    G1    GND @T6G_MB_LIB.T6G(SCH_1):GND   I142 @T6G_MB_LIB.T6G(SCH_1):PAGE102
    G2    GND @T6G_MB_LIB.T6G(SCH_1):GND   I142 @T6G_MB_LIB.T6G(SCH_1):PAGE102
    G3    GND @T6G_MB_LIB.T6G(SCH_1):GND   I142 @T6G_MB_LIB.T6G(SCH_1):PAGE102

 J35 SCONN168_ME1016810202011-SCONN168_ME1016810202011,A
   OB1 FM_OCP_V3_2_PWR_GOOD @T6G_MB_LIB.T6G(SCH_1):FM_OCP_V3_2_PWR_GOOD   I168 @T6G_MB_LIB.T6G(SCH_1):PAGE341
   OB2 OCP_V3_2_MAIN_PWR_EN_R @T6G_MB_LIB.T6G(SCH_1):OCP_V3_2_MAIN_PWR_EN_R   I168 @T6G_MB_LIB.T6G(SCH_1):PAGE341
   OB3 SGPIO_OCP_V3_2_LD_N @T6G_MB_LIB.T6G(SCH_1):SGPIO_OCP_V3_2_LD_N   I168 @T6G_MB_LIB.T6G(SCH_1):PAGE341
   OB4 SGPIO_OCP_V3_2_DATAIN @T6G_MB_LIB.T6G(SCH_1):SGPIO_OCP_V3_2_DATAIN   I168 @T6G_MB_LIB.T6G(SCH_1):PAGE341
   OB5 SGPIO_OCP_V3_2_DATAOUT @T6G_MB_LIB.T6G(SCH_1):SGPIO_OCP_V3_2_DATAOUT   I168 @T6G_MB_LIB.T6G(SCH_1):PAGE341
   OB6 SGPIO_OCP_V3_2_CLK @T6G_MB_LIB.T6G(SCH_1):SGPIO_OCP_V3_2_CLK   I168 @T6G_MB_LIB.T6G(SCH_1):PAGE341
   OB7 OCP_V3_2_ID0 @T6G_MB_LIB.T6G(SCH_1):OCP_V3_2_ID0   I168 @T6G_MB_LIB.T6G(SCH_1):PAGE341
   OB8 NCSI_OCP_V3_2_RXD1 @T6G_MB_LIB.T6G(SCH_1):NCSI_OCP_V3_2_RXD1   I168 @T6G_MB_LIB.T6G(SCH_1):PAGE341
   OB9 NCSI_OCP_V3_2_RXD0 @T6G_MB_LIB.T6G(SCH_1):NCSI_OCP_V3_2_RXD0   I168 @T6G_MB_LIB.T6G(SCH_1):PAGE341
  OB10    GND @T6G_MB_LIB.T6G(SCH_1):GND   I168 @T6G_MB_LIB.T6G(SCH_1):PAGE341
  OB11 CLK_100M_CPU1_CLK04_DN @T6G_MB_LIB.T6G(SCH_1):CLK_100M_CPU1_CLK04_DN   I168 @T6G_MB_LIB.T6G(SCH_1):PAGE341
  OB12 CLK_100M_CPU1_CLK04_DP @T6G_MB_LIB.T6G(SCH_1):CLK_100M_CPU1_CLK04_DP   I168 @T6G_MB_LIB.T6G(SCH_1):PAGE341
  OB13    GND @T6G_MB_LIB.T6G(SCH_1):GND   I168 @T6G_MB_LIB.T6G(SCH_1):PAGE341
  OB14 NCSI_OCP_V3_2_CRS_DV @T6G_MB_LIB.T6G(SCH_1):NCSI_OCP_V3_2_CRS_DV   I168 @T6G_MB_LIB.T6G(SCH_1):PAGE341
    B1 P12V_OCP_V3_2_R @T6G_MB_LIB.T6G(SCH_1):P12V_OCP_V3_2_R   I168 @T6G_MB_LIB.T6G(SCH_1):PAGE341
    B2 P12V_OCP_V3_2_R @T6G_MB_LIB.T6G(SCH_1):P12V_OCP_V3_2_R   I168 @T6G_MB_LIB.T6G(SCH_1):PAGE341
    B3 P12V_OCP_V3_2_R @T6G_MB_LIB.T6G(SCH_1):P12V_OCP_V3_2_R   I168 @T6G_MB_LIB.T6G(SCH_1):PAGE341
    B4 P12V_OCP_V3_2_R @T6G_MB_LIB.T6G(SCH_1):P12V_OCP_V3_2_R   I168 @T6G_MB_LIB.T6G(SCH_1):PAGE341
    B5 P12V_OCP_V3_2_R @T6G_MB_LIB.T6G(SCH_1):P12V_OCP_V3_2_R   I168 @T6G_MB_LIB.T6G(SCH_1):PAGE341
    B6 P12V_OCP_V3_2_R @T6G_MB_LIB.T6G(SCH_1):P12V_OCP_V3_2_R   I168 @T6G_MB_LIB.T6G(SCH_1):PAGE341
    B7 OCP_V3_2_BIF0_R_N @T6G_MB_LIB.T6G(SCH_1):OCP_V3_2_BIF0_R_N   I168 @T6G_MB_LIB.T6G(SCH_1):PAGE341
    B8 OCP_V3_2_BIF1_R_N @T6G_MB_LIB.T6G(SCH_1):OCP_V3_2_BIF1_R_N   I168 @T6G_MB_LIB.T6G(SCH_1):PAGE341
    B9 OCP_V3_2_BIF2_R_N @T6G_MB_LIB.T6G(SCH_1):OCP_V3_2_BIF2_R_N   I168 @T6G_MB_LIB.T6G(SCH_1):PAGE341
   B10 RST_PERST0_OCP_V3_2_N @T6G_MB_LIB.T6G(SCH_1):RST_PERST0_OCP_V3_2_N   I168 @T6G_MB_LIB.T6G(SCH_1):PAGE341
   B11 P3V3_OCP_V3_2 @T6G_MB_LIB.T6G(SCH_1):P3V3_OCP_V3_2   I168 @T6G_MB_LIB.T6G(SCH_1):PAGE341
   B12 OCP_V3_2_AUX_PWR_EN_R @T6G_MB_LIB.T6G(SCH_1):OCP_V3_2_AUX_PWR_EN_R   I168 @T6G_MB_LIB.T6G(SCH_1):PAGE341
   B13    GND @T6G_MB_LIB.T6G(SCH_1):GND   I168 @T6G_MB_LIB.T6G(SCH_1):PAGE341
   B14 CLK_100M_CPU1_CLK02_DN @T6G_MB_LIB.T6G(SCH_1):CLK_100M_CPU1_CLK02_DN   I168 @T6G_MB_LIB.T6G(SCH_1):PAGE341
   B15 CLK_100M_CPU1_CLK02_DP @T6G_MB_LIB.T6G(SCH_1):CLK_100M_CPU1_CLK02_DP   I168 @T6G_MB_LIB.T6G(SCH_1):PAGE341
   B16    GND @T6G_MB_LIB.T6G(SCH_1):GND   I168 @T6G_MB_LIB.T6G(SCH_1):PAGE341
   B17 P5E_CPU1_G1_TX_C_DP<0> @T6G_MB_LIB.T6G(SCH_1):P5E_CPU1_G1_TX_C_DP(0)   I168 @T6G_MB_LIB.T6G(SCH_1):PAGE341
   B18 P5E_CPU1_G1_TX_C_DN<0> @T6G_MB_LIB.T6G(SCH_1):P5E_CPU1_G1_TX_C_DN(0)   I168 @T6G_MB_LIB.T6G(SCH_1):PAGE341
   B19    GND @T6G_MB_LIB.T6G(SCH_1):GND   I168 @T6G_MB_LIB.T6G(SCH_1):PAGE341
   B20 P5E_CPU1_G1_TX_C_DP<1> @T6G_MB_LIB.T6G(SCH_1):P5E_CPU1_G1_TX_C_DP(1)   I168 @T6G_MB_LIB.T6G(SCH_1):PAGE341
   B21 P5E_CPU1_G1_TX_C_DN<1> @T6G_MB_LIB.T6G(SCH_1):P5E_CPU1_G1_TX_C_DN(1)   I168 @T6G_MB_LIB.T6G(SCH_1):PAGE341
   B22    GND @T6G_MB_LIB.T6G(SCH_1):GND   I168 @T6G_MB_LIB.T6G(SCH_1):PAGE341
   B23 P5E_CPU1_G1_TX_C_DP<2> @T6G_MB_LIB.T6G(SCH_1):P5E_CPU1_G1_TX_C_DP(2)   I168 @T6G_MB_LIB.T6G(SCH_1):PAGE341
   B24 P5E_CPU1_G1_TX_C_DN<2> @T6G_MB_LIB.T6G(SCH_1):P5E_CPU1_G1_TX_C_DN(2)   I168 @T6G_MB_LIB.T6G(SCH_1):PAGE341
   B25    GND @T6G_MB_LIB.T6G(SCH_1):GND   I168 @T6G_MB_LIB.T6G(SCH_1):PAGE341
   B26 P5E_CPU1_G1_TX_C_DP<3> @T6G_MB_LIB.T6G(SCH_1):P5E_CPU1_G1_TX_C_DP(3)   I168 @T6G_MB_LIB.T6G(SCH_1):PAGE341
   B27 P5E_CPU1_G1_TX_C_DN<3> @T6G_MB_LIB.T6G(SCH_1):P5E_CPU1_G1_TX_C_DN(3)   I168 @T6G_MB_LIB.T6G(SCH_1):PAGE341
   B28    GND @T6G_MB_LIB.T6G(SCH_1):GND   I168 @T6G_MB_LIB.T6G(SCH_1):PAGE341
   B29    GND @T6G_MB_LIB.T6G(SCH_1):GND   I168 @T6G_MB_LIB.T6G(SCH_1):PAGE341
   B30 P5E_CPU1_G1_TX_C_DP<4> @T6G_MB_LIB.T6G(SCH_1):P5E_CPU1_G1_TX_C_DP(4)   I168 @T6G_MB_LIB.T6G(SCH_1):PAGE341
   B31 P5E_CPU1_G1_TX_C_DN<4> @T6G_MB_LIB.T6G(SCH_1):P5E_CPU1_G1_TX_C_DN(4)   I168 @T6G_MB_LIB.T6G(SCH_1):PAGE341
   B32    GND @T6G_MB_LIB.T6G(SCH_1):GND   I168 @T6G_MB_LIB.T6G(SCH_1):PAGE341
   B33 P5E_CPU1_G1_TX_C_DP<5> @T6G_MB_LIB.T6G(SCH_1):P5E_CPU1_G1_TX_C_DP(5)   I168 @T6G_MB_LIB.T6G(SCH_1):PAGE341
   B34 P5E_CPU1_G1_TX_C_DN<5> @T6G_MB_LIB.T6G(SCH_1):P5E_CPU1_G1_TX_C_DN(5)   I168 @T6G_MB_LIB.T6G(SCH_1):PAGE341
   B35    GND @T6G_MB_LIB.T6G(SCH_1):GND   I168 @T6G_MB_LIB.T6G(SCH_1):PAGE341
   B36 P5E_CPU1_G1_TX_C_DP<6> @T6G_MB_LIB.T6G(SCH_1):P5E_CPU1_G1_TX_C_DP(6)   I168 @T6G_MB_LIB.T6G(SCH_1):PAGE341
   B37 P5E_CPU1_G1_TX_C_DN<6> @T6G_MB_LIB.T6G(SCH_1):P5E_CPU1_G1_TX_C_DN(6)   I168 @T6G_MB_LIB.T6G(SCH_1):PAGE341
   B38    GND @T6G_MB_LIB.T6G(SCH_1):GND   I168 @T6G_MB_LIB.T6G(SCH_1):PAGE341
   B39 P5E_CPU1_G1_TX_C_DP<7> @T6G_MB_LIB.T6G(SCH_1):P5E_CPU1_G1_TX_C_DP(7)   I168 @T6G_MB_LIB.T6G(SCH_1):PAGE341
   B40 P5E_CPU1_G1_TX_C_DN<7> @T6G_MB_LIB.T6G(SCH_1):P5E_CPU1_G1_TX_C_DN(7)   I168 @T6G_MB_LIB.T6G(SCH_1):PAGE341
   B41    GND @T6G_MB_LIB.T6G(SCH_1):GND   I168 @T6G_MB_LIB.T6G(SCH_1):PAGE341
   B42 OCP_V3_2_PRSNT0_R_N @T6G_MB_LIB.T6G(SCH_1):OCP_V3_2_PRSNT0_R_N   I168 @T6G_MB_LIB.T6G(SCH_1):PAGE341
   B43    GND @T6G_MB_LIB.T6G(SCH_1):GND   I168 @T6G_MB_LIB.T6G(SCH_1):PAGE341
   B44 P5E_CPU1_G1_TX_C_DP<8> @T6G_MB_LIB.T6G(SCH_1):P5E_CPU1_G1_TX_C_DP(8)   I168 @T6G_MB_LIB.T6G(SCH_1):PAGE341
   B45 P5E_CPU1_G1_TX_C_DN<8> @T6G_MB_LIB.T6G(SCH_1):P5E_CPU1_G1_TX_C_DN(8)   I168 @T6G_MB_LIB.T6G(SCH_1):PAGE341
   B46    GND @T6G_MB_LIB.T6G(SCH_1):GND   I168 @T6G_MB_LIB.T6G(SCH_1):PAGE341
   B47 P5E_CPU1_G1_TX_C_DP<9> @T6G_MB_LIB.T6G(SCH_1):P5E_CPU1_G1_TX_C_DP(9)   I168 @T6G_MB_LIB.T6G(SCH_1):PAGE341
   B48 P5E_CPU1_G1_TX_C_DN<9> @T6G_MB_LIB.T6G(SCH_1):P5E_CPU1_G1_TX_C_DN(9)   I168 @T6G_MB_LIB.T6G(SCH_1):PAGE341
   B49    GND @T6G_MB_LIB.T6G(SCH_1):GND   I168 @T6G_MB_LIB.T6G(SCH_1):PAGE341
   B50 P5E_CPU1_G1_TX_C_DP<10> @T6G_MB_LIB.T6G(SCH_1):P5E_CPU1_G1_TX_C_DP(10)   I168 @T6G_MB_LIB.T6G(SCH_1):PAGE341
   B51 P5E_CPU1_G1_TX_C_DN<10> @T6G_MB_LIB.T6G(SCH_1):P5E_CPU1_G1_TX_C_DN(10)   I168 @T6G_MB_LIB.T6G(SCH_1):PAGE341
   B52    GND @T6G_MB_LIB.T6G(SCH_1):GND   I168 @T6G_MB_LIB.T6G(SCH_1):PAGE341
   B53 P5E_CPU1_G1_TX_C_DP<11> @T6G_MB_LIB.T6G(SCH_1):P5E_CPU1_G1_TX_C_DP(11)   I168 @T6G_MB_LIB.T6G(SCH_1):PAGE341
   B54 P5E_CPU1_G1_TX_C_DN<11> @T6G_MB_LIB.T6G(SCH_1):P5E_CPU1_G1_TX_C_DN(11)   I168 @T6G_MB_LIB.T6G(SCH_1):PAGE341
   B55    GND @T6G_MB_LIB.T6G(SCH_1):GND   I168 @T6G_MB_LIB.T6G(SCH_1):PAGE341
   B56 P5E_CPU1_G1_TX_C_DP<12> @T6G_MB_LIB.T6G(SCH_1):P5E_CPU1_G1_TX_C_DP(12)   I168 @T6G_MB_LIB.T6G(SCH_1):PAGE341
   OA1 RST_PERST2_OCP_V3_2_N @T6G_MB_LIB.T6G(SCH_1):RST_PERST2_OCP_V3_2_N   I168 @T6G_MB_LIB.T6G(SCH_1):PAGE341
   OA2 RST_PERST3_OCP_V3_2_N @T6G_MB_LIB.T6G(SCH_1):RST_PERST3_OCP_V3_2_N   I168 @T6G_MB_LIB.T6G(SCH_1):PAGE341
   OA3 IRQ_LVC3_OCP_V3_2_WAKE_N @T6G_MB_LIB.T6G(SCH_1):IRQ_LVC3_OCP_V3_2_WAKE_N   I168 @T6G_MB_LIB.T6G(SCH_1):PAGE341
   OA4 OCP_V3_2_ISO1_RBT_ARB_IN @T6G_MB_LIB.T6G(SCH_1):OCP_V3_2_ISO1_RBT_ARB_IN   I168 @T6G_MB_LIB.T6G(SCH_1):PAGE341
   OA5 OCP_V3_2_ISO2_RBT_ARB_OUT @T6G_MB_LIB.T6G(SCH_1):OCP_V3_2_ISO2_RBT_ARB_OUT   I168 @T6G_MB_LIB.T6G(SCH_1):PAGE341
   OA6 OCP_V3_2_ID1 @T6G_MB_LIB.T6G(SCH_1):OCP_V3_2_ID1   I168 @T6G_MB_LIB.T6G(SCH_1):PAGE341
   OA7 NCSI_OCP_V3_2_TX_EN @T6G_MB_LIB.T6G(SCH_1):NCSI_OCP_V3_2_TX_EN   I168 @T6G_MB_LIB.T6G(SCH_1):PAGE341
   OA8 NCSI_OCP_V3_2_TXD1 @T6G_MB_LIB.T6G(SCH_1):NCSI_OCP_V3_2_TXD1   I168 @T6G_MB_LIB.T6G(SCH_1):PAGE341
   OA9 NCSI_OCP_V3_2_TXD0 @T6G_MB_LIB.T6G(SCH_1):NCSI_OCP_V3_2_TXD0   I168 @T6G_MB_LIB.T6G(SCH_1):PAGE341
  OA10    GND @T6G_MB_LIB.T6G(SCH_1):GND   I168 @T6G_MB_LIB.T6G(SCH_1):PAGE341
  OA11 CLK_100M_CPU1_CLK05_DN @T6G_MB_LIB.T6G(SCH_1):CLK_100M_CPU1_CLK05_DN   I168 @T6G_MB_LIB.T6G(SCH_1):PAGE341
  OA12 CLK_100M_CPU1_CLK05_DP @T6G_MB_LIB.T6G(SCH_1):CLK_100M_CPU1_CLK05_DP   I168 @T6G_MB_LIB.T6G(SCH_1):PAGE341
  OA13    GND @T6G_MB_LIB.T6G(SCH_1):GND   I168 @T6G_MB_LIB.T6G(SCH_1):PAGE341
  OA14 CLK_50M_NCSI_OCP_V3_2_ISO @T6G_MB_LIB.T6G(SCH_1):CLK_50M_NCSI_OCP_V3_2_ISO   I168 @T6G_MB_LIB.T6G(SCH_1):PAGE341
    A1    GND @T6G_MB_LIB.T6G(SCH_1):GND   I168 @T6G_MB_LIB.T6G(SCH_1):PAGE341
    A2    GND @T6G_MB_LIB.T6G(SCH_1):GND   I168 @T6G_MB_LIB.T6G(SCH_1):PAGE341
    A3    GND @T6G_MB_LIB.T6G(SCH_1):GND   I168 @T6G_MB_LIB.T6G(SCH_1):PAGE341
    A4    GND @T6G_MB_LIB.T6G(SCH_1):GND   I168 @T6G_MB_LIB.T6G(SCH_1):PAGE341
    A5    GND @T6G_MB_LIB.T6G(SCH_1):GND   I168 @T6G_MB_LIB.T6G(SCH_1):PAGE341
    A6    GND @T6G_MB_LIB.T6G(SCH_1):GND   I168 @T6G_MB_LIB.T6G(SCH_1):PAGE341
    A7 SMB_OCP_V3_2_3V3AUX_BUF_R_SCL @T6G_MB_LIB.T6G(SCH_1):SMB_OCP_V3_2_3V3AUX_BUF_R_SCL   I168 @T6G_MB_LIB.T6G(SCH_1):PAGE341
    A8 SMB_OCP_V3_2_3V3AUX_BUF_R_SDA @T6G_MB_LIB.T6G(SCH_1):SMB_OCP_V3_2_3V3AUX_BUF_R_SDA   I168 @T6G_MB_LIB.T6G(SCH_1):PAGE341
    A9 RST_SMB_OCP_V3_2_N @T6G_MB_LIB.T6G(SCH_1):RST_SMB_OCP_V3_2_N   I168 @T6G_MB_LIB.T6G(SCH_1):PAGE341
   A10 OCP_V3_2_PRSNTA_R_N @T6G_MB_LIB.T6G(SCH_1):OCP_V3_2_PRSNTA_R_N   I168 @T6G_MB_LIB.T6G(SCH_1):PAGE341
   A11 RST_PERST1_OCP_V3_2_N @T6G_MB_LIB.T6G(SCH_1):RST_PERST1_OCP_V3_2_N   I168 @T6G_MB_LIB.T6G(SCH_1):PAGE341
   A12 OCP_V3_2_PRSNT2_R_N @T6G_MB_LIB.T6G(SCH_1):OCP_V3_2_PRSNT2_R_N   I168 @T6G_MB_LIB.T6G(SCH_1):PAGE341
   A13    GND @T6G_MB_LIB.T6G(SCH_1):GND   I168 @T6G_MB_LIB.T6G(SCH_1):PAGE341
   A14 CLK_100M_CPU1_CLK03_DN @T6G_MB_LIB.T6G(SCH_1):CLK_100M_CPU1_CLK03_DN   I168 @T6G_MB_LIB.T6G(SCH_1):PAGE341
   A15 CLK_100M_CPU1_CLK03_DP @T6G_MB_LIB.T6G(SCH_1):CLK_100M_CPU1_CLK03_DP   I168 @T6G_MB_LIB.T6G(SCH_1):PAGE341
   A16    GND @T6G_MB_LIB.T6G(SCH_1):GND   I168 @T6G_MB_LIB.T6G(SCH_1):PAGE341
   A17 P5E_CPU1_G1_RX_DN<0> @T6G_MB_LIB.T6G(SCH_1):P5E_CPU1_G1_RX_DN(0)   I168 @T6G_MB_LIB.T6G(SCH_1):PAGE341
   A18 P5E_CPU1_G1_RX_DP<0> @T6G_MB_LIB.T6G(SCH_1):P5E_CPU1_G1_RX_DP(0)   I168 @T6G_MB_LIB.T6G(SCH_1):PAGE341
   A19    GND @T6G_MB_LIB.T6G(SCH_1):GND   I168 @T6G_MB_LIB.T6G(SCH_1):PAGE341
   A20 P5E_CPU1_G1_RX_DN<1> @T6G_MB_LIB.T6G(SCH_1):P5E_CPU1_G1_RX_DN(1)   I168 @T6G_MB_LIB.T6G(SCH_1):PAGE341
   A21 P5E_CPU1_G1_RX_DP<1> @T6G_MB_LIB.T6G(SCH_1):P5E_CPU1_G1_RX_DP(1)   I168 @T6G_MB_LIB.T6G(SCH_1):PAGE341
   A22    GND @T6G_MB_LIB.T6G(SCH_1):GND   I168 @T6G_MB_LIB.T6G(SCH_1):PAGE341
   A23 P5E_CPU1_G1_RX_DN<2> @T6G_MB_LIB.T6G(SCH_1):P5E_CPU1_G1_RX_DN(2)   I168 @T6G_MB_LIB.T6G(SCH_1):PAGE341
   A24 P5E_CPU1_G1_RX_DP<2> @T6G_MB_LIB.T6G(SCH_1):P5E_CPU1_G1_RX_DP(2)   I168 @T6G_MB_LIB.T6G(SCH_1):PAGE341
   A25    GND @T6G_MB_LIB.T6G(SCH_1):GND   I168 @T6G_MB_LIB.T6G(SCH_1):PAGE341
   A26 P5E_CPU1_G1_RX_DN<3> @T6G_MB_LIB.T6G(SCH_1):P5E_CPU1_G1_RX_DN(3)   I168 @T6G_MB_LIB.T6G(SCH_1):PAGE341
   A27 P5E_CPU1_G1_RX_DP<3> @T6G_MB_LIB.T6G(SCH_1):P5E_CPU1_G1_RX_DP(3)   I168 @T6G_MB_LIB.T6G(SCH_1):PAGE341
   A28    GND @T6G_MB_LIB.T6G(SCH_1):GND   I168 @T6G_MB_LIB.T6G(SCH_1):PAGE341
   A29    GND @T6G_MB_LIB.T6G(SCH_1):GND   I168 @T6G_MB_LIB.T6G(SCH_1):PAGE341
   A30 P5E_CPU1_G1_RX_DN<4> @T6G_MB_LIB.T6G(SCH_1):P5E_CPU1_G1_RX_DN(4)   I168 @T6G_MB_LIB.T6G(SCH_1):PAGE341
   A31 P5E_CPU1_G1_RX_DP<4> @T6G_MB_LIB.T6G(SCH_1):P5E_CPU1_G1_RX_DP(4)   I168 @T6G_MB_LIB.T6G(SCH_1):PAGE341
   A32    GND @T6G_MB_LIB.T6G(SCH_1):GND   I168 @T6G_MB_LIB.T6G(SCH_1):PAGE341
   A33 P5E_CPU1_G1_RX_DN<5> @T6G_MB_LIB.T6G(SCH_1):P5E_CPU1_G1_RX_DN(5)   I168 @T6G_MB_LIB.T6G(SCH_1):PAGE341
   A34 P5E_CPU1_G1_RX_DP<5> @T6G_MB_LIB.T6G(SCH_1):P5E_CPU1_G1_RX_DP(5)   I168 @T6G_MB_LIB.T6G(SCH_1):PAGE341
   A35    GND @T6G_MB_LIB.T6G(SCH_1):GND   I168 @T6G_MB_LIB.T6G(SCH_1):PAGE341
   A36 P5E_CPU1_G1_RX_DN<6> @T6G_MB_LIB.T6G(SCH_1):P5E_CPU1_G1_RX_DN(6)   I168 @T6G_MB_LIB.T6G(SCH_1):PAGE341
   A37 P5E_CPU1_G1_RX_DP<6> @T6G_MB_LIB.T6G(SCH_1):P5E_CPU1_G1_RX_DP(6)   I168 @T6G_MB_LIB.T6G(SCH_1):PAGE341
   A38    GND @T6G_MB_LIB.T6G(SCH_1):GND   I168 @T6G_MB_LIB.T6G(SCH_1):PAGE341
   A39 P5E_CPU1_G1_RX_DN<7> @T6G_MB_LIB.T6G(SCH_1):P5E_CPU1_G1_RX_DN(7)   I168 @T6G_MB_LIB.T6G(SCH_1):PAGE341
   A40 P5E_CPU1_G1_RX_DP<7> @T6G_MB_LIB.T6G(SCH_1):P5E_CPU1_G1_RX_DP(7)   I168 @T6G_MB_LIB.T6G(SCH_1):PAGE341
   A41    GND @T6G_MB_LIB.T6G(SCH_1):GND   I168 @T6G_MB_LIB.T6G(SCH_1):PAGE341
   A42 OCP_V3_2_PRSNT1_R_N @T6G_MB_LIB.T6G(SCH_1):OCP_V3_2_PRSNT1_R_N   I168 @T6G_MB_LIB.T6G(SCH_1):PAGE341
   A43    GND @T6G_MB_LIB.T6G(SCH_1):GND   I168 @T6G_MB_LIB.T6G(SCH_1):PAGE341
   A44 P5E_CPU1_G1_RX_DN<8> @T6G_MB_LIB.T6G(SCH_1):P5E_CPU1_G1_RX_DN(8)   I168 @T6G_MB_LIB.T6G(SCH_1):PAGE341
   A45 P5E_CPU1_G1_RX_DP<8> @T6G_MB_LIB.T6G(SCH_1):P5E_CPU1_G1_RX_DP(8)   I168 @T6G_MB_LIB.T6G(SCH_1):PAGE341
   A46    GND @T6G_MB_LIB.T6G(SCH_1):GND   I168 @T6G_MB_LIB.T6G(SCH_1):PAGE341
   A47 P5E_CPU1_G1_RX_DN<9> @T6G_MB_LIB.T6G(SCH_1):P5E_CPU1_G1_RX_DN(9)   I168 @T6G_MB_LIB.T6G(SCH_1):PAGE341
   A48 P5E_CPU1_G1_RX_DP<9> @T6G_MB_LIB.T6G(SCH_1):P5E_CPU1_G1_RX_DP(9)   I168 @T6G_MB_LIB.T6G(SCH_1):PAGE341
   A49    GND @T6G_MB_LIB.T6G(SCH_1):GND   I168 @T6G_MB_LIB.T6G(SCH_1):PAGE341
   A50 P5E_CPU1_G1_RX_DN<10> @T6G_MB_LIB.T6G(SCH_1):P5E_CPU1_G1_RX_DN(10)   I168 @T6G_MB_LIB.T6G(SCH_1):PAGE341
   A51 P5E_CPU1_G1_RX_DP<10> @T6G_MB_LIB.T6G(SCH_1):P5E_CPU1_G1_RX_DP(10)   I168 @T6G_MB_LIB.T6G(SCH_1):PAGE341
   A52    GND @T6G_MB_LIB.T6G(SCH_1):GND   I168 @T6G_MB_LIB.T6G(SCH_1):PAGE341
   A53 P5E_CPU1_G1_RX_DN<11> @T6G_MB_LIB.T6G(SCH_1):P5E_CPU1_G1_RX_DN(11)   I168 @T6G_MB_LIB.T6G(SCH_1):PAGE341
   A54 P5E_CPU1_G1_RX_DP<11> @T6G_MB_LIB.T6G(SCH_1):P5E_CPU1_G1_RX_DP(11)   I168 @T6G_MB_LIB.T6G(SCH_1):PAGE341
   A55    GND @T6G_MB_LIB.T6G(SCH_1):GND   I168 @T6G_MB_LIB.T6G(SCH_1):PAGE341
   A56 P5E_CPU1_G1_RX_DN<12> @T6G_MB_LIB.T6G(SCH_1):P5E_CPU1_G1_RX_DN(12)   I168 @T6G_MB_LIB.T6G(SCH_1):PAGE341
   A57 P5E_CPU1_G1_RX_DP<12> @T6G_MB_LIB.T6G(SCH_1):P5E_CPU1_G1_RX_DP(12)   I168 @T6G_MB_LIB.T6G(SCH_1):PAGE341
   A58    GND @T6G_MB_LIB.T6G(SCH_1):GND   I168 @T6G_MB_LIB.T6G(SCH_1):PAGE341
   A59 P5E_CPU1_G1_RX_DN<13> @T6G_MB_LIB.T6G(SCH_1):P5E_CPU1_G1_RX_DN(13)   I168 @T6G_MB_LIB.T6G(SCH_1):PAGE341
   A60 P5E_CPU1_G1_RX_DP<13> @T6G_MB_LIB.T6G(SCH_1):P5E_CPU1_G1_RX_DP(13)   I168 @T6G_MB_LIB.T6G(SCH_1):PAGE341
   A61    GND @T6G_MB_LIB.T6G(SCH_1):GND   I168 @T6G_MB_LIB.T6G(SCH_1):PAGE341
   A62 P5E_CPU1_G1_RX_DN<14> @T6G_MB_LIB.T6G(SCH_1):P5E_CPU1_G1_RX_DN(14)   I168 @T6G_MB_LIB.T6G(SCH_1):PAGE341
   A63 P5E_CPU1_G1_RX_DP<14> @T6G_MB_LIB.T6G(SCH_1):P5E_CPU1_G1_RX_DP(14)   I168 @T6G_MB_LIB.T6G(SCH_1):PAGE341
   A64    GND @T6G_MB_LIB.T6G(SCH_1):GND   I168 @T6G_MB_LIB.T6G(SCH_1):PAGE341
   A65 P5E_CPU1_G1_RX_DN<15> @T6G_MB_LIB.T6G(SCH_1):P5E_CPU1_G1_RX_DN(15)   I168 @T6G_MB_LIB.T6G(SCH_1):PAGE341
   A66 P5E_CPU1_G1_RX_DP<15> @T6G_MB_LIB.T6G(SCH_1):P5E_CPU1_G1_RX_DP(15)   I168 @T6G_MB_LIB.T6G(SCH_1):PAGE341
   A67    GND @T6G_MB_LIB.T6G(SCH_1):GND   I168 @T6G_MB_LIB.T6G(SCH_1):PAGE341
   A68 USB2_P10_DN @T6G_MB_LIB.T6G(SCH_1):USB2_P10_DN   I168 @T6G_MB_LIB.T6G(SCH_1):PAGE341
   A69 USB2_P10_DP @T6G_MB_LIB.T6G(SCH_1):USB2_P10_DP   I168 @T6G_MB_LIB.T6G(SCH_1):PAGE341
   A70 OCP_V3_2_PWRBRK_N @T6G_MB_LIB.T6G(SCH_1):OCP_V3_2_PWRBRK_N   I168 @T6G_MB_LIB.T6G(SCH_1):PAGE341
   B57 P5E_CPU1_G1_TX_C_DN<12> @T6G_MB_LIB.T6G(SCH_1):P5E_CPU1_G1_TX_C_DN(12)   I168 @T6G_MB_LIB.T6G(SCH_1):PAGE341
   B58    GND @T6G_MB_LIB.T6G(SCH_1):GND   I168 @T6G_MB_LIB.T6G(SCH_1):PAGE341
   B59 P5E_CPU1_G1_TX_C_DP<13> @T6G_MB_LIB.T6G(SCH_1):P5E_CPU1_G1_TX_C_DP(13)   I168 @T6G_MB_LIB.T6G(SCH_1):PAGE341
   B60 P5E_CPU1_G1_TX_C_DN<13> @T6G_MB_LIB.T6G(SCH_1):P5E_CPU1_G1_TX_C_DN(13)   I168 @T6G_MB_LIB.T6G(SCH_1):PAGE341
   B61    GND @T6G_MB_LIB.T6G(SCH_1):GND   I168 @T6G_MB_LIB.T6G(SCH_1):PAGE341
   B62 P5E_CPU1_G1_TX_C_DP<14> @T6G_MB_LIB.T6G(SCH_1):P5E_CPU1_G1_TX_C_DP(14)   I168 @T6G_MB_LIB.T6G(SCH_1):PAGE341
   B63 P5E_CPU1_G1_TX_C_DN<14> @T6G_MB_LIB.T6G(SCH_1):P5E_CPU1_G1_TX_C_DN(14)   I168 @T6G_MB_LIB.T6G(SCH_1):PAGE341
   B64    GND @T6G_MB_LIB.T6G(SCH_1):GND   I168 @T6G_MB_LIB.T6G(SCH_1):PAGE341
   B65 P5E_CPU1_G1_TX_C_DP<15> @T6G_MB_LIB.T6G(SCH_1):P5E_CPU1_G1_TX_C_DP(15)   I168 @T6G_MB_LIB.T6G(SCH_1):PAGE341
   B66 P5E_CPU1_G1_TX_C_DN<15> @T6G_MB_LIB.T6G(SCH_1):P5E_CPU1_G1_TX_C_DN(15)   I168 @T6G_MB_LIB.T6G(SCH_1):PAGE341
   B67    GND @T6G_MB_LIB.T6G(SCH_1):GND   I168 @T6G_MB_LIB.T6G(SCH_1):PAGE341
   B68 TP_OCP_V3_2_B68 @T6G_MB_LIB.T6G(SCH_1):TP_OCP_V3_2_B68   I168 @T6G_MB_LIB.T6G(SCH_1):PAGE341
   B69 TP_OCP_V3_2_B69 @T6G_MB_LIB.T6G(SCH_1):TP_OCP_V3_2_B69   I168 @T6G_MB_LIB.T6G(SCH_1):PAGE341
   B70 OCP_V3_2_PRSNT3_R_N @T6G_MB_LIB.T6G(SCH_1):OCP_V3_2_PRSNT3_R_N   I168 @T6G_MB_LIB.T6G(SCH_1):PAGE341
    G1    GND @T6G_MB_LIB.T6G(SCH_1):GND   I168 @T6G_MB_LIB.T6G(SCH_1):PAGE341
    G2    GND @T6G_MB_LIB.T6G(SCH_1):GND   I168 @T6G_MB_LIB.T6G(SCH_1):PAGE341
    G3    GND @T6G_MB_LIB.T6G(SCH_1):GND   I168 @T6G_MB_LIB.T6G(SCH_1):PAGE341
    G4    GND @T6G_MB_LIB.T6G(SCH_1):GND   I168 @T6G_MB_LIB.T6G(SCH_1):PAGE341
    G5    GND @T6G_MB_LIB.T6G(SCH_1):GND   I168 @T6G_MB_LIB.T6G(SCH_1):PAGE341

 J37 SCONN288_DDR506112002KQ-SCONN288_DDR506112002KQ,SMA
     3 P3V3_AUX @T6G_MB_LIB.T6G(SCH_1):P3V3_AUX    I22 @T6G_MB_LIB.T6G(SCH_1):PAGE108
     2     NC     NC    I22 @T6G_MB_LIB.T6G(SCH_1):PAGE108
   144     NC     NC    I22 @T6G_MB_LIB.T6G(SCH_1):PAGE108
   149     NC     NC    I22 @T6G_MB_LIB.T6G(SCH_1):PAGE108
   150     NC     NC    I22 @T6G_MB_LIB.T6G(SCH_1):PAGE108
   220     NC     NC    I22 @T6G_MB_LIB.T6G(SCH_1):PAGE108
   231     NC     NC    I22 @T6G_MB_LIB.T6G(SCH_1):PAGE108
   232     NC     NC    I22 @T6G_MB_LIB.T6G(SCH_1):PAGE108
   207 M_L_CPU1_RESET_N @T6G_MB_LIB.T6G(SCH_1):M_L_CPU1_RESET_N    I22 @T6G_MB_LIB.T6G(SCH_1):PAGE108
   147 PWRGD_CHL_CPU1_DIMM @T6G_MB_LIB.T6G(SCH_1):PWRGD_CHL_CPU1_DIMM    I22 @T6G_MB_LIB.T6G(SCH_1):PAGE108
   227 M_L_CPU1_SB_PAR @T6G_MB_LIB.T6G(SCH_1):M_L_CPU1_SB_PAR    I22 @T6G_MB_LIB.T6G(SCH_1):PAGE108
    74 M_L_CPU1_SA_PAR @T6G_MB_LIB.T6G(SCH_1):M_L_CPU1_SA_PAR    I22 @T6G_MB_LIB.T6G(SCH_1):PAGE108
    87 M_L_CPU1_SB_RSP<0> @T6G_MB_LIB.T6G(SCH_1):M_L_CPU1_SB_RSP(0)    I22 @T6G_MB_LIB.T6G(SCH_1):PAGE108
    86 M_L_CPU1_SA_RSP<0> @T6G_MB_LIB.T6G(SCH_1):M_L_CPU1_SA_RSP(0)    I22 @T6G_MB_LIB.T6G(SCH_1):PAGE108
     5 I3C_SPD_DDRL_CPU1_SDA @T6G_MB_LIB.T6G(SCH_1):I3C_SPD_DDRL_CPU1_SDA    I22 @T6G_MB_LIB.T6G(SCH_1):PAGE108
     4 I3C_SPD_DDRL_CPU1_SCL @T6G_MB_LIB.T6G(SCH_1):I3C_SPD_DDRL_CPU1_SCL    I22 @T6G_MB_LIB.T6G(SCH_1):PAGE108
   148 PD_CHL_CPU1_DIMM_SAA @T6G_MB_LIB.T6G(SCH_1):PD_CHL_CPU1_DIMM_SAA    I22 @T6G_MB_LIB.T6G(SCH_1):PAGE108
   100 M_L_CPU1_SB_DQ<0> @T6G_MB_LIB.T6G(SCH_1):M_L_CPU1_SB_DQ(0)    I22 @T6G_MB_LIB.T6G(SCH_1):PAGE108
   102 M_L_CPU1_SB_DQ<1> @T6G_MB_LIB.T6G(SCH_1):M_L_CPU1_SB_DQ(1)    I22 @T6G_MB_LIB.T6G(SCH_1):PAGE108
   245 M_L_CPU1_SB_DQ<2> @T6G_MB_LIB.T6G(SCH_1):M_L_CPU1_SB_DQ(2)    I22 @T6G_MB_LIB.T6G(SCH_1):PAGE108
   247 M_L_CPU1_SB_DQ<3> @T6G_MB_LIB.T6G(SCH_1):M_L_CPU1_SB_DQ(3)    I22 @T6G_MB_LIB.T6G(SCH_1):PAGE108
   107 M_L_CPU1_SB_DQ<4> @T6G_MB_LIB.T6G(SCH_1):M_L_CPU1_SB_DQ(4)    I22 @T6G_MB_LIB.T6G(SCH_1):PAGE108
   109 M_L_CPU1_SB_DQ<5> @T6G_MB_LIB.T6G(SCH_1):M_L_CPU1_SB_DQ(5)    I22 @T6G_MB_LIB.T6G(SCH_1):PAGE108
   252 M_L_CPU1_SB_DQ<6> @T6G_MB_LIB.T6G(SCH_1):M_L_CPU1_SB_DQ(6)    I22 @T6G_MB_LIB.T6G(SCH_1):PAGE108
   254 M_L_CPU1_SB_DQ<7> @T6G_MB_LIB.T6G(SCH_1):M_L_CPU1_SB_DQ(7)    I22 @T6G_MB_LIB.T6G(SCH_1):PAGE108
   111 M_L_CPU1_SB_DQ<8> @T6G_MB_LIB.T6G(SCH_1):M_L_CPU1_SB_DQ(8)    I22 @T6G_MB_LIB.T6G(SCH_1):PAGE108
   113 M_L_CPU1_SB_DQ<9> @T6G_MB_LIB.T6G(SCH_1):M_L_CPU1_SB_DQ(9)    I22 @T6G_MB_LIB.T6G(SCH_1):PAGE108
   256 M_L_CPU1_SB_DQ<10> @T6G_MB_LIB.T6G(SCH_1):M_L_CPU1_SB_DQ(10)    I22 @T6G_MB_LIB.T6G(SCH_1):PAGE108
   258 M_L_CPU1_SB_DQ<11> @T6G_MB_LIB.T6G(SCH_1):M_L_CPU1_SB_DQ(11)    I22 @T6G_MB_LIB.T6G(SCH_1):PAGE108
   118 M_L_CPU1_SB_DQ<12> @T6G_MB_LIB.T6G(SCH_1):M_L_CPU1_SB_DQ(12)    I22 @T6G_MB_LIB.T6G(SCH_1):PAGE108
   120 M_L_CPU1_SB_DQ<13> @T6G_MB_LIB.T6G(SCH_1):M_L_CPU1_SB_DQ(13)    I22 @T6G_MB_LIB.T6G(SCH_1):PAGE108
   263 M_L_CPU1_SB_DQ<14> @T6G_MB_LIB.T6G(SCH_1):M_L_CPU1_SB_DQ(14)    I22 @T6G_MB_LIB.T6G(SCH_1):PAGE108
   265 M_L_CPU1_SB_DQ<15> @T6G_MB_LIB.T6G(SCH_1):M_L_CPU1_SB_DQ(15)    I22 @T6G_MB_LIB.T6G(SCH_1):PAGE108
   122 M_L_CPU1_SB_DQ<16> @T6G_MB_LIB.T6G(SCH_1):M_L_CPU1_SB_DQ(16)    I22 @T6G_MB_LIB.T6G(SCH_1):PAGE108
   124 M_L_CPU1_SB_DQ<17> @T6G_MB_LIB.T6G(SCH_1):M_L_CPU1_SB_DQ(17)    I22 @T6G_MB_LIB.T6G(SCH_1):PAGE108
   267 M_L_CPU1_SB_DQ<18> @T6G_MB_LIB.T6G(SCH_1):M_L_CPU1_SB_DQ(18)    I22 @T6G_MB_LIB.T6G(SCH_1):PAGE108
   269 M_L_CPU1_SB_DQ<19> @T6G_MB_LIB.T6G(SCH_1):M_L_CPU1_SB_DQ(19)    I22 @T6G_MB_LIB.T6G(SCH_1):PAGE108
   129 M_L_CPU1_SB_DQ<20> @T6G_MB_LIB.T6G(SCH_1):M_L_CPU1_SB_DQ(20)    I22 @T6G_MB_LIB.T6G(SCH_1):PAGE108
   131 M_L_CPU1_SB_DQ<21> @T6G_MB_LIB.T6G(SCH_1):M_L_CPU1_SB_DQ(21)    I22 @T6G_MB_LIB.T6G(SCH_1):PAGE108
   274 M_L_CPU1_SB_DQ<22> @T6G_MB_LIB.T6G(SCH_1):M_L_CPU1_SB_DQ(22)    I22 @T6G_MB_LIB.T6G(SCH_1):PAGE108
   276 M_L_CPU1_SB_DQ<23> @T6G_MB_LIB.T6G(SCH_1):M_L_CPU1_SB_DQ(23)    I22 @T6G_MB_LIB.T6G(SCH_1):PAGE108
   133 M_L_CPU1_SB_DQ<24> @T6G_MB_LIB.T6G(SCH_1):M_L_CPU1_SB_DQ(24)    I22 @T6G_MB_LIB.T6G(SCH_1):PAGE108
   135 M_L_CPU1_SB_DQ<25> @T6G_MB_LIB.T6G(SCH_1):M_L_CPU1_SB_DQ(25)    I22 @T6G_MB_LIB.T6G(SCH_1):PAGE108
   278 M_L_CPU1_SB_DQ<26> @T6G_MB_LIB.T6G(SCH_1):M_L_CPU1_SB_DQ(26)    I22 @T6G_MB_LIB.T6G(SCH_1):PAGE108
   280 M_L_CPU1_SB_DQ<27> @T6G_MB_LIB.T6G(SCH_1):M_L_CPU1_SB_DQ(27)    I22 @T6G_MB_LIB.T6G(SCH_1):PAGE108
   140 M_L_CPU1_SB_DQ<28> @T6G_MB_LIB.T6G(SCH_1):M_L_CPU1_SB_DQ(28)    I22 @T6G_MB_LIB.T6G(SCH_1):PAGE108
   142 M_L_CPU1_SB_DQ<29> @T6G_MB_LIB.T6G(SCH_1):M_L_CPU1_SB_DQ(29)    I22 @T6G_MB_LIB.T6G(SCH_1):PAGE108
   285 M_L_CPU1_SB_DQ<30> @T6G_MB_LIB.T6G(SCH_1):M_L_CPU1_SB_DQ(30)    I22 @T6G_MB_LIB.T6G(SCH_1):PAGE108
   287 M_L_CPU1_SB_DQ<31> @T6G_MB_LIB.T6G(SCH_1):M_L_CPU1_SB_DQ(31)    I22 @T6G_MB_LIB.T6G(SCH_1):PAGE108
     7 M_L_CPU1_SA_DQ<0> @T6G_MB_LIB.T6G(SCH_1):M_L_CPU1_SA_DQ(0)    I22 @T6G_MB_LIB.T6G(SCH_1):PAGE108
     9 M_L_CPU1_SA_DQ<1> @T6G_MB_LIB.T6G(SCH_1):M_L_CPU1_SA_DQ(1)    I22 @T6G_MB_LIB.T6G(SCH_1):PAGE108
   152 M_L_CPU1_SA_DQ<2> @T6G_MB_LIB.T6G(SCH_1):M_L_CPU1_SA_DQ(2)    I22 @T6G_MB_LIB.T6G(SCH_1):PAGE108
   154 M_L_CPU1_SA_DQ<3> @T6G_MB_LIB.T6G(SCH_1):M_L_CPU1_SA_DQ(3)    I22 @T6G_MB_LIB.T6G(SCH_1):PAGE108
    14 M_L_CPU1_SA_DQ<4> @T6G_MB_LIB.T6G(SCH_1):M_L_CPU1_SA_DQ(4)    I22 @T6G_MB_LIB.T6G(SCH_1):PAGE108
    16 M_L_CPU1_SA_DQ<5> @T6G_MB_LIB.T6G(SCH_1):M_L_CPU1_SA_DQ(5)    I22 @T6G_MB_LIB.T6G(SCH_1):PAGE108
   159 M_L_CPU1_SA_DQ<6> @T6G_MB_LIB.T6G(SCH_1):M_L_CPU1_SA_DQ(6)    I22 @T6G_MB_LIB.T6G(SCH_1):PAGE108
   161 M_L_CPU1_SA_DQ<7> @T6G_MB_LIB.T6G(SCH_1):M_L_CPU1_SA_DQ(7)    I22 @T6G_MB_LIB.T6G(SCH_1):PAGE108
    18 M_L_CPU1_SA_DQ<8> @T6G_MB_LIB.T6G(SCH_1):M_L_CPU1_SA_DQ(8)    I22 @T6G_MB_LIB.T6G(SCH_1):PAGE108
    20 M_L_CPU1_SA_DQ<9> @T6G_MB_LIB.T6G(SCH_1):M_L_CPU1_SA_DQ(9)    I22 @T6G_MB_LIB.T6G(SCH_1):PAGE108
   163 M_L_CPU1_SA_DQ<10> @T6G_MB_LIB.T6G(SCH_1):M_L_CPU1_SA_DQ(10)    I22 @T6G_MB_LIB.T6G(SCH_1):PAGE108
   165 M_L_CPU1_SA_DQ<11> @T6G_MB_LIB.T6G(SCH_1):M_L_CPU1_SA_DQ(11)    I22 @T6G_MB_LIB.T6G(SCH_1):PAGE108
    25 M_L_CPU1_SA_DQ<12> @T6G_MB_LIB.T6G(SCH_1):M_L_CPU1_SA_DQ(12)    I22 @T6G_MB_LIB.T6G(SCH_1):PAGE108
    27 M_L_CPU1_SA_DQ<13> @T6G_MB_LIB.T6G(SCH_1):M_L_CPU1_SA_DQ(13)    I22 @T6G_MB_LIB.T6G(SCH_1):PAGE108
   170 M_L_CPU1_SA_DQ<14> @T6G_MB_LIB.T6G(SCH_1):M_L_CPU1_SA_DQ(14)    I22 @T6G_MB_LIB.T6G(SCH_1):PAGE108
   172 M_L_CPU1_SA_DQ<15> @T6G_MB_LIB.T6G(SCH_1):M_L_CPU1_SA_DQ(15)    I22 @T6G_MB_LIB.T6G(SCH_1):PAGE108
    29 M_L_CPU1_SA_DQ<16> @T6G_MB_LIB.T6G(SCH_1):M_L_CPU1_SA_DQ(16)    I22 @T6G_MB_LIB.T6G(SCH_1):PAGE108
    31 M_L_CPU1_SA_DQ<17> @T6G_MB_LIB.T6G(SCH_1):M_L_CPU1_SA_DQ(17)    I22 @T6G_MB_LIB.T6G(SCH_1):PAGE108
   174 M_L_CPU1_SA_DQ<18> @T6G_MB_LIB.T6G(SCH_1):M_L_CPU1_SA_DQ(18)    I22 @T6G_MB_LIB.T6G(SCH_1):PAGE108
   176 M_L_CPU1_SA_DQ<19> @T6G_MB_LIB.T6G(SCH_1):M_L_CPU1_SA_DQ(19)    I22 @T6G_MB_LIB.T6G(SCH_1):PAGE108
    36 M_L_CPU1_SA_DQ<20> @T6G_MB_LIB.T6G(SCH_1):M_L_CPU1_SA_DQ(20)    I22 @T6G_MB_LIB.T6G(SCH_1):PAGE108
    38 M_L_CPU1_SA_DQ<21> @T6G_MB_LIB.T6G(SCH_1):M_L_CPU1_SA_DQ(21)    I22 @T6G_MB_LIB.T6G(SCH_1):PAGE108
   181 M_L_CPU1_SA_DQ<22> @T6G_MB_LIB.T6G(SCH_1):M_L_CPU1_SA_DQ(22)    I22 @T6G_MB_LIB.T6G(SCH_1):PAGE108
   183 M_L_CPU1_SA_DQ<23> @T6G_MB_LIB.T6G(SCH_1):M_L_CPU1_SA_DQ(23)    I22 @T6G_MB_LIB.T6G(SCH_1):PAGE108
    40 M_L_CPU1_SA_DQ<24> @T6G_MB_LIB.T6G(SCH_1):M_L_CPU1_SA_DQ(24)    I22 @T6G_MB_LIB.T6G(SCH_1):PAGE108
    42 M_L_CPU1_SA_DQ<25> @T6G_MB_LIB.T6G(SCH_1):M_L_CPU1_SA_DQ(25)    I22 @T6G_MB_LIB.T6G(SCH_1):PAGE108
   185 M_L_CPU1_SA_DQ<26> @T6G_MB_LIB.T6G(SCH_1):M_L_CPU1_SA_DQ(26)    I22 @T6G_MB_LIB.T6G(SCH_1):PAGE108
   187 M_L_CPU1_SA_DQ<27> @T6G_MB_LIB.T6G(SCH_1):M_L_CPU1_SA_DQ(27)    I22 @T6G_MB_LIB.T6G(SCH_1):PAGE108
    47 M_L_CPU1_SA_DQ<28> @T6G_MB_LIB.T6G(SCH_1):M_L_CPU1_SA_DQ(28)    I22 @T6G_MB_LIB.T6G(SCH_1):PAGE108
    49 M_L_CPU1_SA_DQ<29> @T6G_MB_LIB.T6G(SCH_1):M_L_CPU1_SA_DQ(29)    I22 @T6G_MB_LIB.T6G(SCH_1):PAGE108
   192 M_L_CPU1_SA_DQ<30> @T6G_MB_LIB.T6G(SCH_1):M_L_CPU1_SA_DQ(30)    I22 @T6G_MB_LIB.T6G(SCH_1):PAGE108
   229 M_L_CPU1_SB_CS_N<1> @T6G_MB_LIB.T6G(SCH_1):M_L_CPU1_SB_CS_N(1)    I22 @T6G_MB_LIB.T6G(SCH_1):PAGE108
   209 M_L_CPU1_SA_CS_N<1> @T6G_MB_LIB.T6G(SCH_1):M_L_CPU1_SA_CS_N(1)    I22 @T6G_MB_LIB.T6G(SCH_1):PAGE108
    84 M_L_CPU1_SB_CS_N<0> @T6G_MB_LIB.T6G(SCH_1):M_L_CPU1_SB_CS_N(0)    I22 @T6G_MB_LIB.T6G(SCH_1):PAGE108
    64 M_L_CPU1_SA_CS_N<0> @T6G_MB_LIB.T6G(SCH_1):M_L_CPU1_SA_CS_N(0)    I22 @T6G_MB_LIB.T6G(SCH_1):PAGE108
   217 M_L_CPU1_CLK_DP<0> @T6G_MB_LIB.T6G(SCH_1):M_L_CPU1_CLK_DP(0)    I22 @T6G_MB_LIB.T6G(SCH_1):PAGE108
   218 M_L_CPU1_CLK_DN<0> @T6G_MB_LIB.T6G(SCH_1):M_L_CPU1_CLK_DN(0)    I22 @T6G_MB_LIB.T6G(SCH_1):PAGE108
    96 M_L_CPU1_SB_CB<0> @T6G_MB_LIB.T6G(SCH_1):M_L_CPU1_SB_CB(0)    I22 @T6G_MB_LIB.T6G(SCH_1):PAGE108
    98 M_L_CPU1_SB_CB<1> @T6G_MB_LIB.T6G(SCH_1):M_L_CPU1_SB_CB(1)    I22 @T6G_MB_LIB.T6G(SCH_1):PAGE108
   241 M_L_CPU1_SB_CB<2> @T6G_MB_LIB.T6G(SCH_1):M_L_CPU1_SB_CB(2)    I22 @T6G_MB_LIB.T6G(SCH_1):PAGE108
   243 M_L_CPU1_SB_CB<3> @T6G_MB_LIB.T6G(SCH_1):M_L_CPU1_SB_CB(3)    I22 @T6G_MB_LIB.T6G(SCH_1):PAGE108
    89 M_L_CPU1_SB_CB<4> @T6G_MB_LIB.T6G(SCH_1):M_L_CPU1_SB_CB(4)    I22 @T6G_MB_LIB.T6G(SCH_1):PAGE108
    91 M_L_CPU1_SB_CB<5> @T6G_MB_LIB.T6G(SCH_1):M_L_CPU1_SB_CB(5)    I22 @T6G_MB_LIB.T6G(SCH_1):PAGE108
   234 M_L_CPU1_SB_CB<6> @T6G_MB_LIB.T6G(SCH_1):M_L_CPU1_SB_CB(6)    I22 @T6G_MB_LIB.T6G(SCH_1):PAGE108
    51 M_L_CPU1_SA_CB<0> @T6G_MB_LIB.T6G(SCH_1):M_L_CPU1_SA_CB(0)    I22 @T6G_MB_LIB.T6G(SCH_1):PAGE108
   196 M_L_CPU1_SA_CB<2> @T6G_MB_LIB.T6G(SCH_1):M_L_CPU1_SA_CB(2)    I22 @T6G_MB_LIB.T6G(SCH_1):PAGE108
   198 M_L_CPU1_SA_CB<3> @T6G_MB_LIB.T6G(SCH_1):M_L_CPU1_SA_CB(3)    I22 @T6G_MB_LIB.T6G(SCH_1):PAGE108
    60 M_L_CPU1_SA_CB<5> @T6G_MB_LIB.T6G(SCH_1):M_L_CPU1_SA_CB(5)    I22 @T6G_MB_LIB.T6G(SCH_1):PAGE108
   203 M_L_CPU1_SA_CB<6> @T6G_MB_LIB.T6G(SCH_1):M_L_CPU1_SA_CB(6)    I22 @T6G_MB_LIB.T6G(SCH_1):PAGE108
    82 M_L_CPU1_SB_CA<6> @T6G_MB_LIB.T6G(SCH_1):M_L_CPU1_SB_CA(6)    I22 @T6G_MB_LIB.T6G(SCH_1):PAGE108
    72 M_L_CPU1_SA_CA<6> @T6G_MB_LIB.T6G(SCH_1):M_L_CPU1_SA_CA(6)    I22 @T6G_MB_LIB.T6G(SCH_1):PAGE108
   225 M_L_CPU1_SB_CA<5> @T6G_MB_LIB.T6G(SCH_1):M_L_CPU1_SB_CA(5)    I22 @T6G_MB_LIB.T6G(SCH_1):PAGE108
   215 M_L_CPU1_SA_CA<5> @T6G_MB_LIB.T6G(SCH_1):M_L_CPU1_SA_CA(5)    I22 @T6G_MB_LIB.T6G(SCH_1):PAGE108
    80 M_L_CPU1_SB_CA<4> @T6G_MB_LIB.T6G(SCH_1):M_L_CPU1_SB_CA(4)    I22 @T6G_MB_LIB.T6G(SCH_1):PAGE108
    70 M_L_CPU1_SA_CA<4> @T6G_MB_LIB.T6G(SCH_1):M_L_CPU1_SA_CA(4)    I22 @T6G_MB_LIB.T6G(SCH_1):PAGE108
   223 M_L_CPU1_SB_CA<3> @T6G_MB_LIB.T6G(SCH_1):M_L_CPU1_SB_CA(3)    I22 @T6G_MB_LIB.T6G(SCH_1):PAGE108
   213 M_L_CPU1_SA_CA<3> @T6G_MB_LIB.T6G(SCH_1):M_L_CPU1_SA_CA(3)    I22 @T6G_MB_LIB.T6G(SCH_1):PAGE108
    78 M_L_CPU1_SB_CA<2> @T6G_MB_LIB.T6G(SCH_1):M_L_CPU1_SB_CA(2)    I22 @T6G_MB_LIB.T6G(SCH_1):PAGE108
    68 M_L_CPU1_SA_CA<2> @T6G_MB_LIB.T6G(SCH_1):M_L_CPU1_SA_CA(2)    I22 @T6G_MB_LIB.T6G(SCH_1):PAGE108
   221 M_L_CPU1_SB_CA<1> @T6G_MB_LIB.T6G(SCH_1):M_L_CPU1_SB_CA(1)    I22 @T6G_MB_LIB.T6G(SCH_1):PAGE108
   211 M_L_CPU1_SA_CA<1> @T6G_MB_LIB.T6G(SCH_1):M_L_CPU1_SA_CA(1)    I22 @T6G_MB_LIB.T6G(SCH_1):PAGE108
    76 M_L_CPU1_SB_CA<0> @T6G_MB_LIB.T6G(SCH_1):M_L_CPU1_SB_CA(0)    I22 @T6G_MB_LIB.T6G(SCH_1):PAGE108
    66 M_L_CPU1_SA_CA<0> @T6G_MB_LIB.T6G(SCH_1):M_L_CPU1_SA_CA(0)    I22 @T6G_MB_LIB.T6G(SCH_1):PAGE108
    62 M_L_CPU1_ALERT_N @T6G_MB_LIB.T6G(SCH_1):M_L_CPU1_ALERT_N    I22 @T6G_MB_LIB.T6G(SCH_1):PAGE108
   236 M_L_CPU1_SB_CB<7> @T6G_MB_LIB.T6G(SCH_1):M_L_CPU1_SB_CB(7)    I22 @T6G_MB_LIB.T6G(SCH_1):PAGE108
    53 M_L_CPU1_SA_CB<1> @T6G_MB_LIB.T6G(SCH_1):M_L_CPU1_SA_CB(1)    I22 @T6G_MB_LIB.T6G(SCH_1):PAGE108
    58 M_L_CPU1_SA_CB<4> @T6G_MB_LIB.T6G(SCH_1):M_L_CPU1_SA_CB(4)    I22 @T6G_MB_LIB.T6G(SCH_1):PAGE108
   205 M_L_CPU1_SA_CB<7> @T6G_MB_LIB.T6G(SCH_1):M_L_CPU1_SA_CB(7)    I22 @T6G_MB_LIB.T6G(SCH_1):PAGE108
   194 M_L_CPU1_SA_DQ<31> @T6G_MB_LIB.T6G(SCH_1):M_L_CPU1_SA_DQ(31)    I22 @T6G_MB_LIB.T6G(SCH_1):PAGE108
    93 M_L_CPU1_SB_DQS_DP<9> @T6G_MB_LIB.T6G(SCH_1):M_L_CPU1_SB_DQS_DP(9)   I235 @T6G_MB_LIB.T6G(SCH_1):PAGE108
    94 M_L_CPU1_SB_DQS_DN<9> @T6G_MB_LIB.T6G(SCH_1):M_L_CPU1_SB_DQS_DN(9)   I235 @T6G_MB_LIB.T6G(SCH_1):PAGE108
   201 M_L_CPU1_SA_DQS_DP<9> @T6G_MB_LIB.T6G(SCH_1):M_L_CPU1_SA_DQS_DP(9)   I235 @T6G_MB_LIB.T6G(SCH_1):PAGE108
   200 M_L_CPU1_SA_DQS_DN<9> @T6G_MB_LIB.T6G(SCH_1):M_L_CPU1_SA_DQS_DN(9)   I235 @T6G_MB_LIB.T6G(SCH_1):PAGE108
   190 M_L_CPU1_SA_DQS_DP<8> @T6G_MB_LIB.T6G(SCH_1):M_L_CPU1_SA_DQS_DP(8)   I235 @T6G_MB_LIB.T6G(SCH_1):PAGE108
   189 M_L_CPU1_SA_DQS_DN<8> @T6G_MB_LIB.T6G(SCH_1):M_L_CPU1_SA_DQS_DN(8)   I235 @T6G_MB_LIB.T6G(SCH_1):PAGE108
   271 M_L_CPU1_SB_DQS_DN<7> @T6G_MB_LIB.T6G(SCH_1):M_L_CPU1_SB_DQS_DN(7)   I235 @T6G_MB_LIB.T6G(SCH_1):PAGE108
   179 M_L_CPU1_SA_DQS_DP<7> @T6G_MB_LIB.T6G(SCH_1):M_L_CPU1_SA_DQS_DP(7)   I235 @T6G_MB_LIB.T6G(SCH_1):PAGE108
   261 M_L_CPU1_SB_DQS_DP<6> @T6G_MB_LIB.T6G(SCH_1):M_L_CPU1_SB_DQS_DP(6)   I235 @T6G_MB_LIB.T6G(SCH_1):PAGE108
   260 M_L_CPU1_SB_DQS_DN<6> @T6G_MB_LIB.T6G(SCH_1):M_L_CPU1_SB_DQS_DN(6)   I235 @T6G_MB_LIB.T6G(SCH_1):PAGE108
   167 M_L_CPU1_SA_DQS_DN<6> @T6G_MB_LIB.T6G(SCH_1):M_L_CPU1_SA_DQS_DN(6)   I235 @T6G_MB_LIB.T6G(SCH_1):PAGE108
   250 M_L_CPU1_SB_DQS_DP<5> @T6G_MB_LIB.T6G(SCH_1):M_L_CPU1_SB_DQS_DP(5)   I235 @T6G_MB_LIB.T6G(SCH_1):PAGE108
   249 M_L_CPU1_SB_DQS_DN<5> @T6G_MB_LIB.T6G(SCH_1):M_L_CPU1_SB_DQS_DN(5)   I235 @T6G_MB_LIB.T6G(SCH_1):PAGE108
   157 M_L_CPU1_SA_DQS_DP<5> @T6G_MB_LIB.T6G(SCH_1):M_L_CPU1_SA_DQS_DP(5)   I235 @T6G_MB_LIB.T6G(SCH_1):PAGE108
   156 M_L_CPU1_SA_DQS_DN<5> @T6G_MB_LIB.T6G(SCH_1):M_L_CPU1_SA_DQS_DN(5)   I235 @T6G_MB_LIB.T6G(SCH_1):PAGE108
   239 M_L_CPU1_SB_DQS_DP<4> @T6G_MB_LIB.T6G(SCH_1):M_L_CPU1_SB_DQS_DP(4)   I235 @T6G_MB_LIB.T6G(SCH_1):PAGE108
   238 M_L_CPU1_SB_DQS_DN<4> @T6G_MB_LIB.T6G(SCH_1):M_L_CPU1_SB_DQS_DN(4)   I235 @T6G_MB_LIB.T6G(SCH_1):PAGE108
    55 M_L_CPU1_SA_DQS_DP<4> @T6G_MB_LIB.T6G(SCH_1):M_L_CPU1_SA_DQS_DP(4)   I235 @T6G_MB_LIB.T6G(SCH_1):PAGE108
    56 M_L_CPU1_SA_DQS_DN<4> @T6G_MB_LIB.T6G(SCH_1):M_L_CPU1_SA_DQS_DN(4)   I235 @T6G_MB_LIB.T6G(SCH_1):PAGE108
   137 M_L_CPU1_SB_DQS_DP<3> @T6G_MB_LIB.T6G(SCH_1):M_L_CPU1_SB_DQS_DP(3)   I235 @T6G_MB_LIB.T6G(SCH_1):PAGE108
   138 M_L_CPU1_SB_DQS_DN<3> @T6G_MB_LIB.T6G(SCH_1):M_L_CPU1_SB_DQS_DN(3)   I235 @T6G_MB_LIB.T6G(SCH_1):PAGE108
    44 M_L_CPU1_SA_DQS_DP<3> @T6G_MB_LIB.T6G(SCH_1):M_L_CPU1_SA_DQS_DP(3)   I235 @T6G_MB_LIB.T6G(SCH_1):PAGE108
    45 M_L_CPU1_SA_DQS_DN<3> @T6G_MB_LIB.T6G(SCH_1):M_L_CPU1_SA_DQS_DN(3)   I235 @T6G_MB_LIB.T6G(SCH_1):PAGE108
   126 M_L_CPU1_SB_DQS_DP<2> @T6G_MB_LIB.T6G(SCH_1):M_L_CPU1_SB_DQS_DP(2)   I235 @T6G_MB_LIB.T6G(SCH_1):PAGE108
   127 M_L_CPU1_SB_DQS_DN<2> @T6G_MB_LIB.T6G(SCH_1):M_L_CPU1_SB_DQS_DN(2)   I235 @T6G_MB_LIB.T6G(SCH_1):PAGE108
    33 M_L_CPU1_SA_DQS_DP<2> @T6G_MB_LIB.T6G(SCH_1):M_L_CPU1_SA_DQS_DP(2)   I235 @T6G_MB_LIB.T6G(SCH_1):PAGE108
    34 M_L_CPU1_SA_DQS_DN<2> @T6G_MB_LIB.T6G(SCH_1):M_L_CPU1_SA_DQS_DN(2)   I235 @T6G_MB_LIB.T6G(SCH_1):PAGE108
   115 M_L_CPU1_SB_DQS_DP<1> @T6G_MB_LIB.T6G(SCH_1):M_L_CPU1_SB_DQS_DP(1)   I235 @T6G_MB_LIB.T6G(SCH_1):PAGE108
   116 M_L_CPU1_SB_DQS_DN<1> @T6G_MB_LIB.T6G(SCH_1):M_L_CPU1_SB_DQS_DN(1)   I235 @T6G_MB_LIB.T6G(SCH_1):PAGE108
    22 M_L_CPU1_SA_DQS_DP<1> @T6G_MB_LIB.T6G(SCH_1):M_L_CPU1_SA_DQS_DP(1)   I235 @T6G_MB_LIB.T6G(SCH_1):PAGE108
    23 M_L_CPU1_SA_DQS_DN<1> @T6G_MB_LIB.T6G(SCH_1):M_L_CPU1_SA_DQS_DN(1)   I235 @T6G_MB_LIB.T6G(SCH_1):PAGE108
   104 M_L_CPU1_SB_DQS_DP<0> @T6G_MB_LIB.T6G(SCH_1):M_L_CPU1_SB_DQS_DP(0)   I235 @T6G_MB_LIB.T6G(SCH_1):PAGE108
   105 M_L_CPU1_SB_DQS_DN<0> @T6G_MB_LIB.T6G(SCH_1):M_L_CPU1_SB_DQS_DN(0)   I235 @T6G_MB_LIB.T6G(SCH_1):PAGE108
    11 M_L_CPU1_SA_DQS_DP<0> @T6G_MB_LIB.T6G(SCH_1):M_L_CPU1_SA_DQS_DP(0)   I235 @T6G_MB_LIB.T6G(SCH_1):PAGE108
    12 M_L_CPU1_SA_DQS_DN<0> @T6G_MB_LIB.T6G(SCH_1):M_L_CPU1_SA_DQS_DN(0)   I235 @T6G_MB_LIB.T6G(SCH_1):PAGE108
   272 M_L_CPU1_SB_DQS_DP<7> @T6G_MB_LIB.T6G(SCH_1):M_L_CPU1_SB_DQS_DP(7)   I235 @T6G_MB_LIB.T6G(SCH_1):PAGE108
   282 M_L_CPU1_SB_DQS_DN<8> @T6G_MB_LIB.T6G(SCH_1):M_L_CPU1_SB_DQS_DN(8)   I235 @T6G_MB_LIB.T6G(SCH_1):PAGE108
   283 M_L_CPU1_SB_DQS_DP<8> @T6G_MB_LIB.T6G(SCH_1):M_L_CPU1_SB_DQS_DP(8)   I235 @T6G_MB_LIB.T6G(SCH_1):PAGE108
   168 M_L_CPU1_SA_DQS_DP<6> @T6G_MB_LIB.T6G(SCH_1):M_L_CPU1_SA_DQS_DP(6)   I235 @T6G_MB_LIB.T6G(SCH_1):PAGE108
   178 M_L_CPU1_SA_DQS_DN<7> @T6G_MB_LIB.T6G(SCH_1):M_L_CPU1_SA_DQS_DN(7)   I235 @T6G_MB_LIB.T6G(SCH_1):PAGE108
     6    GND @T6G_MB_LIB.T6G(SCH_1):GND   I138 @T6G_MB_LIB.T6G(SCH_1):PAGE108
     8    GND @T6G_MB_LIB.T6G(SCH_1):GND   I138 @T6G_MB_LIB.T6G(SCH_1):PAGE108
    10    GND @T6G_MB_LIB.T6G(SCH_1):GND   I138 @T6G_MB_LIB.T6G(SCH_1):PAGE108
    13    GND @T6G_MB_LIB.T6G(SCH_1):GND   I138 @T6G_MB_LIB.T6G(SCH_1):PAGE108
    15    GND @T6G_MB_LIB.T6G(SCH_1):GND   I138 @T6G_MB_LIB.T6G(SCH_1):PAGE108
    17    GND @T6G_MB_LIB.T6G(SCH_1):GND   I138 @T6G_MB_LIB.T6G(SCH_1):PAGE108
    19    GND @T6G_MB_LIB.T6G(SCH_1):GND   I138 @T6G_MB_LIB.T6G(SCH_1):PAGE108
    21    GND @T6G_MB_LIB.T6G(SCH_1):GND   I138 @T6G_MB_LIB.T6G(SCH_1):PAGE108
    24    GND @T6G_MB_LIB.T6G(SCH_1):GND   I138 @T6G_MB_LIB.T6G(SCH_1):PAGE108
    26    GND @T6G_MB_LIB.T6G(SCH_1):GND   I138 @T6G_MB_LIB.T6G(SCH_1):PAGE108
    28    GND @T6G_MB_LIB.T6G(SCH_1):GND   I138 @T6G_MB_LIB.T6G(SCH_1):PAGE108
    30    GND @T6G_MB_LIB.T6G(SCH_1):GND   I138 @T6G_MB_LIB.T6G(SCH_1):PAGE108
    32    GND @T6G_MB_LIB.T6G(SCH_1):GND   I138 @T6G_MB_LIB.T6G(SCH_1):PAGE108
    35    GND @T6G_MB_LIB.T6G(SCH_1):GND   I138 @T6G_MB_LIB.T6G(SCH_1):PAGE108
    37    GND @T6G_MB_LIB.T6G(SCH_1):GND   I138 @T6G_MB_LIB.T6G(SCH_1):PAGE108
    39    GND @T6G_MB_LIB.T6G(SCH_1):GND   I138 @T6G_MB_LIB.T6G(SCH_1):PAGE108
    41    GND @T6G_MB_LIB.T6G(SCH_1):GND   I138 @T6G_MB_LIB.T6G(SCH_1):PAGE108
    43    GND @T6G_MB_LIB.T6G(SCH_1):GND   I138 @T6G_MB_LIB.T6G(SCH_1):PAGE108
    46    GND @T6G_MB_LIB.T6G(SCH_1):GND   I138 @T6G_MB_LIB.T6G(SCH_1):PAGE108
    48    GND @T6G_MB_LIB.T6G(SCH_1):GND   I138 @T6G_MB_LIB.T6G(SCH_1):PAGE108
    50    GND @T6G_MB_LIB.T6G(SCH_1):GND   I138 @T6G_MB_LIB.T6G(SCH_1):PAGE108
    52    GND @T6G_MB_LIB.T6G(SCH_1):GND   I138 @T6G_MB_LIB.T6G(SCH_1):PAGE108
    54    GND @T6G_MB_LIB.T6G(SCH_1):GND   I138 @T6G_MB_LIB.T6G(SCH_1):PAGE108
    57    GND @T6G_MB_LIB.T6G(SCH_1):GND   I138 @T6G_MB_LIB.T6G(SCH_1):PAGE108
    59    GND @T6G_MB_LIB.T6G(SCH_1):GND   I138 @T6G_MB_LIB.T6G(SCH_1):PAGE108
    61    GND @T6G_MB_LIB.T6G(SCH_1):GND   I138 @T6G_MB_LIB.T6G(SCH_1):PAGE108
    63    GND @T6G_MB_LIB.T6G(SCH_1):GND   I138 @T6G_MB_LIB.T6G(SCH_1):PAGE108
    65    GND @T6G_MB_LIB.T6G(SCH_1):GND   I138 @T6G_MB_LIB.T6G(SCH_1):PAGE108
    67    GND @T6G_MB_LIB.T6G(SCH_1):GND   I138 @T6G_MB_LIB.T6G(SCH_1):PAGE108
    69    GND @T6G_MB_LIB.T6G(SCH_1):GND   I138 @T6G_MB_LIB.T6G(SCH_1):PAGE108
    71    GND @T6G_MB_LIB.T6G(SCH_1):GND   I138 @T6G_MB_LIB.T6G(SCH_1):PAGE108
    73    GND @T6G_MB_LIB.T6G(SCH_1):GND   I138 @T6G_MB_LIB.T6G(SCH_1):PAGE108
    75    GND @T6G_MB_LIB.T6G(SCH_1):GND   I138 @T6G_MB_LIB.T6G(SCH_1):PAGE108
    77    GND @T6G_MB_LIB.T6G(SCH_1):GND   I138 @T6G_MB_LIB.T6G(SCH_1):PAGE108
    79    GND @T6G_MB_LIB.T6G(SCH_1):GND   I138 @T6G_MB_LIB.T6G(SCH_1):PAGE108
    81    GND @T6G_MB_LIB.T6G(SCH_1):GND   I138 @T6G_MB_LIB.T6G(SCH_1):PAGE108
    83    GND @T6G_MB_LIB.T6G(SCH_1):GND   I138 @T6G_MB_LIB.T6G(SCH_1):PAGE108
    85    GND @T6G_MB_LIB.T6G(SCH_1):GND   I138 @T6G_MB_LIB.T6G(SCH_1):PAGE108
    88    GND @T6G_MB_LIB.T6G(SCH_1):GND   I138 @T6G_MB_LIB.T6G(SCH_1):PAGE108
    90    GND @T6G_MB_LIB.T6G(SCH_1):GND   I138 @T6G_MB_LIB.T6G(SCH_1):PAGE108
    92    GND @T6G_MB_LIB.T6G(SCH_1):GND   I138 @T6G_MB_LIB.T6G(SCH_1):PAGE108
    95    GND @T6G_MB_LIB.T6G(SCH_1):GND   I138 @T6G_MB_LIB.T6G(SCH_1):PAGE108
    97    GND @T6G_MB_LIB.T6G(SCH_1):GND   I138 @T6G_MB_LIB.T6G(SCH_1):PAGE108
    99    GND @T6G_MB_LIB.T6G(SCH_1):GND   I138 @T6G_MB_LIB.T6G(SCH_1):PAGE108
   101    GND @T6G_MB_LIB.T6G(SCH_1):GND   I138 @T6G_MB_LIB.T6G(SCH_1):PAGE108
   103    GND @T6G_MB_LIB.T6G(SCH_1):GND   I138 @T6G_MB_LIB.T6G(SCH_1):PAGE108
   106    GND @T6G_MB_LIB.T6G(SCH_1):GND   I138 @T6G_MB_LIB.T6G(SCH_1):PAGE108
   108    GND @T6G_MB_LIB.T6G(SCH_1):GND   I138 @T6G_MB_LIB.T6G(SCH_1):PAGE108
   110    GND @T6G_MB_LIB.T6G(SCH_1):GND   I138 @T6G_MB_LIB.T6G(SCH_1):PAGE108
   112    GND @T6G_MB_LIB.T6G(SCH_1):GND   I138 @T6G_MB_LIB.T6G(SCH_1):PAGE108
   114    GND @T6G_MB_LIB.T6G(SCH_1):GND   I138 @T6G_MB_LIB.T6G(SCH_1):PAGE108
   117    GND @T6G_MB_LIB.T6G(SCH_1):GND   I138 @T6G_MB_LIB.T6G(SCH_1):PAGE108
   119    GND @T6G_MB_LIB.T6G(SCH_1):GND   I138 @T6G_MB_LIB.T6G(SCH_1):PAGE108
   121    GND @T6G_MB_LIB.T6G(SCH_1):GND   I138 @T6G_MB_LIB.T6G(SCH_1):PAGE108
   123    GND @T6G_MB_LIB.T6G(SCH_1):GND   I138 @T6G_MB_LIB.T6G(SCH_1):PAGE108
   125    GND @T6G_MB_LIB.T6G(SCH_1):GND   I138 @T6G_MB_LIB.T6G(SCH_1):PAGE108
   128    GND @T6G_MB_LIB.T6G(SCH_1):GND   I138 @T6G_MB_LIB.T6G(SCH_1):PAGE108
   130    GND @T6G_MB_LIB.T6G(SCH_1):GND   I138 @T6G_MB_LIB.T6G(SCH_1):PAGE108
   134    GND @T6G_MB_LIB.T6G(SCH_1):GND   I138 @T6G_MB_LIB.T6G(SCH_1):PAGE108
   143    GND @T6G_MB_LIB.T6G(SCH_1):GND   I138 @T6G_MB_LIB.T6G(SCH_1):PAGE108
   151    GND @T6G_MB_LIB.T6G(SCH_1):GND   I138 @T6G_MB_LIB.T6G(SCH_1):PAGE108
   153    GND @T6G_MB_LIB.T6G(SCH_1):GND   I138 @T6G_MB_LIB.T6G(SCH_1):PAGE108
   155    GND @T6G_MB_LIB.T6G(SCH_1):GND   I138 @T6G_MB_LIB.T6G(SCH_1):PAGE108
   158    GND @T6G_MB_LIB.T6G(SCH_1):GND   I138 @T6G_MB_LIB.T6G(SCH_1):PAGE108
   160    GND @T6G_MB_LIB.T6G(SCH_1):GND   I138 @T6G_MB_LIB.T6G(SCH_1):PAGE108
   162    GND @T6G_MB_LIB.T6G(SCH_1):GND   I138 @T6G_MB_LIB.T6G(SCH_1):PAGE108
   164    GND @T6G_MB_LIB.T6G(SCH_1):GND   I138 @T6G_MB_LIB.T6G(SCH_1):PAGE108
   166    GND @T6G_MB_LIB.T6G(SCH_1):GND   I138 @T6G_MB_LIB.T6G(SCH_1):PAGE108
   169    GND @T6G_MB_LIB.T6G(SCH_1):GND   I138 @T6G_MB_LIB.T6G(SCH_1):PAGE108
   171    GND @T6G_MB_LIB.T6G(SCH_1):GND   I138 @T6G_MB_LIB.T6G(SCH_1):PAGE108
   173    GND @T6G_MB_LIB.T6G(SCH_1):GND   I138 @T6G_MB_LIB.T6G(SCH_1):PAGE108
   175    GND @T6G_MB_LIB.T6G(SCH_1):GND   I138 @T6G_MB_LIB.T6G(SCH_1):PAGE108
   177    GND @T6G_MB_LIB.T6G(SCH_1):GND   I138 @T6G_MB_LIB.T6G(SCH_1):PAGE108
   180    GND @T6G_MB_LIB.T6G(SCH_1):GND   I138 @T6G_MB_LIB.T6G(SCH_1):PAGE108
   182    GND @T6G_MB_LIB.T6G(SCH_1):GND   I138 @T6G_MB_LIB.T6G(SCH_1):PAGE108
   184    GND @T6G_MB_LIB.T6G(SCH_1):GND   I138 @T6G_MB_LIB.T6G(SCH_1):PAGE108
   186    GND @T6G_MB_LIB.T6G(SCH_1):GND   I138 @T6G_MB_LIB.T6G(SCH_1):PAGE108
   188    GND @T6G_MB_LIB.T6G(SCH_1):GND   I138 @T6G_MB_LIB.T6G(SCH_1):PAGE108
   191    GND @T6G_MB_LIB.T6G(SCH_1):GND   I138 @T6G_MB_LIB.T6G(SCH_1):PAGE108
   193    GND @T6G_MB_LIB.T6G(SCH_1):GND   I138 @T6G_MB_LIB.T6G(SCH_1):PAGE108
   195    GND @T6G_MB_LIB.T6G(SCH_1):GND   I138 @T6G_MB_LIB.T6G(SCH_1):PAGE108
   197    GND @T6G_MB_LIB.T6G(SCH_1):GND   I138 @T6G_MB_LIB.T6G(SCH_1):PAGE108
   199    GND @T6G_MB_LIB.T6G(SCH_1):GND   I138 @T6G_MB_LIB.T6G(SCH_1):PAGE108
   202    GND @T6G_MB_LIB.T6G(SCH_1):GND   I138 @T6G_MB_LIB.T6G(SCH_1):PAGE108
   204    GND @T6G_MB_LIB.T6G(SCH_1):GND   I138 @T6G_MB_LIB.T6G(SCH_1):PAGE108
   206    GND @T6G_MB_LIB.T6G(SCH_1):GND   I138 @T6G_MB_LIB.T6G(SCH_1):PAGE108
   208    GND @T6G_MB_LIB.T6G(SCH_1):GND   I138 @T6G_MB_LIB.T6G(SCH_1):PAGE108
   210    GND @T6G_MB_LIB.T6G(SCH_1):GND   I138 @T6G_MB_LIB.T6G(SCH_1):PAGE108
   212    GND @T6G_MB_LIB.T6G(SCH_1):GND   I138 @T6G_MB_LIB.T6G(SCH_1):PAGE108
   214    GND @T6G_MB_LIB.T6G(SCH_1):GND   I138 @T6G_MB_LIB.T6G(SCH_1):PAGE108
   216    GND @T6G_MB_LIB.T6G(SCH_1):GND   I138 @T6G_MB_LIB.T6G(SCH_1):PAGE108
   219    GND @T6G_MB_LIB.T6G(SCH_1):GND   I138 @T6G_MB_LIB.T6G(SCH_1):PAGE108
   222    GND @T6G_MB_LIB.T6G(SCH_1):GND   I138 @T6G_MB_LIB.T6G(SCH_1):PAGE108
   224    GND @T6G_MB_LIB.T6G(SCH_1):GND   I138 @T6G_MB_LIB.T6G(SCH_1):PAGE108
   226    GND @T6G_MB_LIB.T6G(SCH_1):GND   I138 @T6G_MB_LIB.T6G(SCH_1):PAGE108
   228    GND @T6G_MB_LIB.T6G(SCH_1):GND   I138 @T6G_MB_LIB.T6G(SCH_1):PAGE108
   233    GND @T6G_MB_LIB.T6G(SCH_1):GND   I138 @T6G_MB_LIB.T6G(SCH_1):PAGE108
   237    GND @T6G_MB_LIB.T6G(SCH_1):GND   I138 @T6G_MB_LIB.T6G(SCH_1):PAGE108
   242    GND @T6G_MB_LIB.T6G(SCH_1):GND   I138 @T6G_MB_LIB.T6G(SCH_1):PAGE108
   244    GND @T6G_MB_LIB.T6G(SCH_1):GND   I138 @T6G_MB_LIB.T6G(SCH_1):PAGE108
   246    GND @T6G_MB_LIB.T6G(SCH_1):GND   I138 @T6G_MB_LIB.T6G(SCH_1):PAGE108
   248    GND @T6G_MB_LIB.T6G(SCH_1):GND   I138 @T6G_MB_LIB.T6G(SCH_1):PAGE108
   251    GND @T6G_MB_LIB.T6G(SCH_1):GND   I138 @T6G_MB_LIB.T6G(SCH_1):PAGE108
   253    GND @T6G_MB_LIB.T6G(SCH_1):GND   I138 @T6G_MB_LIB.T6G(SCH_1):PAGE108
   255    GND @T6G_MB_LIB.T6G(SCH_1):GND   I138 @T6G_MB_LIB.T6G(SCH_1):PAGE108
   257    GND @T6G_MB_LIB.T6G(SCH_1):GND   I138 @T6G_MB_LIB.T6G(SCH_1):PAGE108
   259    GND @T6G_MB_LIB.T6G(SCH_1):GND   I138 @T6G_MB_LIB.T6G(SCH_1):PAGE108
   262    GND @T6G_MB_LIB.T6G(SCH_1):GND   I138 @T6G_MB_LIB.T6G(SCH_1):PAGE108
   264    GND @T6G_MB_LIB.T6G(SCH_1):GND   I138 @T6G_MB_LIB.T6G(SCH_1):PAGE108
   266    GND @T6G_MB_LIB.T6G(SCH_1):GND   I138 @T6G_MB_LIB.T6G(SCH_1):PAGE108
   268    GND @T6G_MB_LIB.T6G(SCH_1):GND   I138 @T6G_MB_LIB.T6G(SCH_1):PAGE108
   270    GND @T6G_MB_LIB.T6G(SCH_1):GND   I138 @T6G_MB_LIB.T6G(SCH_1):PAGE108
   273    GND @T6G_MB_LIB.T6G(SCH_1):GND   I138 @T6G_MB_LIB.T6G(SCH_1):PAGE108
   275    GND @T6G_MB_LIB.T6G(SCH_1):GND   I138 @T6G_MB_LIB.T6G(SCH_1):PAGE108
   277    GND @T6G_MB_LIB.T6G(SCH_1):GND   I138 @T6G_MB_LIB.T6G(SCH_1):PAGE108
   279    GND @T6G_MB_LIB.T6G(SCH_1):GND   I138 @T6G_MB_LIB.T6G(SCH_1):PAGE108
   281    GND @T6G_MB_LIB.T6G(SCH_1):GND   I138 @T6G_MB_LIB.T6G(SCH_1):PAGE108
   284    GND @T6G_MB_LIB.T6G(SCH_1):GND   I138 @T6G_MB_LIB.T6G(SCH_1):PAGE108
   286    GND @T6G_MB_LIB.T6G(SCH_1):GND   I138 @T6G_MB_LIB.T6G(SCH_1):PAGE108
   288    GND @T6G_MB_LIB.T6G(SCH_1):GND   I138 @T6G_MB_LIB.T6G(SCH_1):PAGE108
     1 P12V_MEM_CPU1 @T6G_MB_LIB.T6G(SCH_1):P12V_MEM_CPU1   I138 @T6G_MB_LIB.T6G(SCH_1):PAGE108
   145 P12V_MEM_CPU1 @T6G_MB_LIB.T6G(SCH_1):P12V_MEM_CPU1   I138 @T6G_MB_LIB.T6G(SCH_1):PAGE108
   146 P12V_MEM_CPU1 @T6G_MB_LIB.T6G(SCH_1):P12V_MEM_CPU1   I138 @T6G_MB_LIB.T6G(SCH_1):PAGE108
   230    GND @T6G_MB_LIB.T6G(SCH_1):GND   I138 @T6G_MB_LIB.T6G(SCH_1):PAGE108
   235    GND @T6G_MB_LIB.T6G(SCH_1):GND   I138 @T6G_MB_LIB.T6G(SCH_1):PAGE108
   240    GND @T6G_MB_LIB.T6G(SCH_1):GND   I138 @T6G_MB_LIB.T6G(SCH_1):PAGE108
   132    GND @T6G_MB_LIB.T6G(SCH_1):GND   I138 @T6G_MB_LIB.T6G(SCH_1):PAGE108
   136    GND @T6G_MB_LIB.T6G(SCH_1):GND   I138 @T6G_MB_LIB.T6G(SCH_1):PAGE108
   139    GND @T6G_MB_LIB.T6G(SCH_1):GND   I138 @T6G_MB_LIB.T6G(SCH_1):PAGE108
   141    GND @T6G_MB_LIB.T6G(SCH_1):GND   I138 @T6G_MB_LIB.T6G(SCH_1):PAGE108
    G1    GND @T6G_MB_LIB.T6G(SCH_1):GND   I138 @T6G_MB_LIB.T6G(SCH_1):PAGE108
    G2    GND @T6G_MB_LIB.T6G(SCH_1):GND   I138 @T6G_MB_LIB.T6G(SCH_1):PAGE108
    G3    GND @T6G_MB_LIB.T6G(SCH_1):GND   I138 @T6G_MB_LIB.T6G(SCH_1):PAGE108

 J38 SCONN168_ME1016810202011-SCONN168_ME1016810202011,A
   OB1 FM_OCP_SFF_PWR_GOOD @T6G_MB_LIB.T6G(SCH_1):FM_OCP_SFF_PWR_GOOD   I168 @T6G_MB_LIB.T6G(SCH_1):PAGE335
   OB2 OCP_SFF_MAIN_PWR_EN_R @T6G_MB_LIB.T6G(SCH_1):OCP_SFF_MAIN_PWR_EN_R   I168 @T6G_MB_LIB.T6G(SCH_1):PAGE335
   OB3 SGPIO_OCP_SFF_LD_N @T6G_MB_LIB.T6G(SCH_1):SGPIO_OCP_SFF_LD_N   I168 @T6G_MB_LIB.T6G(SCH_1):PAGE335
   OB4 SGPIO_OCP_SFF_DATAIN @T6G_MB_LIB.T6G(SCH_1):SGPIO_OCP_SFF_DATAIN   I168 @T6G_MB_LIB.T6G(SCH_1):PAGE335
   OB5 SGPIO_OCP_SFF_DATAOUT @T6G_MB_LIB.T6G(SCH_1):SGPIO_OCP_SFF_DATAOUT   I168 @T6G_MB_LIB.T6G(SCH_1):PAGE335
   OB6 SGPIO_OCP_SFF_CLK @T6G_MB_LIB.T6G(SCH_1):SGPIO_OCP_SFF_CLK   I168 @T6G_MB_LIB.T6G(SCH_1):PAGE335
   OB7 OCP_SFF_ID0 @T6G_MB_LIB.T6G(SCH_1):OCP_SFF_ID0   I168 @T6G_MB_LIB.T6G(SCH_1):PAGE335
   OB8 NCSI_OCP_SFF_RXD1 @T6G_MB_LIB.T6G(SCH_1):NCSI_OCP_SFF_RXD1   I168 @T6G_MB_LIB.T6G(SCH_1):PAGE335
   OB9 NCSI_OCP_SFF_RXD0 @T6G_MB_LIB.T6G(SCH_1):NCSI_OCP_SFF_RXD0   I168 @T6G_MB_LIB.T6G(SCH_1):PAGE335
  OB10    GND @T6G_MB_LIB.T6G(SCH_1):GND   I168 @T6G_MB_LIB.T6G(SCH_1):PAGE335
  OB11 CLK_100M_CPU0_CLK04_DN @T6G_MB_LIB.T6G(SCH_1):CLK_100M_CPU0_CLK04_DN   I168 @T6G_MB_LIB.T6G(SCH_1):PAGE335
  OB12 CLK_100M_CPU0_CLK04_DP @T6G_MB_LIB.T6G(SCH_1):CLK_100M_CPU0_CLK04_DP   I168 @T6G_MB_LIB.T6G(SCH_1):PAGE335
  OB13    GND @T6G_MB_LIB.T6G(SCH_1):GND   I168 @T6G_MB_LIB.T6G(SCH_1):PAGE335
  OB14 NCSI_OCP_SFF_CRS_DV @T6G_MB_LIB.T6G(SCH_1):NCSI_OCP_SFF_CRS_DV   I168 @T6G_MB_LIB.T6G(SCH_1):PAGE335
    B1 P12V_OCP_SFF_R @T6G_MB_LIB.T6G(SCH_1):P12V_OCP_SFF_R   I168 @T6G_MB_LIB.T6G(SCH_1):PAGE335
    B2 P12V_OCP_SFF_R @T6G_MB_LIB.T6G(SCH_1):P12V_OCP_SFF_R   I168 @T6G_MB_LIB.T6G(SCH_1):PAGE335
    B3 P12V_OCP_SFF_R @T6G_MB_LIB.T6G(SCH_1):P12V_OCP_SFF_R   I168 @T6G_MB_LIB.T6G(SCH_1):PAGE335
    B4 P12V_OCP_SFF_R @T6G_MB_LIB.T6G(SCH_1):P12V_OCP_SFF_R   I168 @T6G_MB_LIB.T6G(SCH_1):PAGE335
    B5 P12V_OCP_SFF_R @T6G_MB_LIB.T6G(SCH_1):P12V_OCP_SFF_R   I168 @T6G_MB_LIB.T6G(SCH_1):PAGE335
    B6 P12V_OCP_SFF_R @T6G_MB_LIB.T6G(SCH_1):P12V_OCP_SFF_R   I168 @T6G_MB_LIB.T6G(SCH_1):PAGE335
    B7 OCP_SFF_BIF0_R_N @T6G_MB_LIB.T6G(SCH_1):OCP_SFF_BIF0_R_N   I168 @T6G_MB_LIB.T6G(SCH_1):PAGE335
    B8 OCP_SFF_BIF1_R_N @T6G_MB_LIB.T6G(SCH_1):OCP_SFF_BIF1_R_N   I168 @T6G_MB_LIB.T6G(SCH_1):PAGE335
    B9 OCP_SFF_BIF2_R_N @T6G_MB_LIB.T6G(SCH_1):OCP_SFF_BIF2_R_N   I168 @T6G_MB_LIB.T6G(SCH_1):PAGE335
   B10 RST_PERST0_OCP_SFF_N @T6G_MB_LIB.T6G(SCH_1):RST_PERST0_OCP_SFF_N   I168 @T6G_MB_LIB.T6G(SCH_1):PAGE335
   B11 P3V3_OCP_SFF @T6G_MB_LIB.T6G(SCH_1):P3V3_OCP_SFF   I168 @T6G_MB_LIB.T6G(SCH_1):PAGE335
   B12 OCP_SFF_AUX_PWR_EN_R @T6G_MB_LIB.T6G(SCH_1):OCP_SFF_AUX_PWR_EN_R   I168 @T6G_MB_LIB.T6G(SCH_1):PAGE335
   B13    GND @T6G_MB_LIB.T6G(SCH_1):GND   I168 @T6G_MB_LIB.T6G(SCH_1):PAGE335
   B14 CLK_100M_CPU0_CLK02_DN @T6G_MB_LIB.T6G(SCH_1):CLK_100M_CPU0_CLK02_DN   I168 @T6G_MB_LIB.T6G(SCH_1):PAGE335
   B15 CLK_100M_CPU0_CLK02_DP @T6G_MB_LIB.T6G(SCH_1):CLK_100M_CPU0_CLK02_DP   I168 @T6G_MB_LIB.T6G(SCH_1):PAGE335
   B16    GND @T6G_MB_LIB.T6G(SCH_1):GND   I168 @T6G_MB_LIB.T6G(SCH_1):PAGE335
   B17 P5E_CPU0_G3_TX_C_DP<0> @T6G_MB_LIB.T6G(SCH_1):P5E_CPU0_G3_TX_C_DP(0)   I168 @T6G_MB_LIB.T6G(SCH_1):PAGE335
   B18 P5E_CPU0_G3_TX_C_DN<0> @T6G_MB_LIB.T6G(SCH_1):P5E_CPU0_G3_TX_C_DN(0)   I168 @T6G_MB_LIB.T6G(SCH_1):PAGE335
   B19    GND @T6G_MB_LIB.T6G(SCH_1):GND   I168 @T6G_MB_LIB.T6G(SCH_1):PAGE335
   B20 P5E_CPU0_G3_TX_C_DP<1> @T6G_MB_LIB.T6G(SCH_1):P5E_CPU0_G3_TX_C_DP(1)   I168 @T6G_MB_LIB.T6G(SCH_1):PAGE335
   B21 P5E_CPU0_G3_TX_C_DN<1> @T6G_MB_LIB.T6G(SCH_1):P5E_CPU0_G3_TX_C_DN(1)   I168 @T6G_MB_LIB.T6G(SCH_1):PAGE335
   B22    GND @T6G_MB_LIB.T6G(SCH_1):GND   I168 @T6G_MB_LIB.T6G(SCH_1):PAGE335
   B23 P5E_CPU0_G3_TX_C_DP<2> @T6G_MB_LIB.T6G(SCH_1):P5E_CPU0_G3_TX_C_DP(2)   I168 @T6G_MB_LIB.T6G(SCH_1):PAGE335
   B24 P5E_CPU0_G3_TX_C_DN<2> @T6G_MB_LIB.T6G(SCH_1):P5E_CPU0_G3_TX_C_DN(2)   I168 @T6G_MB_LIB.T6G(SCH_1):PAGE335
   B25    GND @T6G_MB_LIB.T6G(SCH_1):GND   I168 @T6G_MB_LIB.T6G(SCH_1):PAGE335
   B26 P5E_CPU0_G3_TX_C_DP<3> @T6G_MB_LIB.T6G(SCH_1):P5E_CPU0_G3_TX_C_DP(3)   I168 @T6G_MB_LIB.T6G(SCH_1):PAGE335
   B27 P5E_CPU0_G3_TX_C_DN<3> @T6G_MB_LIB.T6G(SCH_1):P5E_CPU0_G3_TX_C_DN(3)   I168 @T6G_MB_LIB.T6G(SCH_1):PAGE335
   B28    GND @T6G_MB_LIB.T6G(SCH_1):GND   I168 @T6G_MB_LIB.T6G(SCH_1):PAGE335
   B29    GND @T6G_MB_LIB.T6G(SCH_1):GND   I168 @T6G_MB_LIB.T6G(SCH_1):PAGE335
   B30 P5E_CPU0_G3_TX_C_DP<4> @T6G_MB_LIB.T6G(SCH_1):P5E_CPU0_G3_TX_C_DP(4)   I168 @T6G_MB_LIB.T6G(SCH_1):PAGE335
   B31 P5E_CPU0_G3_TX_C_DN<4> @T6G_MB_LIB.T6G(SCH_1):P5E_CPU0_G3_TX_C_DN(4)   I168 @T6G_MB_LIB.T6G(SCH_1):PAGE335
   B32    GND @T6G_MB_LIB.T6G(SCH_1):GND   I168 @T6G_MB_LIB.T6G(SCH_1):PAGE335
   B33 P5E_CPU0_G3_TX_C_DP<5> @T6G_MB_LIB.T6G(SCH_1):P5E_CPU0_G3_TX_C_DP(5)   I168 @T6G_MB_LIB.T6G(SCH_1):PAGE335
   B34 P5E_CPU0_G3_TX_C_DN<5> @T6G_MB_LIB.T6G(SCH_1):P5E_CPU0_G3_TX_C_DN(5)   I168 @T6G_MB_LIB.T6G(SCH_1):PAGE335
   B35    GND @T6G_MB_LIB.T6G(SCH_1):GND   I168 @T6G_MB_LIB.T6G(SCH_1):PAGE335
   B36 P5E_CPU0_G3_TX_C_DP<6> @T6G_MB_LIB.T6G(SCH_1):P5E_CPU0_G3_TX_C_DP(6)   I168 @T6G_MB_LIB.T6G(SCH_1):PAGE335
   B37 P5E_CPU0_G3_TX_C_DN<6> @T6G_MB_LIB.T6G(SCH_1):P5E_CPU0_G3_TX_C_DN(6)   I168 @T6G_MB_LIB.T6G(SCH_1):PAGE335
   B38    GND @T6G_MB_LIB.T6G(SCH_1):GND   I168 @T6G_MB_LIB.T6G(SCH_1):PAGE335
   B39 P5E_CPU0_G3_TX_C_DP<7> @T6G_MB_LIB.T6G(SCH_1):P5E_CPU0_G3_TX_C_DP(7)   I168 @T6G_MB_LIB.T6G(SCH_1):PAGE335
   B40 P5E_CPU0_G3_TX_C_DN<7> @T6G_MB_LIB.T6G(SCH_1):P5E_CPU0_G3_TX_C_DN(7)   I168 @T6G_MB_LIB.T6G(SCH_1):PAGE335
   B41    GND @T6G_MB_LIB.T6G(SCH_1):GND   I168 @T6G_MB_LIB.T6G(SCH_1):PAGE335
   B42 OCP_SFF_PRSNT0_R_N @T6G_MB_LIB.T6G(SCH_1):OCP_SFF_PRSNT0_R_N   I168 @T6G_MB_LIB.T6G(SCH_1):PAGE335
   B43    GND @T6G_MB_LIB.T6G(SCH_1):GND   I168 @T6G_MB_LIB.T6G(SCH_1):PAGE335
   B44 P5E_CPU0_G3_TX_C_DP<8> @T6G_MB_LIB.T6G(SCH_1):P5E_CPU0_G3_TX_C_DP(8)   I168 @T6G_MB_LIB.T6G(SCH_1):PAGE335
   B45 P5E_CPU0_G3_TX_C_DN<8> @T6G_MB_LIB.T6G(SCH_1):P5E_CPU0_G3_TX_C_DN(8)   I168 @T6G_MB_LIB.T6G(SCH_1):PAGE335
   B46    GND @T6G_MB_LIB.T6G(SCH_1):GND   I168 @T6G_MB_LIB.T6G(SCH_1):PAGE335
   B47 P5E_CPU0_G3_TX_C_DP<9> @T6G_MB_LIB.T6G(SCH_1):P5E_CPU0_G3_TX_C_DP(9)   I168 @T6G_MB_LIB.T6G(SCH_1):PAGE335
   B48 P5E_CPU0_G3_TX_C_DN<9> @T6G_MB_LIB.T6G(SCH_1):P5E_CPU0_G3_TX_C_DN(9)   I168 @T6G_MB_LIB.T6G(SCH_1):PAGE335
   B49    GND @T6G_MB_LIB.T6G(SCH_1):GND   I168 @T6G_MB_LIB.T6G(SCH_1):PAGE335
   B50 P5E_CPU0_G3_TX_C_DP<10> @T6G_MB_LIB.T6G(SCH_1):P5E_CPU0_G3_TX_C_DP(10)   I168 @T6G_MB_LIB.T6G(SCH_1):PAGE335
   B51 P5E_CPU0_G3_TX_C_DN<10> @T6G_MB_LIB.T6G(SCH_1):P5E_CPU0_G3_TX_C_DN(10)   I168 @T6G_MB_LIB.T6G(SCH_1):PAGE335
   B52    GND @T6G_MB_LIB.T6G(SCH_1):GND   I168 @T6G_MB_LIB.T6G(SCH_1):PAGE335
   B53 P5E_CPU0_G3_TX_C_DP<11> @T6G_MB_LIB.T6G(SCH_1):P5E_CPU0_G3_TX_C_DP(11)   I168 @T6G_MB_LIB.T6G(SCH_1):PAGE335
   B54 P5E_CPU0_G3_TX_C_DN<11> @T6G_MB_LIB.T6G(SCH_1):P5E_CPU0_G3_TX_C_DN(11)   I168 @T6G_MB_LIB.T6G(SCH_1):PAGE335
   B55    GND @T6G_MB_LIB.T6G(SCH_1):GND   I168 @T6G_MB_LIB.T6G(SCH_1):PAGE335
   B56 P5E_CPU0_G3_TX_C_DP<12> @T6G_MB_LIB.T6G(SCH_1):P5E_CPU0_G3_TX_C_DP(12)   I168 @T6G_MB_LIB.T6G(SCH_1):PAGE335
   OA1 RST_PERST2_OCP_SFF_N @T6G_MB_LIB.T6G(SCH_1):RST_PERST2_OCP_SFF_N   I168 @T6G_MB_LIB.T6G(SCH_1):PAGE335
   OA2 RST_PERST3_OCP_SFF_N @T6G_MB_LIB.T6G(SCH_1):RST_PERST3_OCP_SFF_N   I168 @T6G_MB_LIB.T6G(SCH_1):PAGE335
   OA3 IRQ_LVC3_OCP_SFF_WAKE_N @T6G_MB_LIB.T6G(SCH_1):IRQ_LVC3_OCP_SFF_WAKE_N   I168 @T6G_MB_LIB.T6G(SCH_1):PAGE335
   OA4 OCP_SFF_ISO1_RBT_ARB_IN @T6G_MB_LIB.T6G(SCH_1):OCP_SFF_ISO1_RBT_ARB_IN   I168 @T6G_MB_LIB.T6G(SCH_1):PAGE335
   OA5 OCP_SFF_ISO2_RBT_ARB_OUT @T6G_MB_LIB.T6G(SCH_1):OCP_SFF_ISO2_RBT_ARB_OUT   I168 @T6G_MB_LIB.T6G(SCH_1):PAGE335
   OA6 OCP_SFF_ID1 @T6G_MB_LIB.T6G(SCH_1):OCP_SFF_ID1   I168 @T6G_MB_LIB.T6G(SCH_1):PAGE335
   OA7 NCSI_OCP_SFF_TX_EN @T6G_MB_LIB.T6G(SCH_1):NCSI_OCP_SFF_TX_EN   I168 @T6G_MB_LIB.T6G(SCH_1):PAGE335
   OA8 NCSI_OCP_SFF_TXD1 @T6G_MB_LIB.T6G(SCH_1):NCSI_OCP_SFF_TXD1   I168 @T6G_MB_LIB.T6G(SCH_1):PAGE335
   OA9 NCSI_OCP_SFF_TXD0 @T6G_MB_LIB.T6G(SCH_1):NCSI_OCP_SFF_TXD0   I168 @T6G_MB_LIB.T6G(SCH_1):PAGE335
  OA10    GND @T6G_MB_LIB.T6G(SCH_1):GND   I168 @T6G_MB_LIB.T6G(SCH_1):PAGE335
  OA11 CLK_100M_CPU0_CLK05_DN @T6G_MB_LIB.T6G(SCH_1):CLK_100M_CPU0_CLK05_DN   I168 @T6G_MB_LIB.T6G(SCH_1):PAGE335
  OA12 CLK_100M_CPU0_CLK05_DP @T6G_MB_LIB.T6G(SCH_1):CLK_100M_CPU0_CLK05_DP   I168 @T6G_MB_LIB.T6G(SCH_1):PAGE335
  OA13    GND @T6G_MB_LIB.T6G(SCH_1):GND   I168 @T6G_MB_LIB.T6G(SCH_1):PAGE335
  OA14 CLK_50M_NCSI_OCP_SFF_ISO @T6G_MB_LIB.T6G(SCH_1):CLK_50M_NCSI_OCP_SFF_ISO   I168 @T6G_MB_LIB.T6G(SCH_1):PAGE335
    A1    GND @T6G_MB_LIB.T6G(SCH_1):GND   I168 @T6G_MB_LIB.T6G(SCH_1):PAGE335
    A2    GND @T6G_MB_LIB.T6G(SCH_1):GND   I168 @T6G_MB_LIB.T6G(SCH_1):PAGE335
    A3    GND @T6G_MB_LIB.T6G(SCH_1):GND   I168 @T6G_MB_LIB.T6G(SCH_1):PAGE335
    A4    GND @T6G_MB_LIB.T6G(SCH_1):GND   I168 @T6G_MB_LIB.T6G(SCH_1):PAGE335
    A5    GND @T6G_MB_LIB.T6G(SCH_1):GND   I168 @T6G_MB_LIB.T6G(SCH_1):PAGE335
    A6    GND @T6G_MB_LIB.T6G(SCH_1):GND   I168 @T6G_MB_LIB.T6G(SCH_1):PAGE335
    A7 SMB_OCP_SFF_3V3AUX_BUF_R_SCL @T6G_MB_LIB.T6G(SCH_1):SMB_OCP_SFF_3V3AUX_BUF_R_SCL   I168 @T6G_MB_LIB.T6G(SCH_1):PAGE335
    A8 SMB_OCP_SFF_3V3AUX_BUF_R_SDA @T6G_MB_LIB.T6G(SCH_1):SMB_OCP_SFF_3V3AUX_BUF_R_SDA   I168 @T6G_MB_LIB.T6G(SCH_1):PAGE335
    A9 RST_SMB_OCP_SFF_N @T6G_MB_LIB.T6G(SCH_1):RST_SMB_OCP_SFF_N   I168 @T6G_MB_LIB.T6G(SCH_1):PAGE335
   A10 OCP_SFF_PRSNTA_R_N @T6G_MB_LIB.T6G(SCH_1):OCP_SFF_PRSNTA_R_N   I168 @T6G_MB_LIB.T6G(SCH_1):PAGE335
   A11 RST_PERST1_OCP_SFF_N @T6G_MB_LIB.T6G(SCH_1):RST_PERST1_OCP_SFF_N   I168 @T6G_MB_LIB.T6G(SCH_1):PAGE335
   A12 OCP_SFF_PRSNT2_R_N @T6G_MB_LIB.T6G(SCH_1):OCP_SFF_PRSNT2_R_N   I168 @T6G_MB_LIB.T6G(SCH_1):PAGE335
   A13    GND @T6G_MB_LIB.T6G(SCH_1):GND   I168 @T6G_MB_LIB.T6G(SCH_1):PAGE335
   A14 CLK_100M_CPU0_CLK03_DN @T6G_MB_LIB.T6G(SCH_1):CLK_100M_CPU0_CLK03_DN   I168 @T6G_MB_LIB.T6G(SCH_1):PAGE335
   A15 CLK_100M_CPU0_CLK03_DP @T6G_MB_LIB.T6G(SCH_1):CLK_100M_CPU0_CLK03_DP   I168 @T6G_MB_LIB.T6G(SCH_1):PAGE335
   A16    GND @T6G_MB_LIB.T6G(SCH_1):GND   I168 @T6G_MB_LIB.T6G(SCH_1):PAGE335
   A17 P5E_CPU0_G3_RX_DN<0> @T6G_MB_LIB.T6G(SCH_1):P5E_CPU0_G3_RX_DN(0)   I168 @T6G_MB_LIB.T6G(SCH_1):PAGE335
   A18 P5E_CPU0_G3_RX_DP<0> @T6G_MB_LIB.T6G(SCH_1):P5E_CPU0_G3_RX_DP(0)   I168 @T6G_MB_LIB.T6G(SCH_1):PAGE335
   A19    GND @T6G_MB_LIB.T6G(SCH_1):GND   I168 @T6G_MB_LIB.T6G(SCH_1):PAGE335
   A20 P5E_CPU0_G3_RX_DN<1> @T6G_MB_LIB.T6G(SCH_1):P5E_CPU0_G3_RX_DN(1)   I168 @T6G_MB_LIB.T6G(SCH_1):PAGE335
   A21 P5E_CPU0_G3_RX_DP<1> @T6G_MB_LIB.T6G(SCH_1):P5E_CPU0_G3_RX_DP(1)   I168 @T6G_MB_LIB.T6G(SCH_1):PAGE335
   A22    GND @T6G_MB_LIB.T6G(SCH_1):GND   I168 @T6G_MB_LIB.T6G(SCH_1):PAGE335
   A23 P5E_CPU0_G3_RX_DN<2> @T6G_MB_LIB.T6G(SCH_1):P5E_CPU0_G3_RX_DN(2)   I168 @T6G_MB_LIB.T6G(SCH_1):PAGE335
   A24 P5E_CPU0_G3_RX_DP<2> @T6G_MB_LIB.T6G(SCH_1):P5E_CPU0_G3_RX_DP(2)   I168 @T6G_MB_LIB.T6G(SCH_1):PAGE335
   A25    GND @T6G_MB_LIB.T6G(SCH_1):GND   I168 @T6G_MB_LIB.T6G(SCH_1):PAGE335
   A26 P5E_CPU0_G3_RX_DN<3> @T6G_MB_LIB.T6G(SCH_1):P5E_CPU0_G3_RX_DN(3)   I168 @T6G_MB_LIB.T6G(SCH_1):PAGE335
   A27 P5E_CPU0_G3_RX_DP<3> @T6G_MB_LIB.T6G(SCH_1):P5E_CPU0_G3_RX_DP(3)   I168 @T6G_MB_LIB.T6G(SCH_1):PAGE335
   A28    GND @T6G_MB_LIB.T6G(SCH_1):GND   I168 @T6G_MB_LIB.T6G(SCH_1):PAGE335
   A29    GND @T6G_MB_LIB.T6G(SCH_1):GND   I168 @T6G_MB_LIB.T6G(SCH_1):PAGE335
   A30 P5E_CPU0_G3_RX_DN<4> @T6G_MB_LIB.T6G(SCH_1):P5E_CPU0_G3_RX_DN(4)   I168 @T6G_MB_LIB.T6G(SCH_1):PAGE335
   A31 P5E_CPU0_G3_RX_DP<4> @T6G_MB_LIB.T6G(SCH_1):P5E_CPU0_G3_RX_DP(4)   I168 @T6G_MB_LIB.T6G(SCH_1):PAGE335
   A32    GND @T6G_MB_LIB.T6G(SCH_1):GND   I168 @T6G_MB_LIB.T6G(SCH_1):PAGE335
   A33 P5E_CPU0_G3_RX_DN<5> @T6G_MB_LIB.T6G(SCH_1):P5E_CPU0_G3_RX_DN(5)   I168 @T6G_MB_LIB.T6G(SCH_1):PAGE335
   A34 P5E_CPU0_G3_RX_DP<5> @T6G_MB_LIB.T6G(SCH_1):P5E_CPU0_G3_RX_DP(5)   I168 @T6G_MB_LIB.T6G(SCH_1):PAGE335
   A35    GND @T6G_MB_LIB.T6G(SCH_1):GND   I168 @T6G_MB_LIB.T6G(SCH_1):PAGE335
   A36 P5E_CPU0_G3_RX_DN<6> @T6G_MB_LIB.T6G(SCH_1):P5E_CPU0_G3_RX_DN(6)   I168 @T6G_MB_LIB.T6G(SCH_1):PAGE335
   A37 P5E_CPU0_G3_RX_DP<6> @T6G_MB_LIB.T6G(SCH_1):P5E_CPU0_G3_RX_DP(6)   I168 @T6G_MB_LIB.T6G(SCH_1):PAGE335
   A38    GND @T6G_MB_LIB.T6G(SCH_1):GND   I168 @T6G_MB_LIB.T6G(SCH_1):PAGE335
   A39 P5E_CPU0_G3_RX_DN<7> @T6G_MB_LIB.T6G(SCH_1):P5E_CPU0_G3_RX_DN(7)   I168 @T6G_MB_LIB.T6G(SCH_1):PAGE335
   A40 P5E_CPU0_G3_RX_DP<7> @T6G_MB_LIB.T6G(SCH_1):P5E_CPU0_G3_RX_DP(7)   I168 @T6G_MB_LIB.T6G(SCH_1):PAGE335
   A41    GND @T6G_MB_LIB.T6G(SCH_1):GND   I168 @T6G_MB_LIB.T6G(SCH_1):PAGE335
   A42 OCP_SFF_PRSNT1_R_N @T6G_MB_LIB.T6G(SCH_1):OCP_SFF_PRSNT1_R_N   I168 @T6G_MB_LIB.T6G(SCH_1):PAGE335
   A43    GND @T6G_MB_LIB.T6G(SCH_1):GND   I168 @T6G_MB_LIB.T6G(SCH_1):PAGE335
   A44 P5E_CPU0_G3_RX_DN<8> @T6G_MB_LIB.T6G(SCH_1):P5E_CPU0_G3_RX_DN(8)   I168 @T6G_MB_LIB.T6G(SCH_1):PAGE335
   A45 P5E_CPU0_G3_RX_DP<8> @T6G_MB_LIB.T6G(SCH_1):P5E_CPU0_G3_RX_DP(8)   I168 @T6G_MB_LIB.T6G(SCH_1):PAGE335
   A46    GND @T6G_MB_LIB.T6G(SCH_1):GND   I168 @T6G_MB_LIB.T6G(SCH_1):PAGE335
   A47 P5E_CPU0_G3_RX_DN<9> @T6G_MB_LIB.T6G(SCH_1):P5E_CPU0_G3_RX_DN(9)   I168 @T6G_MB_LIB.T6G(SCH_1):PAGE335
   A48 P5E_CPU0_G3_RX_DP<9> @T6G_MB_LIB.T6G(SCH_1):P5E_CPU0_G3_RX_DP(9)   I168 @T6G_MB_LIB.T6G(SCH_1):PAGE335
   A49    GND @T6G_MB_LIB.T6G(SCH_1):GND   I168 @T6G_MB_LIB.T6G(SCH_1):PAGE335
   A50 P5E_CPU0_G3_RX_DN<10> @T6G_MB_LIB.T6G(SCH_1):P5E_CPU0_G3_RX_DN(10)   I168 @T6G_MB_LIB.T6G(SCH_1):PAGE335
   A51 P5E_CPU0_G3_RX_DP<10> @T6G_MB_LIB.T6G(SCH_1):P5E_CPU0_G3_RX_DP(10)   I168 @T6G_MB_LIB.T6G(SCH_1):PAGE335
   A52    GND @T6G_MB_LIB.T6G(SCH_1):GND   I168 @T6G_MB_LIB.T6G(SCH_1):PAGE335
   A53 P5E_CPU0_G3_RX_DN<11> @T6G_MB_LIB.T6G(SCH_1):P5E_CPU0_G3_RX_DN(11)   I168 @T6G_MB_LIB.T6G(SCH_1):PAGE335
   A54 P5E_CPU0_G3_RX_DP<11> @T6G_MB_LIB.T6G(SCH_1):P5E_CPU0_G3_RX_DP(11)   I168 @T6G_MB_LIB.T6G(SCH_1):PAGE335
   A55    GND @T6G_MB_LIB.T6G(SCH_1):GND   I168 @T6G_MB_LIB.T6G(SCH_1):PAGE335
   A56 P5E_CPU0_G3_RX_DN<12> @T6G_MB_LIB.T6G(SCH_1):P5E_CPU0_G3_RX_DN(12)   I168 @T6G_MB_LIB.T6G(SCH_1):PAGE335
   A57 P5E_CPU0_G3_RX_DP<12> @T6G_MB_LIB.T6G(SCH_1):P5E_CPU0_G3_RX_DP(12)   I168 @T6G_MB_LIB.T6G(SCH_1):PAGE335
   A58    GND @T6G_MB_LIB.T6G(SCH_1):GND   I168 @T6G_MB_LIB.T6G(SCH_1):PAGE335
   A59 P5E_CPU0_G3_RX_DN<13> @T6G_MB_LIB.T6G(SCH_1):P5E_CPU0_G3_RX_DN(13)   I168 @T6G_MB_LIB.T6G(SCH_1):PAGE335
   A60 P5E_CPU0_G3_RX_DP<13> @T6G_MB_LIB.T6G(SCH_1):P5E_CPU0_G3_RX_DP(13)   I168 @T6G_MB_LIB.T6G(SCH_1):PAGE335
   A61    GND @T6G_MB_LIB.T6G(SCH_1):GND   I168 @T6G_MB_LIB.T6G(SCH_1):PAGE335
   A62 P5E_CPU0_G3_RX_DN<14> @T6G_MB_LIB.T6G(SCH_1):P5E_CPU0_G3_RX_DN(14)   I168 @T6G_MB_LIB.T6G(SCH_1):PAGE335
   A63 P5E_CPU0_G3_RX_DP<14> @T6G_MB_LIB.T6G(SCH_1):P5E_CPU0_G3_RX_DP(14)   I168 @T6G_MB_LIB.T6G(SCH_1):PAGE335
   A64    GND @T6G_MB_LIB.T6G(SCH_1):GND   I168 @T6G_MB_LIB.T6G(SCH_1):PAGE335
   A65 P5E_CPU0_G3_RX_DN<15> @T6G_MB_LIB.T6G(SCH_1):P5E_CPU0_G3_RX_DN(15)   I168 @T6G_MB_LIB.T6G(SCH_1):PAGE335
   A66 P5E_CPU0_G3_RX_DP<15> @T6G_MB_LIB.T6G(SCH_1):P5E_CPU0_G3_RX_DP(15)   I168 @T6G_MB_LIB.T6G(SCH_1):PAGE335
   A67    GND @T6G_MB_LIB.T6G(SCH_1):GND   I168 @T6G_MB_LIB.T6G(SCH_1):PAGE335
   A68 USB2_P11_DN @T6G_MB_LIB.T6G(SCH_1):USB2_P11_DN   I168 @T6G_MB_LIB.T6G(SCH_1):PAGE335
   A69 USB2_P11_DP @T6G_MB_LIB.T6G(SCH_1):USB2_P11_DP   I168 @T6G_MB_LIB.T6G(SCH_1):PAGE335
   A70 OCP_SFF_PWRBRK_N @T6G_MB_LIB.T6G(SCH_1):OCP_SFF_PWRBRK_N   I168 @T6G_MB_LIB.T6G(SCH_1):PAGE335
   B57 P5E_CPU0_G3_TX_C_DN<12> @T6G_MB_LIB.T6G(SCH_1):P5E_CPU0_G3_TX_C_DN(12)   I168 @T6G_MB_LIB.T6G(SCH_1):PAGE335
   B58    GND @T6G_MB_LIB.T6G(SCH_1):GND   I168 @T6G_MB_LIB.T6G(SCH_1):PAGE335
   B59 P5E_CPU0_G3_TX_C_DP<13> @T6G_MB_LIB.T6G(SCH_1):P5E_CPU0_G3_TX_C_DP(13)   I168 @T6G_MB_LIB.T6G(SCH_1):PAGE335
   B60 P5E_CPU0_G3_TX_C_DN<13> @T6G_MB_LIB.T6G(SCH_1):P5E_CPU0_G3_TX_C_DN(13)   I168 @T6G_MB_LIB.T6G(SCH_1):PAGE335
   B61    GND @T6G_MB_LIB.T6G(SCH_1):GND   I168 @T6G_MB_LIB.T6G(SCH_1):PAGE335
   B62 P5E_CPU0_G3_TX_C_DP<14> @T6G_MB_LIB.T6G(SCH_1):P5E_CPU0_G3_TX_C_DP(14)   I168 @T6G_MB_LIB.T6G(SCH_1):PAGE335
   B63 P5E_CPU0_G3_TX_C_DN<14> @T6G_MB_LIB.T6G(SCH_1):P5E_CPU0_G3_TX_C_DN(14)   I168 @T6G_MB_LIB.T6G(SCH_1):PAGE335
   B64    GND @T6G_MB_LIB.T6G(SCH_1):GND   I168 @T6G_MB_LIB.T6G(SCH_1):PAGE335
   B65 P5E_CPU0_G3_TX_C_DP<15> @T6G_MB_LIB.T6G(SCH_1):P5E_CPU0_G3_TX_C_DP(15)   I168 @T6G_MB_LIB.T6G(SCH_1):PAGE335
   B66 P5E_CPU0_G3_TX_C_DN<15> @T6G_MB_LIB.T6G(SCH_1):P5E_CPU0_G3_TX_C_DN(15)   I168 @T6G_MB_LIB.T6G(SCH_1):PAGE335
   B67    GND @T6G_MB_LIB.T6G(SCH_1):GND   I168 @T6G_MB_LIB.T6G(SCH_1):PAGE335
   B68 TP_OCP_SFF_B68 @T6G_MB_LIB.T6G(SCH_1):TP_OCP_SFF_B68   I168 @T6G_MB_LIB.T6G(SCH_1):PAGE335
   B69 TP_OCP_SFF_B69 @T6G_MB_LIB.T6G(SCH_1):TP_OCP_SFF_B69   I168 @T6G_MB_LIB.T6G(SCH_1):PAGE335
   B70 OCP_SFF_PRSNT3_R_N @T6G_MB_LIB.T6G(SCH_1):OCP_SFF_PRSNT3_R_N   I168 @T6G_MB_LIB.T6G(SCH_1):PAGE335
    G1    GND @T6G_MB_LIB.T6G(SCH_1):GND   I168 @T6G_MB_LIB.T6G(SCH_1):PAGE335
    G2    GND @T6G_MB_LIB.T6G(SCH_1):GND   I168 @T6G_MB_LIB.T6G(SCH_1):PAGE335
    G3    GND @T6G_MB_LIB.T6G(SCH_1):GND   I168 @T6G_MB_LIB.T6G(SCH_1):PAGE335
    G4    GND @T6G_MB_LIB.T6G(SCH_1):GND   I168 @T6G_MB_LIB.T6G(SCH_1):PAGE335
    G5    GND @T6G_MB_LIB.T6G(SCH_1):GND   I168 @T6G_MB_LIB.T6G(SCH_1):PAGE335

 J41 SCONN168_ME1016810202011-SCONN168_ME1016810202011,A
   OB1 P12V_SCM @T6G_MB_LIB.T6G(SCH_1):P12V_SCM   I176 @T6G_MB_LIB.T6G(SCH_1):PAGE348
   OB2 P12V_SCM @T6G_MB_LIB.T6G(SCH_1):P12V_SCM   I176 @T6G_MB_LIB.T6G(SCH_1):PAGE348
   OB3 PRSNT0_N @T6G_MB_LIB.T6G(SCH_1):PRSNT0_N   I176 @T6G_MB_LIB.T6G(SCH_1):PAGE348
   OB4    GND @T6G_MB_LIB.T6G(SCH_1):GND   I176 @T6G_MB_LIB.T6G(SCH_1):PAGE348
   OB5 UART_BMC_BIC_TX @T6G_MB_LIB.T6G(SCH_1):UART_BMC_BIC_TX   I176 @T6G_MB_LIB.T6G(SCH_1):PAGE348
   OB6 UART_BMC_BIC_BUF_RX @T6G_MB_LIB.T6G(SCH_1):UART_BMC_BIC_BUF_RX   I176 @T6G_MB_LIB.T6G(SCH_1):PAGE348
   OB7    GND @T6G_MB_LIB.T6G(SCH_1):GND   I176 @T6G_MB_LIB.T6G(SCH_1):PAGE348
   OB8 UART_CPU0_SCM_LVC3_UART1_RX @T6G_MB_LIB.T6G(SCH_1):UART_CPU0_SCM_LVC3_UART1_RX   I176 @T6G_MB_LIB.T6G(SCH_1):PAGE348
   OB9 UART_CPU0_SCM_LVC3_UART1_R1_TX @T6G_MB_LIB.T6G(SCH_1):UART_CPU0_SCM_LVC3_UART1_R1_TX   I176 @T6G_MB_LIB.T6G(SCH_1):PAGE348
  OB10    GND @T6G_MB_LIB.T6G(SCH_1):GND   I176 @T6G_MB_LIB.T6G(SCH_1):PAGE348
  OB11 RST_SRST_PLD_BMC_N @T6G_MB_LIB.T6G(SCH_1):RST_SRST_PLD_BMC_N   I176 @T6G_MB_LIB.T6G(SCH_1):PAGE348
  OB12 SPI_CPU0_LVC3_TPM_CS_N @T6G_MB_LIB.T6G(SCH_1):SPI_CPU0_LVC3_TPM_CS_N   I176 @T6G_MB_LIB.T6G(SCH_1):PAGE348
  OB13 FPGA_IO3V3_RSVD_1 @T6G_MB_LIB.T6G(SCH_1):FPGA_IO3V3_RSVD_1   I176 @T6G_MB_LIB.T6G(SCH_1):PAGE348
  OB14 FM_SOL_UART_CH_SEL_R @T6G_MB_LIB.T6G(SCH_1):FM_SOL_UART_CH_SEL_R   I176 @T6G_MB_LIB.T6G(SCH_1):PAGE348
    B1 CLK_ESPI_CPU0_CLK1 @T6G_MB_LIB.T6G(SCH_1):CLK_ESPI_CPU0_CLK1   I176 @T6G_MB_LIB.T6G(SCH_1):PAGE348
    B2 ESPI_CPU0_CS1_N @T6G_MB_LIB.T6G(SCH_1):ESPI_CPU0_CS1_N   I176 @T6G_MB_LIB.T6G(SCH_1):PAGE348
    B3 ESPI_CPU0_ALERT_N @T6G_MB_LIB.T6G(SCH_1):ESPI_CPU0_ALERT_N   I176 @T6G_MB_LIB.T6G(SCH_1):PAGE348
    B4 RST_ESPI_CPU0_RSTOUT_N @T6G_MB_LIB.T6G(SCH_1):RST_ESPI_CPU0_RSTOUT_N   I176 @T6G_MB_LIB.T6G(SCH_1):PAGE348
    B5 ESPI_CPU0_D0 @T6G_MB_LIB.T6G(SCH_1):ESPI_CPU0_D0   I176 @T6G_MB_LIB.T6G(SCH_1):PAGE348
    B6 ESPI_CPU0_D1 @T6G_MB_LIB.T6G(SCH_1):ESPI_CPU0_D1   I176 @T6G_MB_LIB.T6G(SCH_1):PAGE348
    B7 ESPI_CPU0_D2 @T6G_MB_LIB.T6G(SCH_1):ESPI_CPU0_D2   I176 @T6G_MB_LIB.T6G(SCH_1):PAGE348
    B8 ESPI_CPU0_D3 @T6G_MB_LIB.T6G(SCH_1):ESPI_CPU0_D3   I176 @T6G_MB_LIB.T6G(SCH_1):PAGE348
    B9 FM_LPC_ESPI_SEL @T6G_MB_LIB.T6G(SCH_1):FM_LPC_ESPI_SEL   I176 @T6G_MB_LIB.T6G(SCH_1):PAGE348
   B10    GND @T6G_MB_LIB.T6G(SCH_1):GND   I176 @T6G_MB_LIB.T6G(SCH_1):PAGE348
   B11 SPI_CPU0_LVC3_SCM_CLK @T6G_MB_LIB.T6G(SCH_1):SPI_CPU0_LVC3_SCM_CLK   I176 @T6G_MB_LIB.T6G(SCH_1):PAGE348
   B12 SPI_CPU0_LVC3_SCM_CS0_N @T6G_MB_LIB.T6G(SCH_1):SPI_CPU0_LVC3_SCM_CS0_N   I176 @T6G_MB_LIB.T6G(SCH_1):PAGE348
   B13 SPI_CPU0_LVC3_SCM_D0 @T6G_MB_LIB.T6G(SCH_1):SPI_CPU0_LVC3_SCM_D0   I176 @T6G_MB_LIB.T6G(SCH_1):PAGE348
   B14 SPI_CPU0_LVC3_SCM_D1 @T6G_MB_LIB.T6G(SCH_1):SPI_CPU0_LVC3_SCM_D1   I176 @T6G_MB_LIB.T6G(SCH_1):PAGE348
   B15 SPI_CPU0_LVC3_SCM_D2 @T6G_MB_LIB.T6G(SCH_1):SPI_CPU0_LVC3_SCM_D2   I176 @T6G_MB_LIB.T6G(SCH_1):PAGE348
   B16 SPI_CPU0_LVC3_SCM_D3 @T6G_MB_LIB.T6G(SCH_1):SPI_CPU0_LVC3_SCM_D3   I176 @T6G_MB_LIB.T6G(SCH_1):PAGE348
   B17    GND @T6G_MB_LIB.T6G(SCH_1):GND   I176 @T6G_MB_LIB.T6G(SCH_1):PAGE348
   B18 CLK_50M_RMII_BMC_OCP @T6G_MB_LIB.T6G(SCH_1):CLK_50M_RMII_BMC_OCP   I176 @T6G_MB_LIB.T6G(SCH_1):PAGE348
   B19 RMII_OCP_BMC_CRSDV @T6G_MB_LIB.T6G(SCH_1):RMII_OCP_BMC_CRSDV   I176 @T6G_MB_LIB.T6G(SCH_1):PAGE348
   B20 RMII_BMC_OCP_TX_EN @T6G_MB_LIB.T6G(SCH_1):RMII_BMC_OCP_TX_EN   I176 @T6G_MB_LIB.T6G(SCH_1):PAGE348
   B21 RMII_BMC_OCP_TXD_0 @T6G_MB_LIB.T6G(SCH_1):RMII_BMC_OCP_TXD_0   I176 @T6G_MB_LIB.T6G(SCH_1):PAGE348
   B22 RMII_BMC_OCP_TXD_1 @T6G_MB_LIB.T6G(SCH_1):RMII_BMC_OCP_TXD_1   I176 @T6G_MB_LIB.T6G(SCH_1):PAGE348
   B23 RMII_BMC_OCP_RX_ER @T6G_MB_LIB.T6G(SCH_1):RMII_BMC_OCP_RX_ER   I176 @T6G_MB_LIB.T6G(SCH_1):PAGE348
   B24 RMII_OCP_BMC_RXD_0 @T6G_MB_LIB.T6G(SCH_1):RMII_OCP_BMC_RXD_0   I176 @T6G_MB_LIB.T6G(SCH_1):PAGE348
   B25 RMII_OCP_BMC_RXD_1 @T6G_MB_LIB.T6G(SCH_1):RMII_OCP_BMC_RXD_1   I176 @T6G_MB_LIB.T6G(SCH_1):PAGE348
   B26    GND @T6G_MB_LIB.T6G(SCH_1):GND   I176 @T6G_MB_LIB.T6G(SCH_1):PAGE348
   B27 TP_PECI_BMC @T6G_MB_LIB.T6G(SCH_1):TP_PECI_BMC   I176 @T6G_MB_LIB.T6G(SCH_1):PAGE348
   B28 TP_PVCCIO_PECI_BMC @T6G_MB_LIB.T6G(SCH_1):TP_PVCCIO_PECI_BMC   I176 @T6G_MB_LIB.T6G(SCH_1):PAGE348
   B29 SGPIO_SCM_DO_R_<0> @T6G_MB_LIB.T6G(SCH_1):SGPIO_SCM_DO_R_(0)   I176 @T6G_MB_LIB.T6G(SCH_1):PAGE348
   B30 SGPIO_SCM_CLK_R_<0> @T6G_MB_LIB.T6G(SCH_1):SGPIO_SCM_CLK_R_(0)   I176 @T6G_MB_LIB.T6G(SCH_1):PAGE348
   B31 SGPIO_SCM_DI_R_<0> @T6G_MB_LIB.T6G(SCH_1):SGPIO_SCM_DI_R_(0)   I176 @T6G_MB_LIB.T6G(SCH_1):PAGE348
   B32 SGPIO_SCM_LD_R_<0> @T6G_MB_LIB.T6G(SCH_1):SGPIO_SCM_LD_R_(0)   I176 @T6G_MB_LIB.T6G(SCH_1):PAGE348
   B33    GND @T6G_MB_LIB.T6G(SCH_1):GND   I176 @T6G_MB_LIB.T6G(SCH_1):PAGE348
   B34 SGPIO_SCM_DO_R_<1> @T6G_MB_LIB.T6G(SCH_1):SGPIO_SCM_DO_R_(1)   I176 @T6G_MB_LIB.T6G(SCH_1):PAGE348
   B35 SGPIO_SCM_CLK_R_<1> @T6G_MB_LIB.T6G(SCH_1):SGPIO_SCM_CLK_R_(1)   I176 @T6G_MB_LIB.T6G(SCH_1):PAGE348
   B36 SGPIO_SCM_DI_R_<1> @T6G_MB_LIB.T6G(SCH_1):SGPIO_SCM_DI_R_(1)   I176 @T6G_MB_LIB.T6G(SCH_1):PAGE348
   B37 SGPIO_SCM_LD_R_<1> @T6G_MB_LIB.T6G(SCH_1):SGPIO_SCM_LD_R_(1)   I176 @T6G_MB_LIB.T6G(SCH_1):PAGE348
   B38    GND @T6G_MB_LIB.T6G(SCH_1):GND   I176 @T6G_MB_LIB.T6G(SCH_1):PAGE348
   B39 SGPIO_SCM_RESET_R_N @T6G_MB_LIB.T6G(SCH_1):SGPIO_SCM_RESET_R_N   I176 @T6G_MB_LIB.T6G(SCH_1):PAGE348
   B40 SGPIO_SCM_INTR_R1_N @T6G_MB_LIB.T6G(SCH_1):SGPIO_SCM_INTR_R1_N   I176 @T6G_MB_LIB.T6G(SCH_1):PAGE348
   B41 SCM_VDD_RTC @T6G_MB_LIB.T6G(SCH_1):SCM_VDD_RTC   I176 @T6G_MB_LIB.T6G(SCH_1):PAGE348
   B42 FM_AC_PWR_BTN_N @T6G_MB_LIB.T6G(SCH_1):FM_AC_PWR_BTN_N   I176 @T6G_MB_LIB.T6G(SCH_1):PAGE348
   B43 TP_SPI_2_PLD_CLK @T6G_MB_LIB.T6G(SCH_1):TP_SPI_2_PLD_CLK   I176 @T6G_MB_LIB.T6G(SCH_1):PAGE348
   B44 TP_SPI_2_PLD_CS_N @T6G_MB_LIB.T6G(SCH_1):TP_SPI_2_PLD_CS_N   I176 @T6G_MB_LIB.T6G(SCH_1):PAGE348
   B45 TP_SPI_2_PLD_IO0 @T6G_MB_LIB.T6G(SCH_1):TP_SPI_2_PLD_IO0   I176 @T6G_MB_LIB.T6G(SCH_1):PAGE348
   B46 TP_SPI_2_PLD_IO1 @T6G_MB_LIB.T6G(SCH_1):TP_SPI_2_PLD_IO1   I176 @T6G_MB_LIB.T6G(SCH_1):PAGE348
   B47 TP_SPI_2_PLD_IO2 @T6G_MB_LIB.T6G(SCH_1):TP_SPI_2_PLD_IO2   I176 @T6G_MB_LIB.T6G(SCH_1):PAGE348
   B48 TP_SPI_2_PLD_IO3 @T6G_MB_LIB.T6G(SCH_1):TP_SPI_2_PLD_IO3   I176 @T6G_MB_LIB.T6G(SCH_1):PAGE348
   B49    GND @T6G_MB_LIB.T6G(SCH_1):GND   I176 @T6G_MB_LIB.T6G(SCH_1):PAGE348
   B50 USB2_HOST_BMC_B_DP @T6G_MB_LIB.T6G(SCH_1):USB2_HOST_BMC_B_DP   I176 @T6G_MB_LIB.T6G(SCH_1):PAGE348
   B51 USB2_HOST_BMC_B_DN @T6G_MB_LIB.T6G(SCH_1):USB2_HOST_BMC_B_DN   I176 @T6G_MB_LIB.T6G(SCH_1):PAGE348
   B52    GND @T6G_MB_LIB.T6G(SCH_1):GND   I176 @T6G_MB_LIB.T6G(SCH_1):PAGE348
   B53 USB2_CPU0_P1_DP @T6G_MB_LIB.T6G(SCH_1):USB2_CPU0_P1_DP   I176 @T6G_MB_LIB.T6G(SCH_1):PAGE348
   B54 USB2_CPU0_P1_DN @T6G_MB_LIB.T6G(SCH_1):USB2_CPU0_P1_DN   I176 @T6G_MB_LIB.T6G(SCH_1):PAGE348
   B55    GND @T6G_MB_LIB.T6G(SCH_1):GND   I176 @T6G_MB_LIB.T6G(SCH_1):PAGE348
   B56 USB2_HUB_EXT_DP @T6G_MB_LIB.T6G(SCH_1):USB2_HUB_EXT_DP   I176 @T6G_MB_LIB.T6G(SCH_1):PAGE348
   OA1 P12V_SCM @T6G_MB_LIB.T6G(SCH_1):P12V_SCM   I176 @T6G_MB_LIB.T6G(SCH_1):PAGE348
   OA2 P12V_SCM @T6G_MB_LIB.T6G(SCH_1):P12V_SCM   I176 @T6G_MB_LIB.T6G(SCH_1):PAGE348
   OA3    GND @T6G_MB_LIB.T6G(SCH_1):GND   I176 @T6G_MB_LIB.T6G(SCH_1):PAGE348
   OA4    GND @T6G_MB_LIB.T6G(SCH_1):GND   I176 @T6G_MB_LIB.T6G(SCH_1):PAGE348
   OA5 I3C_SCM_0_SCL @T6G_MB_LIB.T6G(SCH_1):I3C_SCM_0_SCL   I176 @T6G_MB_LIB.T6G(SCH_1):PAGE348
   OA6 I3C_SCM_0_SDA @T6G_MB_LIB.T6G(SCH_1):I3C_SCM_0_SDA   I176 @T6G_MB_LIB.T6G(SCH_1):PAGE348
   OA7 I3C_SCM_1_SCL @T6G_MB_LIB.T6G(SCH_1):I3C_SCM_1_SCL   I176 @T6G_MB_LIB.T6G(SCH_1):PAGE348
   OA8 I3C_SCM_1_SDA @T6G_MB_LIB.T6G(SCH_1):I3C_SCM_1_SDA   I176 @T6G_MB_LIB.T6G(SCH_1):PAGE348
   OA9 I3C_SCM_2_SCL @T6G_MB_LIB.T6G(SCH_1):I3C_SCM_2_SCL   I176 @T6G_MB_LIB.T6G(SCH_1):PAGE348
  OA10 I3C_SCM_2_SDA @T6G_MB_LIB.T6G(SCH_1):I3C_SCM_2_SDA   I176 @T6G_MB_LIB.T6G(SCH_1):PAGE348
  OA11 I3C_SCM_3_SCL @T6G_MB_LIB.T6G(SCH_1):I3C_SCM_3_SCL   I176 @T6G_MB_LIB.T6G(SCH_1):PAGE348
  OA12 I3C_SCM_3_SDA @T6G_MB_LIB.T6G(SCH_1):I3C_SCM_3_SDA   I176 @T6G_MB_LIB.T6G(SCH_1):PAGE348
  OA13    GND @T6G_MB_LIB.T6G(SCH_1):GND   I176 @T6G_MB_LIB.T6G(SCH_1):PAGE348
  OA14 VIRTUAL_RESEAT @T6G_MB_LIB.T6G(SCH_1):VIRTUAL_RESEAT   I176 @T6G_MB_LIB.T6G(SCH_1):PAGE348
    A1 SMB_OCP_SFF_3V3AUX_SCL_R0 @T6G_MB_LIB.T6G(SCH_1):SMB_OCP_SFF_3V3AUX_SCL_R0   I176 @T6G_MB_LIB.T6G(SCH_1):PAGE348
    A2 SMB_OCP_SFF_3V3AUX_SDA_R0 @T6G_MB_LIB.T6G(SCH_1):SMB_OCP_SFF_3V3AUX_SDA_R0   I176 @T6G_MB_LIB.T6G(SCH_1):PAGE348
    A3 SMB_CPU0_CPU1_APML_SCL_R @T6G_MB_LIB.T6G(SCH_1):SMB_CPU0_CPU1_APML_SCL_R   I176 @T6G_MB_LIB.T6G(SCH_1):PAGE348
    A4 SMB_CPU0_CPU1_APML_SDA_R @T6G_MB_LIB.T6G(SCH_1):SMB_CPU0_CPU1_APML_SDA_R   I176 @T6G_MB_LIB.T6G(SCH_1):PAGE348
    A5 SMB_VR_3V3AUX_SCL_R0 @T6G_MB_LIB.T6G(SCH_1):SMB_VR_3V3AUX_SCL_R0   I176 @T6G_MB_LIB.T6G(SCH_1):PAGE348
    A6 SMB_VR_3V3AUX_SDA_R0 @T6G_MB_LIB.T6G(SCH_1):SMB_VR_3V3AUX_SDA_R0   I176 @T6G_MB_LIB.T6G(SCH_1):PAGE348
    A7 SMB_CPU0_CPU1_SEC_SCL_R @T6G_MB_LIB.T6G(SCH_1):SMB_CPU0_CPU1_SEC_SCL_R   I176 @T6G_MB_LIB.T6G(SCH_1):PAGE348
    A8 SMB_CPU0_CPU1_SEC_SDA_R @T6G_MB_LIB.T6G(SCH_1):SMB_CPU0_CPU1_SEC_SDA_R   I176 @T6G_MB_LIB.T6G(SCH_1):PAGE348
    A9 I3C_BMC_SWB_SCL @T6G_MB_LIB.T6G(SCH_1):I3C_BMC_SWB_SCL   I176 @T6G_MB_LIB.T6G(SCH_1):PAGE348
   A10 I3C_BMC_SWB_SDA @T6G_MB_LIB.T6G(SCH_1):I3C_BMC_SWB_SDA   I176 @T6G_MB_LIB.T6G(SCH_1):PAGE348
   A11 SMB_OCP_V3_2_3V3AUX_SCL_R0 @T6G_MB_LIB.T6G(SCH_1):SMB_OCP_V3_2_3V3AUX_SCL_R0   I176 @T6G_MB_LIB.T6G(SCH_1):PAGE348
   A12 SMB_OCP_V3_2_3V3AUX_SDA_R0 @T6G_MB_LIB.T6G(SCH_1):SMB_OCP_V3_2_3V3AUX_SDA_R0   I176 @T6G_MB_LIB.T6G(SCH_1):PAGE348
   A13    GND @T6G_MB_LIB.T6G(SCH_1):GND   I176 @T6G_MB_LIB.T6G(SCH_1):PAGE348
   A14 CLK_100M_CPU0_CLK01_DP @T6G_MB_LIB.T6G(SCH_1):CLK_100M_CPU0_CLK01_DP   I176 @T6G_MB_LIB.T6G(SCH_1):PAGE348
   A15 CLK_100M_CPU0_CLK01_DN @T6G_MB_LIB.T6G(SCH_1):CLK_100M_CPU0_CLK01_DN   I176 @T6G_MB_LIB.T6G(SCH_1):PAGE348
   A16    GND @T6G_MB_LIB.T6G(SCH_1):GND   I176 @T6G_MB_LIB.T6G(SCH_1):PAGE348
   A17 P2E_CPU0_P5_TX_C_DP @T6G_MB_LIB.T6G(SCH_1):P2E_CPU0_P5_TX_C_DP   I176 @T6G_MB_LIB.T6G(SCH_1):PAGE348
   A18 P2E_CPU0_P5_TX_C_DN @T6G_MB_LIB.T6G(SCH_1):P2E_CPU0_P5_TX_C_DN   I176 @T6G_MB_LIB.T6G(SCH_1):PAGE348
   A19    GND @T6G_MB_LIB.T6G(SCH_1):GND   I176 @T6G_MB_LIB.T6G(SCH_1):PAGE348
   A20 P2E_CPU0_P5_RX_DP @T6G_MB_LIB.T6G(SCH_1):P2E_CPU0_P5_RX_DP   I176 @T6G_MB_LIB.T6G(SCH_1):PAGE348
   A21 P2E_CPU0_P5_RX_DN @T6G_MB_LIB.T6G(SCH_1):P2E_CPU0_P5_RX_DN   I176 @T6G_MB_LIB.T6G(SCH_1):PAGE348
   A22    GND @T6G_MB_LIB.T6G(SCH_1):GND   I176 @T6G_MB_LIB.T6G(SCH_1):PAGE348
   A23 SMB_PCIE0_3V3AUX_SCL @T6G_MB_LIB.T6G(SCH_1):SMB_PCIE0_3V3AUX_SCL   I176 @T6G_MB_LIB.T6G(SCH_1):PAGE348
   A24 SMB_PCIE0_3V3AUX_SDA @T6G_MB_LIB.T6G(SCH_1):SMB_PCIE0_3V3AUX_SDA   I176 @T6G_MB_LIB.T6G(SCH_1):PAGE348
   A25 SMB_PMBUS_3V3AUX_SCL_R0 @T6G_MB_LIB.T6G(SCH_1):SMB_PMBUS_3V3AUX_SCL_R0   I176 @T6G_MB_LIB.T6G(SCH_1):PAGE348
   A26 SMB_PMBUS_3V3AUX_SDA_R0 @T6G_MB_LIB.T6G(SCH_1):SMB_PMBUS_3V3AUX_SDA_R0   I176 @T6G_MB_LIB.T6G(SCH_1):PAGE348
   A27 SMB_1_PLD_3V3AUX_SCL_R3 @T6G_MB_LIB.T6G(SCH_1):SMB_1_PLD_3V3AUX_SCL_R3   I176 @T6G_MB_LIB.T6G(SCH_1):PAGE348
   A28 SMB_1_PLD_3V3AUX_SDA_R3 @T6G_MB_LIB.T6G(SCH_1):SMB_1_PLD_3V3AUX_SDA_R3   I176 @T6G_MB_LIB.T6G(SCH_1):PAGE348
   A29 SMB_FAN_3V3AUX_SCL @T6G_MB_LIB.T6G(SCH_1):SMB_FAN_3V3AUX_SCL   I176 @T6G_MB_LIB.T6G(SCH_1):PAGE348
   A30 SMB_FAN_3V3AUX_SDA @T6G_MB_LIB.T6G(SCH_1):SMB_FAN_3V3AUX_SDA   I176 @T6G_MB_LIB.T6G(SCH_1):PAGE348
   A31 SMB_PCIE2_3V3AUX_SCL_R0 @T6G_MB_LIB.T6G(SCH_1):SMB_PCIE2_3V3AUX_SCL_R0   I176 @T6G_MB_LIB.T6G(SCH_1):PAGE348
   A32 SMB_PCIE2_3V3AUX_SDA_R0 @T6G_MB_LIB.T6G(SCH_1):SMB_PCIE2_3V3AUX_SDA_R0   I176 @T6G_MB_LIB.T6G(SCH_1):PAGE348
   A33    GND @T6G_MB_LIB.T6G(SCH_1):GND   I176 @T6G_MB_LIB.T6G(SCH_1):PAGE348
   A34 JTAG_SCM_TCK @T6G_MB_LIB.T6G(SCH_1):JTAG_SCM_TCK   I176 @T6G_MB_LIB.T6G(SCH_1):PAGE348
   A35 JTAG_SCM_TMS @T6G_MB_LIB.T6G(SCH_1):JTAG_SCM_TMS   I176 @T6G_MB_LIB.T6G(SCH_1):PAGE348
   A36 JTAG_SCM_TDI_R @T6G_MB_LIB.T6G(SCH_1):JTAG_SCM_TDI_R   I176 @T6G_MB_LIB.T6G(SCH_1):PAGE348
   A37 JTAG_SCM_TDO_R @T6G_MB_LIB.T6G(SCH_1):JTAG_SCM_TDO_R   I176 @T6G_MB_LIB.T6G(SCH_1):PAGE348
   A38 SMB_PCIE3_3V3AUX_SCL_R @T6G_MB_LIB.T6G(SCH_1):SMB_PCIE3_3V3AUX_SCL_R   I176 @T6G_MB_LIB.T6G(SCH_1):PAGE348
   A39 SMB_PCIE3_3V3AUX_SDA_R @T6G_MB_LIB.T6G(SCH_1):SMB_PCIE3_3V3AUX_SDA_R   I176 @T6G_MB_LIB.T6G(SCH_1):PAGE348
   A40 SMB_HOST_CLK_3V3AUX_SCL_R0 @T6G_MB_LIB.T6G(SCH_1):SMB_HOST_CLK_3V3AUX_SCL_R0   I176 @T6G_MB_LIB.T6G(SCH_1):PAGE348
   A41 SMB_HOST_CLK_3V3AUX_SDA_R0 @T6G_MB_LIB.T6G(SCH_1):SMB_HOST_CLK_3V3AUX_SDA_R0   I176 @T6G_MB_LIB.T6G(SCH_1):PAGE348
   A42    GND @T6G_MB_LIB.T6G(SCH_1):GND   I176 @T6G_MB_LIB.T6G(SCH_1):PAGE348
   A43 FW_RECOVERY @T6G_MB_LIB.T6G(SCH_1):FW_RECOVERY   I176 @T6G_MB_LIB.T6G(SCH_1):PAGE348
   A44 PWRGD_PS_PWROK_R @T6G_MB_LIB.T6G(SCH_1):PWRGD_PS_PWROK_R   I176 @T6G_MB_LIB.T6G(SCH_1):PAGE348
   A45 TP_STBY_EN @T6G_MB_LIB.T6G(SCH_1):TP_STBY_EN   I176 @T6G_MB_LIB.T6G(SCH_1):PAGE348
   A46 RST_MB_STBY_R_N @T6G_MB_LIB.T6G(SCH_1):RST_MB_STBY_R_N   I176 @T6G_MB_LIB.T6G(SCH_1):PAGE348
   A47 SCM_SYS_PWRBTN_R_N @T6G_MB_LIB.T6G(SCH_1):SCM_SYS_PWRBTN_R_N   I176 @T6G_MB_LIB.T6G(SCH_1):PAGE348
   A48 SCM_SYS_PWROK_R1 @T6G_MB_LIB.T6G(SCH_1):SCM_SYS_PWROK_R1   I176 @T6G_MB_LIB.T6G(SCH_1):PAGE348
   A49 SCM_HDT_DBREQ_N @T6G_MB_LIB.T6G(SCH_1):SCM_HDT_DBREQ_N   I176 @T6G_MB_LIB.T6G(SCH_1):PAGE348
   A50 PU_JTAG_DBP_BMC_PRDY_N @T6G_MB_LIB.T6G(SCH_1):PU_JTAG_DBP_BMC_PRDY_N   I176 @T6G_MB_LIB.T6G(SCH_1):PAGE348
   A51 FM_RST_PERST_SCM_N @T6G_MB_LIB.T6G(SCH_1):FM_RST_PERST_SCM_N   I176 @T6G_MB_LIB.T6G(SCH_1):PAGE348
   A52 FM_UARTSW_MSB_R @T6G_MB_LIB.T6G(SCH_1):FM_UARTSW_MSB_R   I176 @T6G_MB_LIB.T6G(SCH_1):PAGE348
   A53 SCM_ROT_CPU_RST_N @T6G_MB_LIB.T6G(SCH_1):SCM_ROT_CPU_RST_N   I176 @T6G_MB_LIB.T6G(SCH_1):PAGE348
   A54 TP_CHASI @T6G_MB_LIB.T6G(SCH_1):TP_CHASI   I176 @T6G_MB_LIB.T6G(SCH_1):PAGE348
   A55 FM_UARTSW_LSB_R @T6G_MB_LIB.T6G(SCH_1):FM_UARTSW_LSB_R   I176 @T6G_MB_LIB.T6G(SCH_1):PAGE348
   A56 IRQ0_A56 @T6G_MB_LIB.T6G(SCH_1):IRQ0_A56   I176 @T6G_MB_LIB.T6G(SCH_1):PAGE348
   A57 FM_SCM_PRSNT1_N @T6G_MB_LIB.T6G(SCH_1):FM_SCM_PRSNT1_N   I176 @T6G_MB_LIB.T6G(SCH_1):PAGE348
   A58    GND @T6G_MB_LIB.T6G(SCH_1):GND   I176 @T6G_MB_LIB.T6G(SCH_1):PAGE348
   A59 USB3_CPU0_BMC_RX_DP @T6G_MB_LIB.T6G(SCH_1):USB3_CPU0_BMC_RX_DP   I176 @T6G_MB_LIB.T6G(SCH_1):PAGE348
   A60 USB3_CPU0_BMC_RX_DN @T6G_MB_LIB.T6G(SCH_1):USB3_CPU0_BMC_RX_DN   I176 @T6G_MB_LIB.T6G(SCH_1):PAGE348
   A61    GND @T6G_MB_LIB.T6G(SCH_1):GND   I176 @T6G_MB_LIB.T6G(SCH_1):PAGE348
   A62 TP_PCIE_RXP<1> @T6G_MB_LIB.T6G(SCH_1):TP_PCIE_RXP(1)   I176 @T6G_MB_LIB.T6G(SCH_1):PAGE348
   A63 TP_PCIE_RXN<1> @T6G_MB_LIB.T6G(SCH_1):TP_PCIE_RXN(1)   I176 @T6G_MB_LIB.T6G(SCH_1):PAGE348
   A64    GND @T6G_MB_LIB.T6G(SCH_1):GND   I176 @T6G_MB_LIB.T6G(SCH_1):PAGE348
   A65 P2E_MB_BMC_RX_BUF_DP<0> @T6G_MB_LIB.T6G(SCH_1):P2E_MB_BMC_RX_BUF_DP(0)   I176 @T6G_MB_LIB.T6G(SCH_1):PAGE348
   A66 P2E_MB_BMC_RX_BUF_DN<0> @T6G_MB_LIB.T6G(SCH_1):P2E_MB_BMC_RX_BUF_DN(0)   I176 @T6G_MB_LIB.T6G(SCH_1):PAGE348
   A67    GND @T6G_MB_LIB.T6G(SCH_1):GND   I176 @T6G_MB_LIB.T6G(SCH_1):PAGE348
   A68 CLK_100M_BMC_RC_DP @T6G_MB_LIB.T6G(SCH_1):CLK_100M_BMC_RC_DP   I176 @T6G_MB_LIB.T6G(SCH_1):PAGE348
   A69 CLK_100M_BMC_RC_DN @T6G_MB_LIB.T6G(SCH_1):CLK_100M_BMC_RC_DN   I176 @T6G_MB_LIB.T6G(SCH_1):PAGE348
   A70    GND @T6G_MB_LIB.T6G(SCH_1):GND   I176 @T6G_MB_LIB.T6G(SCH_1):PAGE348
   B57 USB2_HUB_EXT_DN @T6G_MB_LIB.T6G(SCH_1):USB2_HUB_EXT_DN   I176 @T6G_MB_LIB.T6G(SCH_1):PAGE348
   B58    GND @T6G_MB_LIB.T6G(SCH_1):GND   I176 @T6G_MB_LIB.T6G(SCH_1):PAGE348
   B59 USB3_CPU0_BMC_TX_BUF_C_DP @T6G_MB_LIB.T6G(SCH_1):USB3_CPU0_BMC_TX_BUF_C_DP   I176 @T6G_MB_LIB.T6G(SCH_1):PAGE348
   B60 USB3_CPU0_BMC_TX_BUF_C_DN @T6G_MB_LIB.T6G(SCH_1):USB3_CPU0_BMC_TX_BUF_C_DN   I176 @T6G_MB_LIB.T6G(SCH_1):PAGE348
   B61    GND @T6G_MB_LIB.T6G(SCH_1):GND   I176 @T6G_MB_LIB.T6G(SCH_1):PAGE348
   B62 TP_PCIE_TXP<1> @T6G_MB_LIB.T6G(SCH_1):TP_PCIE_TXP(1)   I176 @T6G_MB_LIB.T6G(SCH_1):PAGE348
   B63 TP_PCIE_TXN<1> @T6G_MB_LIB.T6G(SCH_1):TP_PCIE_TXN(1)   I176 @T6G_MB_LIB.T6G(SCH_1):PAGE348
   B64    GND @T6G_MB_LIB.T6G(SCH_1):GND   I176 @T6G_MB_LIB.T6G(SCH_1):PAGE348
   B65 P2E_MB_BMC_TX_C_DP<0> @T6G_MB_LIB.T6G(SCH_1):P2E_MB_BMC_TX_C_DP(0)   I176 @T6G_MB_LIB.T6G(SCH_1):PAGE348
   B66 P2E_MB_BMC_TX_C_DN<0> @T6G_MB_LIB.T6G(SCH_1):P2E_MB_BMC_TX_C_DN(0)   I176 @T6G_MB_LIB.T6G(SCH_1):PAGE348
   B67    GND @T6G_MB_LIB.T6G(SCH_1):GND   I176 @T6G_MB_LIB.T6G(SCH_1):PAGE348
   B68 TP_PCIE_TXP<3> @T6G_MB_LIB.T6G(SCH_1):TP_PCIE_TXP(3)   I176 @T6G_MB_LIB.T6G(SCH_1):PAGE348
   B69 TP_BEEP_LED @T6G_MB_LIB.T6G(SCH_1):TP_BEEP_LED   I176 @T6G_MB_LIB.T6G(SCH_1):PAGE348
   B70    GND @T6G_MB_LIB.T6G(SCH_1):GND   I176 @T6G_MB_LIB.T6G(SCH_1):PAGE348
    G1    GND @T6G_MB_LIB.T6G(SCH_1):GND   I176 @T6G_MB_LIB.T6G(SCH_1):PAGE348
    G2    GND @T6G_MB_LIB.T6G(SCH_1):GND   I176 @T6G_MB_LIB.T6G(SCH_1):PAGE348
    G3    GND @T6G_MB_LIB.T6G(SCH_1):GND   I176 @T6G_MB_LIB.T6G(SCH_1):PAGE348
    G4    GND @T6G_MB_LIB.T6G(SCH_1):GND   I176 @T6G_MB_LIB.T6G(SCH_1):PAGE348
    G5    GND @T6G_MB_LIB.T6G(SCH_1):GND   I176 @T6G_MB_LIB.T6G(SCH_1):PAGE348

 J45 CONN60_101062636003K02LF-CONN60_10106263-6003K02LFA
    A2 FM_AC_PWR_BTN_PDB_N @T6G_MB_LIB.T6G(SCH_1):FM_AC_PWR_BTN_PDB_N   I466 @T6G_MB_LIB.T6G(SCH_1):PAGE363
    B2 PWRGD_P3V3_AUX_PDB_BUF @T6G_MB_LIB.T6G(SCH_1):PWRGD_P3V3_AUX_PDB_BUF   I466 @T6G_MB_LIB.T6G(SCH_1):PAGE363
    C2 SMB_FAN_3V3AUX_BUF_R_SDA @T6G_MB_LIB.T6G(SCH_1):SMB_FAN_3V3AUX_BUF_R_SDA   I466 @T6G_MB_LIB.T6G(SCH_1):PAGE363
    D2 FM_GPU_HSC_EN_BUF_R1 @T6G_MB_LIB.T6G(SCH_1):FM_GPU_HSC_EN_BUF_R1   I466 @T6G_MB_LIB.T6G(SCH_1):PAGE363
  P1_1    GND @T6G_MB_LIB.T6G(SCH_1):GND   I466 @T6G_MB_LIB.T6G(SCH_1):PAGE363
  P1_2    GND @T6G_MB_LIB.T6G(SCH_1):GND   I466 @T6G_MB_LIB.T6G(SCH_1):PAGE363
  P1_3    GND @T6G_MB_LIB.T6G(SCH_1):GND   I466 @T6G_MB_LIB.T6G(SCH_1):PAGE363
  P1_4    GND @T6G_MB_LIB.T6G(SCH_1):GND   I466 @T6G_MB_LIB.T6G(SCH_1):PAGE363
  P1_5    GND @T6G_MB_LIB.T6G(SCH_1):GND   I466 @T6G_MB_LIB.T6G(SCH_1):PAGE363
  P1_6    GND @T6G_MB_LIB.T6G(SCH_1):GND   I466 @T6G_MB_LIB.T6G(SCH_1):PAGE363
  P1_7    GND @T6G_MB_LIB.T6G(SCH_1):GND   I466 @T6G_MB_LIB.T6G(SCH_1):PAGE363
  P1_8    GND @T6G_MB_LIB.T6G(SCH_1):GND   I466 @T6G_MB_LIB.T6G(SCH_1):PAGE363
  P2_1    GND @T6G_MB_LIB.T6G(SCH_1):GND   I466 @T6G_MB_LIB.T6G(SCH_1):PAGE363
  P2_2    GND @T6G_MB_LIB.T6G(SCH_1):GND   I466 @T6G_MB_LIB.T6G(SCH_1):PAGE363
  P2_3    GND @T6G_MB_LIB.T6G(SCH_1):GND   I466 @T6G_MB_LIB.T6G(SCH_1):PAGE363
  P2_4    GND @T6G_MB_LIB.T6G(SCH_1):GND   I466 @T6G_MB_LIB.T6G(SCH_1):PAGE363
  P2_5    GND @T6G_MB_LIB.T6G(SCH_1):GND   I466 @T6G_MB_LIB.T6G(SCH_1):PAGE363
  P2_6    GND @T6G_MB_LIB.T6G(SCH_1):GND   I466 @T6G_MB_LIB.T6G(SCH_1):PAGE363
  P2_7    GND @T6G_MB_LIB.T6G(SCH_1):GND   I466 @T6G_MB_LIB.T6G(SCH_1):PAGE363
  P2_8    GND @T6G_MB_LIB.T6G(SCH_1):GND   I466 @T6G_MB_LIB.T6G(SCH_1):PAGE363
  P4_1 P12V_PSU @T6G_MB_LIB.T6G(SCH_1):P12V_PSU   I466 @T6G_MB_LIB.T6G(SCH_1):PAGE363
  P4_2 P12V_PSU @T6G_MB_LIB.T6G(SCH_1):P12V_PSU   I466 @T6G_MB_LIB.T6G(SCH_1):PAGE363
  P4_3 P12V_PSU @T6G_MB_LIB.T6G(SCH_1):P12V_PSU   I466 @T6G_MB_LIB.T6G(SCH_1):PAGE363
  P4_4 P12V_PSU @T6G_MB_LIB.T6G(SCH_1):P12V_PSU   I466 @T6G_MB_LIB.T6G(SCH_1):PAGE363
  P4_5 P12V_PSU @T6G_MB_LIB.T6G(SCH_1):P12V_PSU   I466 @T6G_MB_LIB.T6G(SCH_1):PAGE363
  P4_6 P12V_PSU @T6G_MB_LIB.T6G(SCH_1):P12V_PSU   I466 @T6G_MB_LIB.T6G(SCH_1):PAGE363
  P4_7 P12V_PSU @T6G_MB_LIB.T6G(SCH_1):P12V_PSU   I466 @T6G_MB_LIB.T6G(SCH_1):PAGE363
  P4_8 P12V_PSU @T6G_MB_LIB.T6G(SCH_1):P12V_PSU   I466 @T6G_MB_LIB.T6G(SCH_1):PAGE363
    A1 TP_J45_A1 @T6G_MB_LIB.T6G(SCH_1):TP_J45_A1   I466 @T6G_MB_LIB.T6G(SCH_1):PAGE363
    B1 RST_SMB_SWITCH_R_N @T6G_MB_LIB.T6G(SCH_1):RST_SMB_SWITCH_R_N   I466 @T6G_MB_LIB.T6G(SCH_1):PAGE363
    C1 SMB_FAN_3V3AUX_BUF_R_SCL @T6G_MB_LIB.T6G(SCH_1):SMB_FAN_3V3AUX_BUF_R_SCL   I466 @T6G_MB_LIB.T6G(SCH_1):PAGE363
    D1 FM_FAN_PWR_EN_R @T6G_MB_LIB.T6G(SCH_1):FM_FAN_PWR_EN_R   I466 @T6G_MB_LIB.T6G(SCH_1):PAGE363
  P5_1 P12V_PSU @T6G_MB_LIB.T6G(SCH_1):P12V_PSU   I466 @T6G_MB_LIB.T6G(SCH_1):PAGE363
  P5_2 P12V_PSU @T6G_MB_LIB.T6G(SCH_1):P12V_PSU   I466 @T6G_MB_LIB.T6G(SCH_1):PAGE363
  P5_3 P12V_PSU @T6G_MB_LIB.T6G(SCH_1):P12V_PSU   I466 @T6G_MB_LIB.T6G(SCH_1):PAGE363
  P5_4 P12V_PSU @T6G_MB_LIB.T6G(SCH_1):P12V_PSU   I466 @T6G_MB_LIB.T6G(SCH_1):PAGE363
  P5_5 P12V_PSU @T6G_MB_LIB.T6G(SCH_1):P12V_PSU   I466 @T6G_MB_LIB.T6G(SCH_1):PAGE363
  P5_6 P12V_PSU @T6G_MB_LIB.T6G(SCH_1):P12V_PSU   I466 @T6G_MB_LIB.T6G(SCH_1):PAGE363
  P5_7 P12V_PSU @T6G_MB_LIB.T6G(SCH_1):P12V_PSU   I466 @T6G_MB_LIB.T6G(SCH_1):PAGE363
  P5_8 P12V_PSU @T6G_MB_LIB.T6G(SCH_1):P12V_PSU   I466 @T6G_MB_LIB.T6G(SCH_1):PAGE363
  P3_1    GND @T6G_MB_LIB.T6G(SCH_1):GND   I466 @T6G_MB_LIB.T6G(SCH_1):PAGE363
  P3_2    GND @T6G_MB_LIB.T6G(SCH_1):GND   I466 @T6G_MB_LIB.T6G(SCH_1):PAGE363
  P3_3    GND @T6G_MB_LIB.T6G(SCH_1):GND   I466 @T6G_MB_LIB.T6G(SCH_1):PAGE363
  P3_4    GND @T6G_MB_LIB.T6G(SCH_1):GND   I466 @T6G_MB_LIB.T6G(SCH_1):PAGE363
  P3_5    GND @T6G_MB_LIB.T6G(SCH_1):GND   I466 @T6G_MB_LIB.T6G(SCH_1):PAGE363
  P3_6    GND @T6G_MB_LIB.T6G(SCH_1):GND   I466 @T6G_MB_LIB.T6G(SCH_1):PAGE363
  P3_7    GND @T6G_MB_LIB.T6G(SCH_1):GND   I466 @T6G_MB_LIB.T6G(SCH_1):PAGE363
  P3_8    GND @T6G_MB_LIB.T6G(SCH_1):GND   I466 @T6G_MB_LIB.T6G(SCH_1):PAGE363
  P6_1 P12V_PSU @T6G_MB_LIB.T6G(SCH_1):P12V_PSU   I466 @T6G_MB_LIB.T6G(SCH_1):PAGE363
  P6_2 P12V_PSU @T6G_MB_LIB.T6G(SCH_1):P12V_PSU   I466 @T6G_MB_LIB.T6G(SCH_1):PAGE363
  P6_3 P12V_PSU @T6G_MB_LIB.T6G(SCH_1):P12V_PSU   I466 @T6G_MB_LIB.T6G(SCH_1):PAGE363
  P6_4 P12V_PSU @T6G_MB_LIB.T6G(SCH_1):P12V_PSU   I466 @T6G_MB_LIB.T6G(SCH_1):PAGE363
  P6_5 P12V_PSU @T6G_MB_LIB.T6G(SCH_1):P12V_PSU   I466 @T6G_MB_LIB.T6G(SCH_1):PAGE363
  P6_6 P12V_PSU @T6G_MB_LIB.T6G(SCH_1):P12V_PSU   I466 @T6G_MB_LIB.T6G(SCH_1):PAGE363
  P6_7 P12V_PSU @T6G_MB_LIB.T6G(SCH_1):P12V_PSU   I466 @T6G_MB_LIB.T6G(SCH_1):PAGE363
  P6_8 P12V_PSU @T6G_MB_LIB.T6G(SCH_1):P12V_PSU   I466 @T6G_MB_LIB.T6G(SCH_1):PAGE363
    A3 P3V3_PDB_AUX_ADC @T6G_MB_LIB.T6G(SCH_1):P3V3_PDB_AUX_ADC   I466 @T6G_MB_LIB.T6G(SCH_1):PAGE363
    B3    GND @T6G_MB_LIB.T6G(SCH_1):GND   I466 @T6G_MB_LIB.T6G(SCH_1):PAGE363
    C3 HPDB_HSC_PWRGD_R @T6G_MB_LIB.T6G(SCH_1):HPDB_HSC_PWRGD_R   I466 @T6G_MB_LIB.T6G(SCH_1):PAGE363
    D3 PDB_PRSNT_N @T6G_MB_LIB.T6G(SCH_1):PDB_PRSNT_N   I466 @T6G_MB_LIB.T6G(SCH_1):PAGE363

 J48 SCONN8_G802M0083150RD3HR-SCONN8_G802M0083150RD3HR,A
     1 CPU0_BP0 @T6G_MB_LIB.T6G(SCH_1):CPU0_BP0   I424 @T6G_MB_LIB.T6G(SCH_1):PAGE27
     2    GND @T6G_MB_LIB.T6G(SCH_1):GND   I424 @T6G_MB_LIB.T6G(SCH_1):PAGE27
     3 CPU0_BP1 @T6G_MB_LIB.T6G(SCH_1):CPU0_BP1   I424 @T6G_MB_LIB.T6G(SCH_1):PAGE27
     4    GND @T6G_MB_LIB.T6G(SCH_1):GND   I424 @T6G_MB_LIB.T6G(SCH_1):PAGE27
     5 CPU0_BP2 @T6G_MB_LIB.T6G(SCH_1):CPU0_BP2   I424 @T6G_MB_LIB.T6G(SCH_1):PAGE27
     6    GND @T6G_MB_LIB.T6G(SCH_1):GND   I424 @T6G_MB_LIB.T6G(SCH_1):PAGE27
     7 CPU0_BP3 @T6G_MB_LIB.T6G(SCH_1):CPU0_BP3   I424 @T6G_MB_LIB.T6G(SCH_1):PAGE27
     8    GND @T6G_MB_LIB.T6G(SCH_1):GND   I424 @T6G_MB_LIB.T6G(SCH_1):PAGE27

 J49 SCONN8_G802M0083150RD3HR-SCONN8_G802M0083150RD3HR,A
     1 CPU1_BP0 @T6G_MB_LIB.T6G(SCH_1):CPU1_BP0   I419 @T6G_MB_LIB.T6G(SCH_1):PAGE54
     2    GND @T6G_MB_LIB.T6G(SCH_1):GND   I419 @T6G_MB_LIB.T6G(SCH_1):PAGE54
     3 CPU1_BP1 @T6G_MB_LIB.T6G(SCH_1):CPU1_BP1   I419 @T6G_MB_LIB.T6G(SCH_1):PAGE54
     4    GND @T6G_MB_LIB.T6G(SCH_1):GND   I419 @T6G_MB_LIB.T6G(SCH_1):PAGE54
     5 CPU1_BP2 @T6G_MB_LIB.T6G(SCH_1):CPU1_BP2   I419 @T6G_MB_LIB.T6G(SCH_1):PAGE54
     6    GND @T6G_MB_LIB.T6G(SCH_1):GND   I419 @T6G_MB_LIB.T6G(SCH_1):PAGE54
     7 CPU1_BP3 @T6G_MB_LIB.T6G(SCH_1):CPU1_BP3   I419 @T6G_MB_LIB.T6G(SCH_1):PAGE54
     8    GND @T6G_MB_LIB.T6G(SCH_1):GND   I419 @T6G_MB_LIB.T6G(SCH_1):PAGE54

 J54 SCONN20_HSU2101L00007H-SCONN20_HSU2101-L0000-7H,SMA
     1 PVDD18_S5_P0 @T6G_MB_LIB.T6G(SCH_1):PVDD18_S5_P0   I142 @T6G_MB_LIB.T6G(SCH_1):PAGE149
     2 HDT_HDR_R_TCK @T6G_MB_LIB.T6G(SCH_1):HDT_HDR_R_TCK   I142 @T6G_MB_LIB.T6G(SCH_1):PAGE149
     3 PRSNT_HDT_R_N @T6G_MB_LIB.T6G(SCH_1):PRSNT_HDT_R_N   I142 @T6G_MB_LIB.T6G(SCH_1):PAGE149
     4 HDT_HDR_R_TMS @T6G_MB_LIB.T6G(SCH_1):HDT_HDR_R_TMS   I142 @T6G_MB_LIB.T6G(SCH_1):PAGE149
     5    GND @T6G_MB_LIB.T6G(SCH_1):GND   I142 @T6G_MB_LIB.T6G(SCH_1):PAGE149
     6 HDT_HDR_R_TDI @T6G_MB_LIB.T6G(SCH_1):HDT_HDR_R_TDI   I142 @T6G_MB_LIB.T6G(SCH_1):PAGE149
     7    GND @T6G_MB_LIB.T6G(SCH_1):GND   I142 @T6G_MB_LIB.T6G(SCH_1):PAGE149
     8 HDT_HDR_TDO @T6G_MB_LIB.T6G(SCH_1):HDT_HDR_TDO   I142 @T6G_MB_LIB.T6G(SCH_1):PAGE149
     9 HDT_HDR_TRST_N_R @T6G_MB_LIB.T6G(SCH_1):HDT_HDR_TRST_N_R   I142 @T6G_MB_LIB.T6G(SCH_1):PAGE149
    10 HDT_HDR_PWROK @T6G_MB_LIB.T6G(SCH_1):HDT_HDR_PWROK   I142 @T6G_MB_LIB.T6G(SCH_1):PAGE149
    11 HDT_CPU0_XTRIG_L6 @T6G_MB_LIB.T6G(SCH_1):HDT_CPU0_XTRIG_L6   I142 @T6G_MB_LIB.T6G(SCH_1):PAGE149
    12 HDT_HDR_RESET_N @T6G_MB_LIB.T6G(SCH_1):HDT_HDR_RESET_N   I142 @T6G_MB_LIB.T6G(SCH_1):PAGE149
    13 HDT_CPU0_XTRIG_L7 @T6G_MB_LIB.T6G(SCH_1):HDT_CPU0_XTRIG_L7   I142 @T6G_MB_LIB.T6G(SCH_1):PAGE149
    14     NC     NC   I142 @T6G_MB_LIB.T6G(SCH_1):PAGE149
    15 HDT_CPU0_XTRIG_L5 @T6G_MB_LIB.T6G(SCH_1):HDT_CPU0_XTRIG_L5   I142 @T6G_MB_LIB.T6G(SCH_1):PAGE149
    16 HDT_HDR_DBREQ_R_N @T6G_MB_LIB.T6G(SCH_1):HDT_HDR_DBREQ_R_N   I142 @T6G_MB_LIB.T6G(SCH_1):PAGE149
    17    GND @T6G_MB_LIB.T6G(SCH_1):GND   I142 @T6G_MB_LIB.T6G(SCH_1):PAGE149
    18 HDT_CPU0_HDT_CONN_TESTEN @T6G_MB_LIB.T6G(SCH_1):HDT_CPU0_HDT_CONN_TESTEN   I142 @T6G_MB_LIB.T6G(SCH_1):PAGE149
    19 PVDD18_S5_P0 @T6G_MB_LIB.T6G(SCH_1):PVDD18_S5_P0   I142 @T6G_MB_LIB.T6G(SCH_1):PAGE149
    20     NC     NC   I142 @T6G_MB_LIB.T6G(SCH_1):PAGE149

 J57 CONN8_HBB1081L200D8H-CONN8_HBB1081-L200D-8H,THLF,IA
     1 P3V3_AUX @T6G_MB_LIB.T6G(SCH_1):P3V3_AUX    I41 @T6G_MB_LIB.T6G(SCH_1):PAGE84
     2 JTAG_PLD_TDI @T6G_MB_LIB.T6G(SCH_1):JTAG_PLD_TDI    I41 @T6G_MB_LIB.T6G(SCH_1):PAGE84
     3 JTAG_PLD_TDO @T6G_MB_LIB.T6G(SCH_1):JTAG_PLD_TDO    I41 @T6G_MB_LIB.T6G(SCH_1):PAGE84
     4     NC     NC    I41 @T6G_MB_LIB.T6G(SCH_1):PAGE84
     5     NC     NC    I41 @T6G_MB_LIB.T6G(SCH_1):PAGE84
     6 JTAG_PLD_TMS @T6G_MB_LIB.T6G(SCH_1):JTAG_PLD_TMS    I41 @T6G_MB_LIB.T6G(SCH_1):PAGE84
     7    GND @T6G_MB_LIB.T6G(SCH_1):GND    I41 @T6G_MB_LIB.T6G(SCH_1):PAGE84
     8 JTAG_PLD_TCK @T6G_MB_LIB.T6G(SCH_1):JTAG_PLD_TCK    I41 @T6G_MB_LIB.T6G(SCH_1):PAGE84

 J59 SCONN75K_APCI0155P004A-SCONN75K_APCI0155-P004A,SMLA
     2 P3V3_M2_0 @T6G_MB_LIB.T6G(SCH_1):P3V3_M2_0    I88 @T6G_MB_LIB.T6G(SCH_1):PAGE345
     4 P3V3_M2_0 @T6G_MB_LIB.T6G(SCH_1):P3V3_M2_0    I88 @T6G_MB_LIB.T6G(SCH_1):PAGE345
    10 LED_M2_SSD_0_ACT_N @T6G_MB_LIB.T6G(SCH_1):LED_M2_SSD_0_ACT_N    I88 @T6G_MB_LIB.T6G(SCH_1):PAGE345
    12 P3V3_M2_0 @T6G_MB_LIB.T6G(SCH_1):P3V3_M2_0    I88 @T6G_MB_LIB.T6G(SCH_1):PAGE345
    14 P3V3_M2_0 @T6G_MB_LIB.T6G(SCH_1):P3V3_M2_0    I88 @T6G_MB_LIB.T6G(SCH_1):PAGE345
    16 P3V3_M2_0 @T6G_MB_LIB.T6G(SCH_1):P3V3_M2_0    I88 @T6G_MB_LIB.T6G(SCH_1):PAGE345
    18 P3V3_M2_0 @T6G_MB_LIB.T6G(SCH_1):P3V3_M2_0    I88 @T6G_MB_LIB.T6G(SCH_1):PAGE345
    38 PD_M2_0_DEVSLP @T6G_MB_LIB.T6G(SCH_1):PD_M2_0_DEVSLP    I88 @T6G_MB_LIB.T6G(SCH_1):PAGE345
    50 RST_PERST_BUF_M2_0_R_N @T6G_MB_LIB.T6G(SCH_1):RST_PERST_BUF_M2_0_R_N    I88 @T6G_MB_LIB.T6G(SCH_1):PAGE345
    52 M2_SSD0_CLKREQ_EN_N_BUF @T6G_MB_LIB.T6G(SCH_1):M2_SSD0_CLKREQ_EN_N_BUF    I88 @T6G_MB_LIB.T6G(SCH_1):PAGE345
    54 M2_0_PEWAKE_N @T6G_MB_LIB.T6G(SCH_1):M2_0_PEWAKE_N    I88 @T6G_MB_LIB.T6G(SCH_1):PAGE345
    58 NC_M2_0_NC18 @T6G_MB_LIB.T6G(SCH_1):NC_M2_0_NC18    I88 @T6G_MB_LIB.T6G(SCH_1):PAGE345
    68 NC_M2_0_SUSCLK @T6G_MB_LIB.T6G(SCH_1):NC_M2_0_SUSCLK    I88 @T6G_MB_LIB.T6G(SCH_1):PAGE345
    70 P3V3_M2_0 @T6G_MB_LIB.T6G(SCH_1):P3V3_M2_0    I88 @T6G_MB_LIB.T6G(SCH_1):PAGE345
    72 P3V3_M2_0 @T6G_MB_LIB.T6G(SCH_1):P3V3_M2_0    I88 @T6G_MB_LIB.T6G(SCH_1):PAGE345
    74 P3V3_M2_0 @T6G_MB_LIB.T6G(SCH_1):P3V3_M2_0    I88 @T6G_MB_LIB.T6G(SCH_1):PAGE345
    41 P3E_CPU1_P4_RX_DN<0> @T6G_MB_LIB.T6G(SCH_1):P3E_CPU1_P4_RX_DN(0)    I88 @T6G_MB_LIB.T6G(SCH_1):PAGE345
    43 P3E_CPU1_P4_RX_DP<0> @T6G_MB_LIB.T6G(SCH_1):P3E_CPU1_P4_RX_DP(0)    I88 @T6G_MB_LIB.T6G(SCH_1):PAGE345
    47 P3E_CPU1_P4_TX_C_DN<0> @T6G_MB_LIB.T6G(SCH_1):P3E_CPU1_P4_TX_C_DN(0)    I88 @T6G_MB_LIB.T6G(SCH_1):PAGE345
    49 P3E_CPU1_P4_TX_C_DP<0> @T6G_MB_LIB.T6G(SCH_1):P3E_CPU1_P4_TX_C_DP(0)    I88 @T6G_MB_LIB.T6G(SCH_1):PAGE345
    57    GND @T6G_MB_LIB.T6G(SCH_1):GND    I88 @T6G_MB_LIB.T6G(SCH_1):PAGE345
    67 NC_M2_0_NC19 @T6G_MB_LIB.T6G(SCH_1):NC_M2_0_NC19    I88 @T6G_MB_LIB.T6G(SCH_1):PAGE345
    69 FM_M2_SSD_0_PEDET @T6G_MB_LIB.T6G(SCH_1):FM_M2_SSD_0_PEDET    I88 @T6G_MB_LIB.T6G(SCH_1):PAGE345
    71    GND @T6G_MB_LIB.T6G(SCH_1):GND    I88 @T6G_MB_LIB.T6G(SCH_1):PAGE345
    73    GND @T6G_MB_LIB.T6G(SCH_1):GND    I88 @T6G_MB_LIB.T6G(SCH_1):PAGE345
    75    GND @T6G_MB_LIB.T6G(SCH_1):GND    I88 @T6G_MB_LIB.T6G(SCH_1):PAGE345
    G1    GND @T6G_MB_LIB.T6G(SCH_1):GND    I88 @T6G_MB_LIB.T6G(SCH_1):PAGE345
    G2    GND @T6G_MB_LIB.T6G(SCH_1):GND    I88 @T6G_MB_LIB.T6G(SCH_1):PAGE345
     6 NC_M2_0_NC1 @T6G_MB_LIB.T6G(SCH_1):NC_M2_0_NC1    I88 @T6G_MB_LIB.T6G(SCH_1):PAGE345
     8 NC_M2_0_NC2 @T6G_MB_LIB.T6G(SCH_1):NC_M2_0_NC2    I88 @T6G_MB_LIB.T6G(SCH_1):PAGE345
    20 NC_M2_0_NC3 @T6G_MB_LIB.T6G(SCH_1):NC_M2_0_NC3    I88 @T6G_MB_LIB.T6G(SCH_1):PAGE345
    34 NC_M2_0_NC10 @T6G_MB_LIB.T6G(SCH_1):NC_M2_0_NC10    I88 @T6G_MB_LIB.T6G(SCH_1):PAGE345
    56 NC_M2_0_NC17 @T6G_MB_LIB.T6G(SCH_1):NC_M2_0_NC17    I88 @T6G_MB_LIB.T6G(SCH_1):PAGE345
    48 NC_M2_0_NC16 @T6G_MB_LIB.T6G(SCH_1):NC_M2_0_NC16    I88 @T6G_MB_LIB.T6G(SCH_1):PAGE345
    46 NC_M2_0_NC15 @T6G_MB_LIB.T6G(SCH_1):NC_M2_0_NC15    I88 @T6G_MB_LIB.T6G(SCH_1):PAGE345
    44 NC_M2_0_NC14 @T6G_MB_LIB.T6G(SCH_1):NC_M2_0_NC14    I88 @T6G_MB_LIB.T6G(SCH_1):PAGE345
    42 SMB_M2_P1_1V8AUX_SDA @T6G_MB_LIB.T6G(SCH_1):SMB_M2_P1_1V8AUX_SDA    I88 @T6G_MB_LIB.T6G(SCH_1):PAGE345
    40 SMB_M2_P1_1V8AUX_SCL @T6G_MB_LIB.T6G(SCH_1):SMB_M2_P1_1V8AUX_SCL    I88 @T6G_MB_LIB.T6G(SCH_1):PAGE345
    36 NC_M2_0_NC11 @T6G_MB_LIB.T6G(SCH_1):NC_M2_0_NC11    I88 @T6G_MB_LIB.T6G(SCH_1):PAGE345
    32 NC_M2_0_NC9 @T6G_MB_LIB.T6G(SCH_1):NC_M2_0_NC9    I88 @T6G_MB_LIB.T6G(SCH_1):PAGE345
    30 NC_M2_0_NC8 @T6G_MB_LIB.T6G(SCH_1):NC_M2_0_NC8    I88 @T6G_MB_LIB.T6G(SCH_1):PAGE345
    28 NC_M2_0_NC7 @T6G_MB_LIB.T6G(SCH_1):NC_M2_0_NC7    I88 @T6G_MB_LIB.T6G(SCH_1):PAGE345
    26 NC_M2_0_NC6 @T6G_MB_LIB.T6G(SCH_1):NC_M2_0_NC6    I88 @T6G_MB_LIB.T6G(SCH_1):PAGE345
    24 NC_M2_0_NC5 @T6G_MB_LIB.T6G(SCH_1):NC_M2_0_NC5    I88 @T6G_MB_LIB.T6G(SCH_1):PAGE345
    22 NC_M2_0_NC4 @T6G_MB_LIB.T6G(SCH_1):NC_M2_0_NC4    I88 @T6G_MB_LIB.T6G(SCH_1):PAGE345
     1 PCIE_M2_SSD0_PRSNT_N @T6G_MB_LIB.T6G(SCH_1):PCIE_M2_SSD0_PRSNT_N    I88 @T6G_MB_LIB.T6G(SCH_1):PAGE345
     3    GND @T6G_MB_LIB.T6G(SCH_1):GND    I88 @T6G_MB_LIB.T6G(SCH_1):PAGE345
     9    GND @T6G_MB_LIB.T6G(SCH_1):GND    I88 @T6G_MB_LIB.T6G(SCH_1):PAGE345
    15    GND @T6G_MB_LIB.T6G(SCH_1):GND    I88 @T6G_MB_LIB.T6G(SCH_1):PAGE345
    21    GND @T6G_MB_LIB.T6G(SCH_1):GND    I88 @T6G_MB_LIB.T6G(SCH_1):PAGE345
    27    GND @T6G_MB_LIB.T6G(SCH_1):GND    I88 @T6G_MB_LIB.T6G(SCH_1):PAGE345
    33    GND @T6G_MB_LIB.T6G(SCH_1):GND    I88 @T6G_MB_LIB.T6G(SCH_1):PAGE345
    39    GND @T6G_MB_LIB.T6G(SCH_1):GND    I88 @T6G_MB_LIB.T6G(SCH_1):PAGE345
    45    GND @T6G_MB_LIB.T6G(SCH_1):GND    I88 @T6G_MB_LIB.T6G(SCH_1):PAGE345
    51    GND @T6G_MB_LIB.T6G(SCH_1):GND    I88 @T6G_MB_LIB.T6G(SCH_1):PAGE345
     5 P3E_CPU1_P4_RX_DN<3> @T6G_MB_LIB.T6G(SCH_1):P3E_CPU1_P4_RX_DN(3)    I88 @T6G_MB_LIB.T6G(SCH_1):PAGE345
     7 P3E_CPU1_P4_RX_DP<3> @T6G_MB_LIB.T6G(SCH_1):P3E_CPU1_P4_RX_DP(3)    I88 @T6G_MB_LIB.T6G(SCH_1):PAGE345
    11 P3E_CPU1_P4_TX_C_DN<3> @T6G_MB_LIB.T6G(SCH_1):P3E_CPU1_P4_TX_C_DN(3)    I88 @T6G_MB_LIB.T6G(SCH_1):PAGE345
    13 P3E_CPU1_P4_TX_C_DP<3> @T6G_MB_LIB.T6G(SCH_1):P3E_CPU1_P4_TX_C_DP(3)    I88 @T6G_MB_LIB.T6G(SCH_1):PAGE345
    17 P3E_CPU1_P4_RX_DN<2> @T6G_MB_LIB.T6G(SCH_1):P3E_CPU1_P4_RX_DN(2)    I88 @T6G_MB_LIB.T6G(SCH_1):PAGE345
    19 P3E_CPU1_P4_RX_DP<2> @T6G_MB_LIB.T6G(SCH_1):P3E_CPU1_P4_RX_DP(2)    I88 @T6G_MB_LIB.T6G(SCH_1):PAGE345
    23 P3E_CPU1_P4_TX_C_DN<2> @T6G_MB_LIB.T6G(SCH_1):P3E_CPU1_P4_TX_C_DN(2)    I88 @T6G_MB_LIB.T6G(SCH_1):PAGE345
    25 P3E_CPU1_P4_TX_C_DP<2> @T6G_MB_LIB.T6G(SCH_1):P3E_CPU1_P4_TX_C_DP(2)    I88 @T6G_MB_LIB.T6G(SCH_1):PAGE345
    29 P3E_CPU1_P4_RX_DN<1> @T6G_MB_LIB.T6G(SCH_1):P3E_CPU1_P4_RX_DN(1)    I88 @T6G_MB_LIB.T6G(SCH_1):PAGE345
    31 P3E_CPU1_P4_RX_DP<1> @T6G_MB_LIB.T6G(SCH_1):P3E_CPU1_P4_RX_DP(1)    I88 @T6G_MB_LIB.T6G(SCH_1):PAGE345
    35 P3E_CPU1_P4_TX_C_DN<1> @T6G_MB_LIB.T6G(SCH_1):P3E_CPU1_P4_TX_C_DN(1)    I88 @T6G_MB_LIB.T6G(SCH_1):PAGE345
    37 P3E_CPU1_P4_TX_C_DP<1> @T6G_MB_LIB.T6G(SCH_1):P3E_CPU1_P4_TX_C_DP(1)    I88 @T6G_MB_LIB.T6G(SCH_1):PAGE345
    53 CLK_100M_CPU1_CLK12_DN @T6G_MB_LIB.T6G(SCH_1):CLK_100M_CPU1_CLK12_DN    I88 @T6G_MB_LIB.T6G(SCH_1):PAGE345
    55 CLK_100M_CPU1_CLK12_DP @T6G_MB_LIB.T6G(SCH_1):CLK_100M_CPU1_CLK12_DP    I88 @T6G_MB_LIB.T6G(SCH_1):PAGE345

 J63 PICOPROBE_BXA-DELTA-L 4.0,SMLF,EMPTY,TP33
     2 DELTA_L_85_5INCH_TOP_DN @T6G_MB_LIB.T6G(SCH_1):DELTA_L_85_5INCH_TOP_DN    I65 @T6G_MB_LIB.T6G(SCH_1):PAGE211
     3 DELTA_L_GND_1 @T6G_MB_LIB.T6G(SCH_1):DELTA_L_GND_1    I65 @T6G_MB_LIB.T6G(SCH_1):PAGE211
     1 DELTA_L_85_5INCH_TOP_DP @T6G_MB_LIB.T6G(SCH_1):DELTA_L_85_5INCH_TOP_DP    I65 @T6G_MB_LIB.T6G(SCH_1):PAGE211

 J64 PICOPROBE_BXA-DELTA-L 4.0,SMLF,EMPTY,TP33
     2 DELTA_L_85_5INCH_BOT_DN @T6G_MB_LIB.T6G(SCH_1):DELTA_L_85_5INCH_BOT_DN    I67 @T6G_MB_LIB.T6G(SCH_1):PAGE211
     3 DELTA_L_GND_1 @T6G_MB_LIB.T6G(SCH_1):DELTA_L_GND_1    I67 @T6G_MB_LIB.T6G(SCH_1):PAGE211
     1 DELTA_L_85_5INCH_BOT_DP @T6G_MB_LIB.T6G(SCH_1):DELTA_L_85_5INCH_BOT_DP    I67 @T6G_MB_LIB.T6G(SCH_1):PAGE211

 J65 PICOPROBE_BXA-DELTA-L 4.0,SMLF,EMPTY,TP33
     2 DELTA_L_85_5INCH_IN1_DN @T6G_MB_LIB.T6G(SCH_1):DELTA_L_85_5INCH_IN1_DN    I69 @T6G_MB_LIB.T6G(SCH_1):PAGE211
     3 DELTA_L_GND_1 @T6G_MB_LIB.T6G(SCH_1):DELTA_L_GND_1    I69 @T6G_MB_LIB.T6G(SCH_1):PAGE211
     1 DELTA_L_85_5INCH_IN1_DP @T6G_MB_LIB.T6G(SCH_1):DELTA_L_85_5INCH_IN1_DP    I69 @T6G_MB_LIB.T6G(SCH_1):PAGE211

 J66 PICOPROBE_BXA-DELTA-L 4.0,SMLF,EMPTY,TP33
     2 DELTA_L_85_5INCH_IN2_DN @T6G_MB_LIB.T6G(SCH_1):DELTA_L_85_5INCH_IN2_DN    I71 @T6G_MB_LIB.T6G(SCH_1):PAGE211
     3 DELTA_L_GND_1 @T6G_MB_LIB.T6G(SCH_1):DELTA_L_GND_1    I71 @T6G_MB_LIB.T6G(SCH_1):PAGE211
     1 DELTA_L_85_5INCH_IN2_DP @T6G_MB_LIB.T6G(SCH_1):DELTA_L_85_5INCH_IN2_DP    I71 @T6G_MB_LIB.T6G(SCH_1):PAGE211

 J67 SCONN288_DDR506112002KQ-SCONN288_DDR506112002KQ,SMA
     3 P3V3_AUX @T6G_MB_LIB.T6G(SCH_1):P3V3_AUX    I22 @T6G_MB_LIB.T6G(SCH_1):PAGE96
     2     NC     NC    I22 @T6G_MB_LIB.T6G(SCH_1):PAGE96
   144     NC     NC    I22 @T6G_MB_LIB.T6G(SCH_1):PAGE96
   149     NC     NC    I22 @T6G_MB_LIB.T6G(SCH_1):PAGE96
   150     NC     NC    I22 @T6G_MB_LIB.T6G(SCH_1):PAGE96
   220     NC     NC    I22 @T6G_MB_LIB.T6G(SCH_1):PAGE96
   231     NC     NC    I22 @T6G_MB_LIB.T6G(SCH_1):PAGE96
   232     NC     NC    I22 @T6G_MB_LIB.T6G(SCH_1):PAGE96
   207 M_L_CPU0_RESET_N @T6G_MB_LIB.T6G(SCH_1):M_L_CPU0_RESET_N    I22 @T6G_MB_LIB.T6G(SCH_1):PAGE96
   147 PWRGD_CHL_CPU0_DIMM @T6G_MB_LIB.T6G(SCH_1):PWRGD_CHL_CPU0_DIMM    I22 @T6G_MB_LIB.T6G(SCH_1):PAGE96
   227 M_L_CPU0_SB_PAR @T6G_MB_LIB.T6G(SCH_1):M_L_CPU0_SB_PAR    I22 @T6G_MB_LIB.T6G(SCH_1):PAGE96
    74 M_L_CPU0_SA_PAR @T6G_MB_LIB.T6G(SCH_1):M_L_CPU0_SA_PAR    I22 @T6G_MB_LIB.T6G(SCH_1):PAGE96
    87 M_L_CPU0_SB_RSP<0> @T6G_MB_LIB.T6G(SCH_1):M_L_CPU0_SB_RSP(0)    I22 @T6G_MB_LIB.T6G(SCH_1):PAGE96
    86 M_L_CPU0_SA_RSP<0> @T6G_MB_LIB.T6G(SCH_1):M_L_CPU0_SA_RSP(0)    I22 @T6G_MB_LIB.T6G(SCH_1):PAGE96
     5 I3C_SPD_DDRL_CPU0_SDA @T6G_MB_LIB.T6G(SCH_1):I3C_SPD_DDRL_CPU0_SDA    I22 @T6G_MB_LIB.T6G(SCH_1):PAGE96
     4 I3C_SPD_DDRL_CPU0_SCL @T6G_MB_LIB.T6G(SCH_1):I3C_SPD_DDRL_CPU0_SCL    I22 @T6G_MB_LIB.T6G(SCH_1):PAGE96
   148 PD_CHL_CPU0_DIMM_SAA @T6G_MB_LIB.T6G(SCH_1):PD_CHL_CPU0_DIMM_SAA    I22 @T6G_MB_LIB.T6G(SCH_1):PAGE96
   100 M_L_CPU0_SB_DQ<0> @T6G_MB_LIB.T6G(SCH_1):M_L_CPU0_SB_DQ(0)    I22 @T6G_MB_LIB.T6G(SCH_1):PAGE96
   102 M_L_CPU0_SB_DQ<1> @T6G_MB_LIB.T6G(SCH_1):M_L_CPU0_SB_DQ(1)    I22 @T6G_MB_LIB.T6G(SCH_1):PAGE96
   245 M_L_CPU0_SB_DQ<2> @T6G_MB_LIB.T6G(SCH_1):M_L_CPU0_SB_DQ(2)    I22 @T6G_MB_LIB.T6G(SCH_1):PAGE96
   247 M_L_CPU0_SB_DQ<3> @T6G_MB_LIB.T6G(SCH_1):M_L_CPU0_SB_DQ(3)    I22 @T6G_MB_LIB.T6G(SCH_1):PAGE96
   107 M_L_CPU0_SB_DQ<4> @T6G_MB_LIB.T6G(SCH_1):M_L_CPU0_SB_DQ(4)    I22 @T6G_MB_LIB.T6G(SCH_1):PAGE96
   109 M_L_CPU0_SB_DQ<5> @T6G_MB_LIB.T6G(SCH_1):M_L_CPU0_SB_DQ(5)    I22 @T6G_MB_LIB.T6G(SCH_1):PAGE96
   252 M_L_CPU0_SB_DQ<6> @T6G_MB_LIB.T6G(SCH_1):M_L_CPU0_SB_DQ(6)    I22 @T6G_MB_LIB.T6G(SCH_1):PAGE96
   254 M_L_CPU0_SB_DQ<7> @T6G_MB_LIB.T6G(SCH_1):M_L_CPU0_SB_DQ(7)    I22 @T6G_MB_LIB.T6G(SCH_1):PAGE96
   111 M_L_CPU0_SB_DQ<8> @T6G_MB_LIB.T6G(SCH_1):M_L_CPU0_SB_DQ(8)    I22 @T6G_MB_LIB.T6G(SCH_1):PAGE96
   113 M_L_CPU0_SB_DQ<9> @T6G_MB_LIB.T6G(SCH_1):M_L_CPU0_SB_DQ(9)    I22 @T6G_MB_LIB.T6G(SCH_1):PAGE96
   256 M_L_CPU0_SB_DQ<10> @T6G_MB_LIB.T6G(SCH_1):M_L_CPU0_SB_DQ(10)    I22 @T6G_MB_LIB.T6G(SCH_1):PAGE96
   258 M_L_CPU0_SB_DQ<11> @T6G_MB_LIB.T6G(SCH_1):M_L_CPU0_SB_DQ(11)    I22 @T6G_MB_LIB.T6G(SCH_1):PAGE96
   118 M_L_CPU0_SB_DQ<12> @T6G_MB_LIB.T6G(SCH_1):M_L_CPU0_SB_DQ(12)    I22 @T6G_MB_LIB.T6G(SCH_1):PAGE96
   120 M_L_CPU0_SB_DQ<13> @T6G_MB_LIB.T6G(SCH_1):M_L_CPU0_SB_DQ(13)    I22 @T6G_MB_LIB.T6G(SCH_1):PAGE96
   263 M_L_CPU0_SB_DQ<14> @T6G_MB_LIB.T6G(SCH_1):M_L_CPU0_SB_DQ(14)    I22 @T6G_MB_LIB.T6G(SCH_1):PAGE96
   265 M_L_CPU0_SB_DQ<15> @T6G_MB_LIB.T6G(SCH_1):M_L_CPU0_SB_DQ(15)    I22 @T6G_MB_LIB.T6G(SCH_1):PAGE96
   122 M_L_CPU0_SB_DQ<16> @T6G_MB_LIB.T6G(SCH_1):M_L_CPU0_SB_DQ(16)    I22 @T6G_MB_LIB.T6G(SCH_1):PAGE96
   124 M_L_CPU0_SB_DQ<17> @T6G_MB_LIB.T6G(SCH_1):M_L_CPU0_SB_DQ(17)    I22 @T6G_MB_LIB.T6G(SCH_1):PAGE96
   267 M_L_CPU0_SB_DQ<18> @T6G_MB_LIB.T6G(SCH_1):M_L_CPU0_SB_DQ(18)    I22 @T6G_MB_LIB.T6G(SCH_1):PAGE96
   269 M_L_CPU0_SB_DQ<19> @T6G_MB_LIB.T6G(SCH_1):M_L_CPU0_SB_DQ(19)    I22 @T6G_MB_LIB.T6G(SCH_1):PAGE96
   129 M_L_CPU0_SB_DQ<20> @T6G_MB_LIB.T6G(SCH_1):M_L_CPU0_SB_DQ(20)    I22 @T6G_MB_LIB.T6G(SCH_1):PAGE96
   131 M_L_CPU0_SB_DQ<21> @T6G_MB_LIB.T6G(SCH_1):M_L_CPU0_SB_DQ(21)    I22 @T6G_MB_LIB.T6G(SCH_1):PAGE96
   274 M_L_CPU0_SB_DQ<22> @T6G_MB_LIB.T6G(SCH_1):M_L_CPU0_SB_DQ(22)    I22 @T6G_MB_LIB.T6G(SCH_1):PAGE96
   276 M_L_CPU0_SB_DQ<23> @T6G_MB_LIB.T6G(SCH_1):M_L_CPU0_SB_DQ(23)    I22 @T6G_MB_LIB.T6G(SCH_1):PAGE96
   133 M_L_CPU0_SB_DQ<24> @T6G_MB_LIB.T6G(SCH_1):M_L_CPU0_SB_DQ(24)    I22 @T6G_MB_LIB.T6G(SCH_1):PAGE96
   135 M_L_CPU0_SB_DQ<25> @T6G_MB_LIB.T6G(SCH_1):M_L_CPU0_SB_DQ(25)    I22 @T6G_MB_LIB.T6G(SCH_1):PAGE96
   278 M_L_CPU0_SB_DQ<26> @T6G_MB_LIB.T6G(SCH_1):M_L_CPU0_SB_DQ(26)    I22 @T6G_MB_LIB.T6G(SCH_1):PAGE96
   280 M_L_CPU0_SB_DQ<27> @T6G_MB_LIB.T6G(SCH_1):M_L_CPU0_SB_DQ(27)    I22 @T6G_MB_LIB.T6G(SCH_1):PAGE96
   140 M_L_CPU0_SB_DQ<28> @T6G_MB_LIB.T6G(SCH_1):M_L_CPU0_SB_DQ(28)    I22 @T6G_MB_LIB.T6G(SCH_1):PAGE96
   142 M_L_CPU0_SB_DQ<29> @T6G_MB_LIB.T6G(SCH_1):M_L_CPU0_SB_DQ(29)    I22 @T6G_MB_LIB.T6G(SCH_1):PAGE96
   285 M_L_CPU0_SB_DQ<30> @T6G_MB_LIB.T6G(SCH_1):M_L_CPU0_SB_DQ(30)    I22 @T6G_MB_LIB.T6G(SCH_1):PAGE96
   287 M_L_CPU0_SB_DQ<31> @T6G_MB_LIB.T6G(SCH_1):M_L_CPU0_SB_DQ(31)    I22 @T6G_MB_LIB.T6G(SCH_1):PAGE96
     7 M_L_CPU0_SA_DQ<0> @T6G_MB_LIB.T6G(SCH_1):M_L_CPU0_SA_DQ(0)    I22 @T6G_MB_LIB.T6G(SCH_1):PAGE96
     9 M_L_CPU0_SA_DQ<1> @T6G_MB_LIB.T6G(SCH_1):M_L_CPU0_SA_DQ(1)    I22 @T6G_MB_LIB.T6G(SCH_1):PAGE96
   152 M_L_CPU0_SA_DQ<2> @T6G_MB_LIB.T6G(SCH_1):M_L_CPU0_SA_DQ(2)    I22 @T6G_MB_LIB.T6G(SCH_1):PAGE96
   154 M_L_CPU0_SA_DQ<3> @T6G_MB_LIB.T6G(SCH_1):M_L_CPU0_SA_DQ(3)    I22 @T6G_MB_LIB.T6G(SCH_1):PAGE96
    14 M_L_CPU0_SA_DQ<4> @T6G_MB_LIB.T6G(SCH_1):M_L_CPU0_SA_DQ(4)    I22 @T6G_MB_LIB.T6G(SCH_1):PAGE96
    16 M_L_CPU0_SA_DQ<5> @T6G_MB_LIB.T6G(SCH_1):M_L_CPU0_SA_DQ(5)    I22 @T6G_MB_LIB.T6G(SCH_1):PAGE96
   159 M_L_CPU0_SA_DQ<6> @T6G_MB_LIB.T6G(SCH_1):M_L_CPU0_SA_DQ(6)    I22 @T6G_MB_LIB.T6G(SCH_1):PAGE96
   161 M_L_CPU0_SA_DQ<7> @T6G_MB_LIB.T6G(SCH_1):M_L_CPU0_SA_DQ(7)    I22 @T6G_MB_LIB.T6G(SCH_1):PAGE96
    18 M_L_CPU0_SA_DQ<8> @T6G_MB_LIB.T6G(SCH_1):M_L_CPU0_SA_DQ(8)    I22 @T6G_MB_LIB.T6G(SCH_1):PAGE96
    20 M_L_CPU0_SA_DQ<9> @T6G_MB_LIB.T6G(SCH_1):M_L_CPU0_SA_DQ(9)    I22 @T6G_MB_LIB.T6G(SCH_1):PAGE96
   163 M_L_CPU0_SA_DQ<10> @T6G_MB_LIB.T6G(SCH_1):M_L_CPU0_SA_DQ(10)    I22 @T6G_MB_LIB.T6G(SCH_1):PAGE96
   165 M_L_CPU0_SA_DQ<11> @T6G_MB_LIB.T6G(SCH_1):M_L_CPU0_SA_DQ(11)    I22 @T6G_MB_LIB.T6G(SCH_1):PAGE96
    25 M_L_CPU0_SA_DQ<12> @T6G_MB_LIB.T6G(SCH_1):M_L_CPU0_SA_DQ(12)    I22 @T6G_MB_LIB.T6G(SCH_1):PAGE96
    27 M_L_CPU0_SA_DQ<13> @T6G_MB_LIB.T6G(SCH_1):M_L_CPU0_SA_DQ(13)    I22 @T6G_MB_LIB.T6G(SCH_1):PAGE96
   170 M_L_CPU0_SA_DQ<14> @T6G_MB_LIB.T6G(SCH_1):M_L_CPU0_SA_DQ(14)    I22 @T6G_MB_LIB.T6G(SCH_1):PAGE96
   172 M_L_CPU0_SA_DQ<15> @T6G_MB_LIB.T6G(SCH_1):M_L_CPU0_SA_DQ(15)    I22 @T6G_MB_LIB.T6G(SCH_1):PAGE96
    29 M_L_CPU0_SA_DQ<16> @T6G_MB_LIB.T6G(SCH_1):M_L_CPU0_SA_DQ(16)    I22 @T6G_MB_LIB.T6G(SCH_1):PAGE96
    31 M_L_CPU0_SA_DQ<17> @T6G_MB_LIB.T6G(SCH_1):M_L_CPU0_SA_DQ(17)    I22 @T6G_MB_LIB.T6G(SCH_1):PAGE96
   174 M_L_CPU0_SA_DQ<18> @T6G_MB_LIB.T6G(SCH_1):M_L_CPU0_SA_DQ(18)    I22 @T6G_MB_LIB.T6G(SCH_1):PAGE96
   176 M_L_CPU0_SA_DQ<19> @T6G_MB_LIB.T6G(SCH_1):M_L_CPU0_SA_DQ(19)    I22 @T6G_MB_LIB.T6G(SCH_1):PAGE96
    36 M_L_CPU0_SA_DQ<20> @T6G_MB_LIB.T6G(SCH_1):M_L_CPU0_SA_DQ(20)    I22 @T6G_MB_LIB.T6G(SCH_1):PAGE96
    38 M_L_CPU0_SA_DQ<21> @T6G_MB_LIB.T6G(SCH_1):M_L_CPU0_SA_DQ(21)    I22 @T6G_MB_LIB.T6G(SCH_1):PAGE96
   181 M_L_CPU0_SA_DQ<22> @T6G_MB_LIB.T6G(SCH_1):M_L_CPU0_SA_DQ(22)    I22 @T6G_MB_LIB.T6G(SCH_1):PAGE96
   183 M_L_CPU0_SA_DQ<23> @T6G_MB_LIB.T6G(SCH_1):M_L_CPU0_SA_DQ(23)    I22 @T6G_MB_LIB.T6G(SCH_1):PAGE96
    40 M_L_CPU0_SA_DQ<24> @T6G_MB_LIB.T6G(SCH_1):M_L_CPU0_SA_DQ(24)    I22 @T6G_MB_LIB.T6G(SCH_1):PAGE96
    42 M_L_CPU0_SA_DQ<25> @T6G_MB_LIB.T6G(SCH_1):M_L_CPU0_SA_DQ(25)    I22 @T6G_MB_LIB.T6G(SCH_1):PAGE96
   185 M_L_CPU0_SA_DQ<26> @T6G_MB_LIB.T6G(SCH_1):M_L_CPU0_SA_DQ(26)    I22 @T6G_MB_LIB.T6G(SCH_1):PAGE96
   187 M_L_CPU0_SA_DQ<27> @T6G_MB_LIB.T6G(SCH_1):M_L_CPU0_SA_DQ(27)    I22 @T6G_MB_LIB.T6G(SCH_1):PAGE96
    47 M_L_CPU0_SA_DQ<28> @T6G_MB_LIB.T6G(SCH_1):M_L_CPU0_SA_DQ(28)    I22 @T6G_MB_LIB.T6G(SCH_1):PAGE96
    49 M_L_CPU0_SA_DQ<29> @T6G_MB_LIB.T6G(SCH_1):M_L_CPU0_SA_DQ(29)    I22 @T6G_MB_LIB.T6G(SCH_1):PAGE96
   192 M_L_CPU0_SA_DQ<30> @T6G_MB_LIB.T6G(SCH_1):M_L_CPU0_SA_DQ(30)    I22 @T6G_MB_LIB.T6G(SCH_1):PAGE96
   229 M_L_CPU0_SB_CS_N<1> @T6G_MB_LIB.T6G(SCH_1):M_L_CPU0_SB_CS_N(1)    I22 @T6G_MB_LIB.T6G(SCH_1):PAGE96
   209 M_L_CPU0_SA_CS_N<1> @T6G_MB_LIB.T6G(SCH_1):M_L_CPU0_SA_CS_N(1)    I22 @T6G_MB_LIB.T6G(SCH_1):PAGE96
    84 M_L_CPU0_SB_CS_N<0> @T6G_MB_LIB.T6G(SCH_1):M_L_CPU0_SB_CS_N(0)    I22 @T6G_MB_LIB.T6G(SCH_1):PAGE96
    64 M_L_CPU0_SA_CS_N<0> @T6G_MB_LIB.T6G(SCH_1):M_L_CPU0_SA_CS_N(0)    I22 @T6G_MB_LIB.T6G(SCH_1):PAGE96
   217 M_L_CPU0_CLK_DP<0> @T6G_MB_LIB.T6G(SCH_1):M_L_CPU0_CLK_DP(0)    I22 @T6G_MB_LIB.T6G(SCH_1):PAGE96
   218 M_L_CPU0_CLK_DN<0> @T6G_MB_LIB.T6G(SCH_1):M_L_CPU0_CLK_DN(0)    I22 @T6G_MB_LIB.T6G(SCH_1):PAGE96
    96 M_L_CPU0_SB_CB<0> @T6G_MB_LIB.T6G(SCH_1):M_L_CPU0_SB_CB(0)    I22 @T6G_MB_LIB.T6G(SCH_1):PAGE96
    98 M_L_CPU0_SB_CB<1> @T6G_MB_LIB.T6G(SCH_1):M_L_CPU0_SB_CB(1)    I22 @T6G_MB_LIB.T6G(SCH_1):PAGE96
   241 M_L_CPU0_SB_CB<2> @T6G_MB_LIB.T6G(SCH_1):M_L_CPU0_SB_CB(2)    I22 @T6G_MB_LIB.T6G(SCH_1):PAGE96
   243 M_L_CPU0_SB_CB<3> @T6G_MB_LIB.T6G(SCH_1):M_L_CPU0_SB_CB(3)    I22 @T6G_MB_LIB.T6G(SCH_1):PAGE96
    89 M_L_CPU0_SB_CB<4> @T6G_MB_LIB.T6G(SCH_1):M_L_CPU0_SB_CB(4)    I22 @T6G_MB_LIB.T6G(SCH_1):PAGE96
    91 M_L_CPU0_SB_CB<5> @T6G_MB_LIB.T6G(SCH_1):M_L_CPU0_SB_CB(5)    I22 @T6G_MB_LIB.T6G(SCH_1):PAGE96
   234 M_L_CPU0_SB_CB<6> @T6G_MB_LIB.T6G(SCH_1):M_L_CPU0_SB_CB(6)    I22 @T6G_MB_LIB.T6G(SCH_1):PAGE96
    51 M_L_CPU0_SA_CB<0> @T6G_MB_LIB.T6G(SCH_1):M_L_CPU0_SA_CB(0)    I22 @T6G_MB_LIB.T6G(SCH_1):PAGE96
   196 M_L_CPU0_SA_CB<2> @T6G_MB_LIB.T6G(SCH_1):M_L_CPU0_SA_CB(2)    I22 @T6G_MB_LIB.T6G(SCH_1):PAGE96
   198 M_L_CPU0_SA_CB<3> @T6G_MB_LIB.T6G(SCH_1):M_L_CPU0_SA_CB(3)    I22 @T6G_MB_LIB.T6G(SCH_1):PAGE96
    60 M_L_CPU0_SA_CB<5> @T6G_MB_LIB.T6G(SCH_1):M_L_CPU0_SA_CB(5)    I22 @T6G_MB_LIB.T6G(SCH_1):PAGE96
   203 M_L_CPU0_SA_CB<6> @T6G_MB_LIB.T6G(SCH_1):M_L_CPU0_SA_CB(6)    I22 @T6G_MB_LIB.T6G(SCH_1):PAGE96
    82 M_L_CPU0_SB_CA<6> @T6G_MB_LIB.T6G(SCH_1):M_L_CPU0_SB_CA(6)    I22 @T6G_MB_LIB.T6G(SCH_1):PAGE96
    72 M_L_CPU0_SA_CA<6> @T6G_MB_LIB.T6G(SCH_1):M_L_CPU0_SA_CA(6)    I22 @T6G_MB_LIB.T6G(SCH_1):PAGE96
   225 M_L_CPU0_SB_CA<5> @T6G_MB_LIB.T6G(SCH_1):M_L_CPU0_SB_CA(5)    I22 @T6G_MB_LIB.T6G(SCH_1):PAGE96
   215 M_L_CPU0_SA_CA<5> @T6G_MB_LIB.T6G(SCH_1):M_L_CPU0_SA_CA(5)    I22 @T6G_MB_LIB.T6G(SCH_1):PAGE96
    80 M_L_CPU0_SB_CA<4> @T6G_MB_LIB.T6G(SCH_1):M_L_CPU0_SB_CA(4)    I22 @T6G_MB_LIB.T6G(SCH_1):PAGE96
    70 M_L_CPU0_SA_CA<4> @T6G_MB_LIB.T6G(SCH_1):M_L_CPU0_SA_CA(4)    I22 @T6G_MB_LIB.T6G(SCH_1):PAGE96
   223 M_L_CPU0_SB_CA<3> @T6G_MB_LIB.T6G(SCH_1):M_L_CPU0_SB_CA(3)    I22 @T6G_MB_LIB.T6G(SCH_1):PAGE96
   213 M_L_CPU0_SA_CA<3> @T6G_MB_LIB.T6G(SCH_1):M_L_CPU0_SA_CA(3)    I22 @T6G_MB_LIB.T6G(SCH_1):PAGE96
    78 M_L_CPU0_SB_CA<2> @T6G_MB_LIB.T6G(SCH_1):M_L_CPU0_SB_CA(2)    I22 @T6G_MB_LIB.T6G(SCH_1):PAGE96
    68 M_L_CPU0_SA_CA<2> @T6G_MB_LIB.T6G(SCH_1):M_L_CPU0_SA_CA(2)    I22 @T6G_MB_LIB.T6G(SCH_1):PAGE96
   221 M_L_CPU0_SB_CA<1> @T6G_MB_LIB.T6G(SCH_1):M_L_CPU0_SB_CA(1)    I22 @T6G_MB_LIB.T6G(SCH_1):PAGE96
   211 M_L_CPU0_SA_CA<1> @T6G_MB_LIB.T6G(SCH_1):M_L_CPU0_SA_CA(1)    I22 @T6G_MB_LIB.T6G(SCH_1):PAGE96
    76 M_L_CPU0_SB_CA<0> @T6G_MB_LIB.T6G(SCH_1):M_L_CPU0_SB_CA(0)    I22 @T6G_MB_LIB.T6G(SCH_1):PAGE96
    66 M_L_CPU0_SA_CA<0> @T6G_MB_LIB.T6G(SCH_1):M_L_CPU0_SA_CA(0)    I22 @T6G_MB_LIB.T6G(SCH_1):PAGE96
    62 M_L_CPU0_ALERT_N @T6G_MB_LIB.T6G(SCH_1):M_L_CPU0_ALERT_N    I22 @T6G_MB_LIB.T6G(SCH_1):PAGE96
   236 M_L_CPU0_SB_CB<7> @T6G_MB_LIB.T6G(SCH_1):M_L_CPU0_SB_CB(7)    I22 @T6G_MB_LIB.T6G(SCH_1):PAGE96
    53 M_L_CPU0_SA_CB<1> @T6G_MB_LIB.T6G(SCH_1):M_L_CPU0_SA_CB(1)    I22 @T6G_MB_LIB.T6G(SCH_1):PAGE96
    58 M_L_CPU0_SA_CB<4> @T6G_MB_LIB.T6G(SCH_1):M_L_CPU0_SA_CB(4)    I22 @T6G_MB_LIB.T6G(SCH_1):PAGE96
   205 M_L_CPU0_SA_CB<7> @T6G_MB_LIB.T6G(SCH_1):M_L_CPU0_SA_CB(7)    I22 @T6G_MB_LIB.T6G(SCH_1):PAGE96
   194 M_L_CPU0_SA_DQ<31> @T6G_MB_LIB.T6G(SCH_1):M_L_CPU0_SA_DQ(31)    I22 @T6G_MB_LIB.T6G(SCH_1):PAGE96
    93 M_L_CPU0_SB_DQS_DP<9> @T6G_MB_LIB.T6G(SCH_1):M_L_CPU0_SB_DQS_DP(9)   I236 @T6G_MB_LIB.T6G(SCH_1):PAGE96
    94 M_L_CPU0_SB_DQS_DN<9> @T6G_MB_LIB.T6G(SCH_1):M_L_CPU0_SB_DQS_DN(9)   I236 @T6G_MB_LIB.T6G(SCH_1):PAGE96
   201 M_L_CPU0_SA_DQS_DP<9> @T6G_MB_LIB.T6G(SCH_1):M_L_CPU0_SA_DQS_DP(9)   I236 @T6G_MB_LIB.T6G(SCH_1):PAGE96
   200 M_L_CPU0_SA_DQS_DN<9> @T6G_MB_LIB.T6G(SCH_1):M_L_CPU0_SA_DQS_DN(9)   I236 @T6G_MB_LIB.T6G(SCH_1):PAGE96
   190 M_L_CPU0_SA_DQS_DP<8> @T6G_MB_LIB.T6G(SCH_1):M_L_CPU0_SA_DQS_DP(8)   I236 @T6G_MB_LIB.T6G(SCH_1):PAGE96
   189 M_L_CPU0_SA_DQS_DN<8> @T6G_MB_LIB.T6G(SCH_1):M_L_CPU0_SA_DQS_DN(8)   I236 @T6G_MB_LIB.T6G(SCH_1):PAGE96
   271 M_L_CPU0_SB_DQS_DN<7> @T6G_MB_LIB.T6G(SCH_1):M_L_CPU0_SB_DQS_DN(7)   I236 @T6G_MB_LIB.T6G(SCH_1):PAGE96
   179 M_L_CPU0_SA_DQS_DP<7> @T6G_MB_LIB.T6G(SCH_1):M_L_CPU0_SA_DQS_DP(7)   I236 @T6G_MB_LIB.T6G(SCH_1):PAGE96
   261 M_L_CPU0_SB_DQS_DP<6> @T6G_MB_LIB.T6G(SCH_1):M_L_CPU0_SB_DQS_DP(6)   I236 @T6G_MB_LIB.T6G(SCH_1):PAGE96
   260 M_L_CPU0_SB_DQS_DN<6> @T6G_MB_LIB.T6G(SCH_1):M_L_CPU0_SB_DQS_DN(6)   I236 @T6G_MB_LIB.T6G(SCH_1):PAGE96
   167 M_L_CPU0_SA_DQS_DN<6> @T6G_MB_LIB.T6G(SCH_1):M_L_CPU0_SA_DQS_DN(6)   I236 @T6G_MB_LIB.T6G(SCH_1):PAGE96
   250 M_L_CPU0_SB_DQS_DP<5> @T6G_MB_LIB.T6G(SCH_1):M_L_CPU0_SB_DQS_DP(5)   I236 @T6G_MB_LIB.T6G(SCH_1):PAGE96
   249 M_L_CPU0_SB_DQS_DN<5> @T6G_MB_LIB.T6G(SCH_1):M_L_CPU0_SB_DQS_DN(5)   I236 @T6G_MB_LIB.T6G(SCH_1):PAGE96
   157 M_L_CPU0_SA_DQS_DP<5> @T6G_MB_LIB.T6G(SCH_1):M_L_CPU0_SA_DQS_DP(5)   I236 @T6G_MB_LIB.T6G(SCH_1):PAGE96
   156 M_L_CPU0_SA_DQS_DN<5> @T6G_MB_LIB.T6G(SCH_1):M_L_CPU0_SA_DQS_DN(5)   I236 @T6G_MB_LIB.T6G(SCH_1):PAGE96
   239 M_L_CPU0_SB_DQS_DP<4> @T6G_MB_LIB.T6G(SCH_1):M_L_CPU0_SB_DQS_DP(4)   I236 @T6G_MB_LIB.T6G(SCH_1):PAGE96
   238 M_L_CPU0_SB_DQS_DN<4> @T6G_MB_LIB.T6G(SCH_1):M_L_CPU0_SB_DQS_DN(4)   I236 @T6G_MB_LIB.T6G(SCH_1):PAGE96
    55 M_L_CPU0_SA_DQS_DP<4> @T6G_MB_LIB.T6G(SCH_1):M_L_CPU0_SA_DQS_DP(4)   I236 @T6G_MB_LIB.T6G(SCH_1):PAGE96
    56 M_L_CPU0_SA_DQS_DN<4> @T6G_MB_LIB.T6G(SCH_1):M_L_CPU0_SA_DQS_DN(4)   I236 @T6G_MB_LIB.T6G(SCH_1):PAGE96
   137 M_L_CPU0_SB_DQS_DP<3> @T6G_MB_LIB.T6G(SCH_1):M_L_CPU0_SB_DQS_DP(3)   I236 @T6G_MB_LIB.T6G(SCH_1):PAGE96
   138 M_L_CPU0_SB_DQS_DN<3> @T6G_MB_LIB.T6G(SCH_1):M_L_CPU0_SB_DQS_DN(3)   I236 @T6G_MB_LIB.T6G(SCH_1):PAGE96
    44 M_L_CPU0_SA_DQS_DP<3> @T6G_MB_LIB.T6G(SCH_1):M_L_CPU0_SA_DQS_DP(3)   I236 @T6G_MB_LIB.T6G(SCH_1):PAGE96
    45 M_L_CPU0_SA_DQS_DN<3> @T6G_MB_LIB.T6G(SCH_1):M_L_CPU0_SA_DQS_DN(3)   I236 @T6G_MB_LIB.T6G(SCH_1):PAGE96
   126 M_L_CPU0_SB_DQS_DP<2> @T6G_MB_LIB.T6G(SCH_1):M_L_CPU0_SB_DQS_DP(2)   I236 @T6G_MB_LIB.T6G(SCH_1):PAGE96
   127 M_L_CPU0_SB_DQS_DN<2> @T6G_MB_LIB.T6G(SCH_1):M_L_CPU0_SB_DQS_DN(2)   I236 @T6G_MB_LIB.T6G(SCH_1):PAGE96
    33 M_L_CPU0_SA_DQS_DP<2> @T6G_MB_LIB.T6G(SCH_1):M_L_CPU0_SA_DQS_DP(2)   I236 @T6G_MB_LIB.T6G(SCH_1):PAGE96
    34 M_L_CPU0_SA_DQS_DN<2> @T6G_MB_LIB.T6G(SCH_1):M_L_CPU0_SA_DQS_DN(2)   I236 @T6G_MB_LIB.T6G(SCH_1):PAGE96
   115 M_L_CPU0_SB_DQS_DP<1> @T6G_MB_LIB.T6G(SCH_1):M_L_CPU0_SB_DQS_DP(1)   I236 @T6G_MB_LIB.T6G(SCH_1):PAGE96
   116 M_L_CPU0_SB_DQS_DN<1> @T6G_MB_LIB.T6G(SCH_1):M_L_CPU0_SB_DQS_DN(1)   I236 @T6G_MB_LIB.T6G(SCH_1):PAGE96
    22 M_L_CPU0_SA_DQS_DP<1> @T6G_MB_LIB.T6G(SCH_1):M_L_CPU0_SA_DQS_DP(1)   I236 @T6G_MB_LIB.T6G(SCH_1):PAGE96
    23 M_L_CPU0_SA_DQS_DN<1> @T6G_MB_LIB.T6G(SCH_1):M_L_CPU0_SA_DQS_DN(1)   I236 @T6G_MB_LIB.T6G(SCH_1):PAGE96
   104 M_L_CPU0_SB_DQS_DP<0> @T6G_MB_LIB.T6G(SCH_1):M_L_CPU0_SB_DQS_DP(0)   I236 @T6G_MB_LIB.T6G(SCH_1):PAGE96
   105 M_L_CPU0_SB_DQS_DN<0> @T6G_MB_LIB.T6G(SCH_1):M_L_CPU0_SB_DQS_DN(0)   I236 @T6G_MB_LIB.T6G(SCH_1):PAGE96
    11 M_L_CPU0_SA_DQS_DP<0> @T6G_MB_LIB.T6G(SCH_1):M_L_CPU0_SA_DQS_DP(0)   I236 @T6G_MB_LIB.T6G(SCH_1):PAGE96
    12 M_L_CPU0_SA_DQS_DN<0> @T6G_MB_LIB.T6G(SCH_1):M_L_CPU0_SA_DQS_DN(0)   I236 @T6G_MB_LIB.T6G(SCH_1):PAGE96
   272 M_L_CPU0_SB_DQS_DP<7> @T6G_MB_LIB.T6G(SCH_1):M_L_CPU0_SB_DQS_DP(7)   I236 @T6G_MB_LIB.T6G(SCH_1):PAGE96
   282 M_L_CPU0_SB_DQS_DN<8> @T6G_MB_LIB.T6G(SCH_1):M_L_CPU0_SB_DQS_DN(8)   I236 @T6G_MB_LIB.T6G(SCH_1):PAGE96
   283 M_L_CPU0_SB_DQS_DP<8> @T6G_MB_LIB.T6G(SCH_1):M_L_CPU0_SB_DQS_DP(8)   I236 @T6G_MB_LIB.T6G(SCH_1):PAGE96
   168 M_L_CPU0_SA_DQS_DP<6> @T6G_MB_LIB.T6G(SCH_1):M_L_CPU0_SA_DQS_DP(6)   I236 @T6G_MB_LIB.T6G(SCH_1):PAGE96
   178 M_L_CPU0_SA_DQS_DN<7> @T6G_MB_LIB.T6G(SCH_1):M_L_CPU0_SA_DQS_DN(7)   I236 @T6G_MB_LIB.T6G(SCH_1):PAGE96
     6    GND @T6G_MB_LIB.T6G(SCH_1):GND   I140 @T6G_MB_LIB.T6G(SCH_1):PAGE96
     8    GND @T6G_MB_LIB.T6G(SCH_1):GND   I140 @T6G_MB_LIB.T6G(SCH_1):PAGE96
    10    GND @T6G_MB_LIB.T6G(SCH_1):GND   I140 @T6G_MB_LIB.T6G(SCH_1):PAGE96
    13    GND @T6G_MB_LIB.T6G(SCH_1):GND   I140 @T6G_MB_LIB.T6G(SCH_1):PAGE96
    15    GND @T6G_MB_LIB.T6G(SCH_1):GND   I140 @T6G_MB_LIB.T6G(SCH_1):PAGE96
    17    GND @T6G_MB_LIB.T6G(SCH_1):GND   I140 @T6G_MB_LIB.T6G(SCH_1):PAGE96
    19    GND @T6G_MB_LIB.T6G(SCH_1):GND   I140 @T6G_MB_LIB.T6G(SCH_1):PAGE96
    21    GND @T6G_MB_LIB.T6G(SCH_1):GND   I140 @T6G_MB_LIB.T6G(SCH_1):PAGE96
    24    GND @T6G_MB_LIB.T6G(SCH_1):GND   I140 @T6G_MB_LIB.T6G(SCH_1):PAGE96
    26    GND @T6G_MB_LIB.T6G(SCH_1):GND   I140 @T6G_MB_LIB.T6G(SCH_1):PAGE96
    28    GND @T6G_MB_LIB.T6G(SCH_1):GND   I140 @T6G_MB_LIB.T6G(SCH_1):PAGE96
    30    GND @T6G_MB_LIB.T6G(SCH_1):GND   I140 @T6G_MB_LIB.T6G(SCH_1):PAGE96
    32    GND @T6G_MB_LIB.T6G(SCH_1):GND   I140 @T6G_MB_LIB.T6G(SCH_1):PAGE96
    35    GND @T6G_MB_LIB.T6G(SCH_1):GND   I140 @T6G_MB_LIB.T6G(SCH_1):PAGE96
    37    GND @T6G_MB_LIB.T6G(SCH_1):GND   I140 @T6G_MB_LIB.T6G(SCH_1):PAGE96
    39    GND @T6G_MB_LIB.T6G(SCH_1):GND   I140 @T6G_MB_LIB.T6G(SCH_1):PAGE96
    41    GND @T6G_MB_LIB.T6G(SCH_1):GND   I140 @T6G_MB_LIB.T6G(SCH_1):PAGE96
    43    GND @T6G_MB_LIB.T6G(SCH_1):GND   I140 @T6G_MB_LIB.T6G(SCH_1):PAGE96
    46    GND @T6G_MB_LIB.T6G(SCH_1):GND   I140 @T6G_MB_LIB.T6G(SCH_1):PAGE96
    48    GND @T6G_MB_LIB.T6G(SCH_1):GND   I140 @T6G_MB_LIB.T6G(SCH_1):PAGE96
    50    GND @T6G_MB_LIB.T6G(SCH_1):GND   I140 @T6G_MB_LIB.T6G(SCH_1):PAGE96
    52    GND @T6G_MB_LIB.T6G(SCH_1):GND   I140 @T6G_MB_LIB.T6G(SCH_1):PAGE96
    54    GND @T6G_MB_LIB.T6G(SCH_1):GND   I140 @T6G_MB_LIB.T6G(SCH_1):PAGE96
    57    GND @T6G_MB_LIB.T6G(SCH_1):GND   I140 @T6G_MB_LIB.T6G(SCH_1):PAGE96
    59    GND @T6G_MB_LIB.T6G(SCH_1):GND   I140 @T6G_MB_LIB.T6G(SCH_1):PAGE96
    61    GND @T6G_MB_LIB.T6G(SCH_1):GND   I140 @T6G_MB_LIB.T6G(SCH_1):PAGE96
    63    GND @T6G_MB_LIB.T6G(SCH_1):GND   I140 @T6G_MB_LIB.T6G(SCH_1):PAGE96
    65    GND @T6G_MB_LIB.T6G(SCH_1):GND   I140 @T6G_MB_LIB.T6G(SCH_1):PAGE96
    67    GND @T6G_MB_LIB.T6G(SCH_1):GND   I140 @T6G_MB_LIB.T6G(SCH_1):PAGE96
    69    GND @T6G_MB_LIB.T6G(SCH_1):GND   I140 @T6G_MB_LIB.T6G(SCH_1):PAGE96
    71    GND @T6G_MB_LIB.T6G(SCH_1):GND   I140 @T6G_MB_LIB.T6G(SCH_1):PAGE96
    73    GND @T6G_MB_LIB.T6G(SCH_1):GND   I140 @T6G_MB_LIB.T6G(SCH_1):PAGE96
    75    GND @T6G_MB_LIB.T6G(SCH_1):GND   I140 @T6G_MB_LIB.T6G(SCH_1):PAGE96
    77    GND @T6G_MB_LIB.T6G(SCH_1):GND   I140 @T6G_MB_LIB.T6G(SCH_1):PAGE96
    79    GND @T6G_MB_LIB.T6G(SCH_1):GND   I140 @T6G_MB_LIB.T6G(SCH_1):PAGE96
    81    GND @T6G_MB_LIB.T6G(SCH_1):GND   I140 @T6G_MB_LIB.T6G(SCH_1):PAGE96
    83    GND @T6G_MB_LIB.T6G(SCH_1):GND   I140 @T6G_MB_LIB.T6G(SCH_1):PAGE96
    85    GND @T6G_MB_LIB.T6G(SCH_1):GND   I140 @T6G_MB_LIB.T6G(SCH_1):PAGE96
    88    GND @T6G_MB_LIB.T6G(SCH_1):GND   I140 @T6G_MB_LIB.T6G(SCH_1):PAGE96
    90    GND @T6G_MB_LIB.T6G(SCH_1):GND   I140 @T6G_MB_LIB.T6G(SCH_1):PAGE96
    92    GND @T6G_MB_LIB.T6G(SCH_1):GND   I140 @T6G_MB_LIB.T6G(SCH_1):PAGE96
    95    GND @T6G_MB_LIB.T6G(SCH_1):GND   I140 @T6G_MB_LIB.T6G(SCH_1):PAGE96
    97    GND @T6G_MB_LIB.T6G(SCH_1):GND   I140 @T6G_MB_LIB.T6G(SCH_1):PAGE96
    99    GND @T6G_MB_LIB.T6G(SCH_1):GND   I140 @T6G_MB_LIB.T6G(SCH_1):PAGE96
   101    GND @T6G_MB_LIB.T6G(SCH_1):GND   I140 @T6G_MB_LIB.T6G(SCH_1):PAGE96
   103    GND @T6G_MB_LIB.T6G(SCH_1):GND   I140 @T6G_MB_LIB.T6G(SCH_1):PAGE96
   106    GND @T6G_MB_LIB.T6G(SCH_1):GND   I140 @T6G_MB_LIB.T6G(SCH_1):PAGE96
   108    GND @T6G_MB_LIB.T6G(SCH_1):GND   I140 @T6G_MB_LIB.T6G(SCH_1):PAGE96
   110    GND @T6G_MB_LIB.T6G(SCH_1):GND   I140 @T6G_MB_LIB.T6G(SCH_1):PAGE96
   112    GND @T6G_MB_LIB.T6G(SCH_1):GND   I140 @T6G_MB_LIB.T6G(SCH_1):PAGE96
   114    GND @T6G_MB_LIB.T6G(SCH_1):GND   I140 @T6G_MB_LIB.T6G(SCH_1):PAGE96
   117    GND @T6G_MB_LIB.T6G(SCH_1):GND   I140 @T6G_MB_LIB.T6G(SCH_1):PAGE96
   119    GND @T6G_MB_LIB.T6G(SCH_1):GND   I140 @T6G_MB_LIB.T6G(SCH_1):PAGE96
   121    GND @T6G_MB_LIB.T6G(SCH_1):GND   I140 @T6G_MB_LIB.T6G(SCH_1):PAGE96
   123    GND @T6G_MB_LIB.T6G(SCH_1):GND   I140 @T6G_MB_LIB.T6G(SCH_1):PAGE96
   125    GND @T6G_MB_LIB.T6G(SCH_1):GND   I140 @T6G_MB_LIB.T6G(SCH_1):PAGE96
   128    GND @T6G_MB_LIB.T6G(SCH_1):GND   I140 @T6G_MB_LIB.T6G(SCH_1):PAGE96
   130    GND @T6G_MB_LIB.T6G(SCH_1):GND   I140 @T6G_MB_LIB.T6G(SCH_1):PAGE96
   134    GND @T6G_MB_LIB.T6G(SCH_1):GND   I140 @T6G_MB_LIB.T6G(SCH_1):PAGE96
   143    GND @T6G_MB_LIB.T6G(SCH_1):GND   I140 @T6G_MB_LIB.T6G(SCH_1):PAGE96
   151    GND @T6G_MB_LIB.T6G(SCH_1):GND   I140 @T6G_MB_LIB.T6G(SCH_1):PAGE96
   153    GND @T6G_MB_LIB.T6G(SCH_1):GND   I140 @T6G_MB_LIB.T6G(SCH_1):PAGE96
   155    GND @T6G_MB_LIB.T6G(SCH_1):GND   I140 @T6G_MB_LIB.T6G(SCH_1):PAGE96
   158    GND @T6G_MB_LIB.T6G(SCH_1):GND   I140 @T6G_MB_LIB.T6G(SCH_1):PAGE96
   160    GND @T6G_MB_LIB.T6G(SCH_1):GND   I140 @T6G_MB_LIB.T6G(SCH_1):PAGE96
   162    GND @T6G_MB_LIB.T6G(SCH_1):GND   I140 @T6G_MB_LIB.T6G(SCH_1):PAGE96
   164    GND @T6G_MB_LIB.T6G(SCH_1):GND   I140 @T6G_MB_LIB.T6G(SCH_1):PAGE96
   166    GND @T6G_MB_LIB.T6G(SCH_1):GND   I140 @T6G_MB_LIB.T6G(SCH_1):PAGE96
   169    GND @T6G_MB_LIB.T6G(SCH_1):GND   I140 @T6G_MB_LIB.T6G(SCH_1):PAGE96
   171    GND @T6G_MB_LIB.T6G(SCH_1):GND   I140 @T6G_MB_LIB.T6G(SCH_1):PAGE96
   173    GND @T6G_MB_LIB.T6G(SCH_1):GND   I140 @T6G_MB_LIB.T6G(SCH_1):PAGE96
   175    GND @T6G_MB_LIB.T6G(SCH_1):GND   I140 @T6G_MB_LIB.T6G(SCH_1):PAGE96
   177    GND @T6G_MB_LIB.T6G(SCH_1):GND   I140 @T6G_MB_LIB.T6G(SCH_1):PAGE96
   180    GND @T6G_MB_LIB.T6G(SCH_1):GND   I140 @T6G_MB_LIB.T6G(SCH_1):PAGE96
   182    GND @T6G_MB_LIB.T6G(SCH_1):GND   I140 @T6G_MB_LIB.T6G(SCH_1):PAGE96
   184    GND @T6G_MB_LIB.T6G(SCH_1):GND   I140 @T6G_MB_LIB.T6G(SCH_1):PAGE96
   186    GND @T6G_MB_LIB.T6G(SCH_1):GND   I140 @T6G_MB_LIB.T6G(SCH_1):PAGE96
   188    GND @T6G_MB_LIB.T6G(SCH_1):GND   I140 @T6G_MB_LIB.T6G(SCH_1):PAGE96
   191    GND @T6G_MB_LIB.T6G(SCH_1):GND   I140 @T6G_MB_LIB.T6G(SCH_1):PAGE96
   193    GND @T6G_MB_LIB.T6G(SCH_1):GND   I140 @T6G_MB_LIB.T6G(SCH_1):PAGE96
   195    GND @T6G_MB_LIB.T6G(SCH_1):GND   I140 @T6G_MB_LIB.T6G(SCH_1):PAGE96
   197    GND @T6G_MB_LIB.T6G(SCH_1):GND   I140 @T6G_MB_LIB.T6G(SCH_1):PAGE96
   199    GND @T6G_MB_LIB.T6G(SCH_1):GND   I140 @T6G_MB_LIB.T6G(SCH_1):PAGE96
   202    GND @T6G_MB_LIB.T6G(SCH_1):GND   I140 @T6G_MB_LIB.T6G(SCH_1):PAGE96
   204    GND @T6G_MB_LIB.T6G(SCH_1):GND   I140 @T6G_MB_LIB.T6G(SCH_1):PAGE96
   206    GND @T6G_MB_LIB.T6G(SCH_1):GND   I140 @T6G_MB_LIB.T6G(SCH_1):PAGE96
   208    GND @T6G_MB_LIB.T6G(SCH_1):GND   I140 @T6G_MB_LIB.T6G(SCH_1):PAGE96
   210    GND @T6G_MB_LIB.T6G(SCH_1):GND   I140 @T6G_MB_LIB.T6G(SCH_1):PAGE96
   212    GND @T6G_MB_LIB.T6G(SCH_1):GND   I140 @T6G_MB_LIB.T6G(SCH_1):PAGE96
   214    GND @T6G_MB_LIB.T6G(SCH_1):GND   I140 @T6G_MB_LIB.T6G(SCH_1):PAGE96
   216    GND @T6G_MB_LIB.T6G(SCH_1):GND   I140 @T6G_MB_LIB.T6G(SCH_1):PAGE96
   219    GND @T6G_MB_LIB.T6G(SCH_1):GND   I140 @T6G_MB_LIB.T6G(SCH_1):PAGE96
   222    GND @T6G_MB_LIB.T6G(SCH_1):GND   I140 @T6G_MB_LIB.T6G(SCH_1):PAGE96
   224    GND @T6G_MB_LIB.T6G(SCH_1):GND   I140 @T6G_MB_LIB.T6G(SCH_1):PAGE96
   226    GND @T6G_MB_LIB.T6G(SCH_1):GND   I140 @T6G_MB_LIB.T6G(SCH_1):PAGE96
   228    GND @T6G_MB_LIB.T6G(SCH_1):GND   I140 @T6G_MB_LIB.T6G(SCH_1):PAGE96
   233    GND @T6G_MB_LIB.T6G(SCH_1):GND   I140 @T6G_MB_LIB.T6G(SCH_1):PAGE96
   237    GND @T6G_MB_LIB.T6G(SCH_1):GND   I140 @T6G_MB_LIB.T6G(SCH_1):PAGE96
   242    GND @T6G_MB_LIB.T6G(SCH_1):GND   I140 @T6G_MB_LIB.T6G(SCH_1):PAGE96
   244    GND @T6G_MB_LIB.T6G(SCH_1):GND   I140 @T6G_MB_LIB.T6G(SCH_1):PAGE96
   246    GND @T6G_MB_LIB.T6G(SCH_1):GND   I140 @T6G_MB_LIB.T6G(SCH_1):PAGE96
   248    GND @T6G_MB_LIB.T6G(SCH_1):GND   I140 @T6G_MB_LIB.T6G(SCH_1):PAGE96
   251    GND @T6G_MB_LIB.T6G(SCH_1):GND   I140 @T6G_MB_LIB.T6G(SCH_1):PAGE96
   253    GND @T6G_MB_LIB.T6G(SCH_1):GND   I140 @T6G_MB_LIB.T6G(SCH_1):PAGE96
   255    GND @T6G_MB_LIB.T6G(SCH_1):GND   I140 @T6G_MB_LIB.T6G(SCH_1):PAGE96
   257    GND @T6G_MB_LIB.T6G(SCH_1):GND   I140 @T6G_MB_LIB.T6G(SCH_1):PAGE96
   259    GND @T6G_MB_LIB.T6G(SCH_1):GND   I140 @T6G_MB_LIB.T6G(SCH_1):PAGE96
   262    GND @T6G_MB_LIB.T6G(SCH_1):GND   I140 @T6G_MB_LIB.T6G(SCH_1):PAGE96
   264    GND @T6G_MB_LIB.T6G(SCH_1):GND   I140 @T6G_MB_LIB.T6G(SCH_1):PAGE96
   266    GND @T6G_MB_LIB.T6G(SCH_1):GND   I140 @T6G_MB_LIB.T6G(SCH_1):PAGE96
   268    GND @T6G_MB_LIB.T6G(SCH_1):GND   I140 @T6G_MB_LIB.T6G(SCH_1):PAGE96
   270    GND @T6G_MB_LIB.T6G(SCH_1):GND   I140 @T6G_MB_LIB.T6G(SCH_1):PAGE96
   273    GND @T6G_MB_LIB.T6G(SCH_1):GND   I140 @T6G_MB_LIB.T6G(SCH_1):PAGE96
   275    GND @T6G_MB_LIB.T6G(SCH_1):GND   I140 @T6G_MB_LIB.T6G(SCH_1):PAGE96
   277    GND @T6G_MB_LIB.T6G(SCH_1):GND   I140 @T6G_MB_LIB.T6G(SCH_1):PAGE96
   279    GND @T6G_MB_LIB.T6G(SCH_1):GND   I140 @T6G_MB_LIB.T6G(SCH_1):PAGE96
   281    GND @T6G_MB_LIB.T6G(SCH_1):GND   I140 @T6G_MB_LIB.T6G(SCH_1):PAGE96
   284    GND @T6G_MB_LIB.T6G(SCH_1):GND   I140 @T6G_MB_LIB.T6G(SCH_1):PAGE96
   286    GND @T6G_MB_LIB.T6G(SCH_1):GND   I140 @T6G_MB_LIB.T6G(SCH_1):PAGE96
   288    GND @T6G_MB_LIB.T6G(SCH_1):GND   I140 @T6G_MB_LIB.T6G(SCH_1):PAGE96
     1 P12V_MEM_CPU0 @T6G_MB_LIB.T6G(SCH_1):P12V_MEM_CPU0   I140 @T6G_MB_LIB.T6G(SCH_1):PAGE96
   145 P12V_MEM_CPU0 @T6G_MB_LIB.T6G(SCH_1):P12V_MEM_CPU0   I140 @T6G_MB_LIB.T6G(SCH_1):PAGE96
   146 P12V_MEM_CPU0 @T6G_MB_LIB.T6G(SCH_1):P12V_MEM_CPU0   I140 @T6G_MB_LIB.T6G(SCH_1):PAGE96
   230    GND @T6G_MB_LIB.T6G(SCH_1):GND   I140 @T6G_MB_LIB.T6G(SCH_1):PAGE96
   235    GND @T6G_MB_LIB.T6G(SCH_1):GND   I140 @T6G_MB_LIB.T6G(SCH_1):PAGE96
   240    GND @T6G_MB_LIB.T6G(SCH_1):GND   I140 @T6G_MB_LIB.T6G(SCH_1):PAGE96
   132    GND @T6G_MB_LIB.T6G(SCH_1):GND   I140 @T6G_MB_LIB.T6G(SCH_1):PAGE96
   136    GND @T6G_MB_LIB.T6G(SCH_1):GND   I140 @T6G_MB_LIB.T6G(SCH_1):PAGE96
   139    GND @T6G_MB_LIB.T6G(SCH_1):GND   I140 @T6G_MB_LIB.T6G(SCH_1):PAGE96
   141    GND @T6G_MB_LIB.T6G(SCH_1):GND   I140 @T6G_MB_LIB.T6G(SCH_1):PAGE96
    G1    GND @T6G_MB_LIB.T6G(SCH_1):GND   I140 @T6G_MB_LIB.T6G(SCH_1):PAGE96
    G2    GND @T6G_MB_LIB.T6G(SCH_1):GND   I140 @T6G_MB_LIB.T6G(SCH_1):PAGE96
    G3    GND @T6G_MB_LIB.T6G(SCH_1):GND   I140 @T6G_MB_LIB.T6G(SCH_1):PAGE96

 J68 SCONN288_DDR506112002KQ-SCONN288_DDR506112002KQ,SMA
     3 P3V3_AUX @T6G_MB_LIB.T6G(SCH_1):P3V3_AUX    I22 @T6G_MB_LIB.T6G(SCH_1):PAGE94
     2     NC     NC    I22 @T6G_MB_LIB.T6G(SCH_1):PAGE94
   144     NC     NC    I22 @T6G_MB_LIB.T6G(SCH_1):PAGE94
   149     NC     NC    I22 @T6G_MB_LIB.T6G(SCH_1):PAGE94
   150     NC     NC    I22 @T6G_MB_LIB.T6G(SCH_1):PAGE94
   220     NC     NC    I22 @T6G_MB_LIB.T6G(SCH_1):PAGE94
   231     NC     NC    I22 @T6G_MB_LIB.T6G(SCH_1):PAGE94
   232     NC     NC    I22 @T6G_MB_LIB.T6G(SCH_1):PAGE94
   207 M_J_CPU0_RESET_N @T6G_MB_LIB.T6G(SCH_1):M_J_CPU0_RESET_N    I22 @T6G_MB_LIB.T6G(SCH_1):PAGE94
   147 PWRGD_CHJ_CPU0_DIMM @T6G_MB_LIB.T6G(SCH_1):PWRGD_CHJ_CPU0_DIMM    I22 @T6G_MB_LIB.T6G(SCH_1):PAGE94
   227 M_J_CPU0_SB_PAR @T6G_MB_LIB.T6G(SCH_1):M_J_CPU0_SB_PAR    I22 @T6G_MB_LIB.T6G(SCH_1):PAGE94
    74 M_J_CPU0_SA_PAR @T6G_MB_LIB.T6G(SCH_1):M_J_CPU0_SA_PAR    I22 @T6G_MB_LIB.T6G(SCH_1):PAGE94
    87 M_J_CPU0_SB_RSP<0> @T6G_MB_LIB.T6G(SCH_1):M_J_CPU0_SB_RSP(0)    I22 @T6G_MB_LIB.T6G(SCH_1):PAGE94
    86 M_J_CPU0_SA_RSP<0> @T6G_MB_LIB.T6G(SCH_1):M_J_CPU0_SA_RSP(0)    I22 @T6G_MB_LIB.T6G(SCH_1):PAGE94
     5 I3C_SPD_DDRJ_CPU0_SDA @T6G_MB_LIB.T6G(SCH_1):I3C_SPD_DDRJ_CPU0_SDA    I22 @T6G_MB_LIB.T6G(SCH_1):PAGE94
     4 I3C_SPD_DDRJ_CPU0_SCL @T6G_MB_LIB.T6G(SCH_1):I3C_SPD_DDRJ_CPU0_SCL    I22 @T6G_MB_LIB.T6G(SCH_1):PAGE94
   148 PD_CHJ_CPU0_DIMM_SAA @T6G_MB_LIB.T6G(SCH_1):PD_CHJ_CPU0_DIMM_SAA    I22 @T6G_MB_LIB.T6G(SCH_1):PAGE94
   100 M_J_CPU0_SB_DQ<0> @T6G_MB_LIB.T6G(SCH_1):M_J_CPU0_SB_DQ(0)    I22 @T6G_MB_LIB.T6G(SCH_1):PAGE94
   102 M_J_CPU0_SB_DQ<1> @T6G_MB_LIB.T6G(SCH_1):M_J_CPU0_SB_DQ(1)    I22 @T6G_MB_LIB.T6G(SCH_1):PAGE94
   245 M_J_CPU0_SB_DQ<2> @T6G_MB_LIB.T6G(SCH_1):M_J_CPU0_SB_DQ(2)    I22 @T6G_MB_LIB.T6G(SCH_1):PAGE94
   247 M_J_CPU0_SB_DQ<3> @T6G_MB_LIB.T6G(SCH_1):M_J_CPU0_SB_DQ(3)    I22 @T6G_MB_LIB.T6G(SCH_1):PAGE94
   107 M_J_CPU0_SB_DQ<4> @T6G_MB_LIB.T6G(SCH_1):M_J_CPU0_SB_DQ(4)    I22 @T6G_MB_LIB.T6G(SCH_1):PAGE94
   109 M_J_CPU0_SB_DQ<5> @T6G_MB_LIB.T6G(SCH_1):M_J_CPU0_SB_DQ(5)    I22 @T6G_MB_LIB.T6G(SCH_1):PAGE94
   252 M_J_CPU0_SB_DQ<6> @T6G_MB_LIB.T6G(SCH_1):M_J_CPU0_SB_DQ(6)    I22 @T6G_MB_LIB.T6G(SCH_1):PAGE94
   254 M_J_CPU0_SB_DQ<7> @T6G_MB_LIB.T6G(SCH_1):M_J_CPU0_SB_DQ(7)    I22 @T6G_MB_LIB.T6G(SCH_1):PAGE94
   111 M_J_CPU0_SB_DQ<8> @T6G_MB_LIB.T6G(SCH_1):M_J_CPU0_SB_DQ(8)    I22 @T6G_MB_LIB.T6G(SCH_1):PAGE94
   113 M_J_CPU0_SB_DQ<9> @T6G_MB_LIB.T6G(SCH_1):M_J_CPU0_SB_DQ(9)    I22 @T6G_MB_LIB.T6G(SCH_1):PAGE94
   256 M_J_CPU0_SB_DQ<10> @T6G_MB_LIB.T6G(SCH_1):M_J_CPU0_SB_DQ(10)    I22 @T6G_MB_LIB.T6G(SCH_1):PAGE94
   258 M_J_CPU0_SB_DQ<11> @T6G_MB_LIB.T6G(SCH_1):M_J_CPU0_SB_DQ(11)    I22 @T6G_MB_LIB.T6G(SCH_1):PAGE94
   118 M_J_CPU0_SB_DQ<12> @T6G_MB_LIB.T6G(SCH_1):M_J_CPU0_SB_DQ(12)    I22 @T6G_MB_LIB.T6G(SCH_1):PAGE94
   120 M_J_CPU0_SB_DQ<13> @T6G_MB_LIB.T6G(SCH_1):M_J_CPU0_SB_DQ(13)    I22 @T6G_MB_LIB.T6G(SCH_1):PAGE94
   263 M_J_CPU0_SB_DQ<14> @T6G_MB_LIB.T6G(SCH_1):M_J_CPU0_SB_DQ(14)    I22 @T6G_MB_LIB.T6G(SCH_1):PAGE94
   265 M_J_CPU0_SB_DQ<15> @T6G_MB_LIB.T6G(SCH_1):M_J_CPU0_SB_DQ(15)    I22 @T6G_MB_LIB.T6G(SCH_1):PAGE94
   122 M_J_CPU0_SB_DQ<16> @T6G_MB_LIB.T6G(SCH_1):M_J_CPU0_SB_DQ(16)    I22 @T6G_MB_LIB.T6G(SCH_1):PAGE94
   124 M_J_CPU0_SB_DQ<17> @T6G_MB_LIB.T6G(SCH_1):M_J_CPU0_SB_DQ(17)    I22 @T6G_MB_LIB.T6G(SCH_1):PAGE94
   267 M_J_CPU0_SB_DQ<18> @T6G_MB_LIB.T6G(SCH_1):M_J_CPU0_SB_DQ(18)    I22 @T6G_MB_LIB.T6G(SCH_1):PAGE94
   269 M_J_CPU0_SB_DQ<19> @T6G_MB_LIB.T6G(SCH_1):M_J_CPU0_SB_DQ(19)    I22 @T6G_MB_LIB.T6G(SCH_1):PAGE94
   129 M_J_CPU0_SB_DQ<20> @T6G_MB_LIB.T6G(SCH_1):M_J_CPU0_SB_DQ(20)    I22 @T6G_MB_LIB.T6G(SCH_1):PAGE94
   131 M_J_CPU0_SB_DQ<21> @T6G_MB_LIB.T6G(SCH_1):M_J_CPU0_SB_DQ(21)    I22 @T6G_MB_LIB.T6G(SCH_1):PAGE94
   274 M_J_CPU0_SB_DQ<22> @T6G_MB_LIB.T6G(SCH_1):M_J_CPU0_SB_DQ(22)    I22 @T6G_MB_LIB.T6G(SCH_1):PAGE94
   276 M_J_CPU0_SB_DQ<23> @T6G_MB_LIB.T6G(SCH_1):M_J_CPU0_SB_DQ(23)    I22 @T6G_MB_LIB.T6G(SCH_1):PAGE94
   133 M_J_CPU0_SB_DQ<24> @T6G_MB_LIB.T6G(SCH_1):M_J_CPU0_SB_DQ(24)    I22 @T6G_MB_LIB.T6G(SCH_1):PAGE94
   135 M_J_CPU0_SB_DQ<25> @T6G_MB_LIB.T6G(SCH_1):M_J_CPU0_SB_DQ(25)    I22 @T6G_MB_LIB.T6G(SCH_1):PAGE94
   278 M_J_CPU0_SB_DQ<26> @T6G_MB_LIB.T6G(SCH_1):M_J_CPU0_SB_DQ(26)    I22 @T6G_MB_LIB.T6G(SCH_1):PAGE94
   280 M_J_CPU0_SB_DQ<27> @T6G_MB_LIB.T6G(SCH_1):M_J_CPU0_SB_DQ(27)    I22 @T6G_MB_LIB.T6G(SCH_1):PAGE94
   140 M_J_CPU0_SB_DQ<28> @T6G_MB_LIB.T6G(SCH_1):M_J_CPU0_SB_DQ(28)    I22 @T6G_MB_LIB.T6G(SCH_1):PAGE94
   142 M_J_CPU0_SB_DQ<29> @T6G_MB_LIB.T6G(SCH_1):M_J_CPU0_SB_DQ(29)    I22 @T6G_MB_LIB.T6G(SCH_1):PAGE94
   285 M_J_CPU0_SB_DQ<30> @T6G_MB_LIB.T6G(SCH_1):M_J_CPU0_SB_DQ(30)    I22 @T6G_MB_LIB.T6G(SCH_1):PAGE94
   287 M_J_CPU0_SB_DQ<31> @T6G_MB_LIB.T6G(SCH_1):M_J_CPU0_SB_DQ(31)    I22 @T6G_MB_LIB.T6G(SCH_1):PAGE94
     7 M_J_CPU0_SA_DQ<0> @T6G_MB_LIB.T6G(SCH_1):M_J_CPU0_SA_DQ(0)    I22 @T6G_MB_LIB.T6G(SCH_1):PAGE94
     9 M_J_CPU0_SA_DQ<1> @T6G_MB_LIB.T6G(SCH_1):M_J_CPU0_SA_DQ(1)    I22 @T6G_MB_LIB.T6G(SCH_1):PAGE94
   152 M_J_CPU0_SA_DQ<2> @T6G_MB_LIB.T6G(SCH_1):M_J_CPU0_SA_DQ(2)    I22 @T6G_MB_LIB.T6G(SCH_1):PAGE94
   154 M_J_CPU0_SA_DQ<3> @T6G_MB_LIB.T6G(SCH_1):M_J_CPU0_SA_DQ(3)    I22 @T6G_MB_LIB.T6G(SCH_1):PAGE94
    14 M_J_CPU0_SA_DQ<4> @T6G_MB_LIB.T6G(SCH_1):M_J_CPU0_SA_DQ(4)    I22 @T6G_MB_LIB.T6G(SCH_1):PAGE94
    16 M_J_CPU0_SA_DQ<5> @T6G_MB_LIB.T6G(SCH_1):M_J_CPU0_SA_DQ(5)    I22 @T6G_MB_LIB.T6G(SCH_1):PAGE94
   159 M_J_CPU0_SA_DQ<6> @T6G_MB_LIB.T6G(SCH_1):M_J_CPU0_SA_DQ(6)    I22 @T6G_MB_LIB.T6G(SCH_1):PAGE94
   161 M_J_CPU0_SA_DQ<7> @T6G_MB_LIB.T6G(SCH_1):M_J_CPU0_SA_DQ(7)    I22 @T6G_MB_LIB.T6G(SCH_1):PAGE94
    18 M_J_CPU0_SA_DQ<8> @T6G_MB_LIB.T6G(SCH_1):M_J_CPU0_SA_DQ(8)    I22 @T6G_MB_LIB.T6G(SCH_1):PAGE94
    20 M_J_CPU0_SA_DQ<9> @T6G_MB_LIB.T6G(SCH_1):M_J_CPU0_SA_DQ(9)    I22 @T6G_MB_LIB.T6G(SCH_1):PAGE94
   163 M_J_CPU0_SA_DQ<10> @T6G_MB_LIB.T6G(SCH_1):M_J_CPU0_SA_DQ(10)    I22 @T6G_MB_LIB.T6G(SCH_1):PAGE94
   165 M_J_CPU0_SA_DQ<11> @T6G_MB_LIB.T6G(SCH_1):M_J_CPU0_SA_DQ(11)    I22 @T6G_MB_LIB.T6G(SCH_1):PAGE94
    25 M_J_CPU0_SA_DQ<12> @T6G_MB_LIB.T6G(SCH_1):M_J_CPU0_SA_DQ(12)    I22 @T6G_MB_LIB.T6G(SCH_1):PAGE94
    27 M_J_CPU0_SA_DQ<13> @T6G_MB_LIB.T6G(SCH_1):M_J_CPU0_SA_DQ(13)    I22 @T6G_MB_LIB.T6G(SCH_1):PAGE94
   170 M_J_CPU0_SA_DQ<14> @T6G_MB_LIB.T6G(SCH_1):M_J_CPU0_SA_DQ(14)    I22 @T6G_MB_LIB.T6G(SCH_1):PAGE94
   172 M_J_CPU0_SA_DQ<15> @T6G_MB_LIB.T6G(SCH_1):M_J_CPU0_SA_DQ(15)    I22 @T6G_MB_LIB.T6G(SCH_1):PAGE94
    29 M_J_CPU0_SA_DQ<16> @T6G_MB_LIB.T6G(SCH_1):M_J_CPU0_SA_DQ(16)    I22 @T6G_MB_LIB.T6G(SCH_1):PAGE94
    31 M_J_CPU0_SA_DQ<17> @T6G_MB_LIB.T6G(SCH_1):M_J_CPU0_SA_DQ(17)    I22 @T6G_MB_LIB.T6G(SCH_1):PAGE94
   174 M_J_CPU0_SA_DQ<18> @T6G_MB_LIB.T6G(SCH_1):M_J_CPU0_SA_DQ(18)    I22 @T6G_MB_LIB.T6G(SCH_1):PAGE94
   176 M_J_CPU0_SA_DQ<19> @T6G_MB_LIB.T6G(SCH_1):M_J_CPU0_SA_DQ(19)    I22 @T6G_MB_LIB.T6G(SCH_1):PAGE94
    36 M_J_CPU0_SA_DQ<20> @T6G_MB_LIB.T6G(SCH_1):M_J_CPU0_SA_DQ(20)    I22 @T6G_MB_LIB.T6G(SCH_1):PAGE94
    38 M_J_CPU0_SA_DQ<21> @T6G_MB_LIB.T6G(SCH_1):M_J_CPU0_SA_DQ(21)    I22 @T6G_MB_LIB.T6G(SCH_1):PAGE94
   181 M_J_CPU0_SA_DQ<22> @T6G_MB_LIB.T6G(SCH_1):M_J_CPU0_SA_DQ(22)    I22 @T6G_MB_LIB.T6G(SCH_1):PAGE94
   183 M_J_CPU0_SA_DQ<23> @T6G_MB_LIB.T6G(SCH_1):M_J_CPU0_SA_DQ(23)    I22 @T6G_MB_LIB.T6G(SCH_1):PAGE94
    40 M_J_CPU0_SA_DQ<24> @T6G_MB_LIB.T6G(SCH_1):M_J_CPU0_SA_DQ(24)    I22 @T6G_MB_LIB.T6G(SCH_1):PAGE94
    42 M_J_CPU0_SA_DQ<25> @T6G_MB_LIB.T6G(SCH_1):M_J_CPU0_SA_DQ(25)    I22 @T6G_MB_LIB.T6G(SCH_1):PAGE94
   185 M_J_CPU0_SA_DQ<26> @T6G_MB_LIB.T6G(SCH_1):M_J_CPU0_SA_DQ(26)    I22 @T6G_MB_LIB.T6G(SCH_1):PAGE94
   187 M_J_CPU0_SA_DQ<27> @T6G_MB_LIB.T6G(SCH_1):M_J_CPU0_SA_DQ(27)    I22 @T6G_MB_LIB.T6G(SCH_1):PAGE94
    47 M_J_CPU0_SA_DQ<28> @T6G_MB_LIB.T6G(SCH_1):M_J_CPU0_SA_DQ(28)    I22 @T6G_MB_LIB.T6G(SCH_1):PAGE94
    49 M_J_CPU0_SA_DQ<29> @T6G_MB_LIB.T6G(SCH_1):M_J_CPU0_SA_DQ(29)    I22 @T6G_MB_LIB.T6G(SCH_1):PAGE94
   192 M_J_CPU0_SA_DQ<30> @T6G_MB_LIB.T6G(SCH_1):M_J_CPU0_SA_DQ(30)    I22 @T6G_MB_LIB.T6G(SCH_1):PAGE94
   229 M_J_CPU0_SB_CS_N<1> @T6G_MB_LIB.T6G(SCH_1):M_J_CPU0_SB_CS_N(1)    I22 @T6G_MB_LIB.T6G(SCH_1):PAGE94
   209 M_J_CPU0_SA_CS_N<1> @T6G_MB_LIB.T6G(SCH_1):M_J_CPU0_SA_CS_N(1)    I22 @T6G_MB_LIB.T6G(SCH_1):PAGE94
    84 M_J_CPU0_SB_CS_N<0> @T6G_MB_LIB.T6G(SCH_1):M_J_CPU0_SB_CS_N(0)    I22 @T6G_MB_LIB.T6G(SCH_1):PAGE94
    64 M_J_CPU0_SA_CS_N<0> @T6G_MB_LIB.T6G(SCH_1):M_J_CPU0_SA_CS_N(0)    I22 @T6G_MB_LIB.T6G(SCH_1):PAGE94
   217 M_J_CPU0_CLK_DP<0> @T6G_MB_LIB.T6G(SCH_1):M_J_CPU0_CLK_DP(0)    I22 @T6G_MB_LIB.T6G(SCH_1):PAGE94
   218 M_J_CPU0_CLK_DN<0> @T6G_MB_LIB.T6G(SCH_1):M_J_CPU0_CLK_DN(0)    I22 @T6G_MB_LIB.T6G(SCH_1):PAGE94
    96 M_J_CPU0_SB_CB<0> @T6G_MB_LIB.T6G(SCH_1):M_J_CPU0_SB_CB(0)    I22 @T6G_MB_LIB.T6G(SCH_1):PAGE94
    98 M_J_CPU0_SB_CB<1> @T6G_MB_LIB.T6G(SCH_1):M_J_CPU0_SB_CB(1)    I22 @T6G_MB_LIB.T6G(SCH_1):PAGE94
   241 M_J_CPU0_SB_CB<2> @T6G_MB_LIB.T6G(SCH_1):M_J_CPU0_SB_CB(2)    I22 @T6G_MB_LIB.T6G(SCH_1):PAGE94
   243 M_J_CPU0_SB_CB<3> @T6G_MB_LIB.T6G(SCH_1):M_J_CPU0_SB_CB(3)    I22 @T6G_MB_LIB.T6G(SCH_1):PAGE94
    89 M_J_CPU0_SB_CB<4> @T6G_MB_LIB.T6G(SCH_1):M_J_CPU0_SB_CB(4)    I22 @T6G_MB_LIB.T6G(SCH_1):PAGE94
    91 M_J_CPU0_SB_CB<5> @T6G_MB_LIB.T6G(SCH_1):M_J_CPU0_SB_CB(5)    I22 @T6G_MB_LIB.T6G(SCH_1):PAGE94
   234 M_J_CPU0_SB_CB<6> @T6G_MB_LIB.T6G(SCH_1):M_J_CPU0_SB_CB(6)    I22 @T6G_MB_LIB.T6G(SCH_1):PAGE94
    51 M_J_CPU0_SA_CB<0> @T6G_MB_LIB.T6G(SCH_1):M_J_CPU0_SA_CB(0)    I22 @T6G_MB_LIB.T6G(SCH_1):PAGE94
   196 M_J_CPU0_SA_CB<2> @T6G_MB_LIB.T6G(SCH_1):M_J_CPU0_SA_CB(2)    I22 @T6G_MB_LIB.T6G(SCH_1):PAGE94
   198 M_J_CPU0_SA_CB<3> @T6G_MB_LIB.T6G(SCH_1):M_J_CPU0_SA_CB(3)    I22 @T6G_MB_LIB.T6G(SCH_1):PAGE94
    60 M_J_CPU0_SA_CB<5> @T6G_MB_LIB.T6G(SCH_1):M_J_CPU0_SA_CB(5)    I22 @T6G_MB_LIB.T6G(SCH_1):PAGE94
   203 M_J_CPU0_SA_CB<6> @T6G_MB_LIB.T6G(SCH_1):M_J_CPU0_SA_CB(6)    I22 @T6G_MB_LIB.T6G(SCH_1):PAGE94
    82 M_J_CPU0_SB_CA<6> @T6G_MB_LIB.T6G(SCH_1):M_J_CPU0_SB_CA(6)    I22 @T6G_MB_LIB.T6G(SCH_1):PAGE94
    72 M_J_CPU0_SA_CA<6> @T6G_MB_LIB.T6G(SCH_1):M_J_CPU0_SA_CA(6)    I22 @T6G_MB_LIB.T6G(SCH_1):PAGE94
   225 M_J_CPU0_SB_CA<5> @T6G_MB_LIB.T6G(SCH_1):M_J_CPU0_SB_CA(5)    I22 @T6G_MB_LIB.T6G(SCH_1):PAGE94
   215 M_J_CPU0_SA_CA<5> @T6G_MB_LIB.T6G(SCH_1):M_J_CPU0_SA_CA(5)    I22 @T6G_MB_LIB.T6G(SCH_1):PAGE94
    80 M_J_CPU0_SB_CA<4> @T6G_MB_LIB.T6G(SCH_1):M_J_CPU0_SB_CA(4)    I22 @T6G_MB_LIB.T6G(SCH_1):PAGE94
    70 M_J_CPU0_SA_CA<4> @T6G_MB_LIB.T6G(SCH_1):M_J_CPU0_SA_CA(4)    I22 @T6G_MB_LIB.T6G(SCH_1):PAGE94
   223 M_J_CPU0_SB_CA<3> @T6G_MB_LIB.T6G(SCH_1):M_J_CPU0_SB_CA(3)    I22 @T6G_MB_LIB.T6G(SCH_1):PAGE94
   213 M_J_CPU0_SA_CA<3> @T6G_MB_LIB.T6G(SCH_1):M_J_CPU0_SA_CA(3)    I22 @T6G_MB_LIB.T6G(SCH_1):PAGE94
    78 M_J_CPU0_SB_CA<2> @T6G_MB_LIB.T6G(SCH_1):M_J_CPU0_SB_CA(2)    I22 @T6G_MB_LIB.T6G(SCH_1):PAGE94
    68 M_J_CPU0_SA_CA<2> @T6G_MB_LIB.T6G(SCH_1):M_J_CPU0_SA_CA(2)    I22 @T6G_MB_LIB.T6G(SCH_1):PAGE94
   221 M_J_CPU0_SB_CA<1> @T6G_MB_LIB.T6G(SCH_1):M_J_CPU0_SB_CA(1)    I22 @T6G_MB_LIB.T6G(SCH_1):PAGE94
   211 M_J_CPU0_SA_CA<1> @T6G_MB_LIB.T6G(SCH_1):M_J_CPU0_SA_CA(1)    I22 @T6G_MB_LIB.T6G(SCH_1):PAGE94
    76 M_J_CPU0_SB_CA<0> @T6G_MB_LIB.T6G(SCH_1):M_J_CPU0_SB_CA(0)    I22 @T6G_MB_LIB.T6G(SCH_1):PAGE94
    66 M_J_CPU0_SA_CA<0> @T6G_MB_LIB.T6G(SCH_1):M_J_CPU0_SA_CA(0)    I22 @T6G_MB_LIB.T6G(SCH_1):PAGE94
    62 M_J_CPU0_ALERT_N @T6G_MB_LIB.T6G(SCH_1):M_J_CPU0_ALERT_N    I22 @T6G_MB_LIB.T6G(SCH_1):PAGE94
   236 M_J_CPU0_SB_CB<7> @T6G_MB_LIB.T6G(SCH_1):M_J_CPU0_SB_CB(7)    I22 @T6G_MB_LIB.T6G(SCH_1):PAGE94
    53 M_J_CPU0_SA_CB<1> @T6G_MB_LIB.T6G(SCH_1):M_J_CPU0_SA_CB(1)    I22 @T6G_MB_LIB.T6G(SCH_1):PAGE94
    58 M_J_CPU0_SA_CB<4> @T6G_MB_LIB.T6G(SCH_1):M_J_CPU0_SA_CB(4)    I22 @T6G_MB_LIB.T6G(SCH_1):PAGE94
   205 M_J_CPU0_SA_CB<7> @T6G_MB_LIB.T6G(SCH_1):M_J_CPU0_SA_CB(7)    I22 @T6G_MB_LIB.T6G(SCH_1):PAGE94
   194 M_J_CPU0_SA_DQ<31> @T6G_MB_LIB.T6G(SCH_1):M_J_CPU0_SA_DQ(31)    I22 @T6G_MB_LIB.T6G(SCH_1):PAGE94
    93 M_J_CPU0_SB_DQS_DP<9> @T6G_MB_LIB.T6G(SCH_1):M_J_CPU0_SB_DQS_DP(9)   I236 @T6G_MB_LIB.T6G(SCH_1):PAGE94
    94 M_J_CPU0_SB_DQS_DN<9> @T6G_MB_LIB.T6G(SCH_1):M_J_CPU0_SB_DQS_DN(9)   I236 @T6G_MB_LIB.T6G(SCH_1):PAGE94
   201 M_J_CPU0_SA_DQS_DP<9> @T6G_MB_LIB.T6G(SCH_1):M_J_CPU0_SA_DQS_DP(9)   I236 @T6G_MB_LIB.T6G(SCH_1):PAGE94
   200 M_J_CPU0_SA_DQS_DN<9> @T6G_MB_LIB.T6G(SCH_1):M_J_CPU0_SA_DQS_DN(9)   I236 @T6G_MB_LIB.T6G(SCH_1):PAGE94
   190 M_J_CPU0_SA_DQS_DP<8> @T6G_MB_LIB.T6G(SCH_1):M_J_CPU0_SA_DQS_DP(8)   I236 @T6G_MB_LIB.T6G(SCH_1):PAGE94
   189 M_J_CPU0_SA_DQS_DN<8> @T6G_MB_LIB.T6G(SCH_1):M_J_CPU0_SA_DQS_DN(8)   I236 @T6G_MB_LIB.T6G(SCH_1):PAGE94
   271 M_J_CPU0_SB_DQS_DN<7> @T6G_MB_LIB.T6G(SCH_1):M_J_CPU0_SB_DQS_DN(7)   I236 @T6G_MB_LIB.T6G(SCH_1):PAGE94
   179 M_J_CPU0_SA_DQS_DP<7> @T6G_MB_LIB.T6G(SCH_1):M_J_CPU0_SA_DQS_DP(7)   I236 @T6G_MB_LIB.T6G(SCH_1):PAGE94
   261 M_J_CPU0_SB_DQS_DP<6> @T6G_MB_LIB.T6G(SCH_1):M_J_CPU0_SB_DQS_DP(6)   I236 @T6G_MB_LIB.T6G(SCH_1):PAGE94
   260 M_J_CPU0_SB_DQS_DN<6> @T6G_MB_LIB.T6G(SCH_1):M_J_CPU0_SB_DQS_DN(6)   I236 @T6G_MB_LIB.T6G(SCH_1):PAGE94
   167 M_J_CPU0_SA_DQS_DN<6> @T6G_MB_LIB.T6G(SCH_1):M_J_CPU0_SA_DQS_DN(6)   I236 @T6G_MB_LIB.T6G(SCH_1):PAGE94
   250 M_J_CPU0_SB_DQS_DP<5> @T6G_MB_LIB.T6G(SCH_1):M_J_CPU0_SB_DQS_DP(5)   I236 @T6G_MB_LIB.T6G(SCH_1):PAGE94
   249 M_J_CPU0_SB_DQS_DN<5> @T6G_MB_LIB.T6G(SCH_1):M_J_CPU0_SB_DQS_DN(5)   I236 @T6G_MB_LIB.T6G(SCH_1):PAGE94
   157 M_J_CPU0_SA_DQS_DP<5> @T6G_MB_LIB.T6G(SCH_1):M_J_CPU0_SA_DQS_DP(5)   I236 @T6G_MB_LIB.T6G(SCH_1):PAGE94
   156 M_J_CPU0_SA_DQS_DN<5> @T6G_MB_LIB.T6G(SCH_1):M_J_CPU0_SA_DQS_DN(5)   I236 @T6G_MB_LIB.T6G(SCH_1):PAGE94
   239 M_J_CPU0_SB_DQS_DP<4> @T6G_MB_LIB.T6G(SCH_1):M_J_CPU0_SB_DQS_DP(4)   I236 @T6G_MB_LIB.T6G(SCH_1):PAGE94
   238 M_J_CPU0_SB_DQS_DN<4> @T6G_MB_LIB.T6G(SCH_1):M_J_CPU0_SB_DQS_DN(4)   I236 @T6G_MB_LIB.T6G(SCH_1):PAGE94
    55 M_J_CPU0_SA_DQS_DP<4> @T6G_MB_LIB.T6G(SCH_1):M_J_CPU0_SA_DQS_DP(4)   I236 @T6G_MB_LIB.T6G(SCH_1):PAGE94
    56 M_J_CPU0_SA_DQS_DN<4> @T6G_MB_LIB.T6G(SCH_1):M_J_CPU0_SA_DQS_DN(4)   I236 @T6G_MB_LIB.T6G(SCH_1):PAGE94
   137 M_J_CPU0_SB_DQS_DP<3> @T6G_MB_LIB.T6G(SCH_1):M_J_CPU0_SB_DQS_DP(3)   I236 @T6G_MB_LIB.T6G(SCH_1):PAGE94
   138 M_J_CPU0_SB_DQS_DN<3> @T6G_MB_LIB.T6G(SCH_1):M_J_CPU0_SB_DQS_DN(3)   I236 @T6G_MB_LIB.T6G(SCH_1):PAGE94
    44 M_J_CPU0_SA_DQS_DP<3> @T6G_MB_LIB.T6G(SCH_1):M_J_CPU0_SA_DQS_DP(3)   I236 @T6G_MB_LIB.T6G(SCH_1):PAGE94
    45 M_J_CPU0_SA_DQS_DN<3> @T6G_MB_LIB.T6G(SCH_1):M_J_CPU0_SA_DQS_DN(3)   I236 @T6G_MB_LIB.T6G(SCH_1):PAGE94
   126 M_J_CPU0_SB_DQS_DP<2> @T6G_MB_LIB.T6G(SCH_1):M_J_CPU0_SB_DQS_DP(2)   I236 @T6G_MB_LIB.T6G(SCH_1):PAGE94
   127 M_J_CPU0_SB_DQS_DN<2> @T6G_MB_LIB.T6G(SCH_1):M_J_CPU0_SB_DQS_DN(2)   I236 @T6G_MB_LIB.T6G(SCH_1):PAGE94
    33 M_J_CPU0_SA_DQS_DP<2> @T6G_MB_LIB.T6G(SCH_1):M_J_CPU0_SA_DQS_DP(2)   I236 @T6G_MB_LIB.T6G(SCH_1):PAGE94
    34 M_J_CPU0_SA_DQS_DN<2> @T6G_MB_LIB.T6G(SCH_1):M_J_CPU0_SA_DQS_DN(2)   I236 @T6G_MB_LIB.T6G(SCH_1):PAGE94
   115 M_J_CPU0_SB_DQS_DP<1> @T6G_MB_LIB.T6G(SCH_1):M_J_CPU0_SB_DQS_DP(1)   I236 @T6G_MB_LIB.T6G(SCH_1):PAGE94
   116 M_J_CPU0_SB_DQS_DN<1> @T6G_MB_LIB.T6G(SCH_1):M_J_CPU0_SB_DQS_DN(1)   I236 @T6G_MB_LIB.T6G(SCH_1):PAGE94
    22 M_J_CPU0_SA_DQS_DP<1> @T6G_MB_LIB.T6G(SCH_1):M_J_CPU0_SA_DQS_DP(1)   I236 @T6G_MB_LIB.T6G(SCH_1):PAGE94
    23 M_J_CPU0_SA_DQS_DN<1> @T6G_MB_LIB.T6G(SCH_1):M_J_CPU0_SA_DQS_DN(1)   I236 @T6G_MB_LIB.T6G(SCH_1):PAGE94
   104 M_J_CPU0_SB_DQS_DP<0> @T6G_MB_LIB.T6G(SCH_1):M_J_CPU0_SB_DQS_DP(0)   I236 @T6G_MB_LIB.T6G(SCH_1):PAGE94
   105 M_J_CPU0_SB_DQS_DN<0> @T6G_MB_LIB.T6G(SCH_1):M_J_CPU0_SB_DQS_DN(0)   I236 @T6G_MB_LIB.T6G(SCH_1):PAGE94
    11 M_J_CPU0_SA_DQS_DP<0> @T6G_MB_LIB.T6G(SCH_1):M_J_CPU0_SA_DQS_DP(0)   I236 @T6G_MB_LIB.T6G(SCH_1):PAGE94
    12 M_J_CPU0_SA_DQS_DN<0> @T6G_MB_LIB.T6G(SCH_1):M_J_CPU0_SA_DQS_DN(0)   I236 @T6G_MB_LIB.T6G(SCH_1):PAGE94
   272 M_J_CPU0_SB_DQS_DP<7> @T6G_MB_LIB.T6G(SCH_1):M_J_CPU0_SB_DQS_DP(7)   I236 @T6G_MB_LIB.T6G(SCH_1):PAGE94
   282 M_J_CPU0_SB_DQS_DN<8> @T6G_MB_LIB.T6G(SCH_1):M_J_CPU0_SB_DQS_DN(8)   I236 @T6G_MB_LIB.T6G(SCH_1):PAGE94
   283 M_J_CPU0_SB_DQS_DP<8> @T6G_MB_LIB.T6G(SCH_1):M_J_CPU0_SB_DQS_DP(8)   I236 @T6G_MB_LIB.T6G(SCH_1):PAGE94
   168 M_J_CPU0_SA_DQS_DP<6> @T6G_MB_LIB.T6G(SCH_1):M_J_CPU0_SA_DQS_DP(6)   I236 @T6G_MB_LIB.T6G(SCH_1):PAGE94
   178 M_J_CPU0_SA_DQS_DN<7> @T6G_MB_LIB.T6G(SCH_1):M_J_CPU0_SA_DQS_DN(7)   I236 @T6G_MB_LIB.T6G(SCH_1):PAGE94
     6    GND @T6G_MB_LIB.T6G(SCH_1):GND   I177 @T6G_MB_LIB.T6G(SCH_1):PAGE94
     8    GND @T6G_MB_LIB.T6G(SCH_1):GND   I177 @T6G_MB_LIB.T6G(SCH_1):PAGE94
    10    GND @T6G_MB_LIB.T6G(SCH_1):GND   I177 @T6G_MB_LIB.T6G(SCH_1):PAGE94
    13    GND @T6G_MB_LIB.T6G(SCH_1):GND   I177 @T6G_MB_LIB.T6G(SCH_1):PAGE94
    15    GND @T6G_MB_LIB.T6G(SCH_1):GND   I177 @T6G_MB_LIB.T6G(SCH_1):PAGE94
    17    GND @T6G_MB_LIB.T6G(SCH_1):GND   I177 @T6G_MB_LIB.T6G(SCH_1):PAGE94
    19    GND @T6G_MB_LIB.T6G(SCH_1):GND   I177 @T6G_MB_LIB.T6G(SCH_1):PAGE94
    21    GND @T6G_MB_LIB.T6G(SCH_1):GND   I177 @T6G_MB_LIB.T6G(SCH_1):PAGE94
    24    GND @T6G_MB_LIB.T6G(SCH_1):GND   I177 @T6G_MB_LIB.T6G(SCH_1):PAGE94
    26    GND @T6G_MB_LIB.T6G(SCH_1):GND   I177 @T6G_MB_LIB.T6G(SCH_1):PAGE94
    28    GND @T6G_MB_LIB.T6G(SCH_1):GND   I177 @T6G_MB_LIB.T6G(SCH_1):PAGE94
    30    GND @T6G_MB_LIB.T6G(SCH_1):GND   I177 @T6G_MB_LIB.T6G(SCH_1):PAGE94
    32    GND @T6G_MB_LIB.T6G(SCH_1):GND   I177 @T6G_MB_LIB.T6G(SCH_1):PAGE94
    35    GND @T6G_MB_LIB.T6G(SCH_1):GND   I177 @T6G_MB_LIB.T6G(SCH_1):PAGE94
    37    GND @T6G_MB_LIB.T6G(SCH_1):GND   I177 @T6G_MB_LIB.T6G(SCH_1):PAGE94
    39    GND @T6G_MB_LIB.T6G(SCH_1):GND   I177 @T6G_MB_LIB.T6G(SCH_1):PAGE94
    41    GND @T6G_MB_LIB.T6G(SCH_1):GND   I177 @T6G_MB_LIB.T6G(SCH_1):PAGE94
    43    GND @T6G_MB_LIB.T6G(SCH_1):GND   I177 @T6G_MB_LIB.T6G(SCH_1):PAGE94
    46    GND @T6G_MB_LIB.T6G(SCH_1):GND   I177 @T6G_MB_LIB.T6G(SCH_1):PAGE94
    48    GND @T6G_MB_LIB.T6G(SCH_1):GND   I177 @T6G_MB_LIB.T6G(SCH_1):PAGE94
    50    GND @T6G_MB_LIB.T6G(SCH_1):GND   I177 @T6G_MB_LIB.T6G(SCH_1):PAGE94
    52    GND @T6G_MB_LIB.T6G(SCH_1):GND   I177 @T6G_MB_LIB.T6G(SCH_1):PAGE94
    54    GND @T6G_MB_LIB.T6G(SCH_1):GND   I177 @T6G_MB_LIB.T6G(SCH_1):PAGE94
    57    GND @T6G_MB_LIB.T6G(SCH_1):GND   I177 @T6G_MB_LIB.T6G(SCH_1):PAGE94
    59    GND @T6G_MB_LIB.T6G(SCH_1):GND   I177 @T6G_MB_LIB.T6G(SCH_1):PAGE94
    61    GND @T6G_MB_LIB.T6G(SCH_1):GND   I177 @T6G_MB_LIB.T6G(SCH_1):PAGE94
    63    GND @T6G_MB_LIB.T6G(SCH_1):GND   I177 @T6G_MB_LIB.T6G(SCH_1):PAGE94
    65    GND @T6G_MB_LIB.T6G(SCH_1):GND   I177 @T6G_MB_LIB.T6G(SCH_1):PAGE94
    67    GND @T6G_MB_LIB.T6G(SCH_1):GND   I177 @T6G_MB_LIB.T6G(SCH_1):PAGE94
    69    GND @T6G_MB_LIB.T6G(SCH_1):GND   I177 @T6G_MB_LIB.T6G(SCH_1):PAGE94
    71    GND @T6G_MB_LIB.T6G(SCH_1):GND   I177 @T6G_MB_LIB.T6G(SCH_1):PAGE94
    73    GND @T6G_MB_LIB.T6G(SCH_1):GND   I177 @T6G_MB_LIB.T6G(SCH_1):PAGE94
    75    GND @T6G_MB_LIB.T6G(SCH_1):GND   I177 @T6G_MB_LIB.T6G(SCH_1):PAGE94
    77    GND @T6G_MB_LIB.T6G(SCH_1):GND   I177 @T6G_MB_LIB.T6G(SCH_1):PAGE94
    79    GND @T6G_MB_LIB.T6G(SCH_1):GND   I177 @T6G_MB_LIB.T6G(SCH_1):PAGE94
    81    GND @T6G_MB_LIB.T6G(SCH_1):GND   I177 @T6G_MB_LIB.T6G(SCH_1):PAGE94
    83    GND @T6G_MB_LIB.T6G(SCH_1):GND   I177 @T6G_MB_LIB.T6G(SCH_1):PAGE94
    85    GND @T6G_MB_LIB.T6G(SCH_1):GND   I177 @T6G_MB_LIB.T6G(SCH_1):PAGE94
    88    GND @T6G_MB_LIB.T6G(SCH_1):GND   I177 @T6G_MB_LIB.T6G(SCH_1):PAGE94
    90    GND @T6G_MB_LIB.T6G(SCH_1):GND   I177 @T6G_MB_LIB.T6G(SCH_1):PAGE94
    92    GND @T6G_MB_LIB.T6G(SCH_1):GND   I177 @T6G_MB_LIB.T6G(SCH_1):PAGE94
    95    GND @T6G_MB_LIB.T6G(SCH_1):GND   I177 @T6G_MB_LIB.T6G(SCH_1):PAGE94
    97    GND @T6G_MB_LIB.T6G(SCH_1):GND   I177 @T6G_MB_LIB.T6G(SCH_1):PAGE94
    99    GND @T6G_MB_LIB.T6G(SCH_1):GND   I177 @T6G_MB_LIB.T6G(SCH_1):PAGE94
   101    GND @T6G_MB_LIB.T6G(SCH_1):GND   I177 @T6G_MB_LIB.T6G(SCH_1):PAGE94
   103    GND @T6G_MB_LIB.T6G(SCH_1):GND   I177 @T6G_MB_LIB.T6G(SCH_1):PAGE94
   106    GND @T6G_MB_LIB.T6G(SCH_1):GND   I177 @T6G_MB_LIB.T6G(SCH_1):PAGE94
   108    GND @T6G_MB_LIB.T6G(SCH_1):GND   I177 @T6G_MB_LIB.T6G(SCH_1):PAGE94
   110    GND @T6G_MB_LIB.T6G(SCH_1):GND   I177 @T6G_MB_LIB.T6G(SCH_1):PAGE94
   112    GND @T6G_MB_LIB.T6G(SCH_1):GND   I177 @T6G_MB_LIB.T6G(SCH_1):PAGE94
   114    GND @T6G_MB_LIB.T6G(SCH_1):GND   I177 @T6G_MB_LIB.T6G(SCH_1):PAGE94
   117    GND @T6G_MB_LIB.T6G(SCH_1):GND   I177 @T6G_MB_LIB.T6G(SCH_1):PAGE94
   119    GND @T6G_MB_LIB.T6G(SCH_1):GND   I177 @T6G_MB_LIB.T6G(SCH_1):PAGE94
   121    GND @T6G_MB_LIB.T6G(SCH_1):GND   I177 @T6G_MB_LIB.T6G(SCH_1):PAGE94
   123    GND @T6G_MB_LIB.T6G(SCH_1):GND   I177 @T6G_MB_LIB.T6G(SCH_1):PAGE94
   125    GND @T6G_MB_LIB.T6G(SCH_1):GND   I177 @T6G_MB_LIB.T6G(SCH_1):PAGE94
   128    GND @T6G_MB_LIB.T6G(SCH_1):GND   I177 @T6G_MB_LIB.T6G(SCH_1):PAGE94
   130    GND @T6G_MB_LIB.T6G(SCH_1):GND   I177 @T6G_MB_LIB.T6G(SCH_1):PAGE94
   134    GND @T6G_MB_LIB.T6G(SCH_1):GND   I177 @T6G_MB_LIB.T6G(SCH_1):PAGE94
   143    GND @T6G_MB_LIB.T6G(SCH_1):GND   I177 @T6G_MB_LIB.T6G(SCH_1):PAGE94
   151    GND @T6G_MB_LIB.T6G(SCH_1):GND   I177 @T6G_MB_LIB.T6G(SCH_1):PAGE94
   153    GND @T6G_MB_LIB.T6G(SCH_1):GND   I177 @T6G_MB_LIB.T6G(SCH_1):PAGE94
   155    GND @T6G_MB_LIB.T6G(SCH_1):GND   I177 @T6G_MB_LIB.T6G(SCH_1):PAGE94
   158    GND @T6G_MB_LIB.T6G(SCH_1):GND   I177 @T6G_MB_LIB.T6G(SCH_1):PAGE94
   160    GND @T6G_MB_LIB.T6G(SCH_1):GND   I177 @T6G_MB_LIB.T6G(SCH_1):PAGE94
   162    GND @T6G_MB_LIB.T6G(SCH_1):GND   I177 @T6G_MB_LIB.T6G(SCH_1):PAGE94
   164    GND @T6G_MB_LIB.T6G(SCH_1):GND   I177 @T6G_MB_LIB.T6G(SCH_1):PAGE94
   166    GND @T6G_MB_LIB.T6G(SCH_1):GND   I177 @T6G_MB_LIB.T6G(SCH_1):PAGE94
   169    GND @T6G_MB_LIB.T6G(SCH_1):GND   I177 @T6G_MB_LIB.T6G(SCH_1):PAGE94
   171    GND @T6G_MB_LIB.T6G(SCH_1):GND   I177 @T6G_MB_LIB.T6G(SCH_1):PAGE94
   173    GND @T6G_MB_LIB.T6G(SCH_1):GND   I177 @T6G_MB_LIB.T6G(SCH_1):PAGE94
   175    GND @T6G_MB_LIB.T6G(SCH_1):GND   I177 @T6G_MB_LIB.T6G(SCH_1):PAGE94
   177    GND @T6G_MB_LIB.T6G(SCH_1):GND   I177 @T6G_MB_LIB.T6G(SCH_1):PAGE94
   180    GND @T6G_MB_LIB.T6G(SCH_1):GND   I177 @T6G_MB_LIB.T6G(SCH_1):PAGE94
   182    GND @T6G_MB_LIB.T6G(SCH_1):GND   I177 @T6G_MB_LIB.T6G(SCH_1):PAGE94
   184    GND @T6G_MB_LIB.T6G(SCH_1):GND   I177 @T6G_MB_LIB.T6G(SCH_1):PAGE94
   186    GND @T6G_MB_LIB.T6G(SCH_1):GND   I177 @T6G_MB_LIB.T6G(SCH_1):PAGE94
   188    GND @T6G_MB_LIB.T6G(SCH_1):GND   I177 @T6G_MB_LIB.T6G(SCH_1):PAGE94
   191    GND @T6G_MB_LIB.T6G(SCH_1):GND   I177 @T6G_MB_LIB.T6G(SCH_1):PAGE94
   193    GND @T6G_MB_LIB.T6G(SCH_1):GND   I177 @T6G_MB_LIB.T6G(SCH_1):PAGE94
   195    GND @T6G_MB_LIB.T6G(SCH_1):GND   I177 @T6G_MB_LIB.T6G(SCH_1):PAGE94
   197    GND @T6G_MB_LIB.T6G(SCH_1):GND   I177 @T6G_MB_LIB.T6G(SCH_1):PAGE94
   199    GND @T6G_MB_LIB.T6G(SCH_1):GND   I177 @T6G_MB_LIB.T6G(SCH_1):PAGE94
   202    GND @T6G_MB_LIB.T6G(SCH_1):GND   I177 @T6G_MB_LIB.T6G(SCH_1):PAGE94
   204    GND @T6G_MB_LIB.T6G(SCH_1):GND   I177 @T6G_MB_LIB.T6G(SCH_1):PAGE94
   206    GND @T6G_MB_LIB.T6G(SCH_1):GND   I177 @T6G_MB_LIB.T6G(SCH_1):PAGE94
   208    GND @T6G_MB_LIB.T6G(SCH_1):GND   I177 @T6G_MB_LIB.T6G(SCH_1):PAGE94
   210    GND @T6G_MB_LIB.T6G(SCH_1):GND   I177 @T6G_MB_LIB.T6G(SCH_1):PAGE94
   212    GND @T6G_MB_LIB.T6G(SCH_1):GND   I177 @T6G_MB_LIB.T6G(SCH_1):PAGE94
   214    GND @T6G_MB_LIB.T6G(SCH_1):GND   I177 @T6G_MB_LIB.T6G(SCH_1):PAGE94
   216    GND @T6G_MB_LIB.T6G(SCH_1):GND   I177 @T6G_MB_LIB.T6G(SCH_1):PAGE94
   219    GND @T6G_MB_LIB.T6G(SCH_1):GND   I177 @T6G_MB_LIB.T6G(SCH_1):PAGE94
   222    GND @T6G_MB_LIB.T6G(SCH_1):GND   I177 @T6G_MB_LIB.T6G(SCH_1):PAGE94
   224    GND @T6G_MB_LIB.T6G(SCH_1):GND   I177 @T6G_MB_LIB.T6G(SCH_1):PAGE94
   226    GND @T6G_MB_LIB.T6G(SCH_1):GND   I177 @T6G_MB_LIB.T6G(SCH_1):PAGE94
   228    GND @T6G_MB_LIB.T6G(SCH_1):GND   I177 @T6G_MB_LIB.T6G(SCH_1):PAGE94
   233    GND @T6G_MB_LIB.T6G(SCH_1):GND   I177 @T6G_MB_LIB.T6G(SCH_1):PAGE94
   237    GND @T6G_MB_LIB.T6G(SCH_1):GND   I177 @T6G_MB_LIB.T6G(SCH_1):PAGE94
   242    GND @T6G_MB_LIB.T6G(SCH_1):GND   I177 @T6G_MB_LIB.T6G(SCH_1):PAGE94
   244    GND @T6G_MB_LIB.T6G(SCH_1):GND   I177 @T6G_MB_LIB.T6G(SCH_1):PAGE94
   246    GND @T6G_MB_LIB.T6G(SCH_1):GND   I177 @T6G_MB_LIB.T6G(SCH_1):PAGE94
   248    GND @T6G_MB_LIB.T6G(SCH_1):GND   I177 @T6G_MB_LIB.T6G(SCH_1):PAGE94
   251    GND @T6G_MB_LIB.T6G(SCH_1):GND   I177 @T6G_MB_LIB.T6G(SCH_1):PAGE94
   253    GND @T6G_MB_LIB.T6G(SCH_1):GND   I177 @T6G_MB_LIB.T6G(SCH_1):PAGE94
   255    GND @T6G_MB_LIB.T6G(SCH_1):GND   I177 @T6G_MB_LIB.T6G(SCH_1):PAGE94
   257    GND @T6G_MB_LIB.T6G(SCH_1):GND   I177 @T6G_MB_LIB.T6G(SCH_1):PAGE94
   259    GND @T6G_MB_LIB.T6G(SCH_1):GND   I177 @T6G_MB_LIB.T6G(SCH_1):PAGE94
   262    GND @T6G_MB_LIB.T6G(SCH_1):GND   I177 @T6G_MB_LIB.T6G(SCH_1):PAGE94
   264    GND @T6G_MB_LIB.T6G(SCH_1):GND   I177 @T6G_MB_LIB.T6G(SCH_1):PAGE94
   266    GND @T6G_MB_LIB.T6G(SCH_1):GND   I177 @T6G_MB_LIB.T6G(SCH_1):PAGE94
   268    GND @T6G_MB_LIB.T6G(SCH_1):GND   I177 @T6G_MB_LIB.T6G(SCH_1):PAGE94
   270    GND @T6G_MB_LIB.T6G(SCH_1):GND   I177 @T6G_MB_LIB.T6G(SCH_1):PAGE94
   273    GND @T6G_MB_LIB.T6G(SCH_1):GND   I177 @T6G_MB_LIB.T6G(SCH_1):PAGE94
   275    GND @T6G_MB_LIB.T6G(SCH_1):GND   I177 @T6G_MB_LIB.T6G(SCH_1):PAGE94
   277    GND @T6G_MB_LIB.T6G(SCH_1):GND   I177 @T6G_MB_LIB.T6G(SCH_1):PAGE94
   279    GND @T6G_MB_LIB.T6G(SCH_1):GND   I177 @T6G_MB_LIB.T6G(SCH_1):PAGE94
   281    GND @T6G_MB_LIB.T6G(SCH_1):GND   I177 @T6G_MB_LIB.T6G(SCH_1):PAGE94
   284    GND @T6G_MB_LIB.T6G(SCH_1):GND   I177 @T6G_MB_LIB.T6G(SCH_1):PAGE94
   286    GND @T6G_MB_LIB.T6G(SCH_1):GND   I177 @T6G_MB_LIB.T6G(SCH_1):PAGE94
   288    GND @T6G_MB_LIB.T6G(SCH_1):GND   I177 @T6G_MB_LIB.T6G(SCH_1):PAGE94
     1 P12V_MEM_CPU0 @T6G_MB_LIB.T6G(SCH_1):P12V_MEM_CPU0   I177 @T6G_MB_LIB.T6G(SCH_1):PAGE94
   145 P12V_MEM_CPU0 @T6G_MB_LIB.T6G(SCH_1):P12V_MEM_CPU0   I177 @T6G_MB_LIB.T6G(SCH_1):PAGE94
   146 P12V_MEM_CPU0 @T6G_MB_LIB.T6G(SCH_1):P12V_MEM_CPU0   I177 @T6G_MB_LIB.T6G(SCH_1):PAGE94
   230    GND @T6G_MB_LIB.T6G(SCH_1):GND   I177 @T6G_MB_LIB.T6G(SCH_1):PAGE94
   235    GND @T6G_MB_LIB.T6G(SCH_1):GND   I177 @T6G_MB_LIB.T6G(SCH_1):PAGE94
   240    GND @T6G_MB_LIB.T6G(SCH_1):GND   I177 @T6G_MB_LIB.T6G(SCH_1):PAGE94
   132    GND @T6G_MB_LIB.T6G(SCH_1):GND   I177 @T6G_MB_LIB.T6G(SCH_1):PAGE94
   136    GND @T6G_MB_LIB.T6G(SCH_1):GND   I177 @T6G_MB_LIB.T6G(SCH_1):PAGE94
   139    GND @T6G_MB_LIB.T6G(SCH_1):GND   I177 @T6G_MB_LIB.T6G(SCH_1):PAGE94
   141    GND @T6G_MB_LIB.T6G(SCH_1):GND   I177 @T6G_MB_LIB.T6G(SCH_1):PAGE94
    G1    GND @T6G_MB_LIB.T6G(SCH_1):GND   I177 @T6G_MB_LIB.T6G(SCH_1):PAGE94
    G2    GND @T6G_MB_LIB.T6G(SCH_1):GND   I177 @T6G_MB_LIB.T6G(SCH_1):PAGE94
    G3    GND @T6G_MB_LIB.T6G(SCH_1):GND   I177 @T6G_MB_LIB.T6G(SCH_1):PAGE94

 J69 SCONN288_DDR506112002KQ-SCONN288_DDR506112002KQ,SMA
     3 P3V3_AUX @T6G_MB_LIB.T6G(SCH_1):P3V3_AUX    I22 @T6G_MB_LIB.T6G(SCH_1):PAGE92
     2     NC     NC    I22 @T6G_MB_LIB.T6G(SCH_1):PAGE92
   144     NC     NC    I22 @T6G_MB_LIB.T6G(SCH_1):PAGE92
   149     NC     NC    I22 @T6G_MB_LIB.T6G(SCH_1):PAGE92
   150     NC     NC    I22 @T6G_MB_LIB.T6G(SCH_1):PAGE92
   220     NC     NC    I22 @T6G_MB_LIB.T6G(SCH_1):PAGE92
   231     NC     NC    I22 @T6G_MB_LIB.T6G(SCH_1):PAGE92
   232     NC     NC    I22 @T6G_MB_LIB.T6G(SCH_1):PAGE92
   207 M_H_CPU0_RESET_N @T6G_MB_LIB.T6G(SCH_1):M_H_CPU0_RESET_N    I22 @T6G_MB_LIB.T6G(SCH_1):PAGE92
   147 PWRGD_CHH_CPU0_DIMM @T6G_MB_LIB.T6G(SCH_1):PWRGD_CHH_CPU0_DIMM    I22 @T6G_MB_LIB.T6G(SCH_1):PAGE92
   227 M_H_CPU0_SB_PAR @T6G_MB_LIB.T6G(SCH_1):M_H_CPU0_SB_PAR    I22 @T6G_MB_LIB.T6G(SCH_1):PAGE92
    74 M_H_CPU0_SA_PAR @T6G_MB_LIB.T6G(SCH_1):M_H_CPU0_SA_PAR    I22 @T6G_MB_LIB.T6G(SCH_1):PAGE92
    87 M_H_CPU0_SB_RSP<0> @T6G_MB_LIB.T6G(SCH_1):M_H_CPU0_SB_RSP(0)    I22 @T6G_MB_LIB.T6G(SCH_1):PAGE92
    86 M_H_CPU0_SA_RSP<0> @T6G_MB_LIB.T6G(SCH_1):M_H_CPU0_SA_RSP(0)    I22 @T6G_MB_LIB.T6G(SCH_1):PAGE92
     5 I3C_SPD_DDRH_CPU0_SDA @T6G_MB_LIB.T6G(SCH_1):I3C_SPD_DDRH_CPU0_SDA    I22 @T6G_MB_LIB.T6G(SCH_1):PAGE92
     4 I3C_SPD_DDRH_CPU0_SCL @T6G_MB_LIB.T6G(SCH_1):I3C_SPD_DDRH_CPU0_SCL    I22 @T6G_MB_LIB.T6G(SCH_1):PAGE92
   148 PD_CHH_CPU0_DIMM_SAA @T6G_MB_LIB.T6G(SCH_1):PD_CHH_CPU0_DIMM_SAA    I22 @T6G_MB_LIB.T6G(SCH_1):PAGE92
   100 M_H_CPU0_SB_DQ<0> @T6G_MB_LIB.T6G(SCH_1):M_H_CPU0_SB_DQ(0)    I22 @T6G_MB_LIB.T6G(SCH_1):PAGE92
   102 M_H_CPU0_SB_DQ<1> @T6G_MB_LIB.T6G(SCH_1):M_H_CPU0_SB_DQ(1)    I22 @T6G_MB_LIB.T6G(SCH_1):PAGE92
   245 M_H_CPU0_SB_DQ<2> @T6G_MB_LIB.T6G(SCH_1):M_H_CPU0_SB_DQ(2)    I22 @T6G_MB_LIB.T6G(SCH_1):PAGE92
   247 M_H_CPU0_SB_DQ<3> @T6G_MB_LIB.T6G(SCH_1):M_H_CPU0_SB_DQ(3)    I22 @T6G_MB_LIB.T6G(SCH_1):PAGE92
   107 M_H_CPU0_SB_DQ<4> @T6G_MB_LIB.T6G(SCH_1):M_H_CPU0_SB_DQ(4)    I22 @T6G_MB_LIB.T6G(SCH_1):PAGE92
   109 M_H_CPU0_SB_DQ<5> @T6G_MB_LIB.T6G(SCH_1):M_H_CPU0_SB_DQ(5)    I22 @T6G_MB_LIB.T6G(SCH_1):PAGE92
   252 M_H_CPU0_SB_DQ<6> @T6G_MB_LIB.T6G(SCH_1):M_H_CPU0_SB_DQ(6)    I22 @T6G_MB_LIB.T6G(SCH_1):PAGE92
   254 M_H_CPU0_SB_DQ<7> @T6G_MB_LIB.T6G(SCH_1):M_H_CPU0_SB_DQ(7)    I22 @T6G_MB_LIB.T6G(SCH_1):PAGE92
   111 M_H_CPU0_SB_DQ<8> @T6G_MB_LIB.T6G(SCH_1):M_H_CPU0_SB_DQ(8)    I22 @T6G_MB_LIB.T6G(SCH_1):PAGE92
   113 M_H_CPU0_SB_DQ<9> @T6G_MB_LIB.T6G(SCH_1):M_H_CPU0_SB_DQ(9)    I22 @T6G_MB_LIB.T6G(SCH_1):PAGE92
   256 M_H_CPU0_SB_DQ<10> @T6G_MB_LIB.T6G(SCH_1):M_H_CPU0_SB_DQ(10)    I22 @T6G_MB_LIB.T6G(SCH_1):PAGE92
   258 M_H_CPU0_SB_DQ<11> @T6G_MB_LIB.T6G(SCH_1):M_H_CPU0_SB_DQ(11)    I22 @T6G_MB_LIB.T6G(SCH_1):PAGE92
   118 M_H_CPU0_SB_DQ<12> @T6G_MB_LIB.T6G(SCH_1):M_H_CPU0_SB_DQ(12)    I22 @T6G_MB_LIB.T6G(SCH_1):PAGE92
   120 M_H_CPU0_SB_DQ<13> @T6G_MB_LIB.T6G(SCH_1):M_H_CPU0_SB_DQ(13)    I22 @T6G_MB_LIB.T6G(SCH_1):PAGE92
   263 M_H_CPU0_SB_DQ<14> @T6G_MB_LIB.T6G(SCH_1):M_H_CPU0_SB_DQ(14)    I22 @T6G_MB_LIB.T6G(SCH_1):PAGE92
   265 M_H_CPU0_SB_DQ<15> @T6G_MB_LIB.T6G(SCH_1):M_H_CPU0_SB_DQ(15)    I22 @T6G_MB_LIB.T6G(SCH_1):PAGE92
   122 M_H_CPU0_SB_DQ<16> @T6G_MB_LIB.T6G(SCH_1):M_H_CPU0_SB_DQ(16)    I22 @T6G_MB_LIB.T6G(SCH_1):PAGE92
   124 M_H_CPU0_SB_DQ<17> @T6G_MB_LIB.T6G(SCH_1):M_H_CPU0_SB_DQ(17)    I22 @T6G_MB_LIB.T6G(SCH_1):PAGE92
   267 M_H_CPU0_SB_DQ<18> @T6G_MB_LIB.T6G(SCH_1):M_H_CPU0_SB_DQ(18)    I22 @T6G_MB_LIB.T6G(SCH_1):PAGE92
   269 M_H_CPU0_SB_DQ<19> @T6G_MB_LIB.T6G(SCH_1):M_H_CPU0_SB_DQ(19)    I22 @T6G_MB_LIB.T6G(SCH_1):PAGE92
   129 M_H_CPU0_SB_DQ<20> @T6G_MB_LIB.T6G(SCH_1):M_H_CPU0_SB_DQ(20)    I22 @T6G_MB_LIB.T6G(SCH_1):PAGE92
   131 M_H_CPU0_SB_DQ<21> @T6G_MB_LIB.T6G(SCH_1):M_H_CPU0_SB_DQ(21)    I22 @T6G_MB_LIB.T6G(SCH_1):PAGE92
   274 M_H_CPU0_SB_DQ<22> @T6G_MB_LIB.T6G(SCH_1):M_H_CPU0_SB_DQ(22)    I22 @T6G_MB_LIB.T6G(SCH_1):PAGE92
   276 M_H_CPU0_SB_DQ<23> @T6G_MB_LIB.T6G(SCH_1):M_H_CPU0_SB_DQ(23)    I22 @T6G_MB_LIB.T6G(SCH_1):PAGE92
   133 M_H_CPU0_SB_DQ<24> @T6G_MB_LIB.T6G(SCH_1):M_H_CPU0_SB_DQ(24)    I22 @T6G_MB_LIB.T6G(SCH_1):PAGE92
   135 M_H_CPU0_SB_DQ<25> @T6G_MB_LIB.T6G(SCH_1):M_H_CPU0_SB_DQ(25)    I22 @T6G_MB_LIB.T6G(SCH_1):PAGE92
   278 M_H_CPU0_SB_DQ<26> @T6G_MB_LIB.T6G(SCH_1):M_H_CPU0_SB_DQ(26)    I22 @T6G_MB_LIB.T6G(SCH_1):PAGE92
   280 M_H_CPU0_SB_DQ<27> @T6G_MB_LIB.T6G(SCH_1):M_H_CPU0_SB_DQ(27)    I22 @T6G_MB_LIB.T6G(SCH_1):PAGE92
   140 M_H_CPU0_SB_DQ<28> @T6G_MB_LIB.T6G(SCH_1):M_H_CPU0_SB_DQ(28)    I22 @T6G_MB_LIB.T6G(SCH_1):PAGE92
   142 M_H_CPU0_SB_DQ<29> @T6G_MB_LIB.T6G(SCH_1):M_H_CPU0_SB_DQ(29)    I22 @T6G_MB_LIB.T6G(SCH_1):PAGE92
   285 M_H_CPU0_SB_DQ<30> @T6G_MB_LIB.T6G(SCH_1):M_H_CPU0_SB_DQ(30)    I22 @T6G_MB_LIB.T6G(SCH_1):PAGE92
   287 M_H_CPU0_SB_DQ<31> @T6G_MB_LIB.T6G(SCH_1):M_H_CPU0_SB_DQ(31)    I22 @T6G_MB_LIB.T6G(SCH_1):PAGE92
     7 M_H_CPU0_SA_DQ<0> @T6G_MB_LIB.T6G(SCH_1):M_H_CPU0_SA_DQ(0)    I22 @T6G_MB_LIB.T6G(SCH_1):PAGE92
     9 M_H_CPU0_SA_DQ<1> @T6G_MB_LIB.T6G(SCH_1):M_H_CPU0_SA_DQ(1)    I22 @T6G_MB_LIB.T6G(SCH_1):PAGE92
   152 M_H_CPU0_SA_DQ<2> @T6G_MB_LIB.T6G(SCH_1):M_H_CPU0_SA_DQ(2)    I22 @T6G_MB_LIB.T6G(SCH_1):PAGE92
   154 M_H_CPU0_SA_DQ<3> @T6G_MB_LIB.T6G(SCH_1):M_H_CPU0_SA_DQ(3)    I22 @T6G_MB_LIB.T6G(SCH_1):PAGE92
    14 M_H_CPU0_SA_DQ<4> @T6G_MB_LIB.T6G(SCH_1):M_H_CPU0_SA_DQ(4)    I22 @T6G_MB_LIB.T6G(SCH_1):PAGE92
    16 M_H_CPU0_SA_DQ<5> @T6G_MB_LIB.T6G(SCH_1):M_H_CPU0_SA_DQ(5)    I22 @T6G_MB_LIB.T6G(SCH_1):PAGE92
   159 M_H_CPU0_SA_DQ<6> @T6G_MB_LIB.T6G(SCH_1):M_H_CPU0_SA_DQ(6)    I22 @T6G_MB_LIB.T6G(SCH_1):PAGE92
   161 M_H_CPU0_SA_DQ<7> @T6G_MB_LIB.T6G(SCH_1):M_H_CPU0_SA_DQ(7)    I22 @T6G_MB_LIB.T6G(SCH_1):PAGE92
    18 M_H_CPU0_SA_DQ<8> @T6G_MB_LIB.T6G(SCH_1):M_H_CPU0_SA_DQ(8)    I22 @T6G_MB_LIB.T6G(SCH_1):PAGE92
    20 M_H_CPU0_SA_DQ<9> @T6G_MB_LIB.T6G(SCH_1):M_H_CPU0_SA_DQ(9)    I22 @T6G_MB_LIB.T6G(SCH_1):PAGE92
   163 M_H_CPU0_SA_DQ<10> @T6G_MB_LIB.T6G(SCH_1):M_H_CPU0_SA_DQ(10)    I22 @T6G_MB_LIB.T6G(SCH_1):PAGE92
   165 M_H_CPU0_SA_DQ<11> @T6G_MB_LIB.T6G(SCH_1):M_H_CPU0_SA_DQ(11)    I22 @T6G_MB_LIB.T6G(SCH_1):PAGE92
    25 M_H_CPU0_SA_DQ<12> @T6G_MB_LIB.T6G(SCH_1):M_H_CPU0_SA_DQ(12)    I22 @T6G_MB_LIB.T6G(SCH_1):PAGE92
    27 M_H_CPU0_SA_DQ<13> @T6G_MB_LIB.T6G(SCH_1):M_H_CPU0_SA_DQ(13)    I22 @T6G_MB_LIB.T6G(SCH_1):PAGE92
   170 M_H_CPU0_SA_DQ<14> @T6G_MB_LIB.T6G(SCH_1):M_H_CPU0_SA_DQ(14)    I22 @T6G_MB_LIB.T6G(SCH_1):PAGE92
   172 M_H_CPU0_SA_DQ<15> @T6G_MB_LIB.T6G(SCH_1):M_H_CPU0_SA_DQ(15)    I22 @T6G_MB_LIB.T6G(SCH_1):PAGE92
    29 M_H_CPU0_SA_DQ<16> @T6G_MB_LIB.T6G(SCH_1):M_H_CPU0_SA_DQ(16)    I22 @T6G_MB_LIB.T6G(SCH_1):PAGE92
    31 M_H_CPU0_SA_DQ<17> @T6G_MB_LIB.T6G(SCH_1):M_H_CPU0_SA_DQ(17)    I22 @T6G_MB_LIB.T6G(SCH_1):PAGE92
   174 M_H_CPU0_SA_DQ<18> @T6G_MB_LIB.T6G(SCH_1):M_H_CPU0_SA_DQ(18)    I22 @T6G_MB_LIB.T6G(SCH_1):PAGE92
   176 M_H_CPU0_SA_DQ<19> @T6G_MB_LIB.T6G(SCH_1):M_H_CPU0_SA_DQ(19)    I22 @T6G_MB_LIB.T6G(SCH_1):PAGE92
    36 M_H_CPU0_SA_DQ<20> @T6G_MB_LIB.T6G(SCH_1):M_H_CPU0_SA_DQ(20)    I22 @T6G_MB_LIB.T6G(SCH_1):PAGE92
    38 M_H_CPU0_SA_DQ<21> @T6G_MB_LIB.T6G(SCH_1):M_H_CPU0_SA_DQ(21)    I22 @T6G_MB_LIB.T6G(SCH_1):PAGE92
   181 M_H_CPU0_SA_DQ<22> @T6G_MB_LIB.T6G(SCH_1):M_H_CPU0_SA_DQ(22)    I22 @T6G_MB_LIB.T6G(SCH_1):PAGE92
   183 M_H_CPU0_SA_DQ<23> @T6G_MB_LIB.T6G(SCH_1):M_H_CPU0_SA_DQ(23)    I22 @T6G_MB_LIB.T6G(SCH_1):PAGE92
    40 M_H_CPU0_SA_DQ<24> @T6G_MB_LIB.T6G(SCH_1):M_H_CPU0_SA_DQ(24)    I22 @T6G_MB_LIB.T6G(SCH_1):PAGE92
    42 M_H_CPU0_SA_DQ<25> @T6G_MB_LIB.T6G(SCH_1):M_H_CPU0_SA_DQ(25)    I22 @T6G_MB_LIB.T6G(SCH_1):PAGE92
   185 M_H_CPU0_SA_DQ<26> @T6G_MB_LIB.T6G(SCH_1):M_H_CPU0_SA_DQ(26)    I22 @T6G_MB_LIB.T6G(SCH_1):PAGE92
   187 M_H_CPU0_SA_DQ<27> @T6G_MB_LIB.T6G(SCH_1):M_H_CPU0_SA_DQ(27)    I22 @T6G_MB_LIB.T6G(SCH_1):PAGE92
    47 M_H_CPU0_SA_DQ<28> @T6G_MB_LIB.T6G(SCH_1):M_H_CPU0_SA_DQ(28)    I22 @T6G_MB_LIB.T6G(SCH_1):PAGE92
    49 M_H_CPU0_SA_DQ<29> @T6G_MB_LIB.T6G(SCH_1):M_H_CPU0_SA_DQ(29)    I22 @T6G_MB_LIB.T6G(SCH_1):PAGE92
   192 M_H_CPU0_SA_DQ<30> @T6G_MB_LIB.T6G(SCH_1):M_H_CPU0_SA_DQ(30)    I22 @T6G_MB_LIB.T6G(SCH_1):PAGE92
   229 M_H_CPU0_SB_CS_N<1> @T6G_MB_LIB.T6G(SCH_1):M_H_CPU0_SB_CS_N(1)    I22 @T6G_MB_LIB.T6G(SCH_1):PAGE92
   209 M_H_CPU0_SA_CS_N<1> @T6G_MB_LIB.T6G(SCH_1):M_H_CPU0_SA_CS_N(1)    I22 @T6G_MB_LIB.T6G(SCH_1):PAGE92
    84 M_H_CPU0_SB_CS_N<0> @T6G_MB_LIB.T6G(SCH_1):M_H_CPU0_SB_CS_N(0)    I22 @T6G_MB_LIB.T6G(SCH_1):PAGE92
    64 M_H_CPU0_SA_CS_N<0> @T6G_MB_LIB.T6G(SCH_1):M_H_CPU0_SA_CS_N(0)    I22 @T6G_MB_LIB.T6G(SCH_1):PAGE92
   217 M_H_CPU0_CLK_DP<0> @T6G_MB_LIB.T6G(SCH_1):M_H_CPU0_CLK_DP(0)    I22 @T6G_MB_LIB.T6G(SCH_1):PAGE92
   218 M_H_CPU0_CLK_DN<0> @T6G_MB_LIB.T6G(SCH_1):M_H_CPU0_CLK_DN(0)    I22 @T6G_MB_LIB.T6G(SCH_1):PAGE92
    96 M_H_CPU0_SB_CB<0> @T6G_MB_LIB.T6G(SCH_1):M_H_CPU0_SB_CB(0)    I22 @T6G_MB_LIB.T6G(SCH_1):PAGE92
    98 M_H_CPU0_SB_CB<1> @T6G_MB_LIB.T6G(SCH_1):M_H_CPU0_SB_CB(1)    I22 @T6G_MB_LIB.T6G(SCH_1):PAGE92
   241 M_H_CPU0_SB_CB<2> @T6G_MB_LIB.T6G(SCH_1):M_H_CPU0_SB_CB(2)    I22 @T6G_MB_LIB.T6G(SCH_1):PAGE92
   243 M_H_CPU0_SB_CB<3> @T6G_MB_LIB.T6G(SCH_1):M_H_CPU0_SB_CB(3)    I22 @T6G_MB_LIB.T6G(SCH_1):PAGE92
    89 M_H_CPU0_SB_CB<4> @T6G_MB_LIB.T6G(SCH_1):M_H_CPU0_SB_CB(4)    I22 @T6G_MB_LIB.T6G(SCH_1):PAGE92
    91 M_H_CPU0_SB_CB<5> @T6G_MB_LIB.T6G(SCH_1):M_H_CPU0_SB_CB(5)    I22 @T6G_MB_LIB.T6G(SCH_1):PAGE92
   234 M_H_CPU0_SB_CB<6> @T6G_MB_LIB.T6G(SCH_1):M_H_CPU0_SB_CB(6)    I22 @T6G_MB_LIB.T6G(SCH_1):PAGE92
    51 M_H_CPU0_SA_CB<0> @T6G_MB_LIB.T6G(SCH_1):M_H_CPU0_SA_CB(0)    I22 @T6G_MB_LIB.T6G(SCH_1):PAGE92
   196 M_H_CPU0_SA_CB<2> @T6G_MB_LIB.T6G(SCH_1):M_H_CPU0_SA_CB(2)    I22 @T6G_MB_LIB.T6G(SCH_1):PAGE92
   198 M_H_CPU0_SA_CB<3> @T6G_MB_LIB.T6G(SCH_1):M_H_CPU0_SA_CB(3)    I22 @T6G_MB_LIB.T6G(SCH_1):PAGE92
    60 M_H_CPU0_SA_CB<5> @T6G_MB_LIB.T6G(SCH_1):M_H_CPU0_SA_CB(5)    I22 @T6G_MB_LIB.T6G(SCH_1):PAGE92
   203 M_H_CPU0_SA_CB<6> @T6G_MB_LIB.T6G(SCH_1):M_H_CPU0_SA_CB(6)    I22 @T6G_MB_LIB.T6G(SCH_1):PAGE92
    82 M_H_CPU0_SB_CA<6> @T6G_MB_LIB.T6G(SCH_1):M_H_CPU0_SB_CA(6)    I22 @T6G_MB_LIB.T6G(SCH_1):PAGE92
    72 M_H_CPU0_SA_CA<6> @T6G_MB_LIB.T6G(SCH_1):M_H_CPU0_SA_CA(6)    I22 @T6G_MB_LIB.T6G(SCH_1):PAGE92
   225 M_H_CPU0_SB_CA<5> @T6G_MB_LIB.T6G(SCH_1):M_H_CPU0_SB_CA(5)    I22 @T6G_MB_LIB.T6G(SCH_1):PAGE92
   215 M_H_CPU0_SA_CA<5> @T6G_MB_LIB.T6G(SCH_1):M_H_CPU0_SA_CA(5)    I22 @T6G_MB_LIB.T6G(SCH_1):PAGE92
    80 M_H_CPU0_SB_CA<4> @T6G_MB_LIB.T6G(SCH_1):M_H_CPU0_SB_CA(4)    I22 @T6G_MB_LIB.T6G(SCH_1):PAGE92
    70 M_H_CPU0_SA_CA<4> @T6G_MB_LIB.T6G(SCH_1):M_H_CPU0_SA_CA(4)    I22 @T6G_MB_LIB.T6G(SCH_1):PAGE92
   223 M_H_CPU0_SB_CA<3> @T6G_MB_LIB.T6G(SCH_1):M_H_CPU0_SB_CA(3)    I22 @T6G_MB_LIB.T6G(SCH_1):PAGE92
   213 M_H_CPU0_SA_CA<3> @T6G_MB_LIB.T6G(SCH_1):M_H_CPU0_SA_CA(3)    I22 @T6G_MB_LIB.T6G(SCH_1):PAGE92
    78 M_H_CPU0_SB_CA<2> @T6G_MB_LIB.T6G(SCH_1):M_H_CPU0_SB_CA(2)    I22 @T6G_MB_LIB.T6G(SCH_1):PAGE92
    68 M_H_CPU0_SA_CA<2> @T6G_MB_LIB.T6G(SCH_1):M_H_CPU0_SA_CA(2)    I22 @T6G_MB_LIB.T6G(SCH_1):PAGE92
   221 M_H_CPU0_SB_CA<1> @T6G_MB_LIB.T6G(SCH_1):M_H_CPU0_SB_CA(1)    I22 @T6G_MB_LIB.T6G(SCH_1):PAGE92
   211 M_H_CPU0_SA_CA<1> @T6G_MB_LIB.T6G(SCH_1):M_H_CPU0_SA_CA(1)    I22 @T6G_MB_LIB.T6G(SCH_1):PAGE92
    76 M_H_CPU0_SB_CA<0> @T6G_MB_LIB.T6G(SCH_1):M_H_CPU0_SB_CA(0)    I22 @T6G_MB_LIB.T6G(SCH_1):PAGE92
    66 M_H_CPU0_SA_CA<0> @T6G_MB_LIB.T6G(SCH_1):M_H_CPU0_SA_CA(0)    I22 @T6G_MB_LIB.T6G(SCH_1):PAGE92
    62 M_H_CPU0_ALERT_N @T6G_MB_LIB.T6G(SCH_1):M_H_CPU0_ALERT_N    I22 @T6G_MB_LIB.T6G(SCH_1):PAGE92
   236 M_H_CPU0_SB_CB<7> @T6G_MB_LIB.T6G(SCH_1):M_H_CPU0_SB_CB(7)    I22 @T6G_MB_LIB.T6G(SCH_1):PAGE92
    53 M_H_CPU0_SA_CB<1> @T6G_MB_LIB.T6G(SCH_1):M_H_CPU0_SA_CB(1)    I22 @T6G_MB_LIB.T6G(SCH_1):PAGE92
    58 M_H_CPU0_SA_CB<4> @T6G_MB_LIB.T6G(SCH_1):M_H_CPU0_SA_CB(4)    I22 @T6G_MB_LIB.T6G(SCH_1):PAGE92
   205 M_H_CPU0_SA_CB<7> @T6G_MB_LIB.T6G(SCH_1):M_H_CPU0_SA_CB(7)    I22 @T6G_MB_LIB.T6G(SCH_1):PAGE92
   194 M_H_CPU0_SA_DQ<31> @T6G_MB_LIB.T6G(SCH_1):M_H_CPU0_SA_DQ(31)    I22 @T6G_MB_LIB.T6G(SCH_1):PAGE92
    93 M_H_CPU0_SB_DQS_DP<9> @T6G_MB_LIB.T6G(SCH_1):M_H_CPU0_SB_DQS_DP(9)   I237 @T6G_MB_LIB.T6G(SCH_1):PAGE92
    94 M_H_CPU0_SB_DQS_DN<9> @T6G_MB_LIB.T6G(SCH_1):M_H_CPU0_SB_DQS_DN(9)   I237 @T6G_MB_LIB.T6G(SCH_1):PAGE92
   201 M_H_CPU0_SA_DQS_DP<9> @T6G_MB_LIB.T6G(SCH_1):M_H_CPU0_SA_DQS_DP(9)   I237 @T6G_MB_LIB.T6G(SCH_1):PAGE92
   200 M_H_CPU0_SA_DQS_DN<9> @T6G_MB_LIB.T6G(SCH_1):M_H_CPU0_SA_DQS_DN(9)   I237 @T6G_MB_LIB.T6G(SCH_1):PAGE92
   190 M_H_CPU0_SA_DQS_DP<8> @T6G_MB_LIB.T6G(SCH_1):M_H_CPU0_SA_DQS_DP(8)   I237 @T6G_MB_LIB.T6G(SCH_1):PAGE92
   189 M_H_CPU0_SA_DQS_DN<8> @T6G_MB_LIB.T6G(SCH_1):M_H_CPU0_SA_DQS_DN(8)   I237 @T6G_MB_LIB.T6G(SCH_1):PAGE92
   271 M_H_CPU0_SB_DQS_DN<7> @T6G_MB_LIB.T6G(SCH_1):M_H_CPU0_SB_DQS_DN(7)   I237 @T6G_MB_LIB.T6G(SCH_1):PAGE92
   179 M_H_CPU0_SA_DQS_DP<7> @T6G_MB_LIB.T6G(SCH_1):M_H_CPU0_SA_DQS_DP(7)   I237 @T6G_MB_LIB.T6G(SCH_1):PAGE92
   261 M_H_CPU0_SB_DQS_DP<6> @T6G_MB_LIB.T6G(SCH_1):M_H_CPU0_SB_DQS_DP(6)   I237 @T6G_MB_LIB.T6G(SCH_1):PAGE92
   260 M_H_CPU0_SB_DQS_DN<6> @T6G_MB_LIB.T6G(SCH_1):M_H_CPU0_SB_DQS_DN(6)   I237 @T6G_MB_LIB.T6G(SCH_1):PAGE92
   167 M_H_CPU0_SA_DQS_DN<6> @T6G_MB_LIB.T6G(SCH_1):M_H_CPU0_SA_DQS_DN(6)   I237 @T6G_MB_LIB.T6G(SCH_1):PAGE92
   250 M_H_CPU0_SB_DQS_DP<5> @T6G_MB_LIB.T6G(SCH_1):M_H_CPU0_SB_DQS_DP(5)   I237 @T6G_MB_LIB.T6G(SCH_1):PAGE92
   249 M_H_CPU0_SB_DQS_DN<5> @T6G_MB_LIB.T6G(SCH_1):M_H_CPU0_SB_DQS_DN(5)   I237 @T6G_MB_LIB.T6G(SCH_1):PAGE92
   157 M_H_CPU0_SA_DQS_DP<5> @T6G_MB_LIB.T6G(SCH_1):M_H_CPU0_SA_DQS_DP(5)   I237 @T6G_MB_LIB.T6G(SCH_1):PAGE92
   156 M_H_CPU0_SA_DQS_DN<5> @T6G_MB_LIB.T6G(SCH_1):M_H_CPU0_SA_DQS_DN(5)   I237 @T6G_MB_LIB.T6G(SCH_1):PAGE92
   239 M_H_CPU0_SB_DQS_DP<4> @T6G_MB_LIB.T6G(SCH_1):M_H_CPU0_SB_DQS_DP(4)   I237 @T6G_MB_LIB.T6G(SCH_1):PAGE92
   238 M_H_CPU0_SB_DQS_DN<4> @T6G_MB_LIB.T6G(SCH_1):M_H_CPU0_SB_DQS_DN(4)   I237 @T6G_MB_LIB.T6G(SCH_1):PAGE92
    55 M_H_CPU0_SA_DQS_DP<4> @T6G_MB_LIB.T6G(SCH_1):M_H_CPU0_SA_DQS_DP(4)   I237 @T6G_MB_LIB.T6G(SCH_1):PAGE92
    56 M_H_CPU0_SA_DQS_DN<4> @T6G_MB_LIB.T6G(SCH_1):M_H_CPU0_SA_DQS_DN(4)   I237 @T6G_MB_LIB.T6G(SCH_1):PAGE92
   137 M_H_CPU0_SB_DQS_DP<3> @T6G_MB_LIB.T6G(SCH_1):M_H_CPU0_SB_DQS_DP(3)   I237 @T6G_MB_LIB.T6G(SCH_1):PAGE92
   138 M_H_CPU0_SB_DQS_DN<3> @T6G_MB_LIB.T6G(SCH_1):M_H_CPU0_SB_DQS_DN(3)   I237 @T6G_MB_LIB.T6G(SCH_1):PAGE92
    44 M_H_CPU0_SA_DQS_DP<3> @T6G_MB_LIB.T6G(SCH_1):M_H_CPU0_SA_DQS_DP(3)   I237 @T6G_MB_LIB.T6G(SCH_1):PAGE92
    45 M_H_CPU0_SA_DQS_DN<3> @T6G_MB_LIB.T6G(SCH_1):M_H_CPU0_SA_DQS_DN(3)   I237 @T6G_MB_LIB.T6G(SCH_1):PAGE92
   126 M_H_CPU0_SB_DQS_DP<2> @T6G_MB_LIB.T6G(SCH_1):M_H_CPU0_SB_DQS_DP(2)   I237 @T6G_MB_LIB.T6G(SCH_1):PAGE92
   127 M_H_CPU0_SB_DQS_DN<2> @T6G_MB_LIB.T6G(SCH_1):M_H_CPU0_SB_DQS_DN(2)   I237 @T6G_MB_LIB.T6G(SCH_1):PAGE92
    33 M_H_CPU0_SA_DQS_DP<2> @T6G_MB_LIB.T6G(SCH_1):M_H_CPU0_SA_DQS_DP(2)   I237 @T6G_MB_LIB.T6G(SCH_1):PAGE92
    34 M_H_CPU0_SA_DQS_DN<2> @T6G_MB_LIB.T6G(SCH_1):M_H_CPU0_SA_DQS_DN(2)   I237 @T6G_MB_LIB.T6G(SCH_1):PAGE92
   115 M_H_CPU0_SB_DQS_DP<1> @T6G_MB_LIB.T6G(SCH_1):M_H_CPU0_SB_DQS_DP(1)   I237 @T6G_MB_LIB.T6G(SCH_1):PAGE92
   116 M_H_CPU0_SB_DQS_DN<1> @T6G_MB_LIB.T6G(SCH_1):M_H_CPU0_SB_DQS_DN(1)   I237 @T6G_MB_LIB.T6G(SCH_1):PAGE92
    22 M_H_CPU0_SA_DQS_DP<1> @T6G_MB_LIB.T6G(SCH_1):M_H_CPU0_SA_DQS_DP(1)   I237 @T6G_MB_LIB.T6G(SCH_1):PAGE92
    23 M_H_CPU0_SA_DQS_DN<1> @T6G_MB_LIB.T6G(SCH_1):M_H_CPU0_SA_DQS_DN(1)   I237 @T6G_MB_LIB.T6G(SCH_1):PAGE92
   104 M_H_CPU0_SB_DQS_DP<0> @T6G_MB_LIB.T6G(SCH_1):M_H_CPU0_SB_DQS_DP(0)   I237 @T6G_MB_LIB.T6G(SCH_1):PAGE92
   105 M_H_CPU0_SB_DQS_DN<0> @T6G_MB_LIB.T6G(SCH_1):M_H_CPU0_SB_DQS_DN(0)   I237 @T6G_MB_LIB.T6G(SCH_1):PAGE92
    11 M_H_CPU0_SA_DQS_DP<0> @T6G_MB_LIB.T6G(SCH_1):M_H_CPU0_SA_DQS_DP(0)   I237 @T6G_MB_LIB.T6G(SCH_1):PAGE92
    12 M_H_CPU0_SA_DQS_DN<0> @T6G_MB_LIB.T6G(SCH_1):M_H_CPU0_SA_DQS_DN(0)   I237 @T6G_MB_LIB.T6G(SCH_1):PAGE92
   272 M_H_CPU0_SB_DQS_DP<7> @T6G_MB_LIB.T6G(SCH_1):M_H_CPU0_SB_DQS_DP(7)   I237 @T6G_MB_LIB.T6G(SCH_1):PAGE92
   282 M_H_CPU0_SB_DQS_DN<8> @T6G_MB_LIB.T6G(SCH_1):M_H_CPU0_SB_DQS_DN(8)   I237 @T6G_MB_LIB.T6G(SCH_1):PAGE92
   283 M_H_CPU0_SB_DQS_DP<8> @T6G_MB_LIB.T6G(SCH_1):M_H_CPU0_SB_DQS_DP(8)   I237 @T6G_MB_LIB.T6G(SCH_1):PAGE92
   168 M_H_CPU0_SA_DQS_DP<6> @T6G_MB_LIB.T6G(SCH_1):M_H_CPU0_SA_DQS_DP(6)   I237 @T6G_MB_LIB.T6G(SCH_1):PAGE92
   178 M_H_CPU0_SA_DQS_DN<7> @T6G_MB_LIB.T6G(SCH_1):M_H_CPU0_SA_DQS_DN(7)   I237 @T6G_MB_LIB.T6G(SCH_1):PAGE92
     6    GND @T6G_MB_LIB.T6G(SCH_1):GND   I177 @T6G_MB_LIB.T6G(SCH_1):PAGE92
     8    GND @T6G_MB_LIB.T6G(SCH_1):GND   I177 @T6G_MB_LIB.T6G(SCH_1):PAGE92
    10    GND @T6G_MB_LIB.T6G(SCH_1):GND   I177 @T6G_MB_LIB.T6G(SCH_1):PAGE92
    13    GND @T6G_MB_LIB.T6G(SCH_1):GND   I177 @T6G_MB_LIB.T6G(SCH_1):PAGE92
    15    GND @T6G_MB_LIB.T6G(SCH_1):GND   I177 @T6G_MB_LIB.T6G(SCH_1):PAGE92
    17    GND @T6G_MB_LIB.T6G(SCH_1):GND   I177 @T6G_MB_LIB.T6G(SCH_1):PAGE92
    19    GND @T6G_MB_LIB.T6G(SCH_1):GND   I177 @T6G_MB_LIB.T6G(SCH_1):PAGE92
    21    GND @T6G_MB_LIB.T6G(SCH_1):GND   I177 @T6G_MB_LIB.T6G(SCH_1):PAGE92
    24    GND @T6G_MB_LIB.T6G(SCH_1):GND   I177 @T6G_MB_LIB.T6G(SCH_1):PAGE92
    26    GND @T6G_MB_LIB.T6G(SCH_1):GND   I177 @T6G_MB_LIB.T6G(SCH_1):PAGE92
    28    GND @T6G_MB_LIB.T6G(SCH_1):GND   I177 @T6G_MB_LIB.T6G(SCH_1):PAGE92
    30    GND @T6G_MB_LIB.T6G(SCH_1):GND   I177 @T6G_MB_LIB.T6G(SCH_1):PAGE92
    32    GND @T6G_MB_LIB.T6G(SCH_1):GND   I177 @T6G_MB_LIB.T6G(SCH_1):PAGE92
    35    GND @T6G_MB_LIB.T6G(SCH_1):GND   I177 @T6G_MB_LIB.T6G(SCH_1):PAGE92
    37    GND @T6G_MB_LIB.T6G(SCH_1):GND   I177 @T6G_MB_LIB.T6G(SCH_1):PAGE92
    39    GND @T6G_MB_LIB.T6G(SCH_1):GND   I177 @T6G_MB_LIB.T6G(SCH_1):PAGE92
    41    GND @T6G_MB_LIB.T6G(SCH_1):GND   I177 @T6G_MB_LIB.T6G(SCH_1):PAGE92
    43    GND @T6G_MB_LIB.T6G(SCH_1):GND   I177 @T6G_MB_LIB.T6G(SCH_1):PAGE92
    46    GND @T6G_MB_LIB.T6G(SCH_1):GND   I177 @T6G_MB_LIB.T6G(SCH_1):PAGE92
    48    GND @T6G_MB_LIB.T6G(SCH_1):GND   I177 @T6G_MB_LIB.T6G(SCH_1):PAGE92
    50    GND @T6G_MB_LIB.T6G(SCH_1):GND   I177 @T6G_MB_LIB.T6G(SCH_1):PAGE92
    52    GND @T6G_MB_LIB.T6G(SCH_1):GND   I177 @T6G_MB_LIB.T6G(SCH_1):PAGE92
    54    GND @T6G_MB_LIB.T6G(SCH_1):GND   I177 @T6G_MB_LIB.T6G(SCH_1):PAGE92
    57    GND @T6G_MB_LIB.T6G(SCH_1):GND   I177 @T6G_MB_LIB.T6G(SCH_1):PAGE92
    59    GND @T6G_MB_LIB.T6G(SCH_1):GND   I177 @T6G_MB_LIB.T6G(SCH_1):PAGE92
    61    GND @T6G_MB_LIB.T6G(SCH_1):GND   I177 @T6G_MB_LIB.T6G(SCH_1):PAGE92
    63    GND @T6G_MB_LIB.T6G(SCH_1):GND   I177 @T6G_MB_LIB.T6G(SCH_1):PAGE92
    65    GND @T6G_MB_LIB.T6G(SCH_1):GND   I177 @T6G_MB_LIB.T6G(SCH_1):PAGE92
    67    GND @T6G_MB_LIB.T6G(SCH_1):GND   I177 @T6G_MB_LIB.T6G(SCH_1):PAGE92
    69    GND @T6G_MB_LIB.T6G(SCH_1):GND   I177 @T6G_MB_LIB.T6G(SCH_1):PAGE92
    71    GND @T6G_MB_LIB.T6G(SCH_1):GND   I177 @T6G_MB_LIB.T6G(SCH_1):PAGE92
    73    GND @T6G_MB_LIB.T6G(SCH_1):GND   I177 @T6G_MB_LIB.T6G(SCH_1):PAGE92
    75    GND @T6G_MB_LIB.T6G(SCH_1):GND   I177 @T6G_MB_LIB.T6G(SCH_1):PAGE92
    77    GND @T6G_MB_LIB.T6G(SCH_1):GND   I177 @T6G_MB_LIB.T6G(SCH_1):PAGE92
    79    GND @T6G_MB_LIB.T6G(SCH_1):GND   I177 @T6G_MB_LIB.T6G(SCH_1):PAGE92
    81    GND @T6G_MB_LIB.T6G(SCH_1):GND   I177 @T6G_MB_LIB.T6G(SCH_1):PAGE92
    83    GND @T6G_MB_LIB.T6G(SCH_1):GND   I177 @T6G_MB_LIB.T6G(SCH_1):PAGE92
    85    GND @T6G_MB_LIB.T6G(SCH_1):GND   I177 @T6G_MB_LIB.T6G(SCH_1):PAGE92
    88    GND @T6G_MB_LIB.T6G(SCH_1):GND   I177 @T6G_MB_LIB.T6G(SCH_1):PAGE92
    90    GND @T6G_MB_LIB.T6G(SCH_1):GND   I177 @T6G_MB_LIB.T6G(SCH_1):PAGE92
    92    GND @T6G_MB_LIB.T6G(SCH_1):GND   I177 @T6G_MB_LIB.T6G(SCH_1):PAGE92
    95    GND @T6G_MB_LIB.T6G(SCH_1):GND   I177 @T6G_MB_LIB.T6G(SCH_1):PAGE92
    97    GND @T6G_MB_LIB.T6G(SCH_1):GND   I177 @T6G_MB_LIB.T6G(SCH_1):PAGE92
    99    GND @T6G_MB_LIB.T6G(SCH_1):GND   I177 @T6G_MB_LIB.T6G(SCH_1):PAGE92
   101    GND @T6G_MB_LIB.T6G(SCH_1):GND   I177 @T6G_MB_LIB.T6G(SCH_1):PAGE92
   103    GND @T6G_MB_LIB.T6G(SCH_1):GND   I177 @T6G_MB_LIB.T6G(SCH_1):PAGE92
   106    GND @T6G_MB_LIB.T6G(SCH_1):GND   I177 @T6G_MB_LIB.T6G(SCH_1):PAGE92
   108    GND @T6G_MB_LIB.T6G(SCH_1):GND   I177 @T6G_MB_LIB.T6G(SCH_1):PAGE92
   110    GND @T6G_MB_LIB.T6G(SCH_1):GND   I177 @T6G_MB_LIB.T6G(SCH_1):PAGE92
   112    GND @T6G_MB_LIB.T6G(SCH_1):GND   I177 @T6G_MB_LIB.T6G(SCH_1):PAGE92
   114    GND @T6G_MB_LIB.T6G(SCH_1):GND   I177 @T6G_MB_LIB.T6G(SCH_1):PAGE92
   117    GND @T6G_MB_LIB.T6G(SCH_1):GND   I177 @T6G_MB_LIB.T6G(SCH_1):PAGE92
   119    GND @T6G_MB_LIB.T6G(SCH_1):GND   I177 @T6G_MB_LIB.T6G(SCH_1):PAGE92
   121    GND @T6G_MB_LIB.T6G(SCH_1):GND   I177 @T6G_MB_LIB.T6G(SCH_1):PAGE92
   123    GND @T6G_MB_LIB.T6G(SCH_1):GND   I177 @T6G_MB_LIB.T6G(SCH_1):PAGE92
   125    GND @T6G_MB_LIB.T6G(SCH_1):GND   I177 @T6G_MB_LIB.T6G(SCH_1):PAGE92
   128    GND @T6G_MB_LIB.T6G(SCH_1):GND   I177 @T6G_MB_LIB.T6G(SCH_1):PAGE92
   130    GND @T6G_MB_LIB.T6G(SCH_1):GND   I177 @T6G_MB_LIB.T6G(SCH_1):PAGE92
   134    GND @T6G_MB_LIB.T6G(SCH_1):GND   I177 @T6G_MB_LIB.T6G(SCH_1):PAGE92
   143    GND @T6G_MB_LIB.T6G(SCH_1):GND   I177 @T6G_MB_LIB.T6G(SCH_1):PAGE92
   151    GND @T6G_MB_LIB.T6G(SCH_1):GND   I177 @T6G_MB_LIB.T6G(SCH_1):PAGE92
   153    GND @T6G_MB_LIB.T6G(SCH_1):GND   I177 @T6G_MB_LIB.T6G(SCH_1):PAGE92
   155    GND @T6G_MB_LIB.T6G(SCH_1):GND   I177 @T6G_MB_LIB.T6G(SCH_1):PAGE92
   158    GND @T6G_MB_LIB.T6G(SCH_1):GND   I177 @T6G_MB_LIB.T6G(SCH_1):PAGE92
   160    GND @T6G_MB_LIB.T6G(SCH_1):GND   I177 @T6G_MB_LIB.T6G(SCH_1):PAGE92
   162    GND @T6G_MB_LIB.T6G(SCH_1):GND   I177 @T6G_MB_LIB.T6G(SCH_1):PAGE92
   164    GND @T6G_MB_LIB.T6G(SCH_1):GND   I177 @T6G_MB_LIB.T6G(SCH_1):PAGE92
   166    GND @T6G_MB_LIB.T6G(SCH_1):GND   I177 @T6G_MB_LIB.T6G(SCH_1):PAGE92
   169    GND @T6G_MB_LIB.T6G(SCH_1):GND   I177 @T6G_MB_LIB.T6G(SCH_1):PAGE92
   171    GND @T6G_MB_LIB.T6G(SCH_1):GND   I177 @T6G_MB_LIB.T6G(SCH_1):PAGE92
   173    GND @T6G_MB_LIB.T6G(SCH_1):GND   I177 @T6G_MB_LIB.T6G(SCH_1):PAGE92
   175    GND @T6G_MB_LIB.T6G(SCH_1):GND   I177 @T6G_MB_LIB.T6G(SCH_1):PAGE92
   177    GND @T6G_MB_LIB.T6G(SCH_1):GND   I177 @T6G_MB_LIB.T6G(SCH_1):PAGE92
   180    GND @T6G_MB_LIB.T6G(SCH_1):GND   I177 @T6G_MB_LIB.T6G(SCH_1):PAGE92
   182    GND @T6G_MB_LIB.T6G(SCH_1):GND   I177 @T6G_MB_LIB.T6G(SCH_1):PAGE92
   184    GND @T6G_MB_LIB.T6G(SCH_1):GND   I177 @T6G_MB_LIB.T6G(SCH_1):PAGE92
   186    GND @T6G_MB_LIB.T6G(SCH_1):GND   I177 @T6G_MB_LIB.T6G(SCH_1):PAGE92
   188    GND @T6G_MB_LIB.T6G(SCH_1):GND   I177 @T6G_MB_LIB.T6G(SCH_1):PAGE92
   191    GND @T6G_MB_LIB.T6G(SCH_1):GND   I177 @T6G_MB_LIB.T6G(SCH_1):PAGE92
   193    GND @T6G_MB_LIB.T6G(SCH_1):GND   I177 @T6G_MB_LIB.T6G(SCH_1):PAGE92
   195    GND @T6G_MB_LIB.T6G(SCH_1):GND   I177 @T6G_MB_LIB.T6G(SCH_1):PAGE92
   197    GND @T6G_MB_LIB.T6G(SCH_1):GND   I177 @T6G_MB_LIB.T6G(SCH_1):PAGE92
   199    GND @T6G_MB_LIB.T6G(SCH_1):GND   I177 @T6G_MB_LIB.T6G(SCH_1):PAGE92
   202    GND @T6G_MB_LIB.T6G(SCH_1):GND   I177 @T6G_MB_LIB.T6G(SCH_1):PAGE92
   204    GND @T6G_MB_LIB.T6G(SCH_1):GND   I177 @T6G_MB_LIB.T6G(SCH_1):PAGE92
   206    GND @T6G_MB_LIB.T6G(SCH_1):GND   I177 @T6G_MB_LIB.T6G(SCH_1):PAGE92
   208    GND @T6G_MB_LIB.T6G(SCH_1):GND   I177 @T6G_MB_LIB.T6G(SCH_1):PAGE92
   210    GND @T6G_MB_LIB.T6G(SCH_1):GND   I177 @T6G_MB_LIB.T6G(SCH_1):PAGE92
   212    GND @T6G_MB_LIB.T6G(SCH_1):GND   I177 @T6G_MB_LIB.T6G(SCH_1):PAGE92
   214    GND @T6G_MB_LIB.T6G(SCH_1):GND   I177 @T6G_MB_LIB.T6G(SCH_1):PAGE92
   216    GND @T6G_MB_LIB.T6G(SCH_1):GND   I177 @T6G_MB_LIB.T6G(SCH_1):PAGE92
   219    GND @T6G_MB_LIB.T6G(SCH_1):GND   I177 @T6G_MB_LIB.T6G(SCH_1):PAGE92
   222    GND @T6G_MB_LIB.T6G(SCH_1):GND   I177 @T6G_MB_LIB.T6G(SCH_1):PAGE92
   224    GND @T6G_MB_LIB.T6G(SCH_1):GND   I177 @T6G_MB_LIB.T6G(SCH_1):PAGE92
   226    GND @T6G_MB_LIB.T6G(SCH_1):GND   I177 @T6G_MB_LIB.T6G(SCH_1):PAGE92
   228    GND @T6G_MB_LIB.T6G(SCH_1):GND   I177 @T6G_MB_LIB.T6G(SCH_1):PAGE92
   233    GND @T6G_MB_LIB.T6G(SCH_1):GND   I177 @T6G_MB_LIB.T6G(SCH_1):PAGE92
   237    GND @T6G_MB_LIB.T6G(SCH_1):GND   I177 @T6G_MB_LIB.T6G(SCH_1):PAGE92
   242    GND @T6G_MB_LIB.T6G(SCH_1):GND   I177 @T6G_MB_LIB.T6G(SCH_1):PAGE92
   244    GND @T6G_MB_LIB.T6G(SCH_1):GND   I177 @T6G_MB_LIB.T6G(SCH_1):PAGE92
   246    GND @T6G_MB_LIB.T6G(SCH_1):GND   I177 @T6G_MB_LIB.T6G(SCH_1):PAGE92
   248    GND @T6G_MB_LIB.T6G(SCH_1):GND   I177 @T6G_MB_LIB.T6G(SCH_1):PAGE92
   251    GND @T6G_MB_LIB.T6G(SCH_1):GND   I177 @T6G_MB_LIB.T6G(SCH_1):PAGE92
   253    GND @T6G_MB_LIB.T6G(SCH_1):GND   I177 @T6G_MB_LIB.T6G(SCH_1):PAGE92
   255    GND @T6G_MB_LIB.T6G(SCH_1):GND   I177 @T6G_MB_LIB.T6G(SCH_1):PAGE92
   257    GND @T6G_MB_LIB.T6G(SCH_1):GND   I177 @T6G_MB_LIB.T6G(SCH_1):PAGE92
   259    GND @T6G_MB_LIB.T6G(SCH_1):GND   I177 @T6G_MB_LIB.T6G(SCH_1):PAGE92
   262    GND @T6G_MB_LIB.T6G(SCH_1):GND   I177 @T6G_MB_LIB.T6G(SCH_1):PAGE92
   264    GND @T6G_MB_LIB.T6G(SCH_1):GND   I177 @T6G_MB_LIB.T6G(SCH_1):PAGE92
   266    GND @T6G_MB_LIB.T6G(SCH_1):GND   I177 @T6G_MB_LIB.T6G(SCH_1):PAGE92
   268    GND @T6G_MB_LIB.T6G(SCH_1):GND   I177 @T6G_MB_LIB.T6G(SCH_1):PAGE92
   270    GND @T6G_MB_LIB.T6G(SCH_1):GND   I177 @T6G_MB_LIB.T6G(SCH_1):PAGE92
   273    GND @T6G_MB_LIB.T6G(SCH_1):GND   I177 @T6G_MB_LIB.T6G(SCH_1):PAGE92
   275    GND @T6G_MB_LIB.T6G(SCH_1):GND   I177 @T6G_MB_LIB.T6G(SCH_1):PAGE92
   277    GND @T6G_MB_LIB.T6G(SCH_1):GND   I177 @T6G_MB_LIB.T6G(SCH_1):PAGE92
   279    GND @T6G_MB_LIB.T6G(SCH_1):GND   I177 @T6G_MB_LIB.T6G(SCH_1):PAGE92
   281    GND @T6G_MB_LIB.T6G(SCH_1):GND   I177 @T6G_MB_LIB.T6G(SCH_1):PAGE92
   284    GND @T6G_MB_LIB.T6G(SCH_1):GND   I177 @T6G_MB_LIB.T6G(SCH_1):PAGE92
   286    GND @T6G_MB_LIB.T6G(SCH_1):GND   I177 @T6G_MB_LIB.T6G(SCH_1):PAGE92
   288    GND @T6G_MB_LIB.T6G(SCH_1):GND   I177 @T6G_MB_LIB.T6G(SCH_1):PAGE92
     1 P12V_MEM_CPU0 @T6G_MB_LIB.T6G(SCH_1):P12V_MEM_CPU0   I177 @T6G_MB_LIB.T6G(SCH_1):PAGE92
   145 P12V_MEM_CPU0 @T6G_MB_LIB.T6G(SCH_1):P12V_MEM_CPU0   I177 @T6G_MB_LIB.T6G(SCH_1):PAGE92
   146 P12V_MEM_CPU0 @T6G_MB_LIB.T6G(SCH_1):P12V_MEM_CPU0   I177 @T6G_MB_LIB.T6G(SCH_1):PAGE92
   230    GND @T6G_MB_LIB.T6G(SCH_1):GND   I177 @T6G_MB_LIB.T6G(SCH_1):PAGE92
   235    GND @T6G_MB_LIB.T6G(SCH_1):GND   I177 @T6G_MB_LIB.T6G(SCH_1):PAGE92
   240    GND @T6G_MB_LIB.T6G(SCH_1):GND   I177 @T6G_MB_LIB.T6G(SCH_1):PAGE92
   132    GND @T6G_MB_LIB.T6G(SCH_1):GND   I177 @T6G_MB_LIB.T6G(SCH_1):PAGE92
   136    GND @T6G_MB_LIB.T6G(SCH_1):GND   I177 @T6G_MB_LIB.T6G(SCH_1):PAGE92
   139    GND @T6G_MB_LIB.T6G(SCH_1):GND   I177 @T6G_MB_LIB.T6G(SCH_1):PAGE92
   141    GND @T6G_MB_LIB.T6G(SCH_1):GND   I177 @T6G_MB_LIB.T6G(SCH_1):PAGE92
    G1    GND @T6G_MB_LIB.T6G(SCH_1):GND   I177 @T6G_MB_LIB.T6G(SCH_1):PAGE92
    G2    GND @T6G_MB_LIB.T6G(SCH_1):GND   I177 @T6G_MB_LIB.T6G(SCH_1):PAGE92
    G3    GND @T6G_MB_LIB.T6G(SCH_1):GND   I177 @T6G_MB_LIB.T6G(SCH_1):PAGE92

 J70 PICOPROBE_BXA-DELTA-L 4.0,SMLF,EMPTY,TP33
     2 DELTA_L_85_5INCH_BOT_DP @T6G_MB_LIB.T6G(SCH_1):DELTA_L_85_5INCH_BOT_DP    I68 @T6G_MB_LIB.T6G(SCH_1):PAGE211
     3 DELTA_L_GND_1 @T6G_MB_LIB.T6G(SCH_1):DELTA_L_GND_1    I68 @T6G_MB_LIB.T6G(SCH_1):PAGE211
     1 DELTA_L_85_5INCH_BOT_DN @T6G_MB_LIB.T6G(SCH_1):DELTA_L_85_5INCH_BOT_DN    I68 @T6G_MB_LIB.T6G(SCH_1):PAGE211

 J71 PICOPROBE_BXA-DELTA-L 4.0,SMLF,EMPTY,TP33
     2 DELTA_L_85_5INCH_IN1_DP @T6G_MB_LIB.T6G(SCH_1):DELTA_L_85_5INCH_IN1_DP    I70 @T6G_MB_LIB.T6G(SCH_1):PAGE211
     3 DELTA_L_GND_1 @T6G_MB_LIB.T6G(SCH_1):DELTA_L_GND_1    I70 @T6G_MB_LIB.T6G(SCH_1):PAGE211
     1 DELTA_L_85_5INCH_IN1_DN @T6G_MB_LIB.T6G(SCH_1):DELTA_L_85_5INCH_IN1_DN    I70 @T6G_MB_LIB.T6G(SCH_1):PAGE211

 J72 PICOPROBE_BXA-DELTA-L 4.0,SMLF,EMPTY,TP33
     2 DELTA_L_85_5INCH_IN2_DP @T6G_MB_LIB.T6G(SCH_1):DELTA_L_85_5INCH_IN2_DP    I72 @T6G_MB_LIB.T6G(SCH_1):PAGE211
     3 DELTA_L_GND_1 @T6G_MB_LIB.T6G(SCH_1):DELTA_L_GND_1    I72 @T6G_MB_LIB.T6G(SCH_1):PAGE211
     1 DELTA_L_85_5INCH_IN2_DN @T6G_MB_LIB.T6G(SCH_1):DELTA_L_85_5INCH_IN2_DN    I72 @T6G_MB_LIB.T6G(SCH_1):PAGE211

 J73 PICOPROBE_BXA-DELTA-L 4.0,SMLF,EMPTY,TP33
     2 DELTA_L_85_5INCH_IN3_DP @T6G_MB_LIB.T6G(SCH_1):DELTA_L_85_5INCH_IN3_DP    I74 @T6G_MB_LIB.T6G(SCH_1):PAGE211
     3 DELTA_L_GND_1 @T6G_MB_LIB.T6G(SCH_1):DELTA_L_GND_1    I74 @T6G_MB_LIB.T6G(SCH_1):PAGE211
     1 DELTA_L_85_5INCH_IN3_DN @T6G_MB_LIB.T6G(SCH_1):DELTA_L_85_5INCH_IN3_DN    I74 @T6G_MB_LIB.T6G(SCH_1):PAGE211

 J74 PICOPROBE_BXA-DELTA-L 4.0,SMLF,EMPTY,TP33
     2 DELTA_L_85_5INCH_IN4_DP @T6G_MB_LIB.T6G(SCH_1):DELTA_L_85_5INCH_IN4_DP    I76 @T6G_MB_LIB.T6G(SCH_1):PAGE211
     3 DELTA_L_GND_1 @T6G_MB_LIB.T6G(SCH_1):DELTA_L_GND_1    I76 @T6G_MB_LIB.T6G(SCH_1):PAGE211
     1 DELTA_L_85_5INCH_IN4_DN @T6G_MB_LIB.T6G(SCH_1):DELTA_L_85_5INCH_IN4_DN    I76 @T6G_MB_LIB.T6G(SCH_1):PAGE211

 J75 PICOPROBE_BXA-DELTA-L 4.0,SMLF,EMPTY,TP33
     2 DELTA_L_85_10INCH_TOP_DN @T6G_MB_LIB.T6G(SCH_1):DELTA_L_85_10INCH_TOP_DN    I81 @T6G_MB_LIB.T6G(SCH_1):PAGE211
     3 DELTA_L_GND_1 @T6G_MB_LIB.T6G(SCH_1):DELTA_L_GND_1    I81 @T6G_MB_LIB.T6G(SCH_1):PAGE211
     1 DELTA_L_85_10INCH_TOP_DP @T6G_MB_LIB.T6G(SCH_1):DELTA_L_85_10INCH_TOP_DP    I81 @T6G_MB_LIB.T6G(SCH_1):PAGE211

 J76 PICOPROBE_BXA-DELTA-L 4.0,SMLF,EMPTY,TP33
     2 DELTA_L_85_10INCH_BOT_DN @T6G_MB_LIB.T6G(SCH_1):DELTA_L_85_10INCH_BOT_DN    I83 @T6G_MB_LIB.T6G(SCH_1):PAGE211
     3 DELTA_L_GND_1 @T6G_MB_LIB.T6G(SCH_1):DELTA_L_GND_1    I83 @T6G_MB_LIB.T6G(SCH_1):PAGE211
     1 DELTA_L_85_10INCH_BOT_DP @T6G_MB_LIB.T6G(SCH_1):DELTA_L_85_10INCH_BOT_DP    I83 @T6G_MB_LIB.T6G(SCH_1):PAGE211

 J77 PICOPROBE_BXA-DELTA-L 4.0,SMLF,EMPTY,TP33
     2 DELTA_L_85_10INCH_IN1_DN @T6G_MB_LIB.T6G(SCH_1):DELTA_L_85_10INCH_IN1_DN    I85 @T6G_MB_LIB.T6G(SCH_1):PAGE211
     3 DELTA_L_GND_1 @T6G_MB_LIB.T6G(SCH_1):DELTA_L_GND_1    I85 @T6G_MB_LIB.T6G(SCH_1):PAGE211
     1 DELTA_L_85_10INCH_IN1_DP @T6G_MB_LIB.T6G(SCH_1):DELTA_L_85_10INCH_IN1_DP    I85 @T6G_MB_LIB.T6G(SCH_1):PAGE211

 J78 PICOPROBE_BXA-DELTA-L 4.0,SMLF,EMPTY,TP33
     2 DELTA_L_85_10INCH_IN2_DN @T6G_MB_LIB.T6G(SCH_1):DELTA_L_85_10INCH_IN2_DN    I87 @T6G_MB_LIB.T6G(SCH_1):PAGE211
     3 DELTA_L_GND_1 @T6G_MB_LIB.T6G(SCH_1):DELTA_L_GND_1    I87 @T6G_MB_LIB.T6G(SCH_1):PAGE211
     1 DELTA_L_85_10INCH_IN2_DP @T6G_MB_LIB.T6G(SCH_1):DELTA_L_85_10INCH_IN2_DP    I87 @T6G_MB_LIB.T6G(SCH_1):PAGE211

 J79 PICOPROBE_BXA-DELTA-L 4.0,SMLF,EMPTY,TP33
     2 DELTA_L_85_10INCH_IN3_DN @T6G_MB_LIB.T6G(SCH_1):DELTA_L_85_10INCH_IN3_DN    I89 @T6G_MB_LIB.T6G(SCH_1):PAGE211
     3 DELTA_L_GND_1 @T6G_MB_LIB.T6G(SCH_1):DELTA_L_GND_1    I89 @T6G_MB_LIB.T6G(SCH_1):PAGE211
     1 DELTA_L_85_10INCH_IN3_DP @T6G_MB_LIB.T6G(SCH_1):DELTA_L_85_10INCH_IN3_DP    I89 @T6G_MB_LIB.T6G(SCH_1):PAGE211

 J80 PICOPROBE_BXA-DELTA-L 4.0,SMLF,EMPTY,TP33
     2 DELTA_L_85_10INCH_IN4_DN @T6G_MB_LIB.T6G(SCH_1):DELTA_L_85_10INCH_IN4_DN    I91 @T6G_MB_LIB.T6G(SCH_1):PAGE211
     3 DELTA_L_GND_1 @T6G_MB_LIB.T6G(SCH_1):DELTA_L_GND_1    I91 @T6G_MB_LIB.T6G(SCH_1):PAGE211
     1 DELTA_L_85_10INCH_IN4_DP @T6G_MB_LIB.T6G(SCH_1):DELTA_L_85_10INCH_IN4_DP    I91 @T6G_MB_LIB.T6G(SCH_1):PAGE211

 J81 PICOPROBE_BXA-DELTA-L 4.0,SMLF,EMPTY,TP33
     2 DELTA_L_85_10INCH_TOP_DP @T6G_MB_LIB.T6G(SCH_1):DELTA_L_85_10INCH_TOP_DP    I82 @T6G_MB_LIB.T6G(SCH_1):PAGE211
     3 DELTA_L_GND_1 @T6G_MB_LIB.T6G(SCH_1):DELTA_L_GND_1    I82 @T6G_MB_LIB.T6G(SCH_1):PAGE211
     1 DELTA_L_85_10INCH_TOP_DN @T6G_MB_LIB.T6G(SCH_1):DELTA_L_85_10INCH_TOP_DN    I82 @T6G_MB_LIB.T6G(SCH_1):PAGE211

 J82 PICOPROBE_BXA-DELTA-L 4.0,SMLF,EMPTY,TP33
     2 DELTA_L_85_10INCH_BOT_DP @T6G_MB_LIB.T6G(SCH_1):DELTA_L_85_10INCH_BOT_DP    I84 @T6G_MB_LIB.T6G(SCH_1):PAGE211
     3 DELTA_L_GND_1 @T6G_MB_LIB.T6G(SCH_1):DELTA_L_GND_1    I84 @T6G_MB_LIB.T6G(SCH_1):PAGE211
     1 DELTA_L_85_10INCH_BOT_DN @T6G_MB_LIB.T6G(SCH_1):DELTA_L_85_10INCH_BOT_DN    I84 @T6G_MB_LIB.T6G(SCH_1):PAGE211

 J83 PICOPROBE_BXA-DELTA-L 4.0,SMLF,EMPTY,TP33
     2 DELTA_L_85_10INCH_IN1_DP @T6G_MB_LIB.T6G(SCH_1):DELTA_L_85_10INCH_IN1_DP    I86 @T6G_MB_LIB.T6G(SCH_1):PAGE211
     3 DELTA_L_GND_1 @T6G_MB_LIB.T6G(SCH_1):DELTA_L_GND_1    I86 @T6G_MB_LIB.T6G(SCH_1):PAGE211
     1 DELTA_L_85_10INCH_IN1_DN @T6G_MB_LIB.T6G(SCH_1):DELTA_L_85_10INCH_IN1_DN    I86 @T6G_MB_LIB.T6G(SCH_1):PAGE211

 J84 PICOPROBE_BXA-DELTA-L 4.0,SMLF,EMPTY,TP33
     2 DELTA_L_85_10INCH_IN2_DP @T6G_MB_LIB.T6G(SCH_1):DELTA_L_85_10INCH_IN2_DP    I88 @T6G_MB_LIB.T6G(SCH_1):PAGE211
     3 DELTA_L_GND_1 @T6G_MB_LIB.T6G(SCH_1):DELTA_L_GND_1    I88 @T6G_MB_LIB.T6G(SCH_1):PAGE211
     1 DELTA_L_85_10INCH_IN2_DN @T6G_MB_LIB.T6G(SCH_1):DELTA_L_85_10INCH_IN2_DN    I88 @T6G_MB_LIB.T6G(SCH_1):PAGE211

 J85 PICOPROBE_BXA-DELTA-L 4.0,SMLF,EMPTY,TP33
     2 DELTA_L_85_10INCH_IN3_DP @T6G_MB_LIB.T6G(SCH_1):DELTA_L_85_10INCH_IN3_DP    I90 @T6G_MB_LIB.T6G(SCH_1):PAGE211
     3 DELTA_L_GND_1 @T6G_MB_LIB.T6G(SCH_1):DELTA_L_GND_1    I90 @T6G_MB_LIB.T6G(SCH_1):PAGE211
     1 DELTA_L_85_10INCH_IN3_DN @T6G_MB_LIB.T6G(SCH_1):DELTA_L_85_10INCH_IN3_DN    I90 @T6G_MB_LIB.T6G(SCH_1):PAGE211

 J86 PICOPROBE_BXA-DELTA-L 4.0,SMLF,EMPTY,TP33
     2 DELTA_L_85_10INCH_IN4_DP @T6G_MB_LIB.T6G(SCH_1):DELTA_L_85_10INCH_IN4_DP    I92 @T6G_MB_LIB.T6G(SCH_1):PAGE211
     3 DELTA_L_GND_1 @T6G_MB_LIB.T6G(SCH_1):DELTA_L_GND_1    I92 @T6G_MB_LIB.T6G(SCH_1):PAGE211
     1 DELTA_L_85_10INCH_IN4_DN @T6G_MB_LIB.T6G(SCH_1):DELTA_L_85_10INCH_IN4_DN    I92 @T6G_MB_LIB.T6G(SCH_1):PAGE211

 J90 SCONN56_123276793-SCONN56_1-2327679-3,SMLF,IO,DFHSA
    B1 P12V_E1S_0_R @T6G_MB_LIB.T6G(SCH_1):P12V_E1S_0_R    I90 @T6G_MB_LIB.T6G(SCH_1):PAGE297
    B2 P12V_E1S_0_R @T6G_MB_LIB.T6G(SCH_1):P12V_E1S_0_R    I90 @T6G_MB_LIB.T6G(SCH_1):PAGE297
    B3 P12V_E1S_0_R @T6G_MB_LIB.T6G(SCH_1):P12V_E1S_0_R    I90 @T6G_MB_LIB.T6G(SCH_1):PAGE297
    B4 P12V_E1S_0_R @T6G_MB_LIB.T6G(SCH_1):P12V_E1S_0_R    I90 @T6G_MB_LIB.T6G(SCH_1):PAGE297
    B5 P12V_E1S_0_R @T6G_MB_LIB.T6G(SCH_1):P12V_E1S_0_R    I90 @T6G_MB_LIB.T6G(SCH_1):PAGE297
    B6 P12V_E1S_0_R @T6G_MB_LIB.T6G(SCH_1):P12V_E1S_0_R    I90 @T6G_MB_LIB.T6G(SCH_1):PAGE297
    A1    GND @T6G_MB_LIB.T6G(SCH_1):GND    I90 @T6G_MB_LIB.T6G(SCH_1):PAGE297
    A2    GND @T6G_MB_LIB.T6G(SCH_1):GND    I90 @T6G_MB_LIB.T6G(SCH_1):PAGE297
    A3    GND @T6G_MB_LIB.T6G(SCH_1):GND    I90 @T6G_MB_LIB.T6G(SCH_1):PAGE297
    A4    GND @T6G_MB_LIB.T6G(SCH_1):GND    I90 @T6G_MB_LIB.T6G(SCH_1):PAGE297
    A5    GND @T6G_MB_LIB.T6G(SCH_1):GND    I90 @T6G_MB_LIB.T6G(SCH_1):PAGE297
    A6    GND @T6G_MB_LIB.T6G(SCH_1):GND    I90 @T6G_MB_LIB.T6G(SCH_1):PAGE297
    B7 TP_E1S_0_MFG @T6G_MB_LIB.T6G(SCH_1):TP_E1S_0_MFG    I90 @T6G_MB_LIB.T6G(SCH_1):PAGE297
    B8 TP_E1S_0_RFU @T6G_MB_LIB.T6G(SCH_1):TP_E1S_0_RFU    I90 @T6G_MB_LIB.T6G(SCH_1):PAGE297
    B9 PU_E1S_0_DUALPORT_EN_N @T6G_MB_LIB.T6G(SCH_1):PU_E1S_0_DUALPORT_EN_N    I90 @T6G_MB_LIB.T6G(SCH_1):PAGE297
   B11 P3V3_E1S_0 @T6G_MB_LIB.T6G(SCH_1):P3V3_E1S_0    I90 @T6G_MB_LIB.T6G(SCH_1):PAGE297
   B12 E1S_0_PWRDIS @T6G_MB_LIB.T6G(SCH_1):E1S_0_PWRDIS    I90 @T6G_MB_LIB.T6G(SCH_1):PAGE297
   B13    GND @T6G_MB_LIB.T6G(SCH_1):GND    I90 @T6G_MB_LIB.T6G(SCH_1):PAGE297
   B16    GND @T6G_MB_LIB.T6G(SCH_1):GND    I90 @T6G_MB_LIB.T6G(SCH_1):PAGE297
   B19    GND @T6G_MB_LIB.T6G(SCH_1):GND    I90 @T6G_MB_LIB.T6G(SCH_1):PAGE297
   B22    GND @T6G_MB_LIB.T6G(SCH_1):GND    I90 @T6G_MB_LIB.T6G(SCH_1):PAGE297
   B25    GND @T6G_MB_LIB.T6G(SCH_1):GND    I90 @T6G_MB_LIB.T6G(SCH_1):PAGE297
   B28    GND @T6G_MB_LIB.T6G(SCH_1):GND    I90 @T6G_MB_LIB.T6G(SCH_1):PAGE297
   B14 CLK_100M_CPU0_CLK12_DN @T6G_MB_LIB.T6G(SCH_1):CLK_100M_CPU0_CLK12_DN    I90 @T6G_MB_LIB.T6G(SCH_1):PAGE297
   B15 CLK_100M_CPU0_CLK12_DP @T6G_MB_LIB.T6G(SCH_1):CLK_100M_CPU0_CLK12_DP    I90 @T6G_MB_LIB.T6G(SCH_1):PAGE297
   B17 P3E_CPU0_P4_TX_C_DP<0> @T6G_MB_LIB.T6G(SCH_1):P3E_CPU0_P4_TX_C_DP(0)    I90 @T6G_MB_LIB.T6G(SCH_1):PAGE297
   B18 P3E_CPU0_P4_TX_C_DN<0> @T6G_MB_LIB.T6G(SCH_1):P3E_CPU0_P4_TX_C_DN(0)    I90 @T6G_MB_LIB.T6G(SCH_1):PAGE297
   B20 P3E_CPU0_P4_TX_C_DP<1> @T6G_MB_LIB.T6G(SCH_1):P3E_CPU0_P4_TX_C_DP(1)    I90 @T6G_MB_LIB.T6G(SCH_1):PAGE297
   B21 P3E_CPU0_P4_TX_C_DN<1> @T6G_MB_LIB.T6G(SCH_1):P3E_CPU0_P4_TX_C_DN(1)    I90 @T6G_MB_LIB.T6G(SCH_1):PAGE297
   B23 P3E_CPU0_P4_TX_C_DP<2> @T6G_MB_LIB.T6G(SCH_1):P3E_CPU0_P4_TX_C_DP(2)    I90 @T6G_MB_LIB.T6G(SCH_1):PAGE297
   B24 P3E_CPU0_P4_TX_C_DN<2> @T6G_MB_LIB.T6G(SCH_1):P3E_CPU0_P4_TX_C_DN(2)    I90 @T6G_MB_LIB.T6G(SCH_1):PAGE297
   B26 P3E_CPU0_P4_TX_C_DN<3> @T6G_MB_LIB.T6G(SCH_1):P3E_CPU0_P4_TX_C_DN(3)    I90 @T6G_MB_LIB.T6G(SCH_1):PAGE297
   B27 P3E_CPU0_P4_TX_C_DP<3> @T6G_MB_LIB.T6G(SCH_1):P3E_CPU0_P4_TX_C_DP(3)    I90 @T6G_MB_LIB.T6G(SCH_1):PAGE297
    A7 SMB_E1S_3V3AUX_ISO_SCL @T6G_MB_LIB.T6G(SCH_1):SMB_E1S_3V3AUX_ISO_SCL    I90 @T6G_MB_LIB.T6G(SCH_1):PAGE297
    A8 SMB_E1S_3V3AUX_ISO_SDA @T6G_MB_LIB.T6G(SCH_1):SMB_E1S_3V3AUX_ISO_SDA    I90 @T6G_MB_LIB.T6G(SCH_1):PAGE297
    A9 RST_SMB_E1S_0_N @T6G_MB_LIB.T6G(SCH_1):RST_SMB_E1S_0_N    I90 @T6G_MB_LIB.T6G(SCH_1):PAGE297
   A10 FM_LED_ACTIVE_E1S_0_BUF @T6G_MB_LIB.T6G(SCH_1):FM_LED_ACTIVE_E1S_0_BUF    I90 @T6G_MB_LIB.T6G(SCH_1):PAGE297
   B10 RST_PCIE_E1S_PERST_N @T6G_MB_LIB.T6G(SCH_1):RST_PCIE_E1S_PERST_N    I90 @T6G_MB_LIB.T6G(SCH_1):PAGE297
   A11 E1S_0_PERST1_CLKREQ_N @T6G_MB_LIB.T6G(SCH_1):E1S_0_PERST1_CLKREQ_N    I90 @T6G_MB_LIB.T6G(SCH_1):PAGE297
   A12 E1S_0_PRSNT_N @T6G_MB_LIB.T6G(SCH_1):E1S_0_PRSNT_N    I90 @T6G_MB_LIB.T6G(SCH_1):PAGE297
   A13    GND @T6G_MB_LIB.T6G(SCH_1):GND    I90 @T6G_MB_LIB.T6G(SCH_1):PAGE297
   A16    GND @T6G_MB_LIB.T6G(SCH_1):GND    I90 @T6G_MB_LIB.T6G(SCH_1):PAGE297
   A19    GND @T6G_MB_LIB.T6G(SCH_1):GND    I90 @T6G_MB_LIB.T6G(SCH_1):PAGE297
   A22    GND @T6G_MB_LIB.T6G(SCH_1):GND    I90 @T6G_MB_LIB.T6G(SCH_1):PAGE297
   A25    GND @T6G_MB_LIB.T6G(SCH_1):GND    I90 @T6G_MB_LIB.T6G(SCH_1):PAGE297
   A28    GND @T6G_MB_LIB.T6G(SCH_1):GND    I90 @T6G_MB_LIB.T6G(SCH_1):PAGE297
   A14 TP_CLK_100M_E1S_0_DN @T6G_MB_LIB.T6G(SCH_1):TP_CLK_100M_E1S_0_DN    I90 @T6G_MB_LIB.T6G(SCH_1):PAGE297
   A15 TP_CLK_100M_E1S_0_DP @T6G_MB_LIB.T6G(SCH_1):TP_CLK_100M_E1S_0_DP    I90 @T6G_MB_LIB.T6G(SCH_1):PAGE297
   A17 P3E_CPU0_P4_RX_DP<0> @T6G_MB_LIB.T6G(SCH_1):P3E_CPU0_P4_RX_DP(0)    I90 @T6G_MB_LIB.T6G(SCH_1):PAGE297
   A18 P3E_CPU0_P4_RX_DN<0> @T6G_MB_LIB.T6G(SCH_1):P3E_CPU0_P4_RX_DN(0)    I90 @T6G_MB_LIB.T6G(SCH_1):PAGE297
   A20 P3E_CPU0_P4_RX_DP<1> @T6G_MB_LIB.T6G(SCH_1):P3E_CPU0_P4_RX_DP(1)    I90 @T6G_MB_LIB.T6G(SCH_1):PAGE297
   A21 P3E_CPU0_P4_RX_DN<1> @T6G_MB_LIB.T6G(SCH_1):P3E_CPU0_P4_RX_DN(1)    I90 @T6G_MB_LIB.T6G(SCH_1):PAGE297
   A23 P3E_CPU0_P4_RX_DP<2> @T6G_MB_LIB.T6G(SCH_1):P3E_CPU0_P4_RX_DP(2)    I90 @T6G_MB_LIB.T6G(SCH_1):PAGE297
   A24 P3E_CPU0_P4_RX_DN<2> @T6G_MB_LIB.T6G(SCH_1):P3E_CPU0_P4_RX_DN(2)    I90 @T6G_MB_LIB.T6G(SCH_1):PAGE297
   A26 P3E_CPU0_P4_RX_DP<3> @T6G_MB_LIB.T6G(SCH_1):P3E_CPU0_P4_RX_DP(3)    I90 @T6G_MB_LIB.T6G(SCH_1):PAGE297
   A27 P3E_CPU0_P4_RX_DN<3> @T6G_MB_LIB.T6G(SCH_1):P3E_CPU0_P4_RX_DN(3)    I90 @T6G_MB_LIB.T6G(SCH_1):PAGE297
    G2    GND @T6G_MB_LIB.T6G(SCH_1):GND    I90 @T6G_MB_LIB.T6G(SCH_1):PAGE297
    G1    GND @T6G_MB_LIB.T6G(SCH_1):GND    I90 @T6G_MB_LIB.T6G(SCH_1):PAGE297

 J99 SCONN288_DDR506112002KQ-SCONN288_DDR506112002KQ,SMA
     3 P3V3_AUX @T6G_MB_LIB.T6G(SCH_1):P3V3_AUX    I22 @T6G_MB_LIB.T6G(SCH_1):PAGE107
     2     NC     NC    I22 @T6G_MB_LIB.T6G(SCH_1):PAGE107
   144     NC     NC    I22 @T6G_MB_LIB.T6G(SCH_1):PAGE107
   149     NC     NC    I22 @T6G_MB_LIB.T6G(SCH_1):PAGE107
   150     NC     NC    I22 @T6G_MB_LIB.T6G(SCH_1):PAGE107
   220     NC     NC    I22 @T6G_MB_LIB.T6G(SCH_1):PAGE107
   231     NC     NC    I22 @T6G_MB_LIB.T6G(SCH_1):PAGE107
   232     NC     NC    I22 @T6G_MB_LIB.T6G(SCH_1):PAGE107
   207 M_K_CPU1_RESET_N @T6G_MB_LIB.T6G(SCH_1):M_K_CPU1_RESET_N    I22 @T6G_MB_LIB.T6G(SCH_1):PAGE107
   147 PWRGD_CHK_CPU1_DIMM @T6G_MB_LIB.T6G(SCH_1):PWRGD_CHK_CPU1_DIMM    I22 @T6G_MB_LIB.T6G(SCH_1):PAGE107
   227 M_K_CPU1_SB_PAR @T6G_MB_LIB.T6G(SCH_1):M_K_CPU1_SB_PAR    I22 @T6G_MB_LIB.T6G(SCH_1):PAGE107
    74 M_K_CPU1_SA_PAR @T6G_MB_LIB.T6G(SCH_1):M_K_CPU1_SA_PAR    I22 @T6G_MB_LIB.T6G(SCH_1):PAGE107
    87 M_K_CPU1_SB_RSP<0> @T6G_MB_LIB.T6G(SCH_1):M_K_CPU1_SB_RSP(0)    I22 @T6G_MB_LIB.T6G(SCH_1):PAGE107
    86 M_K_CPU1_SA_RSP<0> @T6G_MB_LIB.T6G(SCH_1):M_K_CPU1_SA_RSP(0)    I22 @T6G_MB_LIB.T6G(SCH_1):PAGE107
     5 I3C_SPD_DDRK_CPU1_SDA @T6G_MB_LIB.T6G(SCH_1):I3C_SPD_DDRK_CPU1_SDA    I22 @T6G_MB_LIB.T6G(SCH_1):PAGE107
     4 I3C_SPD_DDRK_CPU1_SCL @T6G_MB_LIB.T6G(SCH_1):I3C_SPD_DDRK_CPU1_SCL    I22 @T6G_MB_LIB.T6G(SCH_1):PAGE107
   148 PD_CHK_CPU1_DIMM_SAA @T6G_MB_LIB.T6G(SCH_1):PD_CHK_CPU1_DIMM_SAA    I22 @T6G_MB_LIB.T6G(SCH_1):PAGE107
   100 M_K_CPU1_SB_DQ<0> @T6G_MB_LIB.T6G(SCH_1):M_K_CPU1_SB_DQ(0)    I22 @T6G_MB_LIB.T6G(SCH_1):PAGE107
   102 M_K_CPU1_SB_DQ<1> @T6G_MB_LIB.T6G(SCH_1):M_K_CPU1_SB_DQ(1)    I22 @T6G_MB_LIB.T6G(SCH_1):PAGE107
   245 M_K_CPU1_SB_DQ<2> @T6G_MB_LIB.T6G(SCH_1):M_K_CPU1_SB_DQ(2)    I22 @T6G_MB_LIB.T6G(SCH_1):PAGE107
   247 M_K_CPU1_SB_DQ<3> @T6G_MB_LIB.T6G(SCH_1):M_K_CPU1_SB_DQ(3)    I22 @T6G_MB_LIB.T6G(SCH_1):PAGE107
   107 M_K_CPU1_SB_DQ<4> @T6G_MB_LIB.T6G(SCH_1):M_K_CPU1_SB_DQ(4)    I22 @T6G_MB_LIB.T6G(SCH_1):PAGE107
   109 M_K_CPU1_SB_DQ<5> @T6G_MB_LIB.T6G(SCH_1):M_K_CPU1_SB_DQ(5)    I22 @T6G_MB_LIB.T6G(SCH_1):PAGE107
   252 M_K_CPU1_SB_DQ<6> @T6G_MB_LIB.T6G(SCH_1):M_K_CPU1_SB_DQ(6)    I22 @T6G_MB_LIB.T6G(SCH_1):PAGE107
   254 M_K_CPU1_SB_DQ<7> @T6G_MB_LIB.T6G(SCH_1):M_K_CPU1_SB_DQ(7)    I22 @T6G_MB_LIB.T6G(SCH_1):PAGE107
   111 M_K_CPU1_SB_DQ<8> @T6G_MB_LIB.T6G(SCH_1):M_K_CPU1_SB_DQ(8)    I22 @T6G_MB_LIB.T6G(SCH_1):PAGE107
   113 M_K_CPU1_SB_DQ<9> @T6G_MB_LIB.T6G(SCH_1):M_K_CPU1_SB_DQ(9)    I22 @T6G_MB_LIB.T6G(SCH_1):PAGE107
   256 M_K_CPU1_SB_DQ<10> @T6G_MB_LIB.T6G(SCH_1):M_K_CPU1_SB_DQ(10)    I22 @T6G_MB_LIB.T6G(SCH_1):PAGE107
   258 M_K_CPU1_SB_DQ<11> @T6G_MB_LIB.T6G(SCH_1):M_K_CPU1_SB_DQ(11)    I22 @T6G_MB_LIB.T6G(SCH_1):PAGE107
   118 M_K_CPU1_SB_DQ<12> @T6G_MB_LIB.T6G(SCH_1):M_K_CPU1_SB_DQ(12)    I22 @T6G_MB_LIB.T6G(SCH_1):PAGE107
   120 M_K_CPU1_SB_DQ<13> @T6G_MB_LIB.T6G(SCH_1):M_K_CPU1_SB_DQ(13)    I22 @T6G_MB_LIB.T6G(SCH_1):PAGE107
   263 M_K_CPU1_SB_DQ<14> @T6G_MB_LIB.T6G(SCH_1):M_K_CPU1_SB_DQ(14)    I22 @T6G_MB_LIB.T6G(SCH_1):PAGE107
   265 M_K_CPU1_SB_DQ<15> @T6G_MB_LIB.T6G(SCH_1):M_K_CPU1_SB_DQ(15)    I22 @T6G_MB_LIB.T6G(SCH_1):PAGE107
   122 M_K_CPU1_SB_DQ<16> @T6G_MB_LIB.T6G(SCH_1):M_K_CPU1_SB_DQ(16)    I22 @T6G_MB_LIB.T6G(SCH_1):PAGE107
   124 M_K_CPU1_SB_DQ<17> @T6G_MB_LIB.T6G(SCH_1):M_K_CPU1_SB_DQ(17)    I22 @T6G_MB_LIB.T6G(SCH_1):PAGE107
   267 M_K_CPU1_SB_DQ<18> @T6G_MB_LIB.T6G(SCH_1):M_K_CPU1_SB_DQ(18)    I22 @T6G_MB_LIB.T6G(SCH_1):PAGE107
   269 M_K_CPU1_SB_DQ<19> @T6G_MB_LIB.T6G(SCH_1):M_K_CPU1_SB_DQ(19)    I22 @T6G_MB_LIB.T6G(SCH_1):PAGE107
   129 M_K_CPU1_SB_DQ<20> @T6G_MB_LIB.T6G(SCH_1):M_K_CPU1_SB_DQ(20)    I22 @T6G_MB_LIB.T6G(SCH_1):PAGE107
   131 M_K_CPU1_SB_DQ<21> @T6G_MB_LIB.T6G(SCH_1):M_K_CPU1_SB_DQ(21)    I22 @T6G_MB_LIB.T6G(SCH_1):PAGE107
   274 M_K_CPU1_SB_DQ<22> @T6G_MB_LIB.T6G(SCH_1):M_K_CPU1_SB_DQ(22)    I22 @T6G_MB_LIB.T6G(SCH_1):PAGE107
   276 M_K_CPU1_SB_DQ<23> @T6G_MB_LIB.T6G(SCH_1):M_K_CPU1_SB_DQ(23)    I22 @T6G_MB_LIB.T6G(SCH_1):PAGE107
   133 M_K_CPU1_SB_DQ<24> @T6G_MB_LIB.T6G(SCH_1):M_K_CPU1_SB_DQ(24)    I22 @T6G_MB_LIB.T6G(SCH_1):PAGE107
   135 M_K_CPU1_SB_DQ<25> @T6G_MB_LIB.T6G(SCH_1):M_K_CPU1_SB_DQ(25)    I22 @T6G_MB_LIB.T6G(SCH_1):PAGE107
   278 M_K_CPU1_SB_DQ<26> @T6G_MB_LIB.T6G(SCH_1):M_K_CPU1_SB_DQ(26)    I22 @T6G_MB_LIB.T6G(SCH_1):PAGE107
   280 M_K_CPU1_SB_DQ<27> @T6G_MB_LIB.T6G(SCH_1):M_K_CPU1_SB_DQ(27)    I22 @T6G_MB_LIB.T6G(SCH_1):PAGE107
   140 M_K_CPU1_SB_DQ<28> @T6G_MB_LIB.T6G(SCH_1):M_K_CPU1_SB_DQ(28)    I22 @T6G_MB_LIB.T6G(SCH_1):PAGE107
   142 M_K_CPU1_SB_DQ<29> @T6G_MB_LIB.T6G(SCH_1):M_K_CPU1_SB_DQ(29)    I22 @T6G_MB_LIB.T6G(SCH_1):PAGE107
   285 M_K_CPU1_SB_DQ<30> @T6G_MB_LIB.T6G(SCH_1):M_K_CPU1_SB_DQ(30)    I22 @T6G_MB_LIB.T6G(SCH_1):PAGE107
   287 M_K_CPU1_SB_DQ<31> @T6G_MB_LIB.T6G(SCH_1):M_K_CPU1_SB_DQ(31)    I22 @T6G_MB_LIB.T6G(SCH_1):PAGE107
     7 M_K_CPU1_SA_DQ<0> @T6G_MB_LIB.T6G(SCH_1):M_K_CPU1_SA_DQ(0)    I22 @T6G_MB_LIB.T6G(SCH_1):PAGE107
     9 M_K_CPU1_SA_DQ<1> @T6G_MB_LIB.T6G(SCH_1):M_K_CPU1_SA_DQ(1)    I22 @T6G_MB_LIB.T6G(SCH_1):PAGE107
   152 M_K_CPU1_SA_DQ<2> @T6G_MB_LIB.T6G(SCH_1):M_K_CPU1_SA_DQ(2)    I22 @T6G_MB_LIB.T6G(SCH_1):PAGE107
   154 M_K_CPU1_SA_DQ<3> @T6G_MB_LIB.T6G(SCH_1):M_K_CPU1_SA_DQ(3)    I22 @T6G_MB_LIB.T6G(SCH_1):PAGE107
    14 M_K_CPU1_SA_DQ<4> @T6G_MB_LIB.T6G(SCH_1):M_K_CPU1_SA_DQ(4)    I22 @T6G_MB_LIB.T6G(SCH_1):PAGE107
    16 M_K_CPU1_SA_DQ<5> @T6G_MB_LIB.T6G(SCH_1):M_K_CPU1_SA_DQ(5)    I22 @T6G_MB_LIB.T6G(SCH_1):PAGE107
   159 M_K_CPU1_SA_DQ<6> @T6G_MB_LIB.T6G(SCH_1):M_K_CPU1_SA_DQ(6)    I22 @T6G_MB_LIB.T6G(SCH_1):PAGE107
   161 M_K_CPU1_SA_DQ<7> @T6G_MB_LIB.T6G(SCH_1):M_K_CPU1_SA_DQ(7)    I22 @T6G_MB_LIB.T6G(SCH_1):PAGE107
    18 M_K_CPU1_SA_DQ<8> @T6G_MB_LIB.T6G(SCH_1):M_K_CPU1_SA_DQ(8)    I22 @T6G_MB_LIB.T6G(SCH_1):PAGE107
    20 M_K_CPU1_SA_DQ<9> @T6G_MB_LIB.T6G(SCH_1):M_K_CPU1_SA_DQ(9)    I22 @T6G_MB_LIB.T6G(SCH_1):PAGE107
   163 M_K_CPU1_SA_DQ<10> @T6G_MB_LIB.T6G(SCH_1):M_K_CPU1_SA_DQ(10)    I22 @T6G_MB_LIB.T6G(SCH_1):PAGE107
   165 M_K_CPU1_SA_DQ<11> @T6G_MB_LIB.T6G(SCH_1):M_K_CPU1_SA_DQ(11)    I22 @T6G_MB_LIB.T6G(SCH_1):PAGE107
    25 M_K_CPU1_SA_DQ<12> @T6G_MB_LIB.T6G(SCH_1):M_K_CPU1_SA_DQ(12)    I22 @T6G_MB_LIB.T6G(SCH_1):PAGE107
    27 M_K_CPU1_SA_DQ<13> @T6G_MB_LIB.T6G(SCH_1):M_K_CPU1_SA_DQ(13)    I22 @T6G_MB_LIB.T6G(SCH_1):PAGE107
   170 M_K_CPU1_SA_DQ<14> @T6G_MB_LIB.T6G(SCH_1):M_K_CPU1_SA_DQ(14)    I22 @T6G_MB_LIB.T6G(SCH_1):PAGE107
   172 M_K_CPU1_SA_DQ<15> @T6G_MB_LIB.T6G(SCH_1):M_K_CPU1_SA_DQ(15)    I22 @T6G_MB_LIB.T6G(SCH_1):PAGE107
    29 M_K_CPU1_SA_DQ<16> @T6G_MB_LIB.T6G(SCH_1):M_K_CPU1_SA_DQ(16)    I22 @T6G_MB_LIB.T6G(SCH_1):PAGE107
    31 M_K_CPU1_SA_DQ<17> @T6G_MB_LIB.T6G(SCH_1):M_K_CPU1_SA_DQ(17)    I22 @T6G_MB_LIB.T6G(SCH_1):PAGE107
   174 M_K_CPU1_SA_DQ<18> @T6G_MB_LIB.T6G(SCH_1):M_K_CPU1_SA_DQ(18)    I22 @T6G_MB_LIB.T6G(SCH_1):PAGE107
   176 M_K_CPU1_SA_DQ<19> @T6G_MB_LIB.T6G(SCH_1):M_K_CPU1_SA_DQ(19)    I22 @T6G_MB_LIB.T6G(SCH_1):PAGE107
    36 M_K_CPU1_SA_DQ<20> @T6G_MB_LIB.T6G(SCH_1):M_K_CPU1_SA_DQ(20)    I22 @T6G_MB_LIB.T6G(SCH_1):PAGE107
    38 M_K_CPU1_SA_DQ<21> @T6G_MB_LIB.T6G(SCH_1):M_K_CPU1_SA_DQ(21)    I22 @T6G_MB_LIB.T6G(SCH_1):PAGE107
   181 M_K_CPU1_SA_DQ<22> @T6G_MB_LIB.T6G(SCH_1):M_K_CPU1_SA_DQ(22)    I22 @T6G_MB_LIB.T6G(SCH_1):PAGE107
   183 M_K_CPU1_SA_DQ<23> @T6G_MB_LIB.T6G(SCH_1):M_K_CPU1_SA_DQ(23)    I22 @T6G_MB_LIB.T6G(SCH_1):PAGE107
    40 M_K_CPU1_SA_DQ<24> @T6G_MB_LIB.T6G(SCH_1):M_K_CPU1_SA_DQ(24)    I22 @T6G_MB_LIB.T6G(SCH_1):PAGE107
    42 M_K_CPU1_SA_DQ<25> @T6G_MB_LIB.T6G(SCH_1):M_K_CPU1_SA_DQ(25)    I22 @T6G_MB_LIB.T6G(SCH_1):PAGE107
   185 M_K_CPU1_SA_DQ<26> @T6G_MB_LIB.T6G(SCH_1):M_K_CPU1_SA_DQ(26)    I22 @T6G_MB_LIB.T6G(SCH_1):PAGE107
   187 M_K_CPU1_SA_DQ<27> @T6G_MB_LIB.T6G(SCH_1):M_K_CPU1_SA_DQ(27)    I22 @T6G_MB_LIB.T6G(SCH_1):PAGE107
    47 M_K_CPU1_SA_DQ<28> @T6G_MB_LIB.T6G(SCH_1):M_K_CPU1_SA_DQ(28)    I22 @T6G_MB_LIB.T6G(SCH_1):PAGE107
    49 M_K_CPU1_SA_DQ<29> @T6G_MB_LIB.T6G(SCH_1):M_K_CPU1_SA_DQ(29)    I22 @T6G_MB_LIB.T6G(SCH_1):PAGE107
   192 M_K_CPU1_SA_DQ<30> @T6G_MB_LIB.T6G(SCH_1):M_K_CPU1_SA_DQ(30)    I22 @T6G_MB_LIB.T6G(SCH_1):PAGE107
   229 M_K_CPU1_SB_CS_N<1> @T6G_MB_LIB.T6G(SCH_1):M_K_CPU1_SB_CS_N(1)    I22 @T6G_MB_LIB.T6G(SCH_1):PAGE107
   209 M_K_CPU1_SA_CS_N<1> @T6G_MB_LIB.T6G(SCH_1):M_K_CPU1_SA_CS_N(1)    I22 @T6G_MB_LIB.T6G(SCH_1):PAGE107
    84 M_K_CPU1_SB_CS_N<0> @T6G_MB_LIB.T6G(SCH_1):M_K_CPU1_SB_CS_N(0)    I22 @T6G_MB_LIB.T6G(SCH_1):PAGE107
    64 M_K_CPU1_SA_CS_N<0> @T6G_MB_LIB.T6G(SCH_1):M_K_CPU1_SA_CS_N(0)    I22 @T6G_MB_LIB.T6G(SCH_1):PAGE107
   217 M_K_CPU1_CLK_DP<0> @T6G_MB_LIB.T6G(SCH_1):M_K_CPU1_CLK_DP(0)    I22 @T6G_MB_LIB.T6G(SCH_1):PAGE107
   218 M_K_CPU1_CLK_DN<0> @T6G_MB_LIB.T6G(SCH_1):M_K_CPU1_CLK_DN(0)    I22 @T6G_MB_LIB.T6G(SCH_1):PAGE107
    96 M_K_CPU1_SB_CB<0> @T6G_MB_LIB.T6G(SCH_1):M_K_CPU1_SB_CB(0)    I22 @T6G_MB_LIB.T6G(SCH_1):PAGE107
    98 M_K_CPU1_SB_CB<1> @T6G_MB_LIB.T6G(SCH_1):M_K_CPU1_SB_CB(1)    I22 @T6G_MB_LIB.T6G(SCH_1):PAGE107
   241 M_K_CPU1_SB_CB<2> @T6G_MB_LIB.T6G(SCH_1):M_K_CPU1_SB_CB(2)    I22 @T6G_MB_LIB.T6G(SCH_1):PAGE107
   243 M_K_CPU1_SB_CB<3> @T6G_MB_LIB.T6G(SCH_1):M_K_CPU1_SB_CB(3)    I22 @T6G_MB_LIB.T6G(SCH_1):PAGE107
    89 M_K_CPU1_SB_CB<4> @T6G_MB_LIB.T6G(SCH_1):M_K_CPU1_SB_CB(4)    I22 @T6G_MB_LIB.T6G(SCH_1):PAGE107
    91 M_K_CPU1_SB_CB<5> @T6G_MB_LIB.T6G(SCH_1):M_K_CPU1_SB_CB(5)    I22 @T6G_MB_LIB.T6G(SCH_1):PAGE107
   234 M_K_CPU1_SB_CB<6> @T6G_MB_LIB.T6G(SCH_1):M_K_CPU1_SB_CB(6)    I22 @T6G_MB_LIB.T6G(SCH_1):PAGE107
    51 M_K_CPU1_SA_CB<0> @T6G_MB_LIB.T6G(SCH_1):M_K_CPU1_SA_CB(0)    I22 @T6G_MB_LIB.T6G(SCH_1):PAGE107
   196 M_K_CPU1_SA_CB<2> @T6G_MB_LIB.T6G(SCH_1):M_K_CPU1_SA_CB(2)    I22 @T6G_MB_LIB.T6G(SCH_1):PAGE107
   198 M_K_CPU1_SA_CB<3> @T6G_MB_LIB.T6G(SCH_1):M_K_CPU1_SA_CB(3)    I22 @T6G_MB_LIB.T6G(SCH_1):PAGE107
    60 M_K_CPU1_SA_CB<5> @T6G_MB_LIB.T6G(SCH_1):M_K_CPU1_SA_CB(5)    I22 @T6G_MB_LIB.T6G(SCH_1):PAGE107
   203 M_K_CPU1_SA_CB<6> @T6G_MB_LIB.T6G(SCH_1):M_K_CPU1_SA_CB(6)    I22 @T6G_MB_LIB.T6G(SCH_1):PAGE107
    82 M_K_CPU1_SB_CA<6> @T6G_MB_LIB.T6G(SCH_1):M_K_CPU1_SB_CA(6)    I22 @T6G_MB_LIB.T6G(SCH_1):PAGE107
    72 M_K_CPU1_SA_CA<6> @T6G_MB_LIB.T6G(SCH_1):M_K_CPU1_SA_CA(6)    I22 @T6G_MB_LIB.T6G(SCH_1):PAGE107
   225 M_K_CPU1_SB_CA<5> @T6G_MB_LIB.T6G(SCH_1):M_K_CPU1_SB_CA(5)    I22 @T6G_MB_LIB.T6G(SCH_1):PAGE107
   215 M_K_CPU1_SA_CA<5> @T6G_MB_LIB.T6G(SCH_1):M_K_CPU1_SA_CA(5)    I22 @T6G_MB_LIB.T6G(SCH_1):PAGE107
    80 M_K_CPU1_SB_CA<4> @T6G_MB_LIB.T6G(SCH_1):M_K_CPU1_SB_CA(4)    I22 @T6G_MB_LIB.T6G(SCH_1):PAGE107
    70 M_K_CPU1_SA_CA<4> @T6G_MB_LIB.T6G(SCH_1):M_K_CPU1_SA_CA(4)    I22 @T6G_MB_LIB.T6G(SCH_1):PAGE107
   223 M_K_CPU1_SB_CA<3> @T6G_MB_LIB.T6G(SCH_1):M_K_CPU1_SB_CA(3)    I22 @T6G_MB_LIB.T6G(SCH_1):PAGE107
   213 M_K_CPU1_SA_CA<3> @T6G_MB_LIB.T6G(SCH_1):M_K_CPU1_SA_CA(3)    I22 @T6G_MB_LIB.T6G(SCH_1):PAGE107
    78 M_K_CPU1_SB_CA<2> @T6G_MB_LIB.T6G(SCH_1):M_K_CPU1_SB_CA(2)    I22 @T6G_MB_LIB.T6G(SCH_1):PAGE107
    68 M_K_CPU1_SA_CA<2> @T6G_MB_LIB.T6G(SCH_1):M_K_CPU1_SA_CA(2)    I22 @T6G_MB_LIB.T6G(SCH_1):PAGE107
   221 M_K_CPU1_SB_CA<1> @T6G_MB_LIB.T6G(SCH_1):M_K_CPU1_SB_CA(1)    I22 @T6G_MB_LIB.T6G(SCH_1):PAGE107
   211 M_K_CPU1_SA_CA<1> @T6G_MB_LIB.T6G(SCH_1):M_K_CPU1_SA_CA(1)    I22 @T6G_MB_LIB.T6G(SCH_1):PAGE107
    76 M_K_CPU1_SB_CA<0> @T6G_MB_LIB.T6G(SCH_1):M_K_CPU1_SB_CA(0)    I22 @T6G_MB_LIB.T6G(SCH_1):PAGE107
    66 M_K_CPU1_SA_CA<0> @T6G_MB_LIB.T6G(SCH_1):M_K_CPU1_SA_CA(0)    I22 @T6G_MB_LIB.T6G(SCH_1):PAGE107
    62 M_K_CPU1_ALERT_N @T6G_MB_LIB.T6G(SCH_1):M_K_CPU1_ALERT_N    I22 @T6G_MB_LIB.T6G(SCH_1):PAGE107
   236 M_K_CPU1_SB_CB<7> @T6G_MB_LIB.T6G(SCH_1):M_K_CPU1_SB_CB(7)    I22 @T6G_MB_LIB.T6G(SCH_1):PAGE107
    53 M_K_CPU1_SA_CB<1> @T6G_MB_LIB.T6G(SCH_1):M_K_CPU1_SA_CB(1)    I22 @T6G_MB_LIB.T6G(SCH_1):PAGE107
    58 M_K_CPU1_SA_CB<4> @T6G_MB_LIB.T6G(SCH_1):M_K_CPU1_SA_CB(4)    I22 @T6G_MB_LIB.T6G(SCH_1):PAGE107
   205 M_K_CPU1_SA_CB<7> @T6G_MB_LIB.T6G(SCH_1):M_K_CPU1_SA_CB(7)    I22 @T6G_MB_LIB.T6G(SCH_1):PAGE107
   194 M_K_CPU1_SA_DQ<31> @T6G_MB_LIB.T6G(SCH_1):M_K_CPU1_SA_DQ(31)    I22 @T6G_MB_LIB.T6G(SCH_1):PAGE107
    93 M_K_CPU1_SB_DQS_DP<9> @T6G_MB_LIB.T6G(SCH_1):M_K_CPU1_SB_DQS_DP(9)   I235 @T6G_MB_LIB.T6G(SCH_1):PAGE107
    94 M_K_CPU1_SB_DQS_DN<9> @T6G_MB_LIB.T6G(SCH_1):M_K_CPU1_SB_DQS_DN(9)   I235 @T6G_MB_LIB.T6G(SCH_1):PAGE107
   201 M_K_CPU1_SA_DQS_DP<9> @T6G_MB_LIB.T6G(SCH_1):M_K_CPU1_SA_DQS_DP(9)   I235 @T6G_MB_LIB.T6G(SCH_1):PAGE107
   200 M_K_CPU1_SA_DQS_DN<9> @T6G_MB_LIB.T6G(SCH_1):M_K_CPU1_SA_DQS_DN(9)   I235 @T6G_MB_LIB.T6G(SCH_1):PAGE107
   190 M_K_CPU1_SA_DQS_DP<8> @T6G_MB_LIB.T6G(SCH_1):M_K_CPU1_SA_DQS_DP(8)   I235 @T6G_MB_LIB.T6G(SCH_1):PAGE107
   189 M_K_CPU1_SA_DQS_DN<8> @T6G_MB_LIB.T6G(SCH_1):M_K_CPU1_SA_DQS_DN(8)   I235 @T6G_MB_LIB.T6G(SCH_1):PAGE107
   271 M_K_CPU1_SB_DQS_DN<7> @T6G_MB_LIB.T6G(SCH_1):M_K_CPU1_SB_DQS_DN(7)   I235 @T6G_MB_LIB.T6G(SCH_1):PAGE107
   179 M_K_CPU1_SA_DQS_DP<7> @T6G_MB_LIB.T6G(SCH_1):M_K_CPU1_SA_DQS_DP(7)   I235 @T6G_MB_LIB.T6G(SCH_1):PAGE107
   261 M_K_CPU1_SB_DQS_DP<6> @T6G_MB_LIB.T6G(SCH_1):M_K_CPU1_SB_DQS_DP(6)   I235 @T6G_MB_LIB.T6G(SCH_1):PAGE107
   260 M_K_CPU1_SB_DQS_DN<6> @T6G_MB_LIB.T6G(SCH_1):M_K_CPU1_SB_DQS_DN(6)   I235 @T6G_MB_LIB.T6G(SCH_1):PAGE107
   167 M_K_CPU1_SA_DQS_DN<6> @T6G_MB_LIB.T6G(SCH_1):M_K_CPU1_SA_DQS_DN(6)   I235 @T6G_MB_LIB.T6G(SCH_1):PAGE107
   250 M_K_CPU1_SB_DQS_DP<5> @T6G_MB_LIB.T6G(SCH_1):M_K_CPU1_SB_DQS_DP(5)   I235 @T6G_MB_LIB.T6G(SCH_1):PAGE107
   249 M_K_CPU1_SB_DQS_DN<5> @T6G_MB_LIB.T6G(SCH_1):M_K_CPU1_SB_DQS_DN(5)   I235 @T6G_MB_LIB.T6G(SCH_1):PAGE107
   157 M_K_CPU1_SA_DQS_DP<5> @T6G_MB_LIB.T6G(SCH_1):M_K_CPU1_SA_DQS_DP(5)   I235 @T6G_MB_LIB.T6G(SCH_1):PAGE107
   156 M_K_CPU1_SA_DQS_DN<5> @T6G_MB_LIB.T6G(SCH_1):M_K_CPU1_SA_DQS_DN(5)   I235 @T6G_MB_LIB.T6G(SCH_1):PAGE107
   239 M_K_CPU1_SB_DQS_DP<4> @T6G_MB_LIB.T6G(SCH_1):M_K_CPU1_SB_DQS_DP(4)   I235 @T6G_MB_LIB.T6G(SCH_1):PAGE107
   238 M_K_CPU1_SB_DQS_DN<4> @T6G_MB_LIB.T6G(SCH_1):M_K_CPU1_SB_DQS_DN(4)   I235 @T6G_MB_LIB.T6G(SCH_1):PAGE107
    55 M_K_CPU1_SA_DQS_DP<4> @T6G_MB_LIB.T6G(SCH_1):M_K_CPU1_SA_DQS_DP(4)   I235 @T6G_MB_LIB.T6G(SCH_1):PAGE107
    56 M_K_CPU1_SA_DQS_DN<4> @T6G_MB_LIB.T6G(SCH_1):M_K_CPU1_SA_DQS_DN(4)   I235 @T6G_MB_LIB.T6G(SCH_1):PAGE107
   137 M_K_CPU1_SB_DQS_DP<3> @T6G_MB_LIB.T6G(SCH_1):M_K_CPU1_SB_DQS_DP(3)   I235 @T6G_MB_LIB.T6G(SCH_1):PAGE107
   138 M_K_CPU1_SB_DQS_DN<3> @T6G_MB_LIB.T6G(SCH_1):M_K_CPU1_SB_DQS_DN(3)   I235 @T6G_MB_LIB.T6G(SCH_1):PAGE107
    44 M_K_CPU1_SA_DQS_DP<3> @T6G_MB_LIB.T6G(SCH_1):M_K_CPU1_SA_DQS_DP(3)   I235 @T6G_MB_LIB.T6G(SCH_1):PAGE107
    45 M_K_CPU1_SA_DQS_DN<3> @T6G_MB_LIB.T6G(SCH_1):M_K_CPU1_SA_DQS_DN(3)   I235 @T6G_MB_LIB.T6G(SCH_1):PAGE107
   126 M_K_CPU1_SB_DQS_DP<2> @T6G_MB_LIB.T6G(SCH_1):M_K_CPU1_SB_DQS_DP(2)   I235 @T6G_MB_LIB.T6G(SCH_1):PAGE107
   127 M_K_CPU1_SB_DQS_DN<2> @T6G_MB_LIB.T6G(SCH_1):M_K_CPU1_SB_DQS_DN(2)   I235 @T6G_MB_LIB.T6G(SCH_1):PAGE107
    33 M_K_CPU1_SA_DQS_DP<2> @T6G_MB_LIB.T6G(SCH_1):M_K_CPU1_SA_DQS_DP(2)   I235 @T6G_MB_LIB.T6G(SCH_1):PAGE107
    34 M_K_CPU1_SA_DQS_DN<2> @T6G_MB_LIB.T6G(SCH_1):M_K_CPU1_SA_DQS_DN(2)   I235 @T6G_MB_LIB.T6G(SCH_1):PAGE107
   115 M_K_CPU1_SB_DQS_DP<1> @T6G_MB_LIB.T6G(SCH_1):M_K_CPU1_SB_DQS_DP(1)   I235 @T6G_MB_LIB.T6G(SCH_1):PAGE107
   116 M_K_CPU1_SB_DQS_DN<1> @T6G_MB_LIB.T6G(SCH_1):M_K_CPU1_SB_DQS_DN(1)   I235 @T6G_MB_LIB.T6G(SCH_1):PAGE107
    22 M_K_CPU1_SA_DQS_DP<1> @T6G_MB_LIB.T6G(SCH_1):M_K_CPU1_SA_DQS_DP(1)   I235 @T6G_MB_LIB.T6G(SCH_1):PAGE107
    23 M_K_CPU1_SA_DQS_DN<1> @T6G_MB_LIB.T6G(SCH_1):M_K_CPU1_SA_DQS_DN(1)   I235 @T6G_MB_LIB.T6G(SCH_1):PAGE107
   104 M_K_CPU1_SB_DQS_DP<0> @T6G_MB_LIB.T6G(SCH_1):M_K_CPU1_SB_DQS_DP(0)   I235 @T6G_MB_LIB.T6G(SCH_1):PAGE107
   105 M_K_CPU1_SB_DQS_DN<0> @T6G_MB_LIB.T6G(SCH_1):M_K_CPU1_SB_DQS_DN(0)   I235 @T6G_MB_LIB.T6G(SCH_1):PAGE107
    11 M_K_CPU1_SA_DQS_DP<0> @T6G_MB_LIB.T6G(SCH_1):M_K_CPU1_SA_DQS_DP(0)   I235 @T6G_MB_LIB.T6G(SCH_1):PAGE107
    12 M_K_CPU1_SA_DQS_DN<0> @T6G_MB_LIB.T6G(SCH_1):M_K_CPU1_SA_DQS_DN(0)   I235 @T6G_MB_LIB.T6G(SCH_1):PAGE107
   272 M_K_CPU1_SB_DQS_DP<7> @T6G_MB_LIB.T6G(SCH_1):M_K_CPU1_SB_DQS_DP(7)   I235 @T6G_MB_LIB.T6G(SCH_1):PAGE107
   282 M_K_CPU1_SB_DQS_DN<8> @T6G_MB_LIB.T6G(SCH_1):M_K_CPU1_SB_DQS_DN(8)   I235 @T6G_MB_LIB.T6G(SCH_1):PAGE107
   283 M_K_CPU1_SB_DQS_DP<8> @T6G_MB_LIB.T6G(SCH_1):M_K_CPU1_SB_DQS_DP(8)   I235 @T6G_MB_LIB.T6G(SCH_1):PAGE107
   168 M_K_CPU1_SA_DQS_DP<6> @T6G_MB_LIB.T6G(SCH_1):M_K_CPU1_SA_DQS_DP(6)   I235 @T6G_MB_LIB.T6G(SCH_1):PAGE107
   178 M_K_CPU1_SA_DQS_DN<7> @T6G_MB_LIB.T6G(SCH_1):M_K_CPU1_SA_DQS_DN(7)   I235 @T6G_MB_LIB.T6G(SCH_1):PAGE107
     6    GND @T6G_MB_LIB.T6G(SCH_1):GND   I139 @T6G_MB_LIB.T6G(SCH_1):PAGE107
     8    GND @T6G_MB_LIB.T6G(SCH_1):GND   I139 @T6G_MB_LIB.T6G(SCH_1):PAGE107
    10    GND @T6G_MB_LIB.T6G(SCH_1):GND   I139 @T6G_MB_LIB.T6G(SCH_1):PAGE107
    13    GND @T6G_MB_LIB.T6G(SCH_1):GND   I139 @T6G_MB_LIB.T6G(SCH_1):PAGE107
    15    GND @T6G_MB_LIB.T6G(SCH_1):GND   I139 @T6G_MB_LIB.T6G(SCH_1):PAGE107
    17    GND @T6G_MB_LIB.T6G(SCH_1):GND   I139 @T6G_MB_LIB.T6G(SCH_1):PAGE107
    19    GND @T6G_MB_LIB.T6G(SCH_1):GND   I139 @T6G_MB_LIB.T6G(SCH_1):PAGE107
    21    GND @T6G_MB_LIB.T6G(SCH_1):GND   I139 @T6G_MB_LIB.T6G(SCH_1):PAGE107
    24    GND @T6G_MB_LIB.T6G(SCH_1):GND   I139 @T6G_MB_LIB.T6G(SCH_1):PAGE107
    26    GND @T6G_MB_LIB.T6G(SCH_1):GND   I139 @T6G_MB_LIB.T6G(SCH_1):PAGE107
    28    GND @T6G_MB_LIB.T6G(SCH_1):GND   I139 @T6G_MB_LIB.T6G(SCH_1):PAGE107
    30    GND @T6G_MB_LIB.T6G(SCH_1):GND   I139 @T6G_MB_LIB.T6G(SCH_1):PAGE107
    32    GND @T6G_MB_LIB.T6G(SCH_1):GND   I139 @T6G_MB_LIB.T6G(SCH_1):PAGE107
    35    GND @T6G_MB_LIB.T6G(SCH_1):GND   I139 @T6G_MB_LIB.T6G(SCH_1):PAGE107
    37    GND @T6G_MB_LIB.T6G(SCH_1):GND   I139 @T6G_MB_LIB.T6G(SCH_1):PAGE107
    39    GND @T6G_MB_LIB.T6G(SCH_1):GND   I139 @T6G_MB_LIB.T6G(SCH_1):PAGE107
    41    GND @T6G_MB_LIB.T6G(SCH_1):GND   I139 @T6G_MB_LIB.T6G(SCH_1):PAGE107
    43    GND @T6G_MB_LIB.T6G(SCH_1):GND   I139 @T6G_MB_LIB.T6G(SCH_1):PAGE107
    46    GND @T6G_MB_LIB.T6G(SCH_1):GND   I139 @T6G_MB_LIB.T6G(SCH_1):PAGE107
    48    GND @T6G_MB_LIB.T6G(SCH_1):GND   I139 @T6G_MB_LIB.T6G(SCH_1):PAGE107
    50    GND @T6G_MB_LIB.T6G(SCH_1):GND   I139 @T6G_MB_LIB.T6G(SCH_1):PAGE107
    52    GND @T6G_MB_LIB.T6G(SCH_1):GND   I139 @T6G_MB_LIB.T6G(SCH_1):PAGE107
    54    GND @T6G_MB_LIB.T6G(SCH_1):GND   I139 @T6G_MB_LIB.T6G(SCH_1):PAGE107
    57    GND @T6G_MB_LIB.T6G(SCH_1):GND   I139 @T6G_MB_LIB.T6G(SCH_1):PAGE107
    59    GND @T6G_MB_LIB.T6G(SCH_1):GND   I139 @T6G_MB_LIB.T6G(SCH_1):PAGE107
    61    GND @T6G_MB_LIB.T6G(SCH_1):GND   I139 @T6G_MB_LIB.T6G(SCH_1):PAGE107
    63    GND @T6G_MB_LIB.T6G(SCH_1):GND   I139 @T6G_MB_LIB.T6G(SCH_1):PAGE107
    65    GND @T6G_MB_LIB.T6G(SCH_1):GND   I139 @T6G_MB_LIB.T6G(SCH_1):PAGE107
    67    GND @T6G_MB_LIB.T6G(SCH_1):GND   I139 @T6G_MB_LIB.T6G(SCH_1):PAGE107
    69    GND @T6G_MB_LIB.T6G(SCH_1):GND   I139 @T6G_MB_LIB.T6G(SCH_1):PAGE107
    71    GND @T6G_MB_LIB.T6G(SCH_1):GND   I139 @T6G_MB_LIB.T6G(SCH_1):PAGE107
    73    GND @T6G_MB_LIB.T6G(SCH_1):GND   I139 @T6G_MB_LIB.T6G(SCH_1):PAGE107
    75    GND @T6G_MB_LIB.T6G(SCH_1):GND   I139 @T6G_MB_LIB.T6G(SCH_1):PAGE107
    77    GND @T6G_MB_LIB.T6G(SCH_1):GND   I139 @T6G_MB_LIB.T6G(SCH_1):PAGE107
    79    GND @T6G_MB_LIB.T6G(SCH_1):GND   I139 @T6G_MB_LIB.T6G(SCH_1):PAGE107
    81    GND @T6G_MB_LIB.T6G(SCH_1):GND   I139 @T6G_MB_LIB.T6G(SCH_1):PAGE107
    83    GND @T6G_MB_LIB.T6G(SCH_1):GND   I139 @T6G_MB_LIB.T6G(SCH_1):PAGE107
    85    GND @T6G_MB_LIB.T6G(SCH_1):GND   I139 @T6G_MB_LIB.T6G(SCH_1):PAGE107
    88    GND @T6G_MB_LIB.T6G(SCH_1):GND   I139 @T6G_MB_LIB.T6G(SCH_1):PAGE107
    90    GND @T6G_MB_LIB.T6G(SCH_1):GND   I139 @T6G_MB_LIB.T6G(SCH_1):PAGE107
    92    GND @T6G_MB_LIB.T6G(SCH_1):GND   I139 @T6G_MB_LIB.T6G(SCH_1):PAGE107
    95    GND @T6G_MB_LIB.T6G(SCH_1):GND   I139 @T6G_MB_LIB.T6G(SCH_1):PAGE107
    97    GND @T6G_MB_LIB.T6G(SCH_1):GND   I139 @T6G_MB_LIB.T6G(SCH_1):PAGE107
    99    GND @T6G_MB_LIB.T6G(SCH_1):GND   I139 @T6G_MB_LIB.T6G(SCH_1):PAGE107
   101    GND @T6G_MB_LIB.T6G(SCH_1):GND   I139 @T6G_MB_LIB.T6G(SCH_1):PAGE107
   103    GND @T6G_MB_LIB.T6G(SCH_1):GND   I139 @T6G_MB_LIB.T6G(SCH_1):PAGE107
   106    GND @T6G_MB_LIB.T6G(SCH_1):GND   I139 @T6G_MB_LIB.T6G(SCH_1):PAGE107
   108    GND @T6G_MB_LIB.T6G(SCH_1):GND   I139 @T6G_MB_LIB.T6G(SCH_1):PAGE107
   110    GND @T6G_MB_LIB.T6G(SCH_1):GND   I139 @T6G_MB_LIB.T6G(SCH_1):PAGE107
   112    GND @T6G_MB_LIB.T6G(SCH_1):GND   I139 @T6G_MB_LIB.T6G(SCH_1):PAGE107
   114    GND @T6G_MB_LIB.T6G(SCH_1):GND   I139 @T6G_MB_LIB.T6G(SCH_1):PAGE107
   117    GND @T6G_MB_LIB.T6G(SCH_1):GND   I139 @T6G_MB_LIB.T6G(SCH_1):PAGE107
   119    GND @T6G_MB_LIB.T6G(SCH_1):GND   I139 @T6G_MB_LIB.T6G(SCH_1):PAGE107
   121    GND @T6G_MB_LIB.T6G(SCH_1):GND   I139 @T6G_MB_LIB.T6G(SCH_1):PAGE107
   123    GND @T6G_MB_LIB.T6G(SCH_1):GND   I139 @T6G_MB_LIB.T6G(SCH_1):PAGE107
   125    GND @T6G_MB_LIB.T6G(SCH_1):GND   I139 @T6G_MB_LIB.T6G(SCH_1):PAGE107
   128    GND @T6G_MB_LIB.T6G(SCH_1):GND   I139 @T6G_MB_LIB.T6G(SCH_1):PAGE107
   130    GND @T6G_MB_LIB.T6G(SCH_1):GND   I139 @T6G_MB_LIB.T6G(SCH_1):PAGE107
   134    GND @T6G_MB_LIB.T6G(SCH_1):GND   I139 @T6G_MB_LIB.T6G(SCH_1):PAGE107
   143    GND @T6G_MB_LIB.T6G(SCH_1):GND   I139 @T6G_MB_LIB.T6G(SCH_1):PAGE107
   151    GND @T6G_MB_LIB.T6G(SCH_1):GND   I139 @T6G_MB_LIB.T6G(SCH_1):PAGE107
   153    GND @T6G_MB_LIB.T6G(SCH_1):GND   I139 @T6G_MB_LIB.T6G(SCH_1):PAGE107
   155    GND @T6G_MB_LIB.T6G(SCH_1):GND   I139 @T6G_MB_LIB.T6G(SCH_1):PAGE107
   158    GND @T6G_MB_LIB.T6G(SCH_1):GND   I139 @T6G_MB_LIB.T6G(SCH_1):PAGE107
   160    GND @T6G_MB_LIB.T6G(SCH_1):GND   I139 @T6G_MB_LIB.T6G(SCH_1):PAGE107
   162    GND @T6G_MB_LIB.T6G(SCH_1):GND   I139 @T6G_MB_LIB.T6G(SCH_1):PAGE107
   164    GND @T6G_MB_LIB.T6G(SCH_1):GND   I139 @T6G_MB_LIB.T6G(SCH_1):PAGE107
   166    GND @T6G_MB_LIB.T6G(SCH_1):GND   I139 @T6G_MB_LIB.T6G(SCH_1):PAGE107
   169    GND @T6G_MB_LIB.T6G(SCH_1):GND   I139 @T6G_MB_LIB.T6G(SCH_1):PAGE107
   171    GND @T6G_MB_LIB.T6G(SCH_1):GND   I139 @T6G_MB_LIB.T6G(SCH_1):PAGE107
   173    GND @T6G_MB_LIB.T6G(SCH_1):GND   I139 @T6G_MB_LIB.T6G(SCH_1):PAGE107
   175    GND @T6G_MB_LIB.T6G(SCH_1):GND   I139 @T6G_MB_LIB.T6G(SCH_1):PAGE107
   177    GND @T6G_MB_LIB.T6G(SCH_1):GND   I139 @T6G_MB_LIB.T6G(SCH_1):PAGE107
   180    GND @T6G_MB_LIB.T6G(SCH_1):GND   I139 @T6G_MB_LIB.T6G(SCH_1):PAGE107
   182    GND @T6G_MB_LIB.T6G(SCH_1):GND   I139 @T6G_MB_LIB.T6G(SCH_1):PAGE107
   184    GND @T6G_MB_LIB.T6G(SCH_1):GND   I139 @T6G_MB_LIB.T6G(SCH_1):PAGE107
   186    GND @T6G_MB_LIB.T6G(SCH_1):GND   I139 @T6G_MB_LIB.T6G(SCH_1):PAGE107
   188    GND @T6G_MB_LIB.T6G(SCH_1):GND   I139 @T6G_MB_LIB.T6G(SCH_1):PAGE107
   191    GND @T6G_MB_LIB.T6G(SCH_1):GND   I139 @T6G_MB_LIB.T6G(SCH_1):PAGE107
   193    GND @T6G_MB_LIB.T6G(SCH_1):GND   I139 @T6G_MB_LIB.T6G(SCH_1):PAGE107
   195    GND @T6G_MB_LIB.T6G(SCH_1):GND   I139 @T6G_MB_LIB.T6G(SCH_1):PAGE107
   197    GND @T6G_MB_LIB.T6G(SCH_1):GND   I139 @T6G_MB_LIB.T6G(SCH_1):PAGE107
   199    GND @T6G_MB_LIB.T6G(SCH_1):GND   I139 @T6G_MB_LIB.T6G(SCH_1):PAGE107
   202    GND @T6G_MB_LIB.T6G(SCH_1):GND   I139 @T6G_MB_LIB.T6G(SCH_1):PAGE107
   204    GND @T6G_MB_LIB.T6G(SCH_1):GND   I139 @T6G_MB_LIB.T6G(SCH_1):PAGE107
   206    GND @T6G_MB_LIB.T6G(SCH_1):GND   I139 @T6G_MB_LIB.T6G(SCH_1):PAGE107
   208    GND @T6G_MB_LIB.T6G(SCH_1):GND   I139 @T6G_MB_LIB.T6G(SCH_1):PAGE107
   210    GND @T6G_MB_LIB.T6G(SCH_1):GND   I139 @T6G_MB_LIB.T6G(SCH_1):PAGE107
   212    GND @T6G_MB_LIB.T6G(SCH_1):GND   I139 @T6G_MB_LIB.T6G(SCH_1):PAGE107
   214    GND @T6G_MB_LIB.T6G(SCH_1):GND   I139 @T6G_MB_LIB.T6G(SCH_1):PAGE107
   216    GND @T6G_MB_LIB.T6G(SCH_1):GND   I139 @T6G_MB_LIB.T6G(SCH_1):PAGE107
   219    GND @T6G_MB_LIB.T6G(SCH_1):GND   I139 @T6G_MB_LIB.T6G(SCH_1):PAGE107
   222    GND @T6G_MB_LIB.T6G(SCH_1):GND   I139 @T6G_MB_LIB.T6G(SCH_1):PAGE107
   224    GND @T6G_MB_LIB.T6G(SCH_1):GND   I139 @T6G_MB_LIB.T6G(SCH_1):PAGE107
   226    GND @T6G_MB_LIB.T6G(SCH_1):GND   I139 @T6G_MB_LIB.T6G(SCH_1):PAGE107
   228    GND @T6G_MB_LIB.T6G(SCH_1):GND   I139 @T6G_MB_LIB.T6G(SCH_1):PAGE107
   233    GND @T6G_MB_LIB.T6G(SCH_1):GND   I139 @T6G_MB_LIB.T6G(SCH_1):PAGE107
   237    GND @T6G_MB_LIB.T6G(SCH_1):GND   I139 @T6G_MB_LIB.T6G(SCH_1):PAGE107
   242    GND @T6G_MB_LIB.T6G(SCH_1):GND   I139 @T6G_MB_LIB.T6G(SCH_1):PAGE107
   244    GND @T6G_MB_LIB.T6G(SCH_1):GND   I139 @T6G_MB_LIB.T6G(SCH_1):PAGE107
   246    GND @T6G_MB_LIB.T6G(SCH_1):GND   I139 @T6G_MB_LIB.T6G(SCH_1):PAGE107
   248    GND @T6G_MB_LIB.T6G(SCH_1):GND   I139 @T6G_MB_LIB.T6G(SCH_1):PAGE107
   251    GND @T6G_MB_LIB.T6G(SCH_1):GND   I139 @T6G_MB_LIB.T6G(SCH_1):PAGE107
   253    GND @T6G_MB_LIB.T6G(SCH_1):GND   I139 @T6G_MB_LIB.T6G(SCH_1):PAGE107
   255    GND @T6G_MB_LIB.T6G(SCH_1):GND   I139 @T6G_MB_LIB.T6G(SCH_1):PAGE107
   257    GND @T6G_MB_LIB.T6G(SCH_1):GND   I139 @T6G_MB_LIB.T6G(SCH_1):PAGE107
   259    GND @T6G_MB_LIB.T6G(SCH_1):GND   I139 @T6G_MB_LIB.T6G(SCH_1):PAGE107
   262    GND @T6G_MB_LIB.T6G(SCH_1):GND   I139 @T6G_MB_LIB.T6G(SCH_1):PAGE107
   264    GND @T6G_MB_LIB.T6G(SCH_1):GND   I139 @T6G_MB_LIB.T6G(SCH_1):PAGE107
   266    GND @T6G_MB_LIB.T6G(SCH_1):GND   I139 @T6G_MB_LIB.T6G(SCH_1):PAGE107
   268    GND @T6G_MB_LIB.T6G(SCH_1):GND   I139 @T6G_MB_LIB.T6G(SCH_1):PAGE107
   270    GND @T6G_MB_LIB.T6G(SCH_1):GND   I139 @T6G_MB_LIB.T6G(SCH_1):PAGE107
   273    GND @T6G_MB_LIB.T6G(SCH_1):GND   I139 @T6G_MB_LIB.T6G(SCH_1):PAGE107
   275    GND @T6G_MB_LIB.T6G(SCH_1):GND   I139 @T6G_MB_LIB.T6G(SCH_1):PAGE107
   277    GND @T6G_MB_LIB.T6G(SCH_1):GND   I139 @T6G_MB_LIB.T6G(SCH_1):PAGE107
   279    GND @T6G_MB_LIB.T6G(SCH_1):GND   I139 @T6G_MB_LIB.T6G(SCH_1):PAGE107
   281    GND @T6G_MB_LIB.T6G(SCH_1):GND   I139 @T6G_MB_LIB.T6G(SCH_1):PAGE107
   284    GND @T6G_MB_LIB.T6G(SCH_1):GND   I139 @T6G_MB_LIB.T6G(SCH_1):PAGE107
   286    GND @T6G_MB_LIB.T6G(SCH_1):GND   I139 @T6G_MB_LIB.T6G(SCH_1):PAGE107
   288    GND @T6G_MB_LIB.T6G(SCH_1):GND   I139 @T6G_MB_LIB.T6G(SCH_1):PAGE107
     1 P12V_MEM_CPU1 @T6G_MB_LIB.T6G(SCH_1):P12V_MEM_CPU1   I139 @T6G_MB_LIB.T6G(SCH_1):PAGE107
   145 P12V_MEM_CPU1 @T6G_MB_LIB.T6G(SCH_1):P12V_MEM_CPU1   I139 @T6G_MB_LIB.T6G(SCH_1):PAGE107
   146 P12V_MEM_CPU1 @T6G_MB_LIB.T6G(SCH_1):P12V_MEM_CPU1   I139 @T6G_MB_LIB.T6G(SCH_1):PAGE107
   230    GND @T6G_MB_LIB.T6G(SCH_1):GND   I139 @T6G_MB_LIB.T6G(SCH_1):PAGE107
   235    GND @T6G_MB_LIB.T6G(SCH_1):GND   I139 @T6G_MB_LIB.T6G(SCH_1):PAGE107
   240    GND @T6G_MB_LIB.T6G(SCH_1):GND   I139 @T6G_MB_LIB.T6G(SCH_1):PAGE107
   132    GND @T6G_MB_LIB.T6G(SCH_1):GND   I139 @T6G_MB_LIB.T6G(SCH_1):PAGE107
   136    GND @T6G_MB_LIB.T6G(SCH_1):GND   I139 @T6G_MB_LIB.T6G(SCH_1):PAGE107
   139    GND @T6G_MB_LIB.T6G(SCH_1):GND   I139 @T6G_MB_LIB.T6G(SCH_1):PAGE107
   141    GND @T6G_MB_LIB.T6G(SCH_1):GND   I139 @T6G_MB_LIB.T6G(SCH_1):PAGE107
    G1    GND @T6G_MB_LIB.T6G(SCH_1):GND   I139 @T6G_MB_LIB.T6G(SCH_1):PAGE107
    G2    GND @T6G_MB_LIB.T6G(SCH_1):GND   I139 @T6G_MB_LIB.T6G(SCH_1):PAGE107
    G3    GND @T6G_MB_LIB.T6G(SCH_1):GND   I139 @T6G_MB_LIB.T6G(SCH_1):PAGE107

J100 SCONN288_DDR506112002KQ-SCONN288_DDR506112002KQ,SMA
     3 P3V3_AUX @T6G_MB_LIB.T6G(SCH_1):P3V3_AUX    I22 @T6G_MB_LIB.T6G(SCH_1):PAGE105
     2     NC     NC    I22 @T6G_MB_LIB.T6G(SCH_1):PAGE105
   144     NC     NC    I22 @T6G_MB_LIB.T6G(SCH_1):PAGE105
   149     NC     NC    I22 @T6G_MB_LIB.T6G(SCH_1):PAGE105
   150     NC     NC    I22 @T6G_MB_LIB.T6G(SCH_1):PAGE105
   220     NC     NC    I22 @T6G_MB_LIB.T6G(SCH_1):PAGE105
   231     NC     NC    I22 @T6G_MB_LIB.T6G(SCH_1):PAGE105
   232     NC     NC    I22 @T6G_MB_LIB.T6G(SCH_1):PAGE105
   207 M_I_CPU1_RESET_N @T6G_MB_LIB.T6G(SCH_1):M_I_CPU1_RESET_N    I22 @T6G_MB_LIB.T6G(SCH_1):PAGE105
   147 PWRGD_CHI_CPU1_DIMM @T6G_MB_LIB.T6G(SCH_1):PWRGD_CHI_CPU1_DIMM    I22 @T6G_MB_LIB.T6G(SCH_1):PAGE105
   227 M_I_CPU1_SB_PAR @T6G_MB_LIB.T6G(SCH_1):M_I_CPU1_SB_PAR    I22 @T6G_MB_LIB.T6G(SCH_1):PAGE105
    74 M_I_CPU1_SA_PAR @T6G_MB_LIB.T6G(SCH_1):M_I_CPU1_SA_PAR    I22 @T6G_MB_LIB.T6G(SCH_1):PAGE105
    87 M_I_CPU1_SB_RSP<0> @T6G_MB_LIB.T6G(SCH_1):M_I_CPU1_SB_RSP(0)    I22 @T6G_MB_LIB.T6G(SCH_1):PAGE105
    86 M_I_CPU1_SA_RSP<0> @T6G_MB_LIB.T6G(SCH_1):M_I_CPU1_SA_RSP(0)    I22 @T6G_MB_LIB.T6G(SCH_1):PAGE105
     5 I3C_SPD_DDRI_CPU1_SDA @T6G_MB_LIB.T6G(SCH_1):I3C_SPD_DDRI_CPU1_SDA    I22 @T6G_MB_LIB.T6G(SCH_1):PAGE105
     4 I3C_SPD_DDRI_CPU1_SCL @T6G_MB_LIB.T6G(SCH_1):I3C_SPD_DDRI_CPU1_SCL    I22 @T6G_MB_LIB.T6G(SCH_1):PAGE105
   148 PD_CHI_CPU1_DIMM_SAA @T6G_MB_LIB.T6G(SCH_1):PD_CHI_CPU1_DIMM_SAA    I22 @T6G_MB_LIB.T6G(SCH_1):PAGE105
   100 M_I_CPU1_SB_DQ<0> @T6G_MB_LIB.T6G(SCH_1):M_I_CPU1_SB_DQ(0)    I22 @T6G_MB_LIB.T6G(SCH_1):PAGE105
   102 M_I_CPU1_SB_DQ<1> @T6G_MB_LIB.T6G(SCH_1):M_I_CPU1_SB_DQ(1)    I22 @T6G_MB_LIB.T6G(SCH_1):PAGE105
   245 M_I_CPU1_SB_DQ<2> @T6G_MB_LIB.T6G(SCH_1):M_I_CPU1_SB_DQ(2)    I22 @T6G_MB_LIB.T6G(SCH_1):PAGE105
   247 M_I_CPU1_SB_DQ<3> @T6G_MB_LIB.T6G(SCH_1):M_I_CPU1_SB_DQ(3)    I22 @T6G_MB_LIB.T6G(SCH_1):PAGE105
   107 M_I_CPU1_SB_DQ<4> @T6G_MB_LIB.T6G(SCH_1):M_I_CPU1_SB_DQ(4)    I22 @T6G_MB_LIB.T6G(SCH_1):PAGE105
   109 M_I_CPU1_SB_DQ<5> @T6G_MB_LIB.T6G(SCH_1):M_I_CPU1_SB_DQ(5)    I22 @T6G_MB_LIB.T6G(SCH_1):PAGE105
   252 M_I_CPU1_SB_DQ<6> @T6G_MB_LIB.T6G(SCH_1):M_I_CPU1_SB_DQ(6)    I22 @T6G_MB_LIB.T6G(SCH_1):PAGE105
   254 M_I_CPU1_SB_DQ<7> @T6G_MB_LIB.T6G(SCH_1):M_I_CPU1_SB_DQ(7)    I22 @T6G_MB_LIB.T6G(SCH_1):PAGE105
   111 M_I_CPU1_SB_DQ<8> @T6G_MB_LIB.T6G(SCH_1):M_I_CPU1_SB_DQ(8)    I22 @T6G_MB_LIB.T6G(SCH_1):PAGE105
   113 M_I_CPU1_SB_DQ<9> @T6G_MB_LIB.T6G(SCH_1):M_I_CPU1_SB_DQ(9)    I22 @T6G_MB_LIB.T6G(SCH_1):PAGE105
   256 M_I_CPU1_SB_DQ<10> @T6G_MB_LIB.T6G(SCH_1):M_I_CPU1_SB_DQ(10)    I22 @T6G_MB_LIB.T6G(SCH_1):PAGE105
   258 M_I_CPU1_SB_DQ<11> @T6G_MB_LIB.T6G(SCH_1):M_I_CPU1_SB_DQ(11)    I22 @T6G_MB_LIB.T6G(SCH_1):PAGE105
   118 M_I_CPU1_SB_DQ<12> @T6G_MB_LIB.T6G(SCH_1):M_I_CPU1_SB_DQ(12)    I22 @T6G_MB_LIB.T6G(SCH_1):PAGE105
   120 M_I_CPU1_SB_DQ<13> @T6G_MB_LIB.T6G(SCH_1):M_I_CPU1_SB_DQ(13)    I22 @T6G_MB_LIB.T6G(SCH_1):PAGE105
   263 M_I_CPU1_SB_DQ<14> @T6G_MB_LIB.T6G(SCH_1):M_I_CPU1_SB_DQ(14)    I22 @T6G_MB_LIB.T6G(SCH_1):PAGE105
   265 M_I_CPU1_SB_DQ<15> @T6G_MB_LIB.T6G(SCH_1):M_I_CPU1_SB_DQ(15)    I22 @T6G_MB_LIB.T6G(SCH_1):PAGE105
   122 M_I_CPU1_SB_DQ<16> @T6G_MB_LIB.T6G(SCH_1):M_I_CPU1_SB_DQ(16)    I22 @T6G_MB_LIB.T6G(SCH_1):PAGE105
   124 M_I_CPU1_SB_DQ<17> @T6G_MB_LIB.T6G(SCH_1):M_I_CPU1_SB_DQ(17)    I22 @T6G_MB_LIB.T6G(SCH_1):PAGE105
   267 M_I_CPU1_SB_DQ<18> @T6G_MB_LIB.T6G(SCH_1):M_I_CPU1_SB_DQ(18)    I22 @T6G_MB_LIB.T6G(SCH_1):PAGE105
   269 M_I_CPU1_SB_DQ<19> @T6G_MB_LIB.T6G(SCH_1):M_I_CPU1_SB_DQ(19)    I22 @T6G_MB_LIB.T6G(SCH_1):PAGE105
   129 M_I_CPU1_SB_DQ<20> @T6G_MB_LIB.T6G(SCH_1):M_I_CPU1_SB_DQ(20)    I22 @T6G_MB_LIB.T6G(SCH_1):PAGE105
   131 M_I_CPU1_SB_DQ<21> @T6G_MB_LIB.T6G(SCH_1):M_I_CPU1_SB_DQ(21)    I22 @T6G_MB_LIB.T6G(SCH_1):PAGE105
   274 M_I_CPU1_SB_DQ<22> @T6G_MB_LIB.T6G(SCH_1):M_I_CPU1_SB_DQ(22)    I22 @T6G_MB_LIB.T6G(SCH_1):PAGE105
   276 M_I_CPU1_SB_DQ<23> @T6G_MB_LIB.T6G(SCH_1):M_I_CPU1_SB_DQ(23)    I22 @T6G_MB_LIB.T6G(SCH_1):PAGE105
   133 M_I_CPU1_SB_DQ<24> @T6G_MB_LIB.T6G(SCH_1):M_I_CPU1_SB_DQ(24)    I22 @T6G_MB_LIB.T6G(SCH_1):PAGE105
   135 M_I_CPU1_SB_DQ<25> @T6G_MB_LIB.T6G(SCH_1):M_I_CPU1_SB_DQ(25)    I22 @T6G_MB_LIB.T6G(SCH_1):PAGE105
   278 M_I_CPU1_SB_DQ<26> @T6G_MB_LIB.T6G(SCH_1):M_I_CPU1_SB_DQ(26)    I22 @T6G_MB_LIB.T6G(SCH_1):PAGE105
   280 M_I_CPU1_SB_DQ<27> @T6G_MB_LIB.T6G(SCH_1):M_I_CPU1_SB_DQ(27)    I22 @T6G_MB_LIB.T6G(SCH_1):PAGE105
   140 M_I_CPU1_SB_DQ<28> @T6G_MB_LIB.T6G(SCH_1):M_I_CPU1_SB_DQ(28)    I22 @T6G_MB_LIB.T6G(SCH_1):PAGE105
   142 M_I_CPU1_SB_DQ<29> @T6G_MB_LIB.T6G(SCH_1):M_I_CPU1_SB_DQ(29)    I22 @T6G_MB_LIB.T6G(SCH_1):PAGE105
   285 M_I_CPU1_SB_DQ<30> @T6G_MB_LIB.T6G(SCH_1):M_I_CPU1_SB_DQ(30)    I22 @T6G_MB_LIB.T6G(SCH_1):PAGE105
   287 M_I_CPU1_SB_DQ<31> @T6G_MB_LIB.T6G(SCH_1):M_I_CPU1_SB_DQ(31)    I22 @T6G_MB_LIB.T6G(SCH_1):PAGE105
     7 M_I_CPU1_SA_DQ<0> @T6G_MB_LIB.T6G(SCH_1):M_I_CPU1_SA_DQ(0)    I22 @T6G_MB_LIB.T6G(SCH_1):PAGE105
     9 M_I_CPU1_SA_DQ<1> @T6G_MB_LIB.T6G(SCH_1):M_I_CPU1_SA_DQ(1)    I22 @T6G_MB_LIB.T6G(SCH_1):PAGE105
   152 M_I_CPU1_SA_DQ<2> @T6G_MB_LIB.T6G(SCH_1):M_I_CPU1_SA_DQ(2)    I22 @T6G_MB_LIB.T6G(SCH_1):PAGE105
   154 M_I_CPU1_SA_DQ<3> @T6G_MB_LIB.T6G(SCH_1):M_I_CPU1_SA_DQ(3)    I22 @T6G_MB_LIB.T6G(SCH_1):PAGE105
    14 M_I_CPU1_SA_DQ<4> @T6G_MB_LIB.T6G(SCH_1):M_I_CPU1_SA_DQ(4)    I22 @T6G_MB_LIB.T6G(SCH_1):PAGE105
    16 M_I_CPU1_SA_DQ<5> @T6G_MB_LIB.T6G(SCH_1):M_I_CPU1_SA_DQ(5)    I22 @T6G_MB_LIB.T6G(SCH_1):PAGE105
   159 M_I_CPU1_SA_DQ<6> @T6G_MB_LIB.T6G(SCH_1):M_I_CPU1_SA_DQ(6)    I22 @T6G_MB_LIB.T6G(SCH_1):PAGE105
   161 M_I_CPU1_SA_DQ<7> @T6G_MB_LIB.T6G(SCH_1):M_I_CPU1_SA_DQ(7)    I22 @T6G_MB_LIB.T6G(SCH_1):PAGE105
    18 M_I_CPU1_SA_DQ<8> @T6G_MB_LIB.T6G(SCH_1):M_I_CPU1_SA_DQ(8)    I22 @T6G_MB_LIB.T6G(SCH_1):PAGE105
    20 M_I_CPU1_SA_DQ<9> @T6G_MB_LIB.T6G(SCH_1):M_I_CPU1_SA_DQ(9)    I22 @T6G_MB_LIB.T6G(SCH_1):PAGE105
   163 M_I_CPU1_SA_DQ<10> @T6G_MB_LIB.T6G(SCH_1):M_I_CPU1_SA_DQ(10)    I22 @T6G_MB_LIB.T6G(SCH_1):PAGE105
   165 M_I_CPU1_SA_DQ<11> @T6G_MB_LIB.T6G(SCH_1):M_I_CPU1_SA_DQ(11)    I22 @T6G_MB_LIB.T6G(SCH_1):PAGE105
    25 M_I_CPU1_SA_DQ<12> @T6G_MB_LIB.T6G(SCH_1):M_I_CPU1_SA_DQ(12)    I22 @T6G_MB_LIB.T6G(SCH_1):PAGE105
    27 M_I_CPU1_SA_DQ<13> @T6G_MB_LIB.T6G(SCH_1):M_I_CPU1_SA_DQ(13)    I22 @T6G_MB_LIB.T6G(SCH_1):PAGE105
   170 M_I_CPU1_SA_DQ<14> @T6G_MB_LIB.T6G(SCH_1):M_I_CPU1_SA_DQ(14)    I22 @T6G_MB_LIB.T6G(SCH_1):PAGE105
   172 M_I_CPU1_SA_DQ<15> @T6G_MB_LIB.T6G(SCH_1):M_I_CPU1_SA_DQ(15)    I22 @T6G_MB_LIB.T6G(SCH_1):PAGE105
    29 M_I_CPU1_SA_DQ<16> @T6G_MB_LIB.T6G(SCH_1):M_I_CPU1_SA_DQ(16)    I22 @T6G_MB_LIB.T6G(SCH_1):PAGE105
    31 M_I_CPU1_SA_DQ<17> @T6G_MB_LIB.T6G(SCH_1):M_I_CPU1_SA_DQ(17)    I22 @T6G_MB_LIB.T6G(SCH_1):PAGE105
   174 M_I_CPU1_SA_DQ<18> @T6G_MB_LIB.T6G(SCH_1):M_I_CPU1_SA_DQ(18)    I22 @T6G_MB_LIB.T6G(SCH_1):PAGE105
   176 M_I_CPU1_SA_DQ<19> @T6G_MB_LIB.T6G(SCH_1):M_I_CPU1_SA_DQ(19)    I22 @T6G_MB_LIB.T6G(SCH_1):PAGE105
    36 M_I_CPU1_SA_DQ<20> @T6G_MB_LIB.T6G(SCH_1):M_I_CPU1_SA_DQ(20)    I22 @T6G_MB_LIB.T6G(SCH_1):PAGE105
    38 M_I_CPU1_SA_DQ<21> @T6G_MB_LIB.T6G(SCH_1):M_I_CPU1_SA_DQ(21)    I22 @T6G_MB_LIB.T6G(SCH_1):PAGE105
   181 M_I_CPU1_SA_DQ<22> @T6G_MB_LIB.T6G(SCH_1):M_I_CPU1_SA_DQ(22)    I22 @T6G_MB_LIB.T6G(SCH_1):PAGE105
   183 M_I_CPU1_SA_DQ<23> @T6G_MB_LIB.T6G(SCH_1):M_I_CPU1_SA_DQ(23)    I22 @T6G_MB_LIB.T6G(SCH_1):PAGE105
    40 M_I_CPU1_SA_DQ<24> @T6G_MB_LIB.T6G(SCH_1):M_I_CPU1_SA_DQ(24)    I22 @T6G_MB_LIB.T6G(SCH_1):PAGE105
    42 M_I_CPU1_SA_DQ<25> @T6G_MB_LIB.T6G(SCH_1):M_I_CPU1_SA_DQ(25)    I22 @T6G_MB_LIB.T6G(SCH_1):PAGE105
   185 M_I_CPU1_SA_DQ<26> @T6G_MB_LIB.T6G(SCH_1):M_I_CPU1_SA_DQ(26)    I22 @T6G_MB_LIB.T6G(SCH_1):PAGE105
   187 M_I_CPU1_SA_DQ<27> @T6G_MB_LIB.T6G(SCH_1):M_I_CPU1_SA_DQ(27)    I22 @T6G_MB_LIB.T6G(SCH_1):PAGE105
    47 M_I_CPU1_SA_DQ<28> @T6G_MB_LIB.T6G(SCH_1):M_I_CPU1_SA_DQ(28)    I22 @T6G_MB_LIB.T6G(SCH_1):PAGE105
    49 M_I_CPU1_SA_DQ<29> @T6G_MB_LIB.T6G(SCH_1):M_I_CPU1_SA_DQ(29)    I22 @T6G_MB_LIB.T6G(SCH_1):PAGE105
   192 M_I_CPU1_SA_DQ<30> @T6G_MB_LIB.T6G(SCH_1):M_I_CPU1_SA_DQ(30)    I22 @T6G_MB_LIB.T6G(SCH_1):PAGE105
   229 M_I_CPU1_SB_CS_N<1> @T6G_MB_LIB.T6G(SCH_1):M_I_CPU1_SB_CS_N(1)    I22 @T6G_MB_LIB.T6G(SCH_1):PAGE105
   209 M_I_CPU1_SA_CS_N<1> @T6G_MB_LIB.T6G(SCH_1):M_I_CPU1_SA_CS_N(1)    I22 @T6G_MB_LIB.T6G(SCH_1):PAGE105
    84 M_I_CPU1_SB_CS_N<0> @T6G_MB_LIB.T6G(SCH_1):M_I_CPU1_SB_CS_N(0)    I22 @T6G_MB_LIB.T6G(SCH_1):PAGE105
    64 M_I_CPU1_SA_CS_N<0> @T6G_MB_LIB.T6G(SCH_1):M_I_CPU1_SA_CS_N(0)    I22 @T6G_MB_LIB.T6G(SCH_1):PAGE105
   217 M_I_CPU1_CLK_DP<0> @T6G_MB_LIB.T6G(SCH_1):M_I_CPU1_CLK_DP(0)    I22 @T6G_MB_LIB.T6G(SCH_1):PAGE105
   218 M_I_CPU1_CLK_DN<0> @T6G_MB_LIB.T6G(SCH_1):M_I_CPU1_CLK_DN(0)    I22 @T6G_MB_LIB.T6G(SCH_1):PAGE105
    96 M_I_CPU1_SB_CB<0> @T6G_MB_LIB.T6G(SCH_1):M_I_CPU1_SB_CB(0)    I22 @T6G_MB_LIB.T6G(SCH_1):PAGE105
    98 M_I_CPU1_SB_CB<1> @T6G_MB_LIB.T6G(SCH_1):M_I_CPU1_SB_CB(1)    I22 @T6G_MB_LIB.T6G(SCH_1):PAGE105
   241 M_I_CPU1_SB_CB<2> @T6G_MB_LIB.T6G(SCH_1):M_I_CPU1_SB_CB(2)    I22 @T6G_MB_LIB.T6G(SCH_1):PAGE105
   243 M_I_CPU1_SB_CB<3> @T6G_MB_LIB.T6G(SCH_1):M_I_CPU1_SB_CB(3)    I22 @T6G_MB_LIB.T6G(SCH_1):PAGE105
    89 M_I_CPU1_SB_CB<4> @T6G_MB_LIB.T6G(SCH_1):M_I_CPU1_SB_CB(4)    I22 @T6G_MB_LIB.T6G(SCH_1):PAGE105
    91 M_I_CPU1_SB_CB<5> @T6G_MB_LIB.T6G(SCH_1):M_I_CPU1_SB_CB(5)    I22 @T6G_MB_LIB.T6G(SCH_1):PAGE105
   234 M_I_CPU1_SB_CB<6> @T6G_MB_LIB.T6G(SCH_1):M_I_CPU1_SB_CB(6)    I22 @T6G_MB_LIB.T6G(SCH_1):PAGE105
    51 M_I_CPU1_SA_CB<0> @T6G_MB_LIB.T6G(SCH_1):M_I_CPU1_SA_CB(0)    I22 @T6G_MB_LIB.T6G(SCH_1):PAGE105
   196 M_I_CPU1_SA_CB<2> @T6G_MB_LIB.T6G(SCH_1):M_I_CPU1_SA_CB(2)    I22 @T6G_MB_LIB.T6G(SCH_1):PAGE105
   198 M_I_CPU1_SA_CB<3> @T6G_MB_LIB.T6G(SCH_1):M_I_CPU1_SA_CB(3)    I22 @T6G_MB_LIB.T6G(SCH_1):PAGE105
    60 M_I_CPU1_SA_CB<5> @T6G_MB_LIB.T6G(SCH_1):M_I_CPU1_SA_CB(5)    I22 @T6G_MB_LIB.T6G(SCH_1):PAGE105
   203 M_I_CPU1_SA_CB<6> @T6G_MB_LIB.T6G(SCH_1):M_I_CPU1_SA_CB(6)    I22 @T6G_MB_LIB.T6G(SCH_1):PAGE105
    82 M_I_CPU1_SB_CA<6> @T6G_MB_LIB.T6G(SCH_1):M_I_CPU1_SB_CA(6)    I22 @T6G_MB_LIB.T6G(SCH_1):PAGE105
    72 M_I_CPU1_SA_CA<6> @T6G_MB_LIB.T6G(SCH_1):M_I_CPU1_SA_CA(6)    I22 @T6G_MB_LIB.T6G(SCH_1):PAGE105
   225 M_I_CPU1_SB_CA<5> @T6G_MB_LIB.T6G(SCH_1):M_I_CPU1_SB_CA(5)    I22 @T6G_MB_LIB.T6G(SCH_1):PAGE105
   215 M_I_CPU1_SA_CA<5> @T6G_MB_LIB.T6G(SCH_1):M_I_CPU1_SA_CA(5)    I22 @T6G_MB_LIB.T6G(SCH_1):PAGE105
    80 M_I_CPU1_SB_CA<4> @T6G_MB_LIB.T6G(SCH_1):M_I_CPU1_SB_CA(4)    I22 @T6G_MB_LIB.T6G(SCH_1):PAGE105
    70 M_I_CPU1_SA_CA<4> @T6G_MB_LIB.T6G(SCH_1):M_I_CPU1_SA_CA(4)    I22 @T6G_MB_LIB.T6G(SCH_1):PAGE105
   223 M_I_CPU1_SB_CA<3> @T6G_MB_LIB.T6G(SCH_1):M_I_CPU1_SB_CA(3)    I22 @T6G_MB_LIB.T6G(SCH_1):PAGE105
   213 M_I_CPU1_SA_CA<3> @T6G_MB_LIB.T6G(SCH_1):M_I_CPU1_SA_CA(3)    I22 @T6G_MB_LIB.T6G(SCH_1):PAGE105
    78 M_I_CPU1_SB_CA<2> @T6G_MB_LIB.T6G(SCH_1):M_I_CPU1_SB_CA(2)    I22 @T6G_MB_LIB.T6G(SCH_1):PAGE105
    68 M_I_CPU1_SA_CA<2> @T6G_MB_LIB.T6G(SCH_1):M_I_CPU1_SA_CA(2)    I22 @T6G_MB_LIB.T6G(SCH_1):PAGE105
   221 M_I_CPU1_SB_CA<1> @T6G_MB_LIB.T6G(SCH_1):M_I_CPU1_SB_CA(1)    I22 @T6G_MB_LIB.T6G(SCH_1):PAGE105
   211 M_I_CPU1_SA_CA<1> @T6G_MB_LIB.T6G(SCH_1):M_I_CPU1_SA_CA(1)    I22 @T6G_MB_LIB.T6G(SCH_1):PAGE105
    76 M_I_CPU1_SB_CA<0> @T6G_MB_LIB.T6G(SCH_1):M_I_CPU1_SB_CA(0)    I22 @T6G_MB_LIB.T6G(SCH_1):PAGE105
    66 M_I_CPU1_SA_CA<0> @T6G_MB_LIB.T6G(SCH_1):M_I_CPU1_SA_CA(0)    I22 @T6G_MB_LIB.T6G(SCH_1):PAGE105
    62 M_I_CPU1_ALERT_N @T6G_MB_LIB.T6G(SCH_1):M_I_CPU1_ALERT_N    I22 @T6G_MB_LIB.T6G(SCH_1):PAGE105
   236 M_I_CPU1_SB_CB<7> @T6G_MB_LIB.T6G(SCH_1):M_I_CPU1_SB_CB(7)    I22 @T6G_MB_LIB.T6G(SCH_1):PAGE105
    53 M_I_CPU1_SA_CB<1> @T6G_MB_LIB.T6G(SCH_1):M_I_CPU1_SA_CB(1)    I22 @T6G_MB_LIB.T6G(SCH_1):PAGE105
    58 M_I_CPU1_SA_CB<4> @T6G_MB_LIB.T6G(SCH_1):M_I_CPU1_SA_CB(4)    I22 @T6G_MB_LIB.T6G(SCH_1):PAGE105
   205 M_I_CPU1_SA_CB<7> @T6G_MB_LIB.T6G(SCH_1):M_I_CPU1_SA_CB(7)    I22 @T6G_MB_LIB.T6G(SCH_1):PAGE105
   194 M_I_CPU1_SA_DQ<31> @T6G_MB_LIB.T6G(SCH_1):M_I_CPU1_SA_DQ(31)    I22 @T6G_MB_LIB.T6G(SCH_1):PAGE105
    93 M_I_CPU1_SB_DQS_DP<9> @T6G_MB_LIB.T6G(SCH_1):M_I_CPU1_SB_DQS_DP(9)   I236 @T6G_MB_LIB.T6G(SCH_1):PAGE105
    94 M_I_CPU1_SB_DQS_DN<9> @T6G_MB_LIB.T6G(SCH_1):M_I_CPU1_SB_DQS_DN(9)   I236 @T6G_MB_LIB.T6G(SCH_1):PAGE105
   201 M_I_CPU1_SA_DQS_DP<9> @T6G_MB_LIB.T6G(SCH_1):M_I_CPU1_SA_DQS_DP(9)   I236 @T6G_MB_LIB.T6G(SCH_1):PAGE105
   200 M_I_CPU1_SA_DQS_DN<9> @T6G_MB_LIB.T6G(SCH_1):M_I_CPU1_SA_DQS_DN(9)   I236 @T6G_MB_LIB.T6G(SCH_1):PAGE105
   190 M_I_CPU1_SA_DQS_DP<8> @T6G_MB_LIB.T6G(SCH_1):M_I_CPU1_SA_DQS_DP(8)   I236 @T6G_MB_LIB.T6G(SCH_1):PAGE105
   189 M_I_CPU1_SA_DQS_DN<8> @T6G_MB_LIB.T6G(SCH_1):M_I_CPU1_SA_DQS_DN(8)   I236 @T6G_MB_LIB.T6G(SCH_1):PAGE105
   271 M_I_CPU1_SB_DQS_DN<7> @T6G_MB_LIB.T6G(SCH_1):M_I_CPU1_SB_DQS_DN(7)   I236 @T6G_MB_LIB.T6G(SCH_1):PAGE105
   179 M_I_CPU1_SA_DQS_DP<7> @T6G_MB_LIB.T6G(SCH_1):M_I_CPU1_SA_DQS_DP(7)   I236 @T6G_MB_LIB.T6G(SCH_1):PAGE105
   261 M_I_CPU1_SB_DQS_DP<6> @T6G_MB_LIB.T6G(SCH_1):M_I_CPU1_SB_DQS_DP(6)   I236 @T6G_MB_LIB.T6G(SCH_1):PAGE105
   260 M_I_CPU1_SB_DQS_DN<6> @T6G_MB_LIB.T6G(SCH_1):M_I_CPU1_SB_DQS_DN(6)   I236 @T6G_MB_LIB.T6G(SCH_1):PAGE105
   167 M_I_CPU1_SA_DQS_DN<6> @T6G_MB_LIB.T6G(SCH_1):M_I_CPU1_SA_DQS_DN(6)   I236 @T6G_MB_LIB.T6G(SCH_1):PAGE105
   250 M_I_CPU1_SB_DQS_DP<5> @T6G_MB_LIB.T6G(SCH_1):M_I_CPU1_SB_DQS_DP(5)   I236 @T6G_MB_LIB.T6G(SCH_1):PAGE105
   249 M_I_CPU1_SB_DQS_DN<5> @T6G_MB_LIB.T6G(SCH_1):M_I_CPU1_SB_DQS_DN(5)   I236 @T6G_MB_LIB.T6G(SCH_1):PAGE105
   157 M_I_CPU1_SA_DQS_DP<5> @T6G_MB_LIB.T6G(SCH_1):M_I_CPU1_SA_DQS_DP(5)   I236 @T6G_MB_LIB.T6G(SCH_1):PAGE105
   156 M_I_CPU1_SA_DQS_DN<5> @T6G_MB_LIB.T6G(SCH_1):M_I_CPU1_SA_DQS_DN(5)   I236 @T6G_MB_LIB.T6G(SCH_1):PAGE105
   239 M_I_CPU1_SB_DQS_DP<4> @T6G_MB_LIB.T6G(SCH_1):M_I_CPU1_SB_DQS_DP(4)   I236 @T6G_MB_LIB.T6G(SCH_1):PAGE105
   238 M_I_CPU1_SB_DQS_DN<4> @T6G_MB_LIB.T6G(SCH_1):M_I_CPU1_SB_DQS_DN(4)   I236 @T6G_MB_LIB.T6G(SCH_1):PAGE105
    55 M_I_CPU1_SA_DQS_DP<4> @T6G_MB_LIB.T6G(SCH_1):M_I_CPU1_SA_DQS_DP(4)   I236 @T6G_MB_LIB.T6G(SCH_1):PAGE105
    56 M_I_CPU1_SA_DQS_DN<4> @T6G_MB_LIB.T6G(SCH_1):M_I_CPU1_SA_DQS_DN(4)   I236 @T6G_MB_LIB.T6G(SCH_1):PAGE105
   137 M_I_CPU1_SB_DQS_DP<3> @T6G_MB_LIB.T6G(SCH_1):M_I_CPU1_SB_DQS_DP(3)   I236 @T6G_MB_LIB.T6G(SCH_1):PAGE105
   138 M_I_CPU1_SB_DQS_DN<3> @T6G_MB_LIB.T6G(SCH_1):M_I_CPU1_SB_DQS_DN(3)   I236 @T6G_MB_LIB.T6G(SCH_1):PAGE105
    44 M_I_CPU1_SA_DQS_DP<3> @T6G_MB_LIB.T6G(SCH_1):M_I_CPU1_SA_DQS_DP(3)   I236 @T6G_MB_LIB.T6G(SCH_1):PAGE105
    45 M_I_CPU1_SA_DQS_DN<3> @T6G_MB_LIB.T6G(SCH_1):M_I_CPU1_SA_DQS_DN(3)   I236 @T6G_MB_LIB.T6G(SCH_1):PAGE105
   126 M_I_CPU1_SB_DQS_DP<2> @T6G_MB_LIB.T6G(SCH_1):M_I_CPU1_SB_DQS_DP(2)   I236 @T6G_MB_LIB.T6G(SCH_1):PAGE105
   127 M_I_CPU1_SB_DQS_DN<2> @T6G_MB_LIB.T6G(SCH_1):M_I_CPU1_SB_DQS_DN(2)   I236 @T6G_MB_LIB.T6G(SCH_1):PAGE105
    33 M_I_CPU1_SA_DQS_DP<2> @T6G_MB_LIB.T6G(SCH_1):M_I_CPU1_SA_DQS_DP(2)   I236 @T6G_MB_LIB.T6G(SCH_1):PAGE105
    34 M_I_CPU1_SA_DQS_DN<2> @T6G_MB_LIB.T6G(SCH_1):M_I_CPU1_SA_DQS_DN(2)   I236 @T6G_MB_LIB.T6G(SCH_1):PAGE105
   115 M_I_CPU1_SB_DQS_DP<1> @T6G_MB_LIB.T6G(SCH_1):M_I_CPU1_SB_DQS_DP(1)   I236 @T6G_MB_LIB.T6G(SCH_1):PAGE105
   116 M_I_CPU1_SB_DQS_DN<1> @T6G_MB_LIB.T6G(SCH_1):M_I_CPU1_SB_DQS_DN(1)   I236 @T6G_MB_LIB.T6G(SCH_1):PAGE105
    22 M_I_CPU1_SA_DQS_DP<1> @T6G_MB_LIB.T6G(SCH_1):M_I_CPU1_SA_DQS_DP(1)   I236 @T6G_MB_LIB.T6G(SCH_1):PAGE105
    23 M_I_CPU1_SA_DQS_DN<1> @T6G_MB_LIB.T6G(SCH_1):M_I_CPU1_SA_DQS_DN(1)   I236 @T6G_MB_LIB.T6G(SCH_1):PAGE105
   104 M_I_CPU1_SB_DQS_DP<0> @T6G_MB_LIB.T6G(SCH_1):M_I_CPU1_SB_DQS_DP(0)   I236 @T6G_MB_LIB.T6G(SCH_1):PAGE105
   105 M_I_CPU1_SB_DQS_DN<0> @T6G_MB_LIB.T6G(SCH_1):M_I_CPU1_SB_DQS_DN(0)   I236 @T6G_MB_LIB.T6G(SCH_1):PAGE105
    11 M_I_CPU1_SA_DQS_DP<0> @T6G_MB_LIB.T6G(SCH_1):M_I_CPU1_SA_DQS_DP(0)   I236 @T6G_MB_LIB.T6G(SCH_1):PAGE105
    12 M_I_CPU1_SA_DQS_DN<0> @T6G_MB_LIB.T6G(SCH_1):M_I_CPU1_SA_DQS_DN(0)   I236 @T6G_MB_LIB.T6G(SCH_1):PAGE105
   272 M_I_CPU1_SB_DQS_DP<7> @T6G_MB_LIB.T6G(SCH_1):M_I_CPU1_SB_DQS_DP(7)   I236 @T6G_MB_LIB.T6G(SCH_1):PAGE105
   282 M_I_CPU1_SB_DQS_DN<8> @T6G_MB_LIB.T6G(SCH_1):M_I_CPU1_SB_DQS_DN(8)   I236 @T6G_MB_LIB.T6G(SCH_1):PAGE105
   283 M_I_CPU1_SB_DQS_DP<8> @T6G_MB_LIB.T6G(SCH_1):M_I_CPU1_SB_DQS_DP(8)   I236 @T6G_MB_LIB.T6G(SCH_1):PAGE105
   168 M_I_CPU1_SA_DQS_DP<6> @T6G_MB_LIB.T6G(SCH_1):M_I_CPU1_SA_DQS_DP(6)   I236 @T6G_MB_LIB.T6G(SCH_1):PAGE105
   178 M_I_CPU1_SA_DQS_DN<7> @T6G_MB_LIB.T6G(SCH_1):M_I_CPU1_SA_DQS_DN(7)   I236 @T6G_MB_LIB.T6G(SCH_1):PAGE105
     6    GND @T6G_MB_LIB.T6G(SCH_1):GND   I176 @T6G_MB_LIB.T6G(SCH_1):PAGE105
     8    GND @T6G_MB_LIB.T6G(SCH_1):GND   I176 @T6G_MB_LIB.T6G(SCH_1):PAGE105
    10    GND @T6G_MB_LIB.T6G(SCH_1):GND   I176 @T6G_MB_LIB.T6G(SCH_1):PAGE105
    13    GND @T6G_MB_LIB.T6G(SCH_1):GND   I176 @T6G_MB_LIB.T6G(SCH_1):PAGE105
    15    GND @T6G_MB_LIB.T6G(SCH_1):GND   I176 @T6G_MB_LIB.T6G(SCH_1):PAGE105
    17    GND @T6G_MB_LIB.T6G(SCH_1):GND   I176 @T6G_MB_LIB.T6G(SCH_1):PAGE105
    19    GND @T6G_MB_LIB.T6G(SCH_1):GND   I176 @T6G_MB_LIB.T6G(SCH_1):PAGE105
    21    GND @T6G_MB_LIB.T6G(SCH_1):GND   I176 @T6G_MB_LIB.T6G(SCH_1):PAGE105
    24    GND @T6G_MB_LIB.T6G(SCH_1):GND   I176 @T6G_MB_LIB.T6G(SCH_1):PAGE105
    26    GND @T6G_MB_LIB.T6G(SCH_1):GND   I176 @T6G_MB_LIB.T6G(SCH_1):PAGE105
    28    GND @T6G_MB_LIB.T6G(SCH_1):GND   I176 @T6G_MB_LIB.T6G(SCH_1):PAGE105
    30    GND @T6G_MB_LIB.T6G(SCH_1):GND   I176 @T6G_MB_LIB.T6G(SCH_1):PAGE105
    32    GND @T6G_MB_LIB.T6G(SCH_1):GND   I176 @T6G_MB_LIB.T6G(SCH_1):PAGE105
    35    GND @T6G_MB_LIB.T6G(SCH_1):GND   I176 @T6G_MB_LIB.T6G(SCH_1):PAGE105
    37    GND @T6G_MB_LIB.T6G(SCH_1):GND   I176 @T6G_MB_LIB.T6G(SCH_1):PAGE105
    39    GND @T6G_MB_LIB.T6G(SCH_1):GND   I176 @T6G_MB_LIB.T6G(SCH_1):PAGE105
    41    GND @T6G_MB_LIB.T6G(SCH_1):GND   I176 @T6G_MB_LIB.T6G(SCH_1):PAGE105
    43    GND @T6G_MB_LIB.T6G(SCH_1):GND   I176 @T6G_MB_LIB.T6G(SCH_1):PAGE105
    46    GND @T6G_MB_LIB.T6G(SCH_1):GND   I176 @T6G_MB_LIB.T6G(SCH_1):PAGE105
    48    GND @T6G_MB_LIB.T6G(SCH_1):GND   I176 @T6G_MB_LIB.T6G(SCH_1):PAGE105
    50    GND @T6G_MB_LIB.T6G(SCH_1):GND   I176 @T6G_MB_LIB.T6G(SCH_1):PAGE105
    52    GND @T6G_MB_LIB.T6G(SCH_1):GND   I176 @T6G_MB_LIB.T6G(SCH_1):PAGE105
    54    GND @T6G_MB_LIB.T6G(SCH_1):GND   I176 @T6G_MB_LIB.T6G(SCH_1):PAGE105
    57    GND @T6G_MB_LIB.T6G(SCH_1):GND   I176 @T6G_MB_LIB.T6G(SCH_1):PAGE105
    59    GND @T6G_MB_LIB.T6G(SCH_1):GND   I176 @T6G_MB_LIB.T6G(SCH_1):PAGE105
    61    GND @T6G_MB_LIB.T6G(SCH_1):GND   I176 @T6G_MB_LIB.T6G(SCH_1):PAGE105
    63    GND @T6G_MB_LIB.T6G(SCH_1):GND   I176 @T6G_MB_LIB.T6G(SCH_1):PAGE105
    65    GND @T6G_MB_LIB.T6G(SCH_1):GND   I176 @T6G_MB_LIB.T6G(SCH_1):PAGE105
    67    GND @T6G_MB_LIB.T6G(SCH_1):GND   I176 @T6G_MB_LIB.T6G(SCH_1):PAGE105
    69    GND @T6G_MB_LIB.T6G(SCH_1):GND   I176 @T6G_MB_LIB.T6G(SCH_1):PAGE105
    71    GND @T6G_MB_LIB.T6G(SCH_1):GND   I176 @T6G_MB_LIB.T6G(SCH_1):PAGE105
    73    GND @T6G_MB_LIB.T6G(SCH_1):GND   I176 @T6G_MB_LIB.T6G(SCH_1):PAGE105
    75    GND @T6G_MB_LIB.T6G(SCH_1):GND   I176 @T6G_MB_LIB.T6G(SCH_1):PAGE105
    77    GND @T6G_MB_LIB.T6G(SCH_1):GND   I176 @T6G_MB_LIB.T6G(SCH_1):PAGE105
    79    GND @T6G_MB_LIB.T6G(SCH_1):GND   I176 @T6G_MB_LIB.T6G(SCH_1):PAGE105
    81    GND @T6G_MB_LIB.T6G(SCH_1):GND   I176 @T6G_MB_LIB.T6G(SCH_1):PAGE105
    83    GND @T6G_MB_LIB.T6G(SCH_1):GND   I176 @T6G_MB_LIB.T6G(SCH_1):PAGE105
    85    GND @T6G_MB_LIB.T6G(SCH_1):GND   I176 @T6G_MB_LIB.T6G(SCH_1):PAGE105
    88    GND @T6G_MB_LIB.T6G(SCH_1):GND   I176 @T6G_MB_LIB.T6G(SCH_1):PAGE105
    90    GND @T6G_MB_LIB.T6G(SCH_1):GND   I176 @T6G_MB_LIB.T6G(SCH_1):PAGE105
    92    GND @T6G_MB_LIB.T6G(SCH_1):GND   I176 @T6G_MB_LIB.T6G(SCH_1):PAGE105
    95    GND @T6G_MB_LIB.T6G(SCH_1):GND   I176 @T6G_MB_LIB.T6G(SCH_1):PAGE105
    97    GND @T6G_MB_LIB.T6G(SCH_1):GND   I176 @T6G_MB_LIB.T6G(SCH_1):PAGE105
    99    GND @T6G_MB_LIB.T6G(SCH_1):GND   I176 @T6G_MB_LIB.T6G(SCH_1):PAGE105
   101    GND @T6G_MB_LIB.T6G(SCH_1):GND   I176 @T6G_MB_LIB.T6G(SCH_1):PAGE105
   103    GND @T6G_MB_LIB.T6G(SCH_1):GND   I176 @T6G_MB_LIB.T6G(SCH_1):PAGE105
   106    GND @T6G_MB_LIB.T6G(SCH_1):GND   I176 @T6G_MB_LIB.T6G(SCH_1):PAGE105
   108    GND @T6G_MB_LIB.T6G(SCH_1):GND   I176 @T6G_MB_LIB.T6G(SCH_1):PAGE105
   110    GND @T6G_MB_LIB.T6G(SCH_1):GND   I176 @T6G_MB_LIB.T6G(SCH_1):PAGE105
   112    GND @T6G_MB_LIB.T6G(SCH_1):GND   I176 @T6G_MB_LIB.T6G(SCH_1):PAGE105
   114    GND @T6G_MB_LIB.T6G(SCH_1):GND   I176 @T6G_MB_LIB.T6G(SCH_1):PAGE105
   117    GND @T6G_MB_LIB.T6G(SCH_1):GND   I176 @T6G_MB_LIB.T6G(SCH_1):PAGE105
   119    GND @T6G_MB_LIB.T6G(SCH_1):GND   I176 @T6G_MB_LIB.T6G(SCH_1):PAGE105
   121    GND @T6G_MB_LIB.T6G(SCH_1):GND   I176 @T6G_MB_LIB.T6G(SCH_1):PAGE105
   123    GND @T6G_MB_LIB.T6G(SCH_1):GND   I176 @T6G_MB_LIB.T6G(SCH_1):PAGE105
   125    GND @T6G_MB_LIB.T6G(SCH_1):GND   I176 @T6G_MB_LIB.T6G(SCH_1):PAGE105
   128    GND @T6G_MB_LIB.T6G(SCH_1):GND   I176 @T6G_MB_LIB.T6G(SCH_1):PAGE105
   130    GND @T6G_MB_LIB.T6G(SCH_1):GND   I176 @T6G_MB_LIB.T6G(SCH_1):PAGE105
   134    GND @T6G_MB_LIB.T6G(SCH_1):GND   I176 @T6G_MB_LIB.T6G(SCH_1):PAGE105
   143    GND @T6G_MB_LIB.T6G(SCH_1):GND   I176 @T6G_MB_LIB.T6G(SCH_1):PAGE105
   151    GND @T6G_MB_LIB.T6G(SCH_1):GND   I176 @T6G_MB_LIB.T6G(SCH_1):PAGE105
   153    GND @T6G_MB_LIB.T6G(SCH_1):GND   I176 @T6G_MB_LIB.T6G(SCH_1):PAGE105
   155    GND @T6G_MB_LIB.T6G(SCH_1):GND   I176 @T6G_MB_LIB.T6G(SCH_1):PAGE105
   158    GND @T6G_MB_LIB.T6G(SCH_1):GND   I176 @T6G_MB_LIB.T6G(SCH_1):PAGE105
   160    GND @T6G_MB_LIB.T6G(SCH_1):GND   I176 @T6G_MB_LIB.T6G(SCH_1):PAGE105
   162    GND @T6G_MB_LIB.T6G(SCH_1):GND   I176 @T6G_MB_LIB.T6G(SCH_1):PAGE105
   164    GND @T6G_MB_LIB.T6G(SCH_1):GND   I176 @T6G_MB_LIB.T6G(SCH_1):PAGE105
   166    GND @T6G_MB_LIB.T6G(SCH_1):GND   I176 @T6G_MB_LIB.T6G(SCH_1):PAGE105
   169    GND @T6G_MB_LIB.T6G(SCH_1):GND   I176 @T6G_MB_LIB.T6G(SCH_1):PAGE105
   171    GND @T6G_MB_LIB.T6G(SCH_1):GND   I176 @T6G_MB_LIB.T6G(SCH_1):PAGE105
   173    GND @T6G_MB_LIB.T6G(SCH_1):GND   I176 @T6G_MB_LIB.T6G(SCH_1):PAGE105
   175    GND @T6G_MB_LIB.T6G(SCH_1):GND   I176 @T6G_MB_LIB.T6G(SCH_1):PAGE105
   177    GND @T6G_MB_LIB.T6G(SCH_1):GND   I176 @T6G_MB_LIB.T6G(SCH_1):PAGE105
   180    GND @T6G_MB_LIB.T6G(SCH_1):GND   I176 @T6G_MB_LIB.T6G(SCH_1):PAGE105
   182    GND @T6G_MB_LIB.T6G(SCH_1):GND   I176 @T6G_MB_LIB.T6G(SCH_1):PAGE105
   184    GND @T6G_MB_LIB.T6G(SCH_1):GND   I176 @T6G_MB_LIB.T6G(SCH_1):PAGE105
   186    GND @T6G_MB_LIB.T6G(SCH_1):GND   I176 @T6G_MB_LIB.T6G(SCH_1):PAGE105
   188    GND @T6G_MB_LIB.T6G(SCH_1):GND   I176 @T6G_MB_LIB.T6G(SCH_1):PAGE105
   191    GND @T6G_MB_LIB.T6G(SCH_1):GND   I176 @T6G_MB_LIB.T6G(SCH_1):PAGE105
   193    GND @T6G_MB_LIB.T6G(SCH_1):GND   I176 @T6G_MB_LIB.T6G(SCH_1):PAGE105
   195    GND @T6G_MB_LIB.T6G(SCH_1):GND   I176 @T6G_MB_LIB.T6G(SCH_1):PAGE105
   197    GND @T6G_MB_LIB.T6G(SCH_1):GND   I176 @T6G_MB_LIB.T6G(SCH_1):PAGE105
   199    GND @T6G_MB_LIB.T6G(SCH_1):GND   I176 @T6G_MB_LIB.T6G(SCH_1):PAGE105
   202    GND @T6G_MB_LIB.T6G(SCH_1):GND   I176 @T6G_MB_LIB.T6G(SCH_1):PAGE105
   204    GND @T6G_MB_LIB.T6G(SCH_1):GND   I176 @T6G_MB_LIB.T6G(SCH_1):PAGE105
   206    GND @T6G_MB_LIB.T6G(SCH_1):GND   I176 @T6G_MB_LIB.T6G(SCH_1):PAGE105
   208    GND @T6G_MB_LIB.T6G(SCH_1):GND   I176 @T6G_MB_LIB.T6G(SCH_1):PAGE105
   210    GND @T6G_MB_LIB.T6G(SCH_1):GND   I176 @T6G_MB_LIB.T6G(SCH_1):PAGE105
   212    GND @T6G_MB_LIB.T6G(SCH_1):GND   I176 @T6G_MB_LIB.T6G(SCH_1):PAGE105
   214    GND @T6G_MB_LIB.T6G(SCH_1):GND   I176 @T6G_MB_LIB.T6G(SCH_1):PAGE105
   216    GND @T6G_MB_LIB.T6G(SCH_1):GND   I176 @T6G_MB_LIB.T6G(SCH_1):PAGE105
   219    GND @T6G_MB_LIB.T6G(SCH_1):GND   I176 @T6G_MB_LIB.T6G(SCH_1):PAGE105
   222    GND @T6G_MB_LIB.T6G(SCH_1):GND   I176 @T6G_MB_LIB.T6G(SCH_1):PAGE105
   224    GND @T6G_MB_LIB.T6G(SCH_1):GND   I176 @T6G_MB_LIB.T6G(SCH_1):PAGE105
   226    GND @T6G_MB_LIB.T6G(SCH_1):GND   I176 @T6G_MB_LIB.T6G(SCH_1):PAGE105
   228    GND @T6G_MB_LIB.T6G(SCH_1):GND   I176 @T6G_MB_LIB.T6G(SCH_1):PAGE105
   233    GND @T6G_MB_LIB.T6G(SCH_1):GND   I176 @T6G_MB_LIB.T6G(SCH_1):PAGE105
   237    GND @T6G_MB_LIB.T6G(SCH_1):GND   I176 @T6G_MB_LIB.T6G(SCH_1):PAGE105
   242    GND @T6G_MB_LIB.T6G(SCH_1):GND   I176 @T6G_MB_LIB.T6G(SCH_1):PAGE105
   244    GND @T6G_MB_LIB.T6G(SCH_1):GND   I176 @T6G_MB_LIB.T6G(SCH_1):PAGE105
   246    GND @T6G_MB_LIB.T6G(SCH_1):GND   I176 @T6G_MB_LIB.T6G(SCH_1):PAGE105
   248    GND @T6G_MB_LIB.T6G(SCH_1):GND   I176 @T6G_MB_LIB.T6G(SCH_1):PAGE105
   251    GND @T6G_MB_LIB.T6G(SCH_1):GND   I176 @T6G_MB_LIB.T6G(SCH_1):PAGE105
   253    GND @T6G_MB_LIB.T6G(SCH_1):GND   I176 @T6G_MB_LIB.T6G(SCH_1):PAGE105
   255    GND @T6G_MB_LIB.T6G(SCH_1):GND   I176 @T6G_MB_LIB.T6G(SCH_1):PAGE105
   257    GND @T6G_MB_LIB.T6G(SCH_1):GND   I176 @T6G_MB_LIB.T6G(SCH_1):PAGE105
   259    GND @T6G_MB_LIB.T6G(SCH_1):GND   I176 @T6G_MB_LIB.T6G(SCH_1):PAGE105
   262    GND @T6G_MB_LIB.T6G(SCH_1):GND   I176 @T6G_MB_LIB.T6G(SCH_1):PAGE105
   264    GND @T6G_MB_LIB.T6G(SCH_1):GND   I176 @T6G_MB_LIB.T6G(SCH_1):PAGE105
   266    GND @T6G_MB_LIB.T6G(SCH_1):GND   I176 @T6G_MB_LIB.T6G(SCH_1):PAGE105
   268    GND @T6G_MB_LIB.T6G(SCH_1):GND   I176 @T6G_MB_LIB.T6G(SCH_1):PAGE105
   270    GND @T6G_MB_LIB.T6G(SCH_1):GND   I176 @T6G_MB_LIB.T6G(SCH_1):PAGE105
   273    GND @T6G_MB_LIB.T6G(SCH_1):GND   I176 @T6G_MB_LIB.T6G(SCH_1):PAGE105
   275    GND @T6G_MB_LIB.T6G(SCH_1):GND   I176 @T6G_MB_LIB.T6G(SCH_1):PAGE105
   277    GND @T6G_MB_LIB.T6G(SCH_1):GND   I176 @T6G_MB_LIB.T6G(SCH_1):PAGE105
   279    GND @T6G_MB_LIB.T6G(SCH_1):GND   I176 @T6G_MB_LIB.T6G(SCH_1):PAGE105
   281    GND @T6G_MB_LIB.T6G(SCH_1):GND   I176 @T6G_MB_LIB.T6G(SCH_1):PAGE105
   284    GND @T6G_MB_LIB.T6G(SCH_1):GND   I176 @T6G_MB_LIB.T6G(SCH_1):PAGE105
   286    GND @T6G_MB_LIB.T6G(SCH_1):GND   I176 @T6G_MB_LIB.T6G(SCH_1):PAGE105
   288    GND @T6G_MB_LIB.T6G(SCH_1):GND   I176 @T6G_MB_LIB.T6G(SCH_1):PAGE105
     1 P12V_MEM_CPU1 @T6G_MB_LIB.T6G(SCH_1):P12V_MEM_CPU1   I176 @T6G_MB_LIB.T6G(SCH_1):PAGE105
   145 P12V_MEM_CPU1 @T6G_MB_LIB.T6G(SCH_1):P12V_MEM_CPU1   I176 @T6G_MB_LIB.T6G(SCH_1):PAGE105
   146 P12V_MEM_CPU1 @T6G_MB_LIB.T6G(SCH_1):P12V_MEM_CPU1   I176 @T6G_MB_LIB.T6G(SCH_1):PAGE105
   230    GND @T6G_MB_LIB.T6G(SCH_1):GND   I176 @T6G_MB_LIB.T6G(SCH_1):PAGE105
   235    GND @T6G_MB_LIB.T6G(SCH_1):GND   I176 @T6G_MB_LIB.T6G(SCH_1):PAGE105
   240    GND @T6G_MB_LIB.T6G(SCH_1):GND   I176 @T6G_MB_LIB.T6G(SCH_1):PAGE105
   132    GND @T6G_MB_LIB.T6G(SCH_1):GND   I176 @T6G_MB_LIB.T6G(SCH_1):PAGE105
   136    GND @T6G_MB_LIB.T6G(SCH_1):GND   I176 @T6G_MB_LIB.T6G(SCH_1):PAGE105
   139    GND @T6G_MB_LIB.T6G(SCH_1):GND   I176 @T6G_MB_LIB.T6G(SCH_1):PAGE105
   141    GND @T6G_MB_LIB.T6G(SCH_1):GND   I176 @T6G_MB_LIB.T6G(SCH_1):PAGE105
    G1    GND @T6G_MB_LIB.T6G(SCH_1):GND   I176 @T6G_MB_LIB.T6G(SCH_1):PAGE105
    G2    GND @T6G_MB_LIB.T6G(SCH_1):GND   I176 @T6G_MB_LIB.T6G(SCH_1):PAGE105
    G3    GND @T6G_MB_LIB.T6G(SCH_1):GND   I176 @T6G_MB_LIB.T6G(SCH_1):PAGE105

J102 SCONN288_DDR506112002KQ-SCONN288_DDR506112002KQ,SMA
     3 P3V3_AUX @T6G_MB_LIB.T6G(SCH_1):P3V3_AUX    I22 @T6G_MB_LIB.T6G(SCH_1):PAGE103
     2     NC     NC    I22 @T6G_MB_LIB.T6G(SCH_1):PAGE103
   144     NC     NC    I22 @T6G_MB_LIB.T6G(SCH_1):PAGE103
   149     NC     NC    I22 @T6G_MB_LIB.T6G(SCH_1):PAGE103
   150     NC     NC    I22 @T6G_MB_LIB.T6G(SCH_1):PAGE103
   220     NC     NC    I22 @T6G_MB_LIB.T6G(SCH_1):PAGE103
   231     NC     NC    I22 @T6G_MB_LIB.T6G(SCH_1):PAGE103
   232     NC     NC    I22 @T6G_MB_LIB.T6G(SCH_1):PAGE103
   207 M_G_CPU1_RESET_N @T6G_MB_LIB.T6G(SCH_1):M_G_CPU1_RESET_N    I22 @T6G_MB_LIB.T6G(SCH_1):PAGE103
   147 PWRGD_CHG_CPU1_DIMM0 @T6G_MB_LIB.T6G(SCH_1):PWRGD_CHG_CPU1_DIMM0    I22 @T6G_MB_LIB.T6G(SCH_1):PAGE103
   227 M_G_CPU1_SB_PAR @T6G_MB_LIB.T6G(SCH_1):M_G_CPU1_SB_PAR    I22 @T6G_MB_LIB.T6G(SCH_1):PAGE103
    74 M_G_CPU1_SA_PAR @T6G_MB_LIB.T6G(SCH_1):M_G_CPU1_SA_PAR    I22 @T6G_MB_LIB.T6G(SCH_1):PAGE103
    87 M_G_CPU1_SB_RSP<0> @T6G_MB_LIB.T6G(SCH_1):M_G_CPU1_SB_RSP(0)    I22 @T6G_MB_LIB.T6G(SCH_1):PAGE103
    86 M_G_CPU1_SA_RSP<0> @T6G_MB_LIB.T6G(SCH_1):M_G_CPU1_SA_RSP(0)    I22 @T6G_MB_LIB.T6G(SCH_1):PAGE103
     5 I3C_SPD_DDRG_CPU1_SDA @T6G_MB_LIB.T6G(SCH_1):I3C_SPD_DDRG_CPU1_SDA    I22 @T6G_MB_LIB.T6G(SCH_1):PAGE103
     4 I3C_SPD_DDRG_CPU1_SCL @T6G_MB_LIB.T6G(SCH_1):I3C_SPD_DDRG_CPU1_SCL    I22 @T6G_MB_LIB.T6G(SCH_1):PAGE103
   148 PD_CHG_CPU1_DIMM0_SAA @T6G_MB_LIB.T6G(SCH_1):PD_CHG_CPU1_DIMM0_SAA    I22 @T6G_MB_LIB.T6G(SCH_1):PAGE103
   100 M_G_CPU1_SB_DQ<0> @T6G_MB_LIB.T6G(SCH_1):M_G_CPU1_SB_DQ(0)    I22 @T6G_MB_LIB.T6G(SCH_1):PAGE103
   102 M_G_CPU1_SB_DQ<1> @T6G_MB_LIB.T6G(SCH_1):M_G_CPU1_SB_DQ(1)    I22 @T6G_MB_LIB.T6G(SCH_1):PAGE103
   245 M_G_CPU1_SB_DQ<2> @T6G_MB_LIB.T6G(SCH_1):M_G_CPU1_SB_DQ(2)    I22 @T6G_MB_LIB.T6G(SCH_1):PAGE103
   247 M_G_CPU1_SB_DQ<3> @T6G_MB_LIB.T6G(SCH_1):M_G_CPU1_SB_DQ(3)    I22 @T6G_MB_LIB.T6G(SCH_1):PAGE103
   107 M_G_CPU1_SB_DQ<4> @T6G_MB_LIB.T6G(SCH_1):M_G_CPU1_SB_DQ(4)    I22 @T6G_MB_LIB.T6G(SCH_1):PAGE103
   109 M_G_CPU1_SB_DQ<5> @T6G_MB_LIB.T6G(SCH_1):M_G_CPU1_SB_DQ(5)    I22 @T6G_MB_LIB.T6G(SCH_1):PAGE103
   252 M_G_CPU1_SB_DQ<6> @T6G_MB_LIB.T6G(SCH_1):M_G_CPU1_SB_DQ(6)    I22 @T6G_MB_LIB.T6G(SCH_1):PAGE103
   254 M_G_CPU1_SB_DQ<7> @T6G_MB_LIB.T6G(SCH_1):M_G_CPU1_SB_DQ(7)    I22 @T6G_MB_LIB.T6G(SCH_1):PAGE103
   111 M_G_CPU1_SB_DQ<8> @T6G_MB_LIB.T6G(SCH_1):M_G_CPU1_SB_DQ(8)    I22 @T6G_MB_LIB.T6G(SCH_1):PAGE103
   113 M_G_CPU1_SB_DQ<9> @T6G_MB_LIB.T6G(SCH_1):M_G_CPU1_SB_DQ(9)    I22 @T6G_MB_LIB.T6G(SCH_1):PAGE103
   256 M_G_CPU1_SB_DQ<10> @T6G_MB_LIB.T6G(SCH_1):M_G_CPU1_SB_DQ(10)    I22 @T6G_MB_LIB.T6G(SCH_1):PAGE103
   258 M_G_CPU1_SB_DQ<11> @T6G_MB_LIB.T6G(SCH_1):M_G_CPU1_SB_DQ(11)    I22 @T6G_MB_LIB.T6G(SCH_1):PAGE103
   118 M_G_CPU1_SB_DQ<12> @T6G_MB_LIB.T6G(SCH_1):M_G_CPU1_SB_DQ(12)    I22 @T6G_MB_LIB.T6G(SCH_1):PAGE103
   120 M_G_CPU1_SB_DQ<13> @T6G_MB_LIB.T6G(SCH_1):M_G_CPU1_SB_DQ(13)    I22 @T6G_MB_LIB.T6G(SCH_1):PAGE103
   263 M_G_CPU1_SB_DQ<14> @T6G_MB_LIB.T6G(SCH_1):M_G_CPU1_SB_DQ(14)    I22 @T6G_MB_LIB.T6G(SCH_1):PAGE103
   265 M_G_CPU1_SB_DQ<15> @T6G_MB_LIB.T6G(SCH_1):M_G_CPU1_SB_DQ(15)    I22 @T6G_MB_LIB.T6G(SCH_1):PAGE103
   122 M_G_CPU1_SB_DQ<16> @T6G_MB_LIB.T6G(SCH_1):M_G_CPU1_SB_DQ(16)    I22 @T6G_MB_LIB.T6G(SCH_1):PAGE103
   124 M_G_CPU1_SB_DQ<17> @T6G_MB_LIB.T6G(SCH_1):M_G_CPU1_SB_DQ(17)    I22 @T6G_MB_LIB.T6G(SCH_1):PAGE103
   267 M_G_CPU1_SB_DQ<18> @T6G_MB_LIB.T6G(SCH_1):M_G_CPU1_SB_DQ(18)    I22 @T6G_MB_LIB.T6G(SCH_1):PAGE103
   269 M_G_CPU1_SB_DQ<19> @T6G_MB_LIB.T6G(SCH_1):M_G_CPU1_SB_DQ(19)    I22 @T6G_MB_LIB.T6G(SCH_1):PAGE103
   129 M_G_CPU1_SB_DQ<20> @T6G_MB_LIB.T6G(SCH_1):M_G_CPU1_SB_DQ(20)    I22 @T6G_MB_LIB.T6G(SCH_1):PAGE103
   131 M_G_CPU1_SB_DQ<21> @T6G_MB_LIB.T6G(SCH_1):M_G_CPU1_SB_DQ(21)    I22 @T6G_MB_LIB.T6G(SCH_1):PAGE103
   274 M_G_CPU1_SB_DQ<22> @T6G_MB_LIB.T6G(SCH_1):M_G_CPU1_SB_DQ(22)    I22 @T6G_MB_LIB.T6G(SCH_1):PAGE103
   276 M_G_CPU1_SB_DQ<23> @T6G_MB_LIB.T6G(SCH_1):M_G_CPU1_SB_DQ(23)    I22 @T6G_MB_LIB.T6G(SCH_1):PAGE103
   133 M_G_CPU1_SB_DQ<24> @T6G_MB_LIB.T6G(SCH_1):M_G_CPU1_SB_DQ(24)    I22 @T6G_MB_LIB.T6G(SCH_1):PAGE103
   135 M_G_CPU1_SB_DQ<25> @T6G_MB_LIB.T6G(SCH_1):M_G_CPU1_SB_DQ(25)    I22 @T6G_MB_LIB.T6G(SCH_1):PAGE103
   278 M_G_CPU1_SB_DQ<26> @T6G_MB_LIB.T6G(SCH_1):M_G_CPU1_SB_DQ(26)    I22 @T6G_MB_LIB.T6G(SCH_1):PAGE103
   280 M_G_CPU1_SB_DQ<27> @T6G_MB_LIB.T6G(SCH_1):M_G_CPU1_SB_DQ(27)    I22 @T6G_MB_LIB.T6G(SCH_1):PAGE103
   140 M_G_CPU1_SB_DQ<28> @T6G_MB_LIB.T6G(SCH_1):M_G_CPU1_SB_DQ(28)    I22 @T6G_MB_LIB.T6G(SCH_1):PAGE103
   142 M_G_CPU1_SB_DQ<29> @T6G_MB_LIB.T6G(SCH_1):M_G_CPU1_SB_DQ(29)    I22 @T6G_MB_LIB.T6G(SCH_1):PAGE103
   285 M_G_CPU1_SB_DQ<30> @T6G_MB_LIB.T6G(SCH_1):M_G_CPU1_SB_DQ(30)    I22 @T6G_MB_LIB.T6G(SCH_1):PAGE103
   287 M_G_CPU1_SB_DQ<31> @T6G_MB_LIB.T6G(SCH_1):M_G_CPU1_SB_DQ(31)    I22 @T6G_MB_LIB.T6G(SCH_1):PAGE103
     7 M_G_CPU1_SA_DQ<0> @T6G_MB_LIB.T6G(SCH_1):M_G_CPU1_SA_DQ(0)    I22 @T6G_MB_LIB.T6G(SCH_1):PAGE103
     9 M_G_CPU1_SA_DQ<1> @T6G_MB_LIB.T6G(SCH_1):M_G_CPU1_SA_DQ(1)    I22 @T6G_MB_LIB.T6G(SCH_1):PAGE103
   152 M_G_CPU1_SA_DQ<2> @T6G_MB_LIB.T6G(SCH_1):M_G_CPU1_SA_DQ(2)    I22 @T6G_MB_LIB.T6G(SCH_1):PAGE103
   154 M_G_CPU1_SA_DQ<3> @T6G_MB_LIB.T6G(SCH_1):M_G_CPU1_SA_DQ(3)    I22 @T6G_MB_LIB.T6G(SCH_1):PAGE103
    14 M_G_CPU1_SA_DQ<4> @T6G_MB_LIB.T6G(SCH_1):M_G_CPU1_SA_DQ(4)    I22 @T6G_MB_LIB.T6G(SCH_1):PAGE103
    16 M_G_CPU1_SA_DQ<5> @T6G_MB_LIB.T6G(SCH_1):M_G_CPU1_SA_DQ(5)    I22 @T6G_MB_LIB.T6G(SCH_1):PAGE103
   159 M_G_CPU1_SA_DQ<6> @T6G_MB_LIB.T6G(SCH_1):M_G_CPU1_SA_DQ(6)    I22 @T6G_MB_LIB.T6G(SCH_1):PAGE103
   161 M_G_CPU1_SA_DQ<7> @T6G_MB_LIB.T6G(SCH_1):M_G_CPU1_SA_DQ(7)    I22 @T6G_MB_LIB.T6G(SCH_1):PAGE103
    18 M_G_CPU1_SA_DQ<8> @T6G_MB_LIB.T6G(SCH_1):M_G_CPU1_SA_DQ(8)    I22 @T6G_MB_LIB.T6G(SCH_1):PAGE103
    20 M_G_CPU1_SA_DQ<9> @T6G_MB_LIB.T6G(SCH_1):M_G_CPU1_SA_DQ(9)    I22 @T6G_MB_LIB.T6G(SCH_1):PAGE103
   163 M_G_CPU1_SA_DQ<10> @T6G_MB_LIB.T6G(SCH_1):M_G_CPU1_SA_DQ(10)    I22 @T6G_MB_LIB.T6G(SCH_1):PAGE103
   165 M_G_CPU1_SA_DQ<11> @T6G_MB_LIB.T6G(SCH_1):M_G_CPU1_SA_DQ(11)    I22 @T6G_MB_LIB.T6G(SCH_1):PAGE103
    25 M_G_CPU1_SA_DQ<12> @T6G_MB_LIB.T6G(SCH_1):M_G_CPU1_SA_DQ(12)    I22 @T6G_MB_LIB.T6G(SCH_1):PAGE103
    27 M_G_CPU1_SA_DQ<13> @T6G_MB_LIB.T6G(SCH_1):M_G_CPU1_SA_DQ(13)    I22 @T6G_MB_LIB.T6G(SCH_1):PAGE103
   170 M_G_CPU1_SA_DQ<14> @T6G_MB_LIB.T6G(SCH_1):M_G_CPU1_SA_DQ(14)    I22 @T6G_MB_LIB.T6G(SCH_1):PAGE103
   172 M_G_CPU1_SA_DQ<15> @T6G_MB_LIB.T6G(SCH_1):M_G_CPU1_SA_DQ(15)    I22 @T6G_MB_LIB.T6G(SCH_1):PAGE103
    29 M_G_CPU1_SA_DQ<16> @T6G_MB_LIB.T6G(SCH_1):M_G_CPU1_SA_DQ(16)    I22 @T6G_MB_LIB.T6G(SCH_1):PAGE103
    31 M_G_CPU1_SA_DQ<17> @T6G_MB_LIB.T6G(SCH_1):M_G_CPU1_SA_DQ(17)    I22 @T6G_MB_LIB.T6G(SCH_1):PAGE103
   174 M_G_CPU1_SA_DQ<18> @T6G_MB_LIB.T6G(SCH_1):M_G_CPU1_SA_DQ(18)    I22 @T6G_MB_LIB.T6G(SCH_1):PAGE103
   176 M_G_CPU1_SA_DQ<19> @T6G_MB_LIB.T6G(SCH_1):M_G_CPU1_SA_DQ(19)    I22 @T6G_MB_LIB.T6G(SCH_1):PAGE103
    36 M_G_CPU1_SA_DQ<20> @T6G_MB_LIB.T6G(SCH_1):M_G_CPU1_SA_DQ(20)    I22 @T6G_MB_LIB.T6G(SCH_1):PAGE103
    38 M_G_CPU1_SA_DQ<21> @T6G_MB_LIB.T6G(SCH_1):M_G_CPU1_SA_DQ(21)    I22 @T6G_MB_LIB.T6G(SCH_1):PAGE103
   181 M_G_CPU1_SA_DQ<22> @T6G_MB_LIB.T6G(SCH_1):M_G_CPU1_SA_DQ(22)    I22 @T6G_MB_LIB.T6G(SCH_1):PAGE103
   183 M_G_CPU1_SA_DQ<23> @T6G_MB_LIB.T6G(SCH_1):M_G_CPU1_SA_DQ(23)    I22 @T6G_MB_LIB.T6G(SCH_1):PAGE103
    40 M_G_CPU1_SA_DQ<24> @T6G_MB_LIB.T6G(SCH_1):M_G_CPU1_SA_DQ(24)    I22 @T6G_MB_LIB.T6G(SCH_1):PAGE103
    42 M_G_CPU1_SA_DQ<25> @T6G_MB_LIB.T6G(SCH_1):M_G_CPU1_SA_DQ(25)    I22 @T6G_MB_LIB.T6G(SCH_1):PAGE103
   185 M_G_CPU1_SA_DQ<26> @T6G_MB_LIB.T6G(SCH_1):M_G_CPU1_SA_DQ(26)    I22 @T6G_MB_LIB.T6G(SCH_1):PAGE103
   187 M_G_CPU1_SA_DQ<27> @T6G_MB_LIB.T6G(SCH_1):M_G_CPU1_SA_DQ(27)    I22 @T6G_MB_LIB.T6G(SCH_1):PAGE103
    47 M_G_CPU1_SA_DQ<28> @T6G_MB_LIB.T6G(SCH_1):M_G_CPU1_SA_DQ(28)    I22 @T6G_MB_LIB.T6G(SCH_1):PAGE103
    49 M_G_CPU1_SA_DQ<29> @T6G_MB_LIB.T6G(SCH_1):M_G_CPU1_SA_DQ(29)    I22 @T6G_MB_LIB.T6G(SCH_1):PAGE103
   192 M_G_CPU1_SA_DQ<30> @T6G_MB_LIB.T6G(SCH_1):M_G_CPU1_SA_DQ(30)    I22 @T6G_MB_LIB.T6G(SCH_1):PAGE103
   229 M_G_CPU1_SB_CS_N<1> @T6G_MB_LIB.T6G(SCH_1):M_G_CPU1_SB_CS_N(1)    I22 @T6G_MB_LIB.T6G(SCH_1):PAGE103
   209 M_G_CPU1_SA_CS_N<1> @T6G_MB_LIB.T6G(SCH_1):M_G_CPU1_SA_CS_N(1)    I22 @T6G_MB_LIB.T6G(SCH_1):PAGE103
    84 M_G_CPU1_SB_CS_N<0> @T6G_MB_LIB.T6G(SCH_1):M_G_CPU1_SB_CS_N(0)    I22 @T6G_MB_LIB.T6G(SCH_1):PAGE103
    64 M_G_CPU1_SA_CS_N<0> @T6G_MB_LIB.T6G(SCH_1):M_G_CPU1_SA_CS_N(0)    I22 @T6G_MB_LIB.T6G(SCH_1):PAGE103
   217 M_G_CPU1_CLK_DP<0> @T6G_MB_LIB.T6G(SCH_1):M_G_CPU1_CLK_DP(0)    I22 @T6G_MB_LIB.T6G(SCH_1):PAGE103
   218 M_G_CPU1_CLK_DN<0> @T6G_MB_LIB.T6G(SCH_1):M_G_CPU1_CLK_DN(0)    I22 @T6G_MB_LIB.T6G(SCH_1):PAGE103
    96 M_G_CPU1_SB_CB<0> @T6G_MB_LIB.T6G(SCH_1):M_G_CPU1_SB_CB(0)    I22 @T6G_MB_LIB.T6G(SCH_1):PAGE103
    98 M_G_CPU1_SB_CB<1> @T6G_MB_LIB.T6G(SCH_1):M_G_CPU1_SB_CB(1)    I22 @T6G_MB_LIB.T6G(SCH_1):PAGE103
   241 M_G_CPU1_SB_CB<2> @T6G_MB_LIB.T6G(SCH_1):M_G_CPU1_SB_CB(2)    I22 @T6G_MB_LIB.T6G(SCH_1):PAGE103
   243 M_G_CPU1_SB_CB<3> @T6G_MB_LIB.T6G(SCH_1):M_G_CPU1_SB_CB(3)    I22 @T6G_MB_LIB.T6G(SCH_1):PAGE103
    89 M_G_CPU1_SB_CB<4> @T6G_MB_LIB.T6G(SCH_1):M_G_CPU1_SB_CB(4)    I22 @T6G_MB_LIB.T6G(SCH_1):PAGE103
    91 M_G_CPU1_SB_CB<5> @T6G_MB_LIB.T6G(SCH_1):M_G_CPU1_SB_CB(5)    I22 @T6G_MB_LIB.T6G(SCH_1):PAGE103
   234 M_G_CPU1_SB_CB<6> @T6G_MB_LIB.T6G(SCH_1):M_G_CPU1_SB_CB(6)    I22 @T6G_MB_LIB.T6G(SCH_1):PAGE103
    51 M_G_CPU1_SA_CB<0> @T6G_MB_LIB.T6G(SCH_1):M_G_CPU1_SA_CB(0)    I22 @T6G_MB_LIB.T6G(SCH_1):PAGE103
   196 M_G_CPU1_SA_CB<2> @T6G_MB_LIB.T6G(SCH_1):M_G_CPU1_SA_CB(2)    I22 @T6G_MB_LIB.T6G(SCH_1):PAGE103
   198 M_G_CPU1_SA_CB<3> @T6G_MB_LIB.T6G(SCH_1):M_G_CPU1_SA_CB(3)    I22 @T6G_MB_LIB.T6G(SCH_1):PAGE103
    60 M_G_CPU1_SA_CB<5> @T6G_MB_LIB.T6G(SCH_1):M_G_CPU1_SA_CB(5)    I22 @T6G_MB_LIB.T6G(SCH_1):PAGE103
   203 M_G_CPU1_SA_CB<6> @T6G_MB_LIB.T6G(SCH_1):M_G_CPU1_SA_CB(6)    I22 @T6G_MB_LIB.T6G(SCH_1):PAGE103
    82 M_G_CPU1_SB_CA<6> @T6G_MB_LIB.T6G(SCH_1):M_G_CPU1_SB_CA(6)    I22 @T6G_MB_LIB.T6G(SCH_1):PAGE103
    72 M_G_CPU1_SA_CA<6> @T6G_MB_LIB.T6G(SCH_1):M_G_CPU1_SA_CA(6)    I22 @T6G_MB_LIB.T6G(SCH_1):PAGE103
   225 M_G_CPU1_SB_CA<5> @T6G_MB_LIB.T6G(SCH_1):M_G_CPU1_SB_CA(5)    I22 @T6G_MB_LIB.T6G(SCH_1):PAGE103
   215 M_G_CPU1_SA_CA<5> @T6G_MB_LIB.T6G(SCH_1):M_G_CPU1_SA_CA(5)    I22 @T6G_MB_LIB.T6G(SCH_1):PAGE103
    80 M_G_CPU1_SB_CA<4> @T6G_MB_LIB.T6G(SCH_1):M_G_CPU1_SB_CA(4)    I22 @T6G_MB_LIB.T6G(SCH_1):PAGE103
    70 M_G_CPU1_SA_CA<4> @T6G_MB_LIB.T6G(SCH_1):M_G_CPU1_SA_CA(4)    I22 @T6G_MB_LIB.T6G(SCH_1):PAGE103
   223 M_G_CPU1_SB_CA<3> @T6G_MB_LIB.T6G(SCH_1):M_G_CPU1_SB_CA(3)    I22 @T6G_MB_LIB.T6G(SCH_1):PAGE103
   213 M_G_CPU1_SA_CA<3> @T6G_MB_LIB.T6G(SCH_1):M_G_CPU1_SA_CA(3)    I22 @T6G_MB_LIB.T6G(SCH_1):PAGE103
    78 M_G_CPU1_SB_CA<2> @T6G_MB_LIB.T6G(SCH_1):M_G_CPU1_SB_CA(2)    I22 @T6G_MB_LIB.T6G(SCH_1):PAGE103
    68 M_G_CPU1_SA_CA<2> @T6G_MB_LIB.T6G(SCH_1):M_G_CPU1_SA_CA(2)    I22 @T6G_MB_LIB.T6G(SCH_1):PAGE103
   221 M_G_CPU1_SB_CA<1> @T6G_MB_LIB.T6G(SCH_1):M_G_CPU1_SB_CA(1)    I22 @T6G_MB_LIB.T6G(SCH_1):PAGE103
   211 M_G_CPU1_SA_CA<1> @T6G_MB_LIB.T6G(SCH_1):M_G_CPU1_SA_CA(1)    I22 @T6G_MB_LIB.T6G(SCH_1):PAGE103
    76 M_G_CPU1_SB_CA<0> @T6G_MB_LIB.T6G(SCH_1):M_G_CPU1_SB_CA(0)    I22 @T6G_MB_LIB.T6G(SCH_1):PAGE103
    66 M_G_CPU1_SA_CA<0> @T6G_MB_LIB.T6G(SCH_1):M_G_CPU1_SA_CA(0)    I22 @T6G_MB_LIB.T6G(SCH_1):PAGE103
    62 M_G_CPU1_ALERT_N @T6G_MB_LIB.T6G(SCH_1):M_G_CPU1_ALERT_N    I22 @T6G_MB_LIB.T6G(SCH_1):PAGE103
   236 M_G_CPU1_SB_CB<7> @T6G_MB_LIB.T6G(SCH_1):M_G_CPU1_SB_CB(7)    I22 @T6G_MB_LIB.T6G(SCH_1):PAGE103
    53 M_G_CPU1_SA_CB<1> @T6G_MB_LIB.T6G(SCH_1):M_G_CPU1_SA_CB(1)    I22 @T6G_MB_LIB.T6G(SCH_1):PAGE103
    58 M_G_CPU1_SA_CB<4> @T6G_MB_LIB.T6G(SCH_1):M_G_CPU1_SA_CB(4)    I22 @T6G_MB_LIB.T6G(SCH_1):PAGE103
   205 M_G_CPU1_SA_CB<7> @T6G_MB_LIB.T6G(SCH_1):M_G_CPU1_SA_CB(7)    I22 @T6G_MB_LIB.T6G(SCH_1):PAGE103
   194 M_G_CPU1_SA_DQ<31> @T6G_MB_LIB.T6G(SCH_1):M_G_CPU1_SA_DQ(31)    I22 @T6G_MB_LIB.T6G(SCH_1):PAGE103
    93 M_G_CPU1_SB_DQS_DP<9> @T6G_MB_LIB.T6G(SCH_1):M_G_CPU1_SB_DQS_DP(9)   I238 @T6G_MB_LIB.T6G(SCH_1):PAGE103
    94 M_G_CPU1_SB_DQS_DN<9> @T6G_MB_LIB.T6G(SCH_1):M_G_CPU1_SB_DQS_DN(9)   I238 @T6G_MB_LIB.T6G(SCH_1):PAGE103
   201 M_G_CPU1_SA_DQS_DP<9> @T6G_MB_LIB.T6G(SCH_1):M_G_CPU1_SA_DQS_DP(9)   I238 @T6G_MB_LIB.T6G(SCH_1):PAGE103
   200 M_G_CPU1_SA_DQS_DN<9> @T6G_MB_LIB.T6G(SCH_1):M_G_CPU1_SA_DQS_DN(9)   I238 @T6G_MB_LIB.T6G(SCH_1):PAGE103
   190 M_G_CPU1_SA_DQS_DP<8> @T6G_MB_LIB.T6G(SCH_1):M_G_CPU1_SA_DQS_DP(8)   I238 @T6G_MB_LIB.T6G(SCH_1):PAGE103
   189 M_G_CPU1_SA_DQS_DN<8> @T6G_MB_LIB.T6G(SCH_1):M_G_CPU1_SA_DQS_DN(8)   I238 @T6G_MB_LIB.T6G(SCH_1):PAGE103
   271 M_G_CPU1_SB_DQS_DN<7> @T6G_MB_LIB.T6G(SCH_1):M_G_CPU1_SB_DQS_DN(7)   I238 @T6G_MB_LIB.T6G(SCH_1):PAGE103
   179 M_G_CPU1_SA_DQS_DP<7> @T6G_MB_LIB.T6G(SCH_1):M_G_CPU1_SA_DQS_DP(7)   I238 @T6G_MB_LIB.T6G(SCH_1):PAGE103
   261 M_G_CPU1_SB_DQS_DP<6> @T6G_MB_LIB.T6G(SCH_1):M_G_CPU1_SB_DQS_DP(6)   I238 @T6G_MB_LIB.T6G(SCH_1):PAGE103
   260 M_G_CPU1_SB_DQS_DN<6> @T6G_MB_LIB.T6G(SCH_1):M_G_CPU1_SB_DQS_DN(6)   I238 @T6G_MB_LIB.T6G(SCH_1):PAGE103
   167 M_G_CPU1_SA_DQS_DN<6> @T6G_MB_LIB.T6G(SCH_1):M_G_CPU1_SA_DQS_DN(6)   I238 @T6G_MB_LIB.T6G(SCH_1):PAGE103
   250 M_G_CPU1_SB_DQS_DP<5> @T6G_MB_LIB.T6G(SCH_1):M_G_CPU1_SB_DQS_DP(5)   I238 @T6G_MB_LIB.T6G(SCH_1):PAGE103
   249 M_G_CPU1_SB_DQS_DN<5> @T6G_MB_LIB.T6G(SCH_1):M_G_CPU1_SB_DQS_DN(5)   I238 @T6G_MB_LIB.T6G(SCH_1):PAGE103
   157 M_G_CPU1_SA_DQS_DP<5> @T6G_MB_LIB.T6G(SCH_1):M_G_CPU1_SA_DQS_DP(5)   I238 @T6G_MB_LIB.T6G(SCH_1):PAGE103
   156 M_G_CPU1_SA_DQS_DN<5> @T6G_MB_LIB.T6G(SCH_1):M_G_CPU1_SA_DQS_DN(5)   I238 @T6G_MB_LIB.T6G(SCH_1):PAGE103
   239 M_G_CPU1_SB_DQS_DP<4> @T6G_MB_LIB.T6G(SCH_1):M_G_CPU1_SB_DQS_DP(4)   I238 @T6G_MB_LIB.T6G(SCH_1):PAGE103
   238 M_G_CPU1_SB_DQS_DN<4> @T6G_MB_LIB.T6G(SCH_1):M_G_CPU1_SB_DQS_DN(4)   I238 @T6G_MB_LIB.T6G(SCH_1):PAGE103
    55 M_G_CPU1_SA_DQS_DP<4> @T6G_MB_LIB.T6G(SCH_1):M_G_CPU1_SA_DQS_DP(4)   I238 @T6G_MB_LIB.T6G(SCH_1):PAGE103
    56 M_G_CPU1_SA_DQS_DN<4> @T6G_MB_LIB.T6G(SCH_1):M_G_CPU1_SA_DQS_DN(4)   I238 @T6G_MB_LIB.T6G(SCH_1):PAGE103
   137 M_G_CPU1_SB_DQS_DP<3> @T6G_MB_LIB.T6G(SCH_1):M_G_CPU1_SB_DQS_DP(3)   I238 @T6G_MB_LIB.T6G(SCH_1):PAGE103
   138 M_G_CPU1_SB_DQS_DN<3> @T6G_MB_LIB.T6G(SCH_1):M_G_CPU1_SB_DQS_DN(3)   I238 @T6G_MB_LIB.T6G(SCH_1):PAGE103
    44 M_G_CPU1_SA_DQS_DP<3> @T6G_MB_LIB.T6G(SCH_1):M_G_CPU1_SA_DQS_DP(3)   I238 @T6G_MB_LIB.T6G(SCH_1):PAGE103
    45 M_G_CPU1_SA_DQS_DN<3> @T6G_MB_LIB.T6G(SCH_1):M_G_CPU1_SA_DQS_DN(3)   I238 @T6G_MB_LIB.T6G(SCH_1):PAGE103
   126 M_G_CPU1_SB_DQS_DP<2> @T6G_MB_LIB.T6G(SCH_1):M_G_CPU1_SB_DQS_DP(2)   I238 @T6G_MB_LIB.T6G(SCH_1):PAGE103
   127 M_G_CPU1_SB_DQS_DN<2> @T6G_MB_LIB.T6G(SCH_1):M_G_CPU1_SB_DQS_DN(2)   I238 @T6G_MB_LIB.T6G(SCH_1):PAGE103
    33 M_G_CPU1_SA_DQS_DP<2> @T6G_MB_LIB.T6G(SCH_1):M_G_CPU1_SA_DQS_DP(2)   I238 @T6G_MB_LIB.T6G(SCH_1):PAGE103
    34 M_G_CPU1_SA_DQS_DN<2> @T6G_MB_LIB.T6G(SCH_1):M_G_CPU1_SA_DQS_DN(2)   I238 @T6G_MB_LIB.T6G(SCH_1):PAGE103
   115 M_G_CPU1_SB_DQS_DP<1> @T6G_MB_LIB.T6G(SCH_1):M_G_CPU1_SB_DQS_DP(1)   I238 @T6G_MB_LIB.T6G(SCH_1):PAGE103
   116 M_G_CPU1_SB_DQS_DN<1> @T6G_MB_LIB.T6G(SCH_1):M_G_CPU1_SB_DQS_DN(1)   I238 @T6G_MB_LIB.T6G(SCH_1):PAGE103
    22 M_G_CPU1_SA_DQS_DP<1> @T6G_MB_LIB.T6G(SCH_1):M_G_CPU1_SA_DQS_DP(1)   I238 @T6G_MB_LIB.T6G(SCH_1):PAGE103
    23 M_G_CPU1_SA_DQS_DN<1> @T6G_MB_LIB.T6G(SCH_1):M_G_CPU1_SA_DQS_DN(1)   I238 @T6G_MB_LIB.T6G(SCH_1):PAGE103
   104 M_G_CPU1_SB_DQS_DP<0> @T6G_MB_LIB.T6G(SCH_1):M_G_CPU1_SB_DQS_DP(0)   I238 @T6G_MB_LIB.T6G(SCH_1):PAGE103
   105 M_G_CPU1_SB_DQS_DN<0> @T6G_MB_LIB.T6G(SCH_1):M_G_CPU1_SB_DQS_DN(0)   I238 @T6G_MB_LIB.T6G(SCH_1):PAGE103
    11 M_G_CPU1_SA_DQS_DP<0> @T6G_MB_LIB.T6G(SCH_1):M_G_CPU1_SA_DQS_DP(0)   I238 @T6G_MB_LIB.T6G(SCH_1):PAGE103
    12 M_G_CPU1_SA_DQS_DN<0> @T6G_MB_LIB.T6G(SCH_1):M_G_CPU1_SA_DQS_DN(0)   I238 @T6G_MB_LIB.T6G(SCH_1):PAGE103
   272 M_G_CPU1_SB_DQS_DP<7> @T6G_MB_LIB.T6G(SCH_1):M_G_CPU1_SB_DQS_DP(7)   I238 @T6G_MB_LIB.T6G(SCH_1):PAGE103
   282 M_G_CPU1_SB_DQS_DN<8> @T6G_MB_LIB.T6G(SCH_1):M_G_CPU1_SB_DQS_DN(8)   I238 @T6G_MB_LIB.T6G(SCH_1):PAGE103
   283 M_G_CPU1_SB_DQS_DP<8> @T6G_MB_LIB.T6G(SCH_1):M_G_CPU1_SB_DQS_DP(8)   I238 @T6G_MB_LIB.T6G(SCH_1):PAGE103
   168 M_G_CPU1_SA_DQS_DP<6> @T6G_MB_LIB.T6G(SCH_1):M_G_CPU1_SA_DQS_DP(6)   I238 @T6G_MB_LIB.T6G(SCH_1):PAGE103
   178 M_G_CPU1_SA_DQS_DN<7> @T6G_MB_LIB.T6G(SCH_1):M_G_CPU1_SA_DQS_DN(7)   I238 @T6G_MB_LIB.T6G(SCH_1):PAGE103
     6    GND @T6G_MB_LIB.T6G(SCH_1):GND   I142 @T6G_MB_LIB.T6G(SCH_1):PAGE103
     8    GND @T6G_MB_LIB.T6G(SCH_1):GND   I142 @T6G_MB_LIB.T6G(SCH_1):PAGE103
    10    GND @T6G_MB_LIB.T6G(SCH_1):GND   I142 @T6G_MB_LIB.T6G(SCH_1):PAGE103
    13    GND @T6G_MB_LIB.T6G(SCH_1):GND   I142 @T6G_MB_LIB.T6G(SCH_1):PAGE103
    15    GND @T6G_MB_LIB.T6G(SCH_1):GND   I142 @T6G_MB_LIB.T6G(SCH_1):PAGE103
    17    GND @T6G_MB_LIB.T6G(SCH_1):GND   I142 @T6G_MB_LIB.T6G(SCH_1):PAGE103
    19    GND @T6G_MB_LIB.T6G(SCH_1):GND   I142 @T6G_MB_LIB.T6G(SCH_1):PAGE103
    21    GND @T6G_MB_LIB.T6G(SCH_1):GND   I142 @T6G_MB_LIB.T6G(SCH_1):PAGE103
    24    GND @T6G_MB_LIB.T6G(SCH_1):GND   I142 @T6G_MB_LIB.T6G(SCH_1):PAGE103
    26    GND @T6G_MB_LIB.T6G(SCH_1):GND   I142 @T6G_MB_LIB.T6G(SCH_1):PAGE103
    28    GND @T6G_MB_LIB.T6G(SCH_1):GND   I142 @T6G_MB_LIB.T6G(SCH_1):PAGE103
    30    GND @T6G_MB_LIB.T6G(SCH_1):GND   I142 @T6G_MB_LIB.T6G(SCH_1):PAGE103
    32    GND @T6G_MB_LIB.T6G(SCH_1):GND   I142 @T6G_MB_LIB.T6G(SCH_1):PAGE103
    35    GND @T6G_MB_LIB.T6G(SCH_1):GND   I142 @T6G_MB_LIB.T6G(SCH_1):PAGE103
    37    GND @T6G_MB_LIB.T6G(SCH_1):GND   I142 @T6G_MB_LIB.T6G(SCH_1):PAGE103
    39    GND @T6G_MB_LIB.T6G(SCH_1):GND   I142 @T6G_MB_LIB.T6G(SCH_1):PAGE103
    41    GND @T6G_MB_LIB.T6G(SCH_1):GND   I142 @T6G_MB_LIB.T6G(SCH_1):PAGE103
    43    GND @T6G_MB_LIB.T6G(SCH_1):GND   I142 @T6G_MB_LIB.T6G(SCH_1):PAGE103
    46    GND @T6G_MB_LIB.T6G(SCH_1):GND   I142 @T6G_MB_LIB.T6G(SCH_1):PAGE103
    48    GND @T6G_MB_LIB.T6G(SCH_1):GND   I142 @T6G_MB_LIB.T6G(SCH_1):PAGE103
    50    GND @T6G_MB_LIB.T6G(SCH_1):GND   I142 @T6G_MB_LIB.T6G(SCH_1):PAGE103
    52    GND @T6G_MB_LIB.T6G(SCH_1):GND   I142 @T6G_MB_LIB.T6G(SCH_1):PAGE103
    54    GND @T6G_MB_LIB.T6G(SCH_1):GND   I142 @T6G_MB_LIB.T6G(SCH_1):PAGE103
    57    GND @T6G_MB_LIB.T6G(SCH_1):GND   I142 @T6G_MB_LIB.T6G(SCH_1):PAGE103
    59    GND @T6G_MB_LIB.T6G(SCH_1):GND   I142 @T6G_MB_LIB.T6G(SCH_1):PAGE103
    61    GND @T6G_MB_LIB.T6G(SCH_1):GND   I142 @T6G_MB_LIB.T6G(SCH_1):PAGE103
    63    GND @T6G_MB_LIB.T6G(SCH_1):GND   I142 @T6G_MB_LIB.T6G(SCH_1):PAGE103
    65    GND @T6G_MB_LIB.T6G(SCH_1):GND   I142 @T6G_MB_LIB.T6G(SCH_1):PAGE103
    67    GND @T6G_MB_LIB.T6G(SCH_1):GND   I142 @T6G_MB_LIB.T6G(SCH_1):PAGE103
    69    GND @T6G_MB_LIB.T6G(SCH_1):GND   I142 @T6G_MB_LIB.T6G(SCH_1):PAGE103
    71    GND @T6G_MB_LIB.T6G(SCH_1):GND   I142 @T6G_MB_LIB.T6G(SCH_1):PAGE103
    73    GND @T6G_MB_LIB.T6G(SCH_1):GND   I142 @T6G_MB_LIB.T6G(SCH_1):PAGE103
    75    GND @T6G_MB_LIB.T6G(SCH_1):GND   I142 @T6G_MB_LIB.T6G(SCH_1):PAGE103
    77    GND @T6G_MB_LIB.T6G(SCH_1):GND   I142 @T6G_MB_LIB.T6G(SCH_1):PAGE103
    79    GND @T6G_MB_LIB.T6G(SCH_1):GND   I142 @T6G_MB_LIB.T6G(SCH_1):PAGE103
    81    GND @T6G_MB_LIB.T6G(SCH_1):GND   I142 @T6G_MB_LIB.T6G(SCH_1):PAGE103
    83    GND @T6G_MB_LIB.T6G(SCH_1):GND   I142 @T6G_MB_LIB.T6G(SCH_1):PAGE103
    85    GND @T6G_MB_LIB.T6G(SCH_1):GND   I142 @T6G_MB_LIB.T6G(SCH_1):PAGE103
    88    GND @T6G_MB_LIB.T6G(SCH_1):GND   I142 @T6G_MB_LIB.T6G(SCH_1):PAGE103
    90    GND @T6G_MB_LIB.T6G(SCH_1):GND   I142 @T6G_MB_LIB.T6G(SCH_1):PAGE103
    92    GND @T6G_MB_LIB.T6G(SCH_1):GND   I142 @T6G_MB_LIB.T6G(SCH_1):PAGE103
    95    GND @T6G_MB_LIB.T6G(SCH_1):GND   I142 @T6G_MB_LIB.T6G(SCH_1):PAGE103
    97    GND @T6G_MB_LIB.T6G(SCH_1):GND   I142 @T6G_MB_LIB.T6G(SCH_1):PAGE103
    99    GND @T6G_MB_LIB.T6G(SCH_1):GND   I142 @T6G_MB_LIB.T6G(SCH_1):PAGE103
   101    GND @T6G_MB_LIB.T6G(SCH_1):GND   I142 @T6G_MB_LIB.T6G(SCH_1):PAGE103
   103    GND @T6G_MB_LIB.T6G(SCH_1):GND   I142 @T6G_MB_LIB.T6G(SCH_1):PAGE103
   106    GND @T6G_MB_LIB.T6G(SCH_1):GND   I142 @T6G_MB_LIB.T6G(SCH_1):PAGE103
   108    GND @T6G_MB_LIB.T6G(SCH_1):GND   I142 @T6G_MB_LIB.T6G(SCH_1):PAGE103
   110    GND @T6G_MB_LIB.T6G(SCH_1):GND   I142 @T6G_MB_LIB.T6G(SCH_1):PAGE103
   112    GND @T6G_MB_LIB.T6G(SCH_1):GND   I142 @T6G_MB_LIB.T6G(SCH_1):PAGE103
   114    GND @T6G_MB_LIB.T6G(SCH_1):GND   I142 @T6G_MB_LIB.T6G(SCH_1):PAGE103
   117    GND @T6G_MB_LIB.T6G(SCH_1):GND   I142 @T6G_MB_LIB.T6G(SCH_1):PAGE103
   119    GND @T6G_MB_LIB.T6G(SCH_1):GND   I142 @T6G_MB_LIB.T6G(SCH_1):PAGE103
   121    GND @T6G_MB_LIB.T6G(SCH_1):GND   I142 @T6G_MB_LIB.T6G(SCH_1):PAGE103
   123    GND @T6G_MB_LIB.T6G(SCH_1):GND   I142 @T6G_MB_LIB.T6G(SCH_1):PAGE103
   125    GND @T6G_MB_LIB.T6G(SCH_1):GND   I142 @T6G_MB_LIB.T6G(SCH_1):PAGE103
   128    GND @T6G_MB_LIB.T6G(SCH_1):GND   I142 @T6G_MB_LIB.T6G(SCH_1):PAGE103
   130    GND @T6G_MB_LIB.T6G(SCH_1):GND   I142 @T6G_MB_LIB.T6G(SCH_1):PAGE103
   134    GND @T6G_MB_LIB.T6G(SCH_1):GND   I142 @T6G_MB_LIB.T6G(SCH_1):PAGE103
   143    GND @T6G_MB_LIB.T6G(SCH_1):GND   I142 @T6G_MB_LIB.T6G(SCH_1):PAGE103
   151    GND @T6G_MB_LIB.T6G(SCH_1):GND   I142 @T6G_MB_LIB.T6G(SCH_1):PAGE103
   153    GND @T6G_MB_LIB.T6G(SCH_1):GND   I142 @T6G_MB_LIB.T6G(SCH_1):PAGE103
   155    GND @T6G_MB_LIB.T6G(SCH_1):GND   I142 @T6G_MB_LIB.T6G(SCH_1):PAGE103
   158    GND @T6G_MB_LIB.T6G(SCH_1):GND   I142 @T6G_MB_LIB.T6G(SCH_1):PAGE103
   160    GND @T6G_MB_LIB.T6G(SCH_1):GND   I142 @T6G_MB_LIB.T6G(SCH_1):PAGE103
   162    GND @T6G_MB_LIB.T6G(SCH_1):GND   I142 @T6G_MB_LIB.T6G(SCH_1):PAGE103
   164    GND @T6G_MB_LIB.T6G(SCH_1):GND   I142 @T6G_MB_LIB.T6G(SCH_1):PAGE103
   166    GND @T6G_MB_LIB.T6G(SCH_1):GND   I142 @T6G_MB_LIB.T6G(SCH_1):PAGE103
   169    GND @T6G_MB_LIB.T6G(SCH_1):GND   I142 @T6G_MB_LIB.T6G(SCH_1):PAGE103
   171    GND @T6G_MB_LIB.T6G(SCH_1):GND   I142 @T6G_MB_LIB.T6G(SCH_1):PAGE103
   173    GND @T6G_MB_LIB.T6G(SCH_1):GND   I142 @T6G_MB_LIB.T6G(SCH_1):PAGE103
   175    GND @T6G_MB_LIB.T6G(SCH_1):GND   I142 @T6G_MB_LIB.T6G(SCH_1):PAGE103
   177    GND @T6G_MB_LIB.T6G(SCH_1):GND   I142 @T6G_MB_LIB.T6G(SCH_1):PAGE103
   180    GND @T6G_MB_LIB.T6G(SCH_1):GND   I142 @T6G_MB_LIB.T6G(SCH_1):PAGE103
   182    GND @T6G_MB_LIB.T6G(SCH_1):GND   I142 @T6G_MB_LIB.T6G(SCH_1):PAGE103
   184    GND @T6G_MB_LIB.T6G(SCH_1):GND   I142 @T6G_MB_LIB.T6G(SCH_1):PAGE103
   186    GND @T6G_MB_LIB.T6G(SCH_1):GND   I142 @T6G_MB_LIB.T6G(SCH_1):PAGE103
   188    GND @T6G_MB_LIB.T6G(SCH_1):GND   I142 @T6G_MB_LIB.T6G(SCH_1):PAGE103
   191    GND @T6G_MB_LIB.T6G(SCH_1):GND   I142 @T6G_MB_LIB.T6G(SCH_1):PAGE103
   193    GND @T6G_MB_LIB.T6G(SCH_1):GND   I142 @T6G_MB_LIB.T6G(SCH_1):PAGE103
   195    GND @T6G_MB_LIB.T6G(SCH_1):GND   I142 @T6G_MB_LIB.T6G(SCH_1):PAGE103
   197    GND @T6G_MB_LIB.T6G(SCH_1):GND   I142 @T6G_MB_LIB.T6G(SCH_1):PAGE103
   199    GND @T6G_MB_LIB.T6G(SCH_1):GND   I142 @T6G_MB_LIB.T6G(SCH_1):PAGE103
   202    GND @T6G_MB_LIB.T6G(SCH_1):GND   I142 @T6G_MB_LIB.T6G(SCH_1):PAGE103
   204    GND @T6G_MB_LIB.T6G(SCH_1):GND   I142 @T6G_MB_LIB.T6G(SCH_1):PAGE103
   206    GND @T6G_MB_LIB.T6G(SCH_1):GND   I142 @T6G_MB_LIB.T6G(SCH_1):PAGE103
   208    GND @T6G_MB_LIB.T6G(SCH_1):GND   I142 @T6G_MB_LIB.T6G(SCH_1):PAGE103
   210    GND @T6G_MB_LIB.T6G(SCH_1):GND   I142 @T6G_MB_LIB.T6G(SCH_1):PAGE103
   212    GND @T6G_MB_LIB.T6G(SCH_1):GND   I142 @T6G_MB_LIB.T6G(SCH_1):PAGE103
   214    GND @T6G_MB_LIB.T6G(SCH_1):GND   I142 @T6G_MB_LIB.T6G(SCH_1):PAGE103
   216    GND @T6G_MB_LIB.T6G(SCH_1):GND   I142 @T6G_MB_LIB.T6G(SCH_1):PAGE103
   219    GND @T6G_MB_LIB.T6G(SCH_1):GND   I142 @T6G_MB_LIB.T6G(SCH_1):PAGE103
   222    GND @T6G_MB_LIB.T6G(SCH_1):GND   I142 @T6G_MB_LIB.T6G(SCH_1):PAGE103
   224    GND @T6G_MB_LIB.T6G(SCH_1):GND   I142 @T6G_MB_LIB.T6G(SCH_1):PAGE103
   226    GND @T6G_MB_LIB.T6G(SCH_1):GND   I142 @T6G_MB_LIB.T6G(SCH_1):PAGE103
   228    GND @T6G_MB_LIB.T6G(SCH_1):GND   I142 @T6G_MB_LIB.T6G(SCH_1):PAGE103
   233    GND @T6G_MB_LIB.T6G(SCH_1):GND   I142 @T6G_MB_LIB.T6G(SCH_1):PAGE103
   237    GND @T6G_MB_LIB.T6G(SCH_1):GND   I142 @T6G_MB_LIB.T6G(SCH_1):PAGE103
   242    GND @T6G_MB_LIB.T6G(SCH_1):GND   I142 @T6G_MB_LIB.T6G(SCH_1):PAGE103
   244    GND @T6G_MB_LIB.T6G(SCH_1):GND   I142 @T6G_MB_LIB.T6G(SCH_1):PAGE103
   246    GND @T6G_MB_LIB.T6G(SCH_1):GND   I142 @T6G_MB_LIB.T6G(SCH_1):PAGE103
   248    GND @T6G_MB_LIB.T6G(SCH_1):GND   I142 @T6G_MB_LIB.T6G(SCH_1):PAGE103
   251    GND @T6G_MB_LIB.T6G(SCH_1):GND   I142 @T6G_MB_LIB.T6G(SCH_1):PAGE103
   253    GND @T6G_MB_LIB.T6G(SCH_1):GND   I142 @T6G_MB_LIB.T6G(SCH_1):PAGE103
   255    GND @T6G_MB_LIB.T6G(SCH_1):GND   I142 @T6G_MB_LIB.T6G(SCH_1):PAGE103
   257    GND @T6G_MB_LIB.T6G(SCH_1):GND   I142 @T6G_MB_LIB.T6G(SCH_1):PAGE103
   259    GND @T6G_MB_LIB.T6G(SCH_1):GND   I142 @T6G_MB_LIB.T6G(SCH_1):PAGE103
   262    GND @T6G_MB_LIB.T6G(SCH_1):GND   I142 @T6G_MB_LIB.T6G(SCH_1):PAGE103
   264    GND @T6G_MB_LIB.T6G(SCH_1):GND   I142 @T6G_MB_LIB.T6G(SCH_1):PAGE103
   266    GND @T6G_MB_LIB.T6G(SCH_1):GND   I142 @T6G_MB_LIB.T6G(SCH_1):PAGE103
   268    GND @T6G_MB_LIB.T6G(SCH_1):GND   I142 @T6G_MB_LIB.T6G(SCH_1):PAGE103
   270    GND @T6G_MB_LIB.T6G(SCH_1):GND   I142 @T6G_MB_LIB.T6G(SCH_1):PAGE103
   273    GND @T6G_MB_LIB.T6G(SCH_1):GND   I142 @T6G_MB_LIB.T6G(SCH_1):PAGE103
   275    GND @T6G_MB_LIB.T6G(SCH_1):GND   I142 @T6G_MB_LIB.T6G(SCH_1):PAGE103
   277    GND @T6G_MB_LIB.T6G(SCH_1):GND   I142 @T6G_MB_LIB.T6G(SCH_1):PAGE103
   279    GND @T6G_MB_LIB.T6G(SCH_1):GND   I142 @T6G_MB_LIB.T6G(SCH_1):PAGE103
   281    GND @T6G_MB_LIB.T6G(SCH_1):GND   I142 @T6G_MB_LIB.T6G(SCH_1):PAGE103
   284    GND @T6G_MB_LIB.T6G(SCH_1):GND   I142 @T6G_MB_LIB.T6G(SCH_1):PAGE103
   286    GND @T6G_MB_LIB.T6G(SCH_1):GND   I142 @T6G_MB_LIB.T6G(SCH_1):PAGE103
   288    GND @T6G_MB_LIB.T6G(SCH_1):GND   I142 @T6G_MB_LIB.T6G(SCH_1):PAGE103
     1 P12V_MEM_CPU1 @T6G_MB_LIB.T6G(SCH_1):P12V_MEM_CPU1   I142 @T6G_MB_LIB.T6G(SCH_1):PAGE103
   145 P12V_MEM_CPU1 @T6G_MB_LIB.T6G(SCH_1):P12V_MEM_CPU1   I142 @T6G_MB_LIB.T6G(SCH_1):PAGE103
   146 P12V_MEM_CPU1 @T6G_MB_LIB.T6G(SCH_1):P12V_MEM_CPU1   I142 @T6G_MB_LIB.T6G(SCH_1):PAGE103
   230    GND @T6G_MB_LIB.T6G(SCH_1):GND   I142 @T6G_MB_LIB.T6G(SCH_1):PAGE103
   235    GND @T6G_MB_LIB.T6G(SCH_1):GND   I142 @T6G_MB_LIB.T6G(SCH_1):PAGE103
   240    GND @T6G_MB_LIB.T6G(SCH_1):GND   I142 @T6G_MB_LIB.T6G(SCH_1):PAGE103
   132    GND @T6G_MB_LIB.T6G(SCH_1):GND   I142 @T6G_MB_LIB.T6G(SCH_1):PAGE103
   136    GND @T6G_MB_LIB.T6G(SCH_1):GND   I142 @T6G_MB_LIB.T6G(SCH_1):PAGE103
   139    GND @T6G_MB_LIB.T6G(SCH_1):GND   I142 @T6G_MB_LIB.T6G(SCH_1):PAGE103
   141    GND @T6G_MB_LIB.T6G(SCH_1):GND   I142 @T6G_MB_LIB.T6G(SCH_1):PAGE103
    G1    GND @T6G_MB_LIB.T6G(SCH_1):GND   I142 @T6G_MB_LIB.T6G(SCH_1):PAGE103
    G2    GND @T6G_MB_LIB.T6G(SCH_1):GND   I142 @T6G_MB_LIB.T6G(SCH_1):PAGE103
    G3    GND @T6G_MB_LIB.T6G(SCH_1):GND   I142 @T6G_MB_LIB.T6G(SCH_1):PAGE103

J105 CONN112_10137002101LF-CONN112_10137002-101LF,THLF,A
    A8    GND @T6G_MB_LIB.T6G(SCH_1):GND    I76 @T6G_MB_LIB.T6G(SCH_1):PAGE326
    A7 GPU_3V3IO_RSVD1 @T6G_MB_LIB.T6G(SCH_1):GPU_3V3IO_RSVD1    I76 @T6G_MB_LIB.T6G(SCH_1):PAGE326
    A6    GND @T6G_MB_LIB.T6G(SCH_1):GND    I76 @T6G_MB_LIB.T6G(SCH_1):PAGE326
    A5 GPU_3V3IO_RSVD3 @T6G_MB_LIB.T6G(SCH_1):GPU_3V3IO_RSVD3    I76 @T6G_MB_LIB.T6G(SCH_1):PAGE326
    B8 P5E_CPU0_P2_RX_BUF_DN<15> @T6G_MB_LIB.T6G(SCH_1):P5E_CPU0_P2_RX_BUF_DN(15)    I76 @T6G_MB_LIB.T6G(SCH_1):PAGE326
    B7    GND @T6G_MB_LIB.T6G(SCH_1):GND    I76 @T6G_MB_LIB.T6G(SCH_1):PAGE326
    B6 P5E_CPU0_P2_RX_BUF_DN<13> @T6G_MB_LIB.T6G(SCH_1):P5E_CPU0_P2_RX_BUF_DN(13)    I76 @T6G_MB_LIB.T6G(SCH_1):PAGE326
    B5    GND @T6G_MB_LIB.T6G(SCH_1):GND    I76 @T6G_MB_LIB.T6G(SCH_1):PAGE326
    C8 P5E_CPU0_P2_RX_BUF_DP<15> @T6G_MB_LIB.T6G(SCH_1):P5E_CPU0_P2_RX_BUF_DP(15)    I76 @T6G_MB_LIB.T6G(SCH_1):PAGE326
    C7 P5E_CPU0_P2_RX_BUF_DN<14> @T6G_MB_LIB.T6G(SCH_1):P5E_CPU0_P2_RX_BUF_DN(14)    I76 @T6G_MB_LIB.T6G(SCH_1):PAGE326
    C6 P5E_CPU0_P2_RX_BUF_DP<13> @T6G_MB_LIB.T6G(SCH_1):P5E_CPU0_P2_RX_BUF_DP(13)    I76 @T6G_MB_LIB.T6G(SCH_1):PAGE326
    C5 P5E_CPU0_P2_RX_BUF_DN<12> @T6G_MB_LIB.T6G(SCH_1):P5E_CPU0_P2_RX_BUF_DN(12)    I76 @T6G_MB_LIB.T6G(SCH_1):PAGE326
    D8    GND @T6G_MB_LIB.T6G(SCH_1):GND    I76 @T6G_MB_LIB.T6G(SCH_1):PAGE326
    D7 P5E_CPU0_P2_RX_BUF_DP<14> @T6G_MB_LIB.T6G(SCH_1):P5E_CPU0_P2_RX_BUF_DP(14)    I76 @T6G_MB_LIB.T6G(SCH_1):PAGE326
    D6    GND @T6G_MB_LIB.T6G(SCH_1):GND    I76 @T6G_MB_LIB.T6G(SCH_1):PAGE326
    D5 P5E_CPU0_P2_RX_BUF_DP<12> @T6G_MB_LIB.T6G(SCH_1):P5E_CPU0_P2_RX_BUF_DP(12)    I76 @T6G_MB_LIB.T6G(SCH_1):PAGE326
    E8 P5E_CPU0_P3_RX_BUF_DN<15> @T6G_MB_LIB.T6G(SCH_1):P5E_CPU0_P3_RX_BUF_DN(15)    I76 @T6G_MB_LIB.T6G(SCH_1):PAGE326
    E7    GND @T6G_MB_LIB.T6G(SCH_1):GND    I76 @T6G_MB_LIB.T6G(SCH_1):PAGE326
    E6 P5E_CPU0_P3_RX_BUF_DN<13> @T6G_MB_LIB.T6G(SCH_1):P5E_CPU0_P3_RX_BUF_DN(13)    I76 @T6G_MB_LIB.T6G(SCH_1):PAGE326
    E5    GND @T6G_MB_LIB.T6G(SCH_1):GND    I76 @T6G_MB_LIB.T6G(SCH_1):PAGE326
    F8 P5E_CPU0_P3_RX_BUF_DP<15> @T6G_MB_LIB.T6G(SCH_1):P5E_CPU0_P3_RX_BUF_DP(15)    I76 @T6G_MB_LIB.T6G(SCH_1):PAGE326
    F7 P5E_CPU0_P3_RX_BUF_DN<14> @T6G_MB_LIB.T6G(SCH_1):P5E_CPU0_P3_RX_BUF_DN(14)    I76 @T6G_MB_LIB.T6G(SCH_1):PAGE326
    F6 P5E_CPU0_P3_RX_BUF_DP<13> @T6G_MB_LIB.T6G(SCH_1):P5E_CPU0_P3_RX_BUF_DP(13)    I76 @T6G_MB_LIB.T6G(SCH_1):PAGE326
    F5 P5E_CPU0_P3_RX_BUF_DN<12> @T6G_MB_LIB.T6G(SCH_1):P5E_CPU0_P3_RX_BUF_DN(12)    I76 @T6G_MB_LIB.T6G(SCH_1):PAGE326
    G8    GND @T6G_MB_LIB.T6G(SCH_1):GND    I76 @T6G_MB_LIB.T6G(SCH_1):PAGE326
    G7 P5E_CPU0_P3_RX_BUF_DP<14> @T6G_MB_LIB.T6G(SCH_1):P5E_CPU0_P3_RX_BUF_DP(14)    I76 @T6G_MB_LIB.T6G(SCH_1):PAGE326
    G6    GND @T6G_MB_LIB.T6G(SCH_1):GND    I76 @T6G_MB_LIB.T6G(SCH_1):PAGE326
    G5 P5E_CPU0_P3_RX_BUF_DP<12> @T6G_MB_LIB.T6G(SCH_1):P5E_CPU0_P3_RX_BUF_DP(12)    I76 @T6G_MB_LIB.T6G(SCH_1):PAGE326
    H8 P5E_CPU0_P2_TX_BUF_C_DN<15> @T6G_MB_LIB.T6G(SCH_1):P5E_CPU0_P2_TX_BUF_C_DN(15)    I76 @T6G_MB_LIB.T6G(SCH_1):PAGE326
    H7    GND @T6G_MB_LIB.T6G(SCH_1):GND    I76 @T6G_MB_LIB.T6G(SCH_1):PAGE326
    H6 P5E_CPU0_P2_TX_BUF_C_DN<13> @T6G_MB_LIB.T6G(SCH_1):P5E_CPU0_P2_TX_BUF_C_DN(13)    I76 @T6G_MB_LIB.T6G(SCH_1):PAGE326
    H5    GND @T6G_MB_LIB.T6G(SCH_1):GND    I76 @T6G_MB_LIB.T6G(SCH_1):PAGE326
    I8 P5E_CPU0_P2_TX_BUF_C_DP<15> @T6G_MB_LIB.T6G(SCH_1):P5E_CPU0_P2_TX_BUF_C_DP(15)    I76 @T6G_MB_LIB.T6G(SCH_1):PAGE326
    I7 P5E_CPU0_P2_TX_BUF_C_DN<14> @T6G_MB_LIB.T6G(SCH_1):P5E_CPU0_P2_TX_BUF_C_DN(14)    I76 @T6G_MB_LIB.T6G(SCH_1):PAGE326
    I6 P5E_CPU0_P2_TX_BUF_C_DP<13> @T6G_MB_LIB.T6G(SCH_1):P5E_CPU0_P2_TX_BUF_C_DP(13)    I76 @T6G_MB_LIB.T6G(SCH_1):PAGE326
    I5 P5E_CPU0_P2_TX_BUF_C_DN<12> @T6G_MB_LIB.T6G(SCH_1):P5E_CPU0_P2_TX_BUF_C_DN(12)    I76 @T6G_MB_LIB.T6G(SCH_1):PAGE326
    J8    GND @T6G_MB_LIB.T6G(SCH_1):GND    I76 @T6G_MB_LIB.T6G(SCH_1):PAGE326
    J7 P5E_CPU0_P2_TX_BUF_C_DP<14> @T6G_MB_LIB.T6G(SCH_1):P5E_CPU0_P2_TX_BUF_C_DP(14)    I76 @T6G_MB_LIB.T6G(SCH_1):PAGE326
    J6    GND @T6G_MB_LIB.T6G(SCH_1):GND    I76 @T6G_MB_LIB.T6G(SCH_1):PAGE326
    J5 P5E_CPU0_P2_TX_BUF_C_DP<12> @T6G_MB_LIB.T6G(SCH_1):P5E_CPU0_P2_TX_BUF_C_DP(12)    I76 @T6G_MB_LIB.T6G(SCH_1):PAGE326
    K8 P5E_CPU0_P3_TX_BUF_C_DN<15> @T6G_MB_LIB.T6G(SCH_1):P5E_CPU0_P3_TX_BUF_C_DN(15)    I76 @T6G_MB_LIB.T6G(SCH_1):PAGE326
    K7    GND @T6G_MB_LIB.T6G(SCH_1):GND    I76 @T6G_MB_LIB.T6G(SCH_1):PAGE326
    K6 P5E_CPU0_P3_TX_BUF_C_DN<13> @T6G_MB_LIB.T6G(SCH_1):P5E_CPU0_P3_TX_BUF_C_DN(13)    I76 @T6G_MB_LIB.T6G(SCH_1):PAGE326
    K5    GND @T6G_MB_LIB.T6G(SCH_1):GND    I76 @T6G_MB_LIB.T6G(SCH_1):PAGE326
    L8 P5E_CPU0_P3_TX_BUF_C_DP<15> @T6G_MB_LIB.T6G(SCH_1):P5E_CPU0_P3_TX_BUF_C_DP(15)    I76 @T6G_MB_LIB.T6G(SCH_1):PAGE326
    L7 P5E_CPU0_P3_TX_BUF_C_DN<14> @T6G_MB_LIB.T6G(SCH_1):P5E_CPU0_P3_TX_BUF_C_DN(14)    I76 @T6G_MB_LIB.T6G(SCH_1):PAGE326
    L6 P5E_CPU0_P3_TX_BUF_C_DP<13> @T6G_MB_LIB.T6G(SCH_1):P5E_CPU0_P3_TX_BUF_C_DP(13)    I76 @T6G_MB_LIB.T6G(SCH_1):PAGE326
    L5 P5E_CPU0_P3_TX_BUF_C_DN<12> @T6G_MB_LIB.T6G(SCH_1):P5E_CPU0_P3_TX_BUF_C_DN(12)    I76 @T6G_MB_LIB.T6G(SCH_1):PAGE326
    M5 P5E_CPU0_P3_TX_BUF_C_DP<12> @T6G_MB_LIB.T6G(SCH_1):P5E_CPU0_P3_TX_BUF_C_DP(12)    I76 @T6G_MB_LIB.T6G(SCH_1):PAGE326
    N5    GND @T6G_MB_LIB.T6G(SCH_1):GND    I76 @T6G_MB_LIB.T6G(SCH_1):PAGE326
    M6    GND @T6G_MB_LIB.T6G(SCH_1):GND    I76 @T6G_MB_LIB.T6G(SCH_1):PAGE326
    N6 RST_SWB_BIC_BUF_N @T6G_MB_LIB.T6G(SCH_1):RST_SWB_BIC_BUF_N    I76 @T6G_MB_LIB.T6G(SCH_1):PAGE326
    M7 P5E_CPU0_P3_TX_BUF_C_DP<14> @T6G_MB_LIB.T6G(SCH_1):P5E_CPU0_P3_TX_BUF_C_DP(14)    I76 @T6G_MB_LIB.T6G(SCH_1):PAGE326
    N7    GND @T6G_MB_LIB.T6G(SCH_1):GND    I76 @T6G_MB_LIB.T6G(SCH_1):PAGE326
    M8    GND @T6G_MB_LIB.T6G(SCH_1):GND    I76 @T6G_MB_LIB.T6G(SCH_1):PAGE326
    N8 RST_BMC_FROM_SWB_N @T6G_MB_LIB.T6G(SCH_1):RST_BMC_FROM_SWB_N    I76 @T6G_MB_LIB.T6G(SCH_1):PAGE326
    A4    GND @T6G_MB_LIB.T6G(SCH_1):GND    I75 @T6G_MB_LIB.T6G(SCH_1):PAGE326
    A3 GPU_WP_HW_CTRL_ISO_N @T6G_MB_LIB.T6G(SCH_1):GPU_WP_HW_CTRL_ISO_N    I75 @T6G_MB_LIB.T6G(SCH_1):PAGE326
    A2    GND @T6G_MB_LIB.T6G(SCH_1):GND    I75 @T6G_MB_LIB.T6G(SCH_1):PAGE326
    A1 GPU_3V3IO_RSVD4 @T6G_MB_LIB.T6G(SCH_1):GPU_3V3IO_RSVD4    I75 @T6G_MB_LIB.T6G(SCH_1):PAGE326
    B4 P5E_CPU0_P2_RX_BUF_DN<11> @T6G_MB_LIB.T6G(SCH_1):P5E_CPU0_P2_RX_BUF_DN(11)    I75 @T6G_MB_LIB.T6G(SCH_1):PAGE326
    B3    GND @T6G_MB_LIB.T6G(SCH_1):GND    I75 @T6G_MB_LIB.T6G(SCH_1):PAGE326
    B2 P5E_CPU0_P2_RX_BUF_DN<9> @T6G_MB_LIB.T6G(SCH_1):P5E_CPU0_P2_RX_BUF_DN(9)    I75 @T6G_MB_LIB.T6G(SCH_1):PAGE326
    B1    GND @T6G_MB_LIB.T6G(SCH_1):GND    I75 @T6G_MB_LIB.T6G(SCH_1):PAGE326
    C4 P5E_CPU0_P2_RX_BUF_DP<11> @T6G_MB_LIB.T6G(SCH_1):P5E_CPU0_P2_RX_BUF_DP(11)    I75 @T6G_MB_LIB.T6G(SCH_1):PAGE326
    C3 P5E_CPU0_P2_RX_BUF_DN<10> @T6G_MB_LIB.T6G(SCH_1):P5E_CPU0_P2_RX_BUF_DN(10)    I75 @T6G_MB_LIB.T6G(SCH_1):PAGE326
    C2 P5E_CPU0_P2_RX_BUF_DP<9> @T6G_MB_LIB.T6G(SCH_1):P5E_CPU0_P2_RX_BUF_DP(9)    I75 @T6G_MB_LIB.T6G(SCH_1):PAGE326
    C1 P5E_CPU0_P2_RX_BUF_DN<8> @T6G_MB_LIB.T6G(SCH_1):P5E_CPU0_P2_RX_BUF_DN(8)    I75 @T6G_MB_LIB.T6G(SCH_1):PAGE326
    D4    GND @T6G_MB_LIB.T6G(SCH_1):GND    I75 @T6G_MB_LIB.T6G(SCH_1):PAGE326
    D3 P5E_CPU0_P2_RX_BUF_DP<10> @T6G_MB_LIB.T6G(SCH_1):P5E_CPU0_P2_RX_BUF_DP(10)    I75 @T6G_MB_LIB.T6G(SCH_1):PAGE326
    D2    GND @T6G_MB_LIB.T6G(SCH_1):GND    I75 @T6G_MB_LIB.T6G(SCH_1):PAGE326
    D1 P5E_CPU0_P2_RX_BUF_DP<8> @T6G_MB_LIB.T6G(SCH_1):P5E_CPU0_P2_RX_BUF_DP(8)    I75 @T6G_MB_LIB.T6G(SCH_1):PAGE326
    E4 P5E_CPU0_P3_RX_BUF_DN<11> @T6G_MB_LIB.T6G(SCH_1):P5E_CPU0_P3_RX_BUF_DN(11)    I75 @T6G_MB_LIB.T6G(SCH_1):PAGE326
    E3    GND @T6G_MB_LIB.T6G(SCH_1):GND    I75 @T6G_MB_LIB.T6G(SCH_1):PAGE326
    E2 P5E_CPU0_P3_RX_BUF_DN<9> @T6G_MB_LIB.T6G(SCH_1):P5E_CPU0_P3_RX_BUF_DN(9)    I75 @T6G_MB_LIB.T6G(SCH_1):PAGE326
    E1    GND @T6G_MB_LIB.T6G(SCH_1):GND    I75 @T6G_MB_LIB.T6G(SCH_1):PAGE326
    F4 P5E_CPU0_P3_RX_BUF_DP<11> @T6G_MB_LIB.T6G(SCH_1):P5E_CPU0_P3_RX_BUF_DP(11)    I75 @T6G_MB_LIB.T6G(SCH_1):PAGE326
    F3 P5E_CPU0_P3_RX_BUF_DN<10> @T6G_MB_LIB.T6G(SCH_1):P5E_CPU0_P3_RX_BUF_DN(10)    I75 @T6G_MB_LIB.T6G(SCH_1):PAGE326
    F2 P5E_CPU0_P3_RX_BUF_DP<9> @T6G_MB_LIB.T6G(SCH_1):P5E_CPU0_P3_RX_BUF_DP(9)    I75 @T6G_MB_LIB.T6G(SCH_1):PAGE326
    F1 P5E_CPU0_P3_RX_BUF_DN<8> @T6G_MB_LIB.T6G(SCH_1):P5E_CPU0_P3_RX_BUF_DN(8)    I75 @T6G_MB_LIB.T6G(SCH_1):PAGE326
    G4    GND @T6G_MB_LIB.T6G(SCH_1):GND    I75 @T6G_MB_LIB.T6G(SCH_1):PAGE326
    G3 P5E_CPU0_P3_RX_BUF_DP<10> @T6G_MB_LIB.T6G(SCH_1):P5E_CPU0_P3_RX_BUF_DP(10)    I75 @T6G_MB_LIB.T6G(SCH_1):PAGE326
    G2    GND @T6G_MB_LIB.T6G(SCH_1):GND    I75 @T6G_MB_LIB.T6G(SCH_1):PAGE326
    G1 P5E_CPU0_P3_RX_BUF_DP<8> @T6G_MB_LIB.T6G(SCH_1):P5E_CPU0_P3_RX_BUF_DP(8)    I75 @T6G_MB_LIB.T6G(SCH_1):PAGE326
    H4 P5E_CPU0_P2_TX_BUF_C_DN<11> @T6G_MB_LIB.T6G(SCH_1):P5E_CPU0_P2_TX_BUF_C_DN(11)    I75 @T6G_MB_LIB.T6G(SCH_1):PAGE326
    H3    GND @T6G_MB_LIB.T6G(SCH_1):GND    I75 @T6G_MB_LIB.T6G(SCH_1):PAGE326
    H2 P5E_CPU0_P2_TX_BUF_C_DN<9> @T6G_MB_LIB.T6G(SCH_1):P5E_CPU0_P2_TX_BUF_C_DN(9)    I75 @T6G_MB_LIB.T6G(SCH_1):PAGE326
    H1    GND @T6G_MB_LIB.T6G(SCH_1):GND    I75 @T6G_MB_LIB.T6G(SCH_1):PAGE326
    I4 P5E_CPU0_P2_TX_BUF_C_DP<11> @T6G_MB_LIB.T6G(SCH_1):P5E_CPU0_P2_TX_BUF_C_DP(11)    I75 @T6G_MB_LIB.T6G(SCH_1):PAGE326
    I3 P5E_CPU0_P2_TX_BUF_C_DN<10> @T6G_MB_LIB.T6G(SCH_1):P5E_CPU0_P2_TX_BUF_C_DN(10)    I75 @T6G_MB_LIB.T6G(SCH_1):PAGE326
    I2 P5E_CPU0_P2_TX_BUF_C_DP<9> @T6G_MB_LIB.T6G(SCH_1):P5E_CPU0_P2_TX_BUF_C_DP(9)    I75 @T6G_MB_LIB.T6G(SCH_1):PAGE326
    I1 P5E_CPU0_P2_TX_BUF_C_DN<8> @T6G_MB_LIB.T6G(SCH_1):P5E_CPU0_P2_TX_BUF_C_DN(8)    I75 @T6G_MB_LIB.T6G(SCH_1):PAGE326
    J4    GND @T6G_MB_LIB.T6G(SCH_1):GND    I75 @T6G_MB_LIB.T6G(SCH_1):PAGE326
    J3 P5E_CPU0_P2_TX_BUF_C_DP<10> @T6G_MB_LIB.T6G(SCH_1):P5E_CPU0_P2_TX_BUF_C_DP(10)    I75 @T6G_MB_LIB.T6G(SCH_1):PAGE326
    J2    GND @T6G_MB_LIB.T6G(SCH_1):GND    I75 @T6G_MB_LIB.T6G(SCH_1):PAGE326
    J1 P5E_CPU0_P2_TX_BUF_C_DP<8> @T6G_MB_LIB.T6G(SCH_1):P5E_CPU0_P2_TX_BUF_C_DP(8)    I75 @T6G_MB_LIB.T6G(SCH_1):PAGE326
    K4 P5E_CPU0_P3_TX_BUF_C_DN<11> @T6G_MB_LIB.T6G(SCH_1):P5E_CPU0_P3_TX_BUF_C_DN(11)    I75 @T6G_MB_LIB.T6G(SCH_1):PAGE326
    K3    GND @T6G_MB_LIB.T6G(SCH_1):GND    I75 @T6G_MB_LIB.T6G(SCH_1):PAGE326
    K2 P5E_CPU0_P3_TX_BUF_C_DN<9> @T6G_MB_LIB.T6G(SCH_1):P5E_CPU0_P3_TX_BUF_C_DN(9)    I75 @T6G_MB_LIB.T6G(SCH_1):PAGE326
    K1    GND @T6G_MB_LIB.T6G(SCH_1):GND    I75 @T6G_MB_LIB.T6G(SCH_1):PAGE326
    L4 P5E_CPU0_P3_TX_BUF_C_DP<11> @T6G_MB_LIB.T6G(SCH_1):P5E_CPU0_P3_TX_BUF_C_DP(11)    I75 @T6G_MB_LIB.T6G(SCH_1):PAGE326
    L3 P5E_CPU0_P3_TX_BUF_C_DN<10> @T6G_MB_LIB.T6G(SCH_1):P5E_CPU0_P3_TX_BUF_C_DN(10)    I75 @T6G_MB_LIB.T6G(SCH_1):PAGE326
    L2 P5E_CPU0_P3_TX_BUF_C_DP<9> @T6G_MB_LIB.T6G(SCH_1):P5E_CPU0_P3_TX_BUF_C_DP(9)    I75 @T6G_MB_LIB.T6G(SCH_1):PAGE326
    L1 P5E_CPU0_P3_TX_BUF_C_DN<8> @T6G_MB_LIB.T6G(SCH_1):P5E_CPU0_P3_TX_BUF_C_DN(8)    I75 @T6G_MB_LIB.T6G(SCH_1):PAGE326
    M1 P5E_CPU0_P3_TX_BUF_C_DP<8> @T6G_MB_LIB.T6G(SCH_1):P5E_CPU0_P3_TX_BUF_C_DP(8)    I75 @T6G_MB_LIB.T6G(SCH_1):PAGE326
    N1    GND @T6G_MB_LIB.T6G(SCH_1):GND    I75 @T6G_MB_LIB.T6G(SCH_1):PAGE326
    M2    GND @T6G_MB_LIB.T6G(SCH_1):GND    I75 @T6G_MB_LIB.T6G(SCH_1):PAGE326
    N2 FM_SWB_PWR_EN_R_BUF @T6G_MB_LIB.T6G(SCH_1):FM_SWB_PWR_EN_R_BUF    I75 @T6G_MB_LIB.T6G(SCH_1):PAGE326
    M3 P5E_CPU0_P3_TX_BUF_C_DP<10> @T6G_MB_LIB.T6G(SCH_1):P5E_CPU0_P3_TX_BUF_C_DP(10)    I75 @T6G_MB_LIB.T6G(SCH_1):PAGE326
    N3    GND @T6G_MB_LIB.T6G(SCH_1):GND    I75 @T6G_MB_LIB.T6G(SCH_1):PAGE326
    M4    GND @T6G_MB_LIB.T6G(SCH_1):GND    I75 @T6G_MB_LIB.T6G(SCH_1):PAGE326
    N4 FM_SWB_BIC_READY_N @T6G_MB_LIB.T6G(SCH_1):FM_SWB_BIC_READY_N    I75 @T6G_MB_LIB.T6G(SCH_1):PAGE326

J106 CONN112_10137002101LF-CONN112_10137002-101LF,THLF,A
    A8    GND @T6G_MB_LIB.T6G(SCH_1):GND    I19 @T6G_MB_LIB.T6G(SCH_1):PAGE327
    A7 PRSNT_CABLE_GPU_A1_N @T6G_MB_LIB.T6G(SCH_1):PRSNT_CABLE_GPU_A1_N    I19 @T6G_MB_LIB.T6G(SCH_1):PAGE327
    A6    GND @T6G_MB_LIB.T6G(SCH_1):GND    I19 @T6G_MB_LIB.T6G(SCH_1):PAGE327
    A5 NC_J106_A5 @T6G_MB_LIB.T6G(SCH_1):NC_J106_A5    I19 @T6G_MB_LIB.T6G(SCH_1):PAGE327
    B8 P5E_CPU0_P2_RX_BUF_DN<7> @T6G_MB_LIB.T6G(SCH_1):P5E_CPU0_P2_RX_BUF_DN(7)    I19 @T6G_MB_LIB.T6G(SCH_1):PAGE327
    B7    GND @T6G_MB_LIB.T6G(SCH_1):GND    I19 @T6G_MB_LIB.T6G(SCH_1):PAGE327
    B6 P5E_CPU0_P2_RX_BUF_DN<5> @T6G_MB_LIB.T6G(SCH_1):P5E_CPU0_P2_RX_BUF_DN(5)    I19 @T6G_MB_LIB.T6G(SCH_1):PAGE327
    B5    GND @T6G_MB_LIB.T6G(SCH_1):GND    I19 @T6G_MB_LIB.T6G(SCH_1):PAGE327
    C8 P5E_CPU0_P2_RX_BUF_DP<7> @T6G_MB_LIB.T6G(SCH_1):P5E_CPU0_P2_RX_BUF_DP(7)    I19 @T6G_MB_LIB.T6G(SCH_1):PAGE327
    C7 P5E_CPU0_P2_RX_BUF_DN<6> @T6G_MB_LIB.T6G(SCH_1):P5E_CPU0_P2_RX_BUF_DN(6)    I19 @T6G_MB_LIB.T6G(SCH_1):PAGE327
    C6 P5E_CPU0_P2_RX_BUF_DP<5> @T6G_MB_LIB.T6G(SCH_1):P5E_CPU0_P2_RX_BUF_DP(5)    I19 @T6G_MB_LIB.T6G(SCH_1):PAGE327
    C5 P5E_CPU0_P2_RX_BUF_DN<4> @T6G_MB_LIB.T6G(SCH_1):P5E_CPU0_P2_RX_BUF_DN(4)    I19 @T6G_MB_LIB.T6G(SCH_1):PAGE327
    D8    GND @T6G_MB_LIB.T6G(SCH_1):GND    I19 @T6G_MB_LIB.T6G(SCH_1):PAGE327
    D7 P5E_CPU0_P2_RX_BUF_DP<6> @T6G_MB_LIB.T6G(SCH_1):P5E_CPU0_P2_RX_BUF_DP(6)    I19 @T6G_MB_LIB.T6G(SCH_1):PAGE327
    D6    GND @T6G_MB_LIB.T6G(SCH_1):GND    I19 @T6G_MB_LIB.T6G(SCH_1):PAGE327
    D5 P5E_CPU0_P2_RX_BUF_DP<4> @T6G_MB_LIB.T6G(SCH_1):P5E_CPU0_P2_RX_BUF_DP(4)    I19 @T6G_MB_LIB.T6G(SCH_1):PAGE327
    E8 P5E_CPU0_P3_RX_BUF_DN<7> @T6G_MB_LIB.T6G(SCH_1):P5E_CPU0_P3_RX_BUF_DN(7)    I19 @T6G_MB_LIB.T6G(SCH_1):PAGE327
    E7    GND @T6G_MB_LIB.T6G(SCH_1):GND    I19 @T6G_MB_LIB.T6G(SCH_1):PAGE327
    E6 P5E_CPU0_P3_RX_BUF_DN<5> @T6G_MB_LIB.T6G(SCH_1):P5E_CPU0_P3_RX_BUF_DN(5)    I19 @T6G_MB_LIB.T6G(SCH_1):PAGE327
    E5    GND @T6G_MB_LIB.T6G(SCH_1):GND    I19 @T6G_MB_LIB.T6G(SCH_1):PAGE327
    F8 P5E_CPU0_P3_RX_BUF_DP<7> @T6G_MB_LIB.T6G(SCH_1):P5E_CPU0_P3_RX_BUF_DP(7)    I19 @T6G_MB_LIB.T6G(SCH_1):PAGE327
    F7 P5E_CPU0_P3_RX_BUF_DN<6> @T6G_MB_LIB.T6G(SCH_1):P5E_CPU0_P3_RX_BUF_DN(6)    I19 @T6G_MB_LIB.T6G(SCH_1):PAGE327
    F6 P5E_CPU0_P3_RX_BUF_DP<5> @T6G_MB_LIB.T6G(SCH_1):P5E_CPU0_P3_RX_BUF_DP(5)    I19 @T6G_MB_LIB.T6G(SCH_1):PAGE327
    F5 P5E_CPU0_P3_RX_BUF_DN<4> @T6G_MB_LIB.T6G(SCH_1):P5E_CPU0_P3_RX_BUF_DN(4)    I19 @T6G_MB_LIB.T6G(SCH_1):PAGE327
    G8    GND @T6G_MB_LIB.T6G(SCH_1):GND    I19 @T6G_MB_LIB.T6G(SCH_1):PAGE327
    G7 P5E_CPU0_P3_RX_BUF_DP<6> @T6G_MB_LIB.T6G(SCH_1):P5E_CPU0_P3_RX_BUF_DP(6)    I19 @T6G_MB_LIB.T6G(SCH_1):PAGE327
    G6    GND @T6G_MB_LIB.T6G(SCH_1):GND    I19 @T6G_MB_LIB.T6G(SCH_1):PAGE327
    G5 P5E_CPU0_P3_RX_BUF_DP<4> @T6G_MB_LIB.T6G(SCH_1):P5E_CPU0_P3_RX_BUF_DP(4)    I19 @T6G_MB_LIB.T6G(SCH_1):PAGE327
    H8 P5E_CPU0_P2_TX_BUF_C_DN<7> @T6G_MB_LIB.T6G(SCH_1):P5E_CPU0_P2_TX_BUF_C_DN(7)    I19 @T6G_MB_LIB.T6G(SCH_1):PAGE327
    H7    GND @T6G_MB_LIB.T6G(SCH_1):GND    I19 @T6G_MB_LIB.T6G(SCH_1):PAGE327
    H6 P5E_CPU0_P2_TX_BUF_C_DN<5> @T6G_MB_LIB.T6G(SCH_1):P5E_CPU0_P2_TX_BUF_C_DN(5)    I19 @T6G_MB_LIB.T6G(SCH_1):PAGE327
    H5    GND @T6G_MB_LIB.T6G(SCH_1):GND    I19 @T6G_MB_LIB.T6G(SCH_1):PAGE327
    I8 P5E_CPU0_P2_TX_BUF_C_DP<7> @T6G_MB_LIB.T6G(SCH_1):P5E_CPU0_P2_TX_BUF_C_DP(7)    I19 @T6G_MB_LIB.T6G(SCH_1):PAGE327
    I7 P5E_CPU0_P2_TX_BUF_C_DN<6> @T6G_MB_LIB.T6G(SCH_1):P5E_CPU0_P2_TX_BUF_C_DN(6)    I19 @T6G_MB_LIB.T6G(SCH_1):PAGE327
    I6 P5E_CPU0_P2_TX_BUF_C_DP<5> @T6G_MB_LIB.T6G(SCH_1):P5E_CPU0_P2_TX_BUF_C_DP(5)    I19 @T6G_MB_LIB.T6G(SCH_1):PAGE327
    I5 P5E_CPU0_P2_TX_BUF_C_DN<4> @T6G_MB_LIB.T6G(SCH_1):P5E_CPU0_P2_TX_BUF_C_DN(4)    I19 @T6G_MB_LIB.T6G(SCH_1):PAGE327
    J8    GND @T6G_MB_LIB.T6G(SCH_1):GND    I19 @T6G_MB_LIB.T6G(SCH_1):PAGE327
    J7 P5E_CPU0_P2_TX_BUF_C_DP<6> @T6G_MB_LIB.T6G(SCH_1):P5E_CPU0_P2_TX_BUF_C_DP(6)    I19 @T6G_MB_LIB.T6G(SCH_1):PAGE327
    J6    GND @T6G_MB_LIB.T6G(SCH_1):GND    I19 @T6G_MB_LIB.T6G(SCH_1):PAGE327
    J5 P5E_CPU0_P2_TX_BUF_C_DP<4> @T6G_MB_LIB.T6G(SCH_1):P5E_CPU0_P2_TX_BUF_C_DP(4)    I19 @T6G_MB_LIB.T6G(SCH_1):PAGE327
    K8 P5E_CPU0_P3_TX_BUF_C_DN<7> @T6G_MB_LIB.T6G(SCH_1):P5E_CPU0_P3_TX_BUF_C_DN(7)    I19 @T6G_MB_LIB.T6G(SCH_1):PAGE327
    K7    GND @T6G_MB_LIB.T6G(SCH_1):GND    I19 @T6G_MB_LIB.T6G(SCH_1):PAGE327
    K6 P5E_CPU0_P3_TX_BUF_C_DN<5> @T6G_MB_LIB.T6G(SCH_1):P5E_CPU0_P3_TX_BUF_C_DN(5)    I19 @T6G_MB_LIB.T6G(SCH_1):PAGE327
    K5    GND @T6G_MB_LIB.T6G(SCH_1):GND    I19 @T6G_MB_LIB.T6G(SCH_1):PAGE327
    L8 P5E_CPU0_P3_TX_BUF_C_DP<7> @T6G_MB_LIB.T6G(SCH_1):P5E_CPU0_P3_TX_BUF_C_DP(7)    I19 @T6G_MB_LIB.T6G(SCH_1):PAGE327
    L7 P5E_CPU0_P3_TX_BUF_C_DN<6> @T6G_MB_LIB.T6G(SCH_1):P5E_CPU0_P3_TX_BUF_C_DN(6)    I19 @T6G_MB_LIB.T6G(SCH_1):PAGE327
    L6 P5E_CPU0_P3_TX_BUF_C_DP<5> @T6G_MB_LIB.T6G(SCH_1):P5E_CPU0_P3_TX_BUF_C_DP(5)    I19 @T6G_MB_LIB.T6G(SCH_1):PAGE327
    L5 P5E_CPU0_P3_TX_BUF_C_DN<4> @T6G_MB_LIB.T6G(SCH_1):P5E_CPU0_P3_TX_BUF_C_DN(4)    I19 @T6G_MB_LIB.T6G(SCH_1):PAGE327
    M5 P5E_CPU0_P3_TX_BUF_C_DP<4> @T6G_MB_LIB.T6G(SCH_1):P5E_CPU0_P3_TX_BUF_C_DP(4)    I19 @T6G_MB_LIB.T6G(SCH_1):PAGE327
    N5    GND @T6G_MB_LIB.T6G(SCH_1):GND    I19 @T6G_MB_LIB.T6G(SCH_1):PAGE327
    M6    GND @T6G_MB_LIB.T6G(SCH_1):GND    I19 @T6G_MB_LIB.T6G(SCH_1):PAGE327
    N6 UART_BMC_BIC_RX @T6G_MB_LIB.T6G(SCH_1):UART_BMC_BIC_RX    I19 @T6G_MB_LIB.T6G(SCH_1):PAGE327
    M7 P5E_CPU0_P3_TX_BUF_C_DP<6> @T6G_MB_LIB.T6G(SCH_1):P5E_CPU0_P3_TX_BUF_C_DP(6)    I19 @T6G_MB_LIB.T6G(SCH_1):PAGE327
    N7    GND @T6G_MB_LIB.T6G(SCH_1):GND    I19 @T6G_MB_LIB.T6G(SCH_1):PAGE327
    M8    GND @T6G_MB_LIB.T6G(SCH_1):GND    I19 @T6G_MB_LIB.T6G(SCH_1):PAGE327
    N8 UART_BMC_BIC_TX @T6G_MB_LIB.T6G(SCH_1):UART_BMC_BIC_TX    I19 @T6G_MB_LIB.T6G(SCH_1):PAGE327
    A4    GND @T6G_MB_LIB.T6G(SCH_1):GND    I74 @T6G_MB_LIB.T6G(SCH_1):PAGE327
    A3 FM_SWB_PWRGD @T6G_MB_LIB.T6G(SCH_1):FM_SWB_PWRGD    I74 @T6G_MB_LIB.T6G(SCH_1):PAGE327
    A2    GND @T6G_MB_LIB.T6G(SCH_1):GND    I74 @T6G_MB_LIB.T6G(SCH_1):PAGE327
    A1 PRSNT_CABLE_SWB_B1_N @T6G_MB_LIB.T6G(SCH_1):PRSNT_CABLE_SWB_B1_N    I74 @T6G_MB_LIB.T6G(SCH_1):PAGE327
    B4 P5E_CPU0_P2_RX_BUF_DN<3> @T6G_MB_LIB.T6G(SCH_1):P5E_CPU0_P2_RX_BUF_DN(3)    I74 @T6G_MB_LIB.T6G(SCH_1):PAGE327
    B3    GND @T6G_MB_LIB.T6G(SCH_1):GND    I74 @T6G_MB_LIB.T6G(SCH_1):PAGE327
    B2 P5E_CPU0_P2_RX_BUF_DN<1> @T6G_MB_LIB.T6G(SCH_1):P5E_CPU0_P2_RX_BUF_DN(1)    I74 @T6G_MB_LIB.T6G(SCH_1):PAGE327
    B1    GND @T6G_MB_LIB.T6G(SCH_1):GND    I74 @T6G_MB_LIB.T6G(SCH_1):PAGE327
    C4 P5E_CPU0_P2_RX_BUF_DP<3> @T6G_MB_LIB.T6G(SCH_1):P5E_CPU0_P2_RX_BUF_DP(3)    I74 @T6G_MB_LIB.T6G(SCH_1):PAGE327
    C3 P5E_CPU0_P2_RX_BUF_DN<2> @T6G_MB_LIB.T6G(SCH_1):P5E_CPU0_P2_RX_BUF_DN(2)    I74 @T6G_MB_LIB.T6G(SCH_1):PAGE327
    C2 P5E_CPU0_P2_RX_BUF_DP<1> @T6G_MB_LIB.T6G(SCH_1):P5E_CPU0_P2_RX_BUF_DP(1)    I74 @T6G_MB_LIB.T6G(SCH_1):PAGE327
    C1 P5E_CPU0_P2_RX_BUF_DN<0> @T6G_MB_LIB.T6G(SCH_1):P5E_CPU0_P2_RX_BUF_DN(0)    I74 @T6G_MB_LIB.T6G(SCH_1):PAGE327
    D4    GND @T6G_MB_LIB.T6G(SCH_1):GND    I74 @T6G_MB_LIB.T6G(SCH_1):PAGE327
    D3 P5E_CPU0_P2_RX_BUF_DP<2> @T6G_MB_LIB.T6G(SCH_1):P5E_CPU0_P2_RX_BUF_DP(2)    I74 @T6G_MB_LIB.T6G(SCH_1):PAGE327
    D2    GND @T6G_MB_LIB.T6G(SCH_1):GND    I74 @T6G_MB_LIB.T6G(SCH_1):PAGE327
    D1 P5E_CPU0_P2_RX_BUF_DP<0> @T6G_MB_LIB.T6G(SCH_1):P5E_CPU0_P2_RX_BUF_DP(0)    I74 @T6G_MB_LIB.T6G(SCH_1):PAGE327
    E4 P5E_CPU0_P3_RX_BUF_DN<3> @T6G_MB_LIB.T6G(SCH_1):P5E_CPU0_P3_RX_BUF_DN(3)    I74 @T6G_MB_LIB.T6G(SCH_1):PAGE327
    E3    GND @T6G_MB_LIB.T6G(SCH_1):GND    I74 @T6G_MB_LIB.T6G(SCH_1):PAGE327
    E2 P5E_CPU0_P3_RX_BUF_DN<1> @T6G_MB_LIB.T6G(SCH_1):P5E_CPU0_P3_RX_BUF_DN(1)    I74 @T6G_MB_LIB.T6G(SCH_1):PAGE327
    E1    GND @T6G_MB_LIB.T6G(SCH_1):GND    I74 @T6G_MB_LIB.T6G(SCH_1):PAGE327
    F4 P5E_CPU0_P3_RX_BUF_DP<3> @T6G_MB_LIB.T6G(SCH_1):P5E_CPU0_P3_RX_BUF_DP(3)    I74 @T6G_MB_LIB.T6G(SCH_1):PAGE327
    F3 P5E_CPU0_P3_RX_BUF_DN<2> @T6G_MB_LIB.T6G(SCH_1):P5E_CPU0_P3_RX_BUF_DN(2)    I74 @T6G_MB_LIB.T6G(SCH_1):PAGE327
    F2 P5E_CPU0_P3_RX_BUF_DP<1> @T6G_MB_LIB.T6G(SCH_1):P5E_CPU0_P3_RX_BUF_DP(1)    I74 @T6G_MB_LIB.T6G(SCH_1):PAGE327
    F1 P5E_CPU0_P3_RX_BUF_DN<0> @T6G_MB_LIB.T6G(SCH_1):P5E_CPU0_P3_RX_BUF_DN(0)    I74 @T6G_MB_LIB.T6G(SCH_1):PAGE327
    G4    GND @T6G_MB_LIB.T6G(SCH_1):GND    I74 @T6G_MB_LIB.T6G(SCH_1):PAGE327
    G3 P5E_CPU0_P3_RX_BUF_DP<2> @T6G_MB_LIB.T6G(SCH_1):P5E_CPU0_P3_RX_BUF_DP(2)    I74 @T6G_MB_LIB.T6G(SCH_1):PAGE327
    G2    GND @T6G_MB_LIB.T6G(SCH_1):GND    I74 @T6G_MB_LIB.T6G(SCH_1):PAGE327
    G1 P5E_CPU0_P3_RX_BUF_DP<0> @T6G_MB_LIB.T6G(SCH_1):P5E_CPU0_P3_RX_BUF_DP(0)    I74 @T6G_MB_LIB.T6G(SCH_1):PAGE327
    H4 P5E_CPU0_P2_TX_BUF_C_DN<3> @T6G_MB_LIB.T6G(SCH_1):P5E_CPU0_P2_TX_BUF_C_DN(3)    I74 @T6G_MB_LIB.T6G(SCH_1):PAGE327
    H3    GND @T6G_MB_LIB.T6G(SCH_1):GND    I74 @T6G_MB_LIB.T6G(SCH_1):PAGE327
    H2 P5E_CPU0_P2_TX_BUF_C_DN<1> @T6G_MB_LIB.T6G(SCH_1):P5E_CPU0_P2_TX_BUF_C_DN(1)    I74 @T6G_MB_LIB.T6G(SCH_1):PAGE327
    H1    GND @T6G_MB_LIB.T6G(SCH_1):GND    I74 @T6G_MB_LIB.T6G(SCH_1):PAGE327
    I4 P5E_CPU0_P2_TX_BUF_C_DP<3> @T6G_MB_LIB.T6G(SCH_1):P5E_CPU0_P2_TX_BUF_C_DP(3)    I74 @T6G_MB_LIB.T6G(SCH_1):PAGE327
    I3 P5E_CPU0_P2_TX_BUF_C_DN<2> @T6G_MB_LIB.T6G(SCH_1):P5E_CPU0_P2_TX_BUF_C_DN(2)    I74 @T6G_MB_LIB.T6G(SCH_1):PAGE327
    I2 P5E_CPU0_P2_TX_BUF_C_DP<1> @T6G_MB_LIB.T6G(SCH_1):P5E_CPU0_P2_TX_BUF_C_DP(1)    I74 @T6G_MB_LIB.T6G(SCH_1):PAGE327
    I1 P5E_CPU0_P2_TX_BUF_C_DN<0> @T6G_MB_LIB.T6G(SCH_1):P5E_CPU0_P2_TX_BUF_C_DN(0)    I74 @T6G_MB_LIB.T6G(SCH_1):PAGE327
    J4    GND @T6G_MB_LIB.T6G(SCH_1):GND    I74 @T6G_MB_LIB.T6G(SCH_1):PAGE327
    J3 P5E_CPU0_P2_TX_BUF_C_DP<2> @T6G_MB_LIB.T6G(SCH_1):P5E_CPU0_P2_TX_BUF_C_DP(2)    I74 @T6G_MB_LIB.T6G(SCH_1):PAGE327
    J2    GND @T6G_MB_LIB.T6G(SCH_1):GND    I74 @T6G_MB_LIB.T6G(SCH_1):PAGE327
    J1 P5E_CPU0_P2_TX_BUF_C_DP<0> @T6G_MB_LIB.T6G(SCH_1):P5E_CPU0_P2_TX_BUF_C_DP(0)    I74 @T6G_MB_LIB.T6G(SCH_1):PAGE327
    K4 P5E_CPU0_P3_TX_BUF_C_DN<3> @T6G_MB_LIB.T6G(SCH_1):P5E_CPU0_P3_TX_BUF_C_DN(3)    I74 @T6G_MB_LIB.T6G(SCH_1):PAGE327
    K3    GND @T6G_MB_LIB.T6G(SCH_1):GND    I74 @T6G_MB_LIB.T6G(SCH_1):PAGE327
    K2 P5E_CPU0_P3_TX_BUF_C_DN<1> @T6G_MB_LIB.T6G(SCH_1):P5E_CPU0_P3_TX_BUF_C_DN(1)    I74 @T6G_MB_LIB.T6G(SCH_1):PAGE327
    K1    GND @T6G_MB_LIB.T6G(SCH_1):GND    I74 @T6G_MB_LIB.T6G(SCH_1):PAGE327
    L4 P5E_CPU0_P3_TX_BUF_C_DP<3> @T6G_MB_LIB.T6G(SCH_1):P5E_CPU0_P3_TX_BUF_C_DP(3)    I74 @T6G_MB_LIB.T6G(SCH_1):PAGE327
    L3 P5E_CPU0_P3_TX_BUF_C_DN<2> @T6G_MB_LIB.T6G(SCH_1):P5E_CPU0_P3_TX_BUF_C_DN(2)    I74 @T6G_MB_LIB.T6G(SCH_1):PAGE327
    L2 P5E_CPU0_P3_TX_BUF_C_DP<1> @T6G_MB_LIB.T6G(SCH_1):P5E_CPU0_P3_TX_BUF_C_DP(1)    I74 @T6G_MB_LIB.T6G(SCH_1):PAGE327
    L1 P5E_CPU0_P3_TX_BUF_C_DN<0> @T6G_MB_LIB.T6G(SCH_1):P5E_CPU0_P3_TX_BUF_C_DN(0)    I74 @T6G_MB_LIB.T6G(SCH_1):PAGE327
    M1 P5E_CPU0_P3_TX_BUF_C_DP<0> @T6G_MB_LIB.T6G(SCH_1):P5E_CPU0_P3_TX_BUF_C_DP(0)    I74 @T6G_MB_LIB.T6G(SCH_1):PAGE327
    N1    GND @T6G_MB_LIB.T6G(SCH_1):GND    I74 @T6G_MB_LIB.T6G(SCH_1):PAGE327
    M2    GND @T6G_MB_LIB.T6G(SCH_1):GND    I74 @T6G_MB_LIB.T6G(SCH_1):PAGE327
    N2 I3C_BMC_SWB_BUF_SDA @T6G_MB_LIB.T6G(SCH_1):I3C_BMC_SWB_BUF_SDA    I74 @T6G_MB_LIB.T6G(SCH_1):PAGE327
    M3 P5E_CPU0_P3_TX_BUF_C_DP<2> @T6G_MB_LIB.T6G(SCH_1):P5E_CPU0_P3_TX_BUF_C_DP(2)    I74 @T6G_MB_LIB.T6G(SCH_1):PAGE327
    N3    GND @T6G_MB_LIB.T6G(SCH_1):GND    I74 @T6G_MB_LIB.T6G(SCH_1):PAGE327
    M4    GND @T6G_MB_LIB.T6G(SCH_1):GND    I74 @T6G_MB_LIB.T6G(SCH_1):PAGE327
    N4 I3C_BMC_SWB_BUF_SCL @T6G_MB_LIB.T6G(SCH_1):I3C_BMC_SWB_BUF_SCL    I74 @T6G_MB_LIB.T6G(SCH_1):PAGE327

J107 CONN112_10137002101LF-CONN112_10137002-101LF,THLF,A
    A8    GND @T6G_MB_LIB.T6G(SCH_1):GND    I70 @T6G_MB_LIB.T6G(SCH_1):PAGE317
    A7 SWB_HSC_PWRGD @T6G_MB_LIB.T6G(SCH_1):SWB_HSC_PWRGD    I70 @T6G_MB_LIB.T6G(SCH_1):PAGE317
    A6    GND @T6G_MB_LIB.T6G(SCH_1):GND    I70 @T6G_MB_LIB.T6G(SCH_1):PAGE317
    A5 NC_J107_A5 @T6G_MB_LIB.T6G(SCH_1):NC_J107_A5    I70 @T6G_MB_LIB.T6G(SCH_1):PAGE317
    B8 P5E_CPU0_P0_RX_BUF_DN<15> @T6G_MB_LIB.T6G(SCH_1):P5E_CPU0_P0_RX_BUF_DN(15)    I70 @T6G_MB_LIB.T6G(SCH_1):PAGE317
    B7    GND @T6G_MB_LIB.T6G(SCH_1):GND    I70 @T6G_MB_LIB.T6G(SCH_1):PAGE317
    B6 P5E_CPU0_P0_RX_BUF_DN<13> @T6G_MB_LIB.T6G(SCH_1):P5E_CPU0_P0_RX_BUF_DN(13)    I70 @T6G_MB_LIB.T6G(SCH_1):PAGE317
    B5    GND @T6G_MB_LIB.T6G(SCH_1):GND    I70 @T6G_MB_LIB.T6G(SCH_1):PAGE317
    C8 P5E_CPU0_P0_RX_BUF_DP<15> @T6G_MB_LIB.T6G(SCH_1):P5E_CPU0_P0_RX_BUF_DP(15)    I70 @T6G_MB_LIB.T6G(SCH_1):PAGE317
    C7 P5E_CPU0_P0_RX_BUF_DN<14> @T6G_MB_LIB.T6G(SCH_1):P5E_CPU0_P0_RX_BUF_DN(14)    I70 @T6G_MB_LIB.T6G(SCH_1):PAGE317
    C6 P5E_CPU0_P0_RX_BUF_DP<13> @T6G_MB_LIB.T6G(SCH_1):P5E_CPU0_P0_RX_BUF_DP(13)    I70 @T6G_MB_LIB.T6G(SCH_1):PAGE317
    C5 P5E_CPU0_P0_RX_BUF_DN<12> @T6G_MB_LIB.T6G(SCH_1):P5E_CPU0_P0_RX_BUF_DN(12)    I70 @T6G_MB_LIB.T6G(SCH_1):PAGE317
    D8    GND @T6G_MB_LIB.T6G(SCH_1):GND    I70 @T6G_MB_LIB.T6G(SCH_1):PAGE317
    D7 P5E_CPU0_P0_RX_BUF_DP<14> @T6G_MB_LIB.T6G(SCH_1):P5E_CPU0_P0_RX_BUF_DP(14)    I70 @T6G_MB_LIB.T6G(SCH_1):PAGE317
    D6    GND @T6G_MB_LIB.T6G(SCH_1):GND    I70 @T6G_MB_LIB.T6G(SCH_1):PAGE317
    D5 P5E_CPU0_P0_RX_BUF_DP<12> @T6G_MB_LIB.T6G(SCH_1):P5E_CPU0_P0_RX_BUF_DP(12)    I70 @T6G_MB_LIB.T6G(SCH_1):PAGE317
    E8 P5E_CPU0_P1_RX_BUF_DN<15> @T6G_MB_LIB.T6G(SCH_1):P5E_CPU0_P1_RX_BUF_DN(15)    I70 @T6G_MB_LIB.T6G(SCH_1):PAGE317
    E7    GND @T6G_MB_LIB.T6G(SCH_1):GND    I70 @T6G_MB_LIB.T6G(SCH_1):PAGE317
    E6 P5E_CPU0_P1_RX_BUF_DN<13> @T6G_MB_LIB.T6G(SCH_1):P5E_CPU0_P1_RX_BUF_DN(13)    I70 @T6G_MB_LIB.T6G(SCH_1):PAGE317
    E5    GND @T6G_MB_LIB.T6G(SCH_1):GND    I70 @T6G_MB_LIB.T6G(SCH_1):PAGE317
    F8 P5E_CPU0_P1_RX_BUF_DP<15> @T6G_MB_LIB.T6G(SCH_1):P5E_CPU0_P1_RX_BUF_DP(15)    I70 @T6G_MB_LIB.T6G(SCH_1):PAGE317
    F7 P5E_CPU0_P1_RX_BUF_DN<14> @T6G_MB_LIB.T6G(SCH_1):P5E_CPU0_P1_RX_BUF_DN(14)    I70 @T6G_MB_LIB.T6G(SCH_1):PAGE317
    F6 P5E_CPU0_P1_RX_BUF_DP<13> @T6G_MB_LIB.T6G(SCH_1):P5E_CPU0_P1_RX_BUF_DP(13)    I70 @T6G_MB_LIB.T6G(SCH_1):PAGE317
    F5 P5E_CPU0_P1_RX_BUF_DN<12> @T6G_MB_LIB.T6G(SCH_1):P5E_CPU0_P1_RX_BUF_DN(12)    I70 @T6G_MB_LIB.T6G(SCH_1):PAGE317
    G8    GND @T6G_MB_LIB.T6G(SCH_1):GND    I70 @T6G_MB_LIB.T6G(SCH_1):PAGE317
    G7 P5E_CPU0_P1_RX_BUF_DP<14> @T6G_MB_LIB.T6G(SCH_1):P5E_CPU0_P1_RX_BUF_DP(14)    I70 @T6G_MB_LIB.T6G(SCH_1):PAGE317
    G6    GND @T6G_MB_LIB.T6G(SCH_1):GND    I70 @T6G_MB_LIB.T6G(SCH_1):PAGE317
    G5 P5E_CPU0_P1_RX_BUF_DP<12> @T6G_MB_LIB.T6G(SCH_1):P5E_CPU0_P1_RX_BUF_DP(12)    I70 @T6G_MB_LIB.T6G(SCH_1):PAGE317
    H8 P5E_CPU0_P0_TX_BUF_C_DN<15> @T6G_MB_LIB.T6G(SCH_1):P5E_CPU0_P0_TX_BUF_C_DN(15)    I70 @T6G_MB_LIB.T6G(SCH_1):PAGE317
    H7    GND @T6G_MB_LIB.T6G(SCH_1):GND    I70 @T6G_MB_LIB.T6G(SCH_1):PAGE317
    H6 P5E_CPU0_P0_TX_BUF_C_DN<13> @T6G_MB_LIB.T6G(SCH_1):P5E_CPU0_P0_TX_BUF_C_DN(13)    I70 @T6G_MB_LIB.T6G(SCH_1):PAGE317
    H5    GND @T6G_MB_LIB.T6G(SCH_1):GND    I70 @T6G_MB_LIB.T6G(SCH_1):PAGE317
    I8 P5E_CPU0_P0_TX_BUF_C_DP<15> @T6G_MB_LIB.T6G(SCH_1):P5E_CPU0_P0_TX_BUF_C_DP(15)    I70 @T6G_MB_LIB.T6G(SCH_1):PAGE317
    I7 P5E_CPU0_P0_TX_BUF_C_DN<14> @T6G_MB_LIB.T6G(SCH_1):P5E_CPU0_P0_TX_BUF_C_DN(14)    I70 @T6G_MB_LIB.T6G(SCH_1):PAGE317
    I6 P5E_CPU0_P0_TX_BUF_C_DP<13> @T6G_MB_LIB.T6G(SCH_1):P5E_CPU0_P0_TX_BUF_C_DP(13)    I70 @T6G_MB_LIB.T6G(SCH_1):PAGE317
    I5 P5E_CPU0_P0_TX_BUF_C_DN<12> @T6G_MB_LIB.T6G(SCH_1):P5E_CPU0_P0_TX_BUF_C_DN(12)    I70 @T6G_MB_LIB.T6G(SCH_1):PAGE317
    J8    GND @T6G_MB_LIB.T6G(SCH_1):GND    I70 @T6G_MB_LIB.T6G(SCH_1):PAGE317
    J7 P5E_CPU0_P0_TX_BUF_C_DP<14> @T6G_MB_LIB.T6G(SCH_1):P5E_CPU0_P0_TX_BUF_C_DP(14)    I70 @T6G_MB_LIB.T6G(SCH_1):PAGE317
    J6    GND @T6G_MB_LIB.T6G(SCH_1):GND    I70 @T6G_MB_LIB.T6G(SCH_1):PAGE317
    J5 P5E_CPU0_P0_TX_BUF_C_DP<12> @T6G_MB_LIB.T6G(SCH_1):P5E_CPU0_P0_TX_BUF_C_DP(12)    I70 @T6G_MB_LIB.T6G(SCH_1):PAGE317
    K8 P5E_CPU0_P1_TX_BUF_C_DN<15> @T6G_MB_LIB.T6G(SCH_1):P5E_CPU0_P1_TX_BUF_C_DN(15)    I70 @T6G_MB_LIB.T6G(SCH_1):PAGE317
    K7    GND @T6G_MB_LIB.T6G(SCH_1):GND    I70 @T6G_MB_LIB.T6G(SCH_1):PAGE317
    K6 P5E_CPU0_P1_TX_BUF_C_DN<13> @T6G_MB_LIB.T6G(SCH_1):P5E_CPU0_P1_TX_BUF_C_DN(13)    I70 @T6G_MB_LIB.T6G(SCH_1):PAGE317
    K5    GND @T6G_MB_LIB.T6G(SCH_1):GND    I70 @T6G_MB_LIB.T6G(SCH_1):PAGE317
    L8 P5E_CPU0_P1_TX_BUF_C_DP<15> @T6G_MB_LIB.T6G(SCH_1):P5E_CPU0_P1_TX_BUF_C_DP(15)    I70 @T6G_MB_LIB.T6G(SCH_1):PAGE317
    L7 P5E_CPU0_P1_TX_BUF_C_DN<14> @T6G_MB_LIB.T6G(SCH_1):P5E_CPU0_P1_TX_BUF_C_DN(14)    I70 @T6G_MB_LIB.T6G(SCH_1):PAGE317
    L6 P5E_CPU0_P1_TX_BUF_C_DP<13> @T6G_MB_LIB.T6G(SCH_1):P5E_CPU0_P1_TX_BUF_C_DP(13)    I70 @T6G_MB_LIB.T6G(SCH_1):PAGE317
    L5 P5E_CPU0_P1_TX_BUF_C_DN<12> @T6G_MB_LIB.T6G(SCH_1):P5E_CPU0_P1_TX_BUF_C_DN(12)    I70 @T6G_MB_LIB.T6G(SCH_1):PAGE317
    M5 P5E_CPU0_P1_TX_BUF_C_DP<12> @T6G_MB_LIB.T6G(SCH_1):P5E_CPU0_P1_TX_BUF_C_DP(12)    I70 @T6G_MB_LIB.T6G(SCH_1):PAGE317
    N5    GND @T6G_MB_LIB.T6G(SCH_1):GND    I70 @T6G_MB_LIB.T6G(SCH_1):PAGE317
    M6    GND @T6G_MB_LIB.T6G(SCH_1):GND    I70 @T6G_MB_LIB.T6G(SCH_1):PAGE317
    N6 NC_J107_N6 @T6G_MB_LIB.T6G(SCH_1):NC_J107_N6    I70 @T6G_MB_LIB.T6G(SCH_1):PAGE317
    M7 P5E_CPU0_P1_TX_BUF_C_DP<14> @T6G_MB_LIB.T6G(SCH_1):P5E_CPU0_P1_TX_BUF_C_DP(14)    I70 @T6G_MB_LIB.T6G(SCH_1):PAGE317
    N7    GND @T6G_MB_LIB.T6G(SCH_1):GND    I70 @T6G_MB_LIB.T6G(SCH_1):PAGE317
    M8    GND @T6G_MB_LIB.T6G(SCH_1):GND    I70 @T6G_MB_LIB.T6G(SCH_1):PAGE317
    N8 SWB_HSC_EN_BUF @T6G_MB_LIB.T6G(SCH_1):SWB_HSC_EN_BUF    I70 @T6G_MB_LIB.T6G(SCH_1):PAGE317
    A4    GND @T6G_MB_LIB.T6G(SCH_1):GND    I49 @T6G_MB_LIB.T6G(SCH_1):PAGE317
    A3 NC_J107_A3 @T6G_MB_LIB.T6G(SCH_1):NC_J107_A3    I49 @T6G_MB_LIB.T6G(SCH_1):PAGE317
    A2    GND @T6G_MB_LIB.T6G(SCH_1):GND    I49 @T6G_MB_LIB.T6G(SCH_1):PAGE317
    A1 NC_J107_A1 @T6G_MB_LIB.T6G(SCH_1):NC_J107_A1    I49 @T6G_MB_LIB.T6G(SCH_1):PAGE317
    B4 P5E_CPU0_P0_RX_BUF_DN<11> @T6G_MB_LIB.T6G(SCH_1):P5E_CPU0_P0_RX_BUF_DN(11)    I49 @T6G_MB_LIB.T6G(SCH_1):PAGE317
    B3    GND @T6G_MB_LIB.T6G(SCH_1):GND    I49 @T6G_MB_LIB.T6G(SCH_1):PAGE317
    B2 P5E_CPU0_P0_RX_BUF_DN<9> @T6G_MB_LIB.T6G(SCH_1):P5E_CPU0_P0_RX_BUF_DN(9)    I49 @T6G_MB_LIB.T6G(SCH_1):PAGE317
    B1    GND @T6G_MB_LIB.T6G(SCH_1):GND    I49 @T6G_MB_LIB.T6G(SCH_1):PAGE317
    C4 P5E_CPU0_P0_RX_BUF_DP<11> @T6G_MB_LIB.T6G(SCH_1):P5E_CPU0_P0_RX_BUF_DP(11)    I49 @T6G_MB_LIB.T6G(SCH_1):PAGE317
    C3 P5E_CPU0_P0_RX_BUF_DN<10> @T6G_MB_LIB.T6G(SCH_1):P5E_CPU0_P0_RX_BUF_DN(10)    I49 @T6G_MB_LIB.T6G(SCH_1):PAGE317
    C2 P5E_CPU0_P0_RX_BUF_DP<9> @T6G_MB_LIB.T6G(SCH_1):P5E_CPU0_P0_RX_BUF_DP(9)    I49 @T6G_MB_LIB.T6G(SCH_1):PAGE317
    C1 P5E_CPU0_P0_RX_BUF_DN<8> @T6G_MB_LIB.T6G(SCH_1):P5E_CPU0_P0_RX_BUF_DN(8)    I49 @T6G_MB_LIB.T6G(SCH_1):PAGE317
    D4    GND @T6G_MB_LIB.T6G(SCH_1):GND    I49 @T6G_MB_LIB.T6G(SCH_1):PAGE317
    D3 P5E_CPU0_P0_RX_BUF_DP<10> @T6G_MB_LIB.T6G(SCH_1):P5E_CPU0_P0_RX_BUF_DP(10)    I49 @T6G_MB_LIB.T6G(SCH_1):PAGE317
    D2    GND @T6G_MB_LIB.T6G(SCH_1):GND    I49 @T6G_MB_LIB.T6G(SCH_1):PAGE317
    D1 P5E_CPU0_P0_RX_BUF_DP<8> @T6G_MB_LIB.T6G(SCH_1):P5E_CPU0_P0_RX_BUF_DP(8)    I49 @T6G_MB_LIB.T6G(SCH_1):PAGE317
    E4 P5E_CPU0_P1_RX_BUF_DN<11> @T6G_MB_LIB.T6G(SCH_1):P5E_CPU0_P1_RX_BUF_DN(11)    I49 @T6G_MB_LIB.T6G(SCH_1):PAGE317
    E3    GND @T6G_MB_LIB.T6G(SCH_1):GND    I49 @T6G_MB_LIB.T6G(SCH_1):PAGE317
    E2 P5E_CPU0_P1_RX_BUF_DN<9> @T6G_MB_LIB.T6G(SCH_1):P5E_CPU0_P1_RX_BUF_DN(9)    I49 @T6G_MB_LIB.T6G(SCH_1):PAGE317
    E1    GND @T6G_MB_LIB.T6G(SCH_1):GND    I49 @T6G_MB_LIB.T6G(SCH_1):PAGE317
    F4 P5E_CPU0_P1_RX_BUF_DP<11> @T6G_MB_LIB.T6G(SCH_1):P5E_CPU0_P1_RX_BUF_DP(11)    I49 @T6G_MB_LIB.T6G(SCH_1):PAGE317
    F3 P5E_CPU0_P1_RX_BUF_DN<10> @T6G_MB_LIB.T6G(SCH_1):P5E_CPU0_P1_RX_BUF_DN(10)    I49 @T6G_MB_LIB.T6G(SCH_1):PAGE317
    F2 P5E_CPU0_P1_RX_BUF_DP<9> @T6G_MB_LIB.T6G(SCH_1):P5E_CPU0_P1_RX_BUF_DP(9)    I49 @T6G_MB_LIB.T6G(SCH_1):PAGE317
    F1 P5E_CPU0_P1_RX_BUF_DN<8> @T6G_MB_LIB.T6G(SCH_1):P5E_CPU0_P1_RX_BUF_DN(8)    I49 @T6G_MB_LIB.T6G(SCH_1):PAGE317
    G4    GND @T6G_MB_LIB.T6G(SCH_1):GND    I49 @T6G_MB_LIB.T6G(SCH_1):PAGE317
    G3 P5E_CPU0_P1_RX_BUF_DP<10> @T6G_MB_LIB.T6G(SCH_1):P5E_CPU0_P1_RX_BUF_DP(10)    I49 @T6G_MB_LIB.T6G(SCH_1):PAGE317
    G2    GND @T6G_MB_LIB.T6G(SCH_1):GND    I49 @T6G_MB_LIB.T6G(SCH_1):PAGE317
    G1 P5E_CPU0_P1_RX_BUF_DP<8> @T6G_MB_LIB.T6G(SCH_1):P5E_CPU0_P1_RX_BUF_DP(8)    I49 @T6G_MB_LIB.T6G(SCH_1):PAGE317
    H4 P5E_CPU0_P0_TX_BUF_C_DN<11> @T6G_MB_LIB.T6G(SCH_1):P5E_CPU0_P0_TX_BUF_C_DN(11)    I49 @T6G_MB_LIB.T6G(SCH_1):PAGE317
    H3    GND @T6G_MB_LIB.T6G(SCH_1):GND    I49 @T6G_MB_LIB.T6G(SCH_1):PAGE317
    H2 P5E_CPU0_P0_TX_BUF_C_DN<9> @T6G_MB_LIB.T6G(SCH_1):P5E_CPU0_P0_TX_BUF_C_DN(9)    I49 @T6G_MB_LIB.T6G(SCH_1):PAGE317
    H1    GND @T6G_MB_LIB.T6G(SCH_1):GND    I49 @T6G_MB_LIB.T6G(SCH_1):PAGE317
    I4 P5E_CPU0_P0_TX_BUF_C_DP<11> @T6G_MB_LIB.T6G(SCH_1):P5E_CPU0_P0_TX_BUF_C_DP(11)    I49 @T6G_MB_LIB.T6G(SCH_1):PAGE317
    I3 P5E_CPU0_P0_TX_BUF_C_DN<10> @T6G_MB_LIB.T6G(SCH_1):P5E_CPU0_P0_TX_BUF_C_DN(10)    I49 @T6G_MB_LIB.T6G(SCH_1):PAGE317
    I2 P5E_CPU0_P0_TX_BUF_C_DP<9> @T6G_MB_LIB.T6G(SCH_1):P5E_CPU0_P0_TX_BUF_C_DP(9)    I49 @T6G_MB_LIB.T6G(SCH_1):PAGE317
    I1 P5E_CPU0_P0_TX_BUF_C_DN<8> @T6G_MB_LIB.T6G(SCH_1):P5E_CPU0_P0_TX_BUF_C_DN(8)    I49 @T6G_MB_LIB.T6G(SCH_1):PAGE317
    J4    GND @T6G_MB_LIB.T6G(SCH_1):GND    I49 @T6G_MB_LIB.T6G(SCH_1):PAGE317
    J3 P5E_CPU0_P0_TX_BUF_C_DP<10> @T6G_MB_LIB.T6G(SCH_1):P5E_CPU0_P0_TX_BUF_C_DP(10)    I49 @T6G_MB_LIB.T6G(SCH_1):PAGE317
    J2    GND @T6G_MB_LIB.T6G(SCH_1):GND    I49 @T6G_MB_LIB.T6G(SCH_1):PAGE317
    J1 P5E_CPU0_P0_TX_BUF_C_DP<8> @T6G_MB_LIB.T6G(SCH_1):P5E_CPU0_P0_TX_BUF_C_DP(8)    I49 @T6G_MB_LIB.T6G(SCH_1):PAGE317
    K4 P5E_CPU0_P1_TX_BUF_C_DN<11> @T6G_MB_LIB.T6G(SCH_1):P5E_CPU0_P1_TX_BUF_C_DN(11)    I49 @T6G_MB_LIB.T6G(SCH_1):PAGE317
    K3    GND @T6G_MB_LIB.T6G(SCH_1):GND    I49 @T6G_MB_LIB.T6G(SCH_1):PAGE317
    K2 P5E_CPU0_P1_TX_BUF_C_DN<9> @T6G_MB_LIB.T6G(SCH_1):P5E_CPU0_P1_TX_BUF_C_DN(9)    I49 @T6G_MB_LIB.T6G(SCH_1):PAGE317
    K1    GND @T6G_MB_LIB.T6G(SCH_1):GND    I49 @T6G_MB_LIB.T6G(SCH_1):PAGE317
    L4 P5E_CPU0_P1_TX_BUF_C_DP<11> @T6G_MB_LIB.T6G(SCH_1):P5E_CPU0_P1_TX_BUF_C_DP(11)    I49 @T6G_MB_LIB.T6G(SCH_1):PAGE317
    L3 P5E_CPU0_P1_TX_BUF_C_DN<10> @T6G_MB_LIB.T6G(SCH_1):P5E_CPU0_P1_TX_BUF_C_DN(10)    I49 @T6G_MB_LIB.T6G(SCH_1):PAGE317
    L2 P5E_CPU0_P1_TX_BUF_C_DP<9> @T6G_MB_LIB.T6G(SCH_1):P5E_CPU0_P1_TX_BUF_C_DP(9)    I49 @T6G_MB_LIB.T6G(SCH_1):PAGE317
    L1 P5E_CPU0_P1_TX_BUF_C_DN<8> @T6G_MB_LIB.T6G(SCH_1):P5E_CPU0_P1_TX_BUF_C_DN(8)    I49 @T6G_MB_LIB.T6G(SCH_1):PAGE317
    M1 P5E_CPU0_P1_TX_BUF_C_DP<8> @T6G_MB_LIB.T6G(SCH_1):P5E_CPU0_P1_TX_BUF_C_DP(8)    I49 @T6G_MB_LIB.T6G(SCH_1):PAGE317
    N1    GND @T6G_MB_LIB.T6G(SCH_1):GND    I49 @T6G_MB_LIB.T6G(SCH_1):PAGE317
    M2    GND @T6G_MB_LIB.T6G(SCH_1):GND    I49 @T6G_MB_LIB.T6G(SCH_1):PAGE317
    N2 PRSNT_CABLE_SWB_B2_N @T6G_MB_LIB.T6G(SCH_1):PRSNT_CABLE_SWB_B2_N    I49 @T6G_MB_LIB.T6G(SCH_1):PAGE317
    M3 P5E_CPU0_P1_TX_BUF_C_DP<10> @T6G_MB_LIB.T6G(SCH_1):P5E_CPU0_P1_TX_BUF_C_DP(10)    I49 @T6G_MB_LIB.T6G(SCH_1):PAGE317
    N3    GND @T6G_MB_LIB.T6G(SCH_1):GND    I49 @T6G_MB_LIB.T6G(SCH_1):PAGE317
    M4    GND @T6G_MB_LIB.T6G(SCH_1):GND    I49 @T6G_MB_LIB.T6G(SCH_1):PAGE317
    N4 NC_J107_N4 @T6G_MB_LIB.T6G(SCH_1):NC_J107_N4    I49 @T6G_MB_LIB.T6G(SCH_1):PAGE317

J108 CONN112_10137002101LF-CONN112_10137002-101LF,THLF,A
    A8    GND @T6G_MB_LIB.T6G(SCH_1):GND    I15 @T6G_MB_LIB.T6G(SCH_1):PAGE320
    A7 GPU_FPGA_OVERT_N @T6G_MB_LIB.T6G(SCH_1):GPU_FPGA_OVERT_N    I15 @T6G_MB_LIB.T6G(SCH_1):PAGE320
    A6    GND @T6G_MB_LIB.T6G(SCH_1):GND    I15 @T6G_MB_LIB.T6G(SCH_1):PAGE320
    A5 GPU_3V3IO_RSVD5_FFU @T6G_MB_LIB.T6G(SCH_1):GPU_3V3IO_RSVD5_FFU    I15 @T6G_MB_LIB.T6G(SCH_1):PAGE320
    B8 P5E_CPU0_P0_RX_BUF_DN<7> @T6G_MB_LIB.T6G(SCH_1):P5E_CPU0_P0_RX_BUF_DN(7)    I15 @T6G_MB_LIB.T6G(SCH_1):PAGE320
    B7    GND @T6G_MB_LIB.T6G(SCH_1):GND    I15 @T6G_MB_LIB.T6G(SCH_1):PAGE320
    B6 P5E_CPU0_P0_RX_BUF_DN<5> @T6G_MB_LIB.T6G(SCH_1):P5E_CPU0_P0_RX_BUF_DN(5)    I15 @T6G_MB_LIB.T6G(SCH_1):PAGE320
    B5    GND @T6G_MB_LIB.T6G(SCH_1):GND    I15 @T6G_MB_LIB.T6G(SCH_1):PAGE320
    C8 P5E_CPU0_P0_RX_BUF_DP<7> @T6G_MB_LIB.T6G(SCH_1):P5E_CPU0_P0_RX_BUF_DP(7)    I15 @T6G_MB_LIB.T6G(SCH_1):PAGE320
    C7 P5E_CPU0_P0_RX_BUF_DN<6> @T6G_MB_LIB.T6G(SCH_1):P5E_CPU0_P0_RX_BUF_DN(6)    I15 @T6G_MB_LIB.T6G(SCH_1):PAGE320
    C6 P5E_CPU0_P0_RX_BUF_DP<5> @T6G_MB_LIB.T6G(SCH_1):P5E_CPU0_P0_RX_BUF_DP(5)    I15 @T6G_MB_LIB.T6G(SCH_1):PAGE320
    C5 P5E_CPU0_P0_RX_BUF_DN<4> @T6G_MB_LIB.T6G(SCH_1):P5E_CPU0_P0_RX_BUF_DN(4)    I15 @T6G_MB_LIB.T6G(SCH_1):PAGE320
    D8    GND @T6G_MB_LIB.T6G(SCH_1):GND    I15 @T6G_MB_LIB.T6G(SCH_1):PAGE320
    D7 P5E_CPU0_P0_RX_BUF_DP<6> @T6G_MB_LIB.T6G(SCH_1):P5E_CPU0_P0_RX_BUF_DP(6)    I15 @T6G_MB_LIB.T6G(SCH_1):PAGE320
    D6    GND @T6G_MB_LIB.T6G(SCH_1):GND    I15 @T6G_MB_LIB.T6G(SCH_1):PAGE320
    D5 P5E_CPU0_P0_RX_BUF_DP<4> @T6G_MB_LIB.T6G(SCH_1):P5E_CPU0_P0_RX_BUF_DP(4)    I15 @T6G_MB_LIB.T6G(SCH_1):PAGE320
    E8 P5E_CPU0_P1_RX_BUF_DN<7> @T6G_MB_LIB.T6G(SCH_1):P5E_CPU0_P1_RX_BUF_DN(7)    I15 @T6G_MB_LIB.T6G(SCH_1):PAGE320
    E7    GND @T6G_MB_LIB.T6G(SCH_1):GND    I15 @T6G_MB_LIB.T6G(SCH_1):PAGE320
    E6 P5E_CPU0_P1_RX_BUF_DN<5> @T6G_MB_LIB.T6G(SCH_1):P5E_CPU0_P1_RX_BUF_DN(5)    I15 @T6G_MB_LIB.T6G(SCH_1):PAGE320
    E5    GND @T6G_MB_LIB.T6G(SCH_1):GND    I15 @T6G_MB_LIB.T6G(SCH_1):PAGE320
    F8 P5E_CPU0_P1_RX_BUF_DP<7> @T6G_MB_LIB.T6G(SCH_1):P5E_CPU0_P1_RX_BUF_DP(7)    I15 @T6G_MB_LIB.T6G(SCH_1):PAGE320
    F7 P5E_CPU0_P1_RX_BUF_DN<6> @T6G_MB_LIB.T6G(SCH_1):P5E_CPU0_P1_RX_BUF_DN(6)    I15 @T6G_MB_LIB.T6G(SCH_1):PAGE320
    F6 P5E_CPU0_P1_RX_BUF_DP<5> @T6G_MB_LIB.T6G(SCH_1):P5E_CPU0_P1_RX_BUF_DP(5)    I15 @T6G_MB_LIB.T6G(SCH_1):PAGE320
    F5 P5E_CPU0_P1_RX_BUF_DN<4> @T6G_MB_LIB.T6G(SCH_1):P5E_CPU0_P1_RX_BUF_DN(4)    I15 @T6G_MB_LIB.T6G(SCH_1):PAGE320
    G8    GND @T6G_MB_LIB.T6G(SCH_1):GND    I15 @T6G_MB_LIB.T6G(SCH_1):PAGE320
    G7 P5E_CPU0_P1_RX_BUF_DP<6> @T6G_MB_LIB.T6G(SCH_1):P5E_CPU0_P1_RX_BUF_DP(6)    I15 @T6G_MB_LIB.T6G(SCH_1):PAGE320
    G6    GND @T6G_MB_LIB.T6G(SCH_1):GND    I15 @T6G_MB_LIB.T6G(SCH_1):PAGE320
    G5 P5E_CPU0_P1_RX_BUF_DP<4> @T6G_MB_LIB.T6G(SCH_1):P5E_CPU0_P1_RX_BUF_DP(4)    I15 @T6G_MB_LIB.T6G(SCH_1):PAGE320
    H8 P5E_CPU0_P0_TX_BUF_C_DN<7> @T6G_MB_LIB.T6G(SCH_1):P5E_CPU0_P0_TX_BUF_C_DN(7)    I15 @T6G_MB_LIB.T6G(SCH_1):PAGE320
    H7    GND @T6G_MB_LIB.T6G(SCH_1):GND    I15 @T6G_MB_LIB.T6G(SCH_1):PAGE320
    H6 P5E_CPU0_P0_TX_BUF_C_DN<5> @T6G_MB_LIB.T6G(SCH_1):P5E_CPU0_P0_TX_BUF_C_DN(5)    I15 @T6G_MB_LIB.T6G(SCH_1):PAGE320
    H5    GND @T6G_MB_LIB.T6G(SCH_1):GND    I15 @T6G_MB_LIB.T6G(SCH_1):PAGE320
    I8 P5E_CPU0_P0_TX_BUF_C_DP<7> @T6G_MB_LIB.T6G(SCH_1):P5E_CPU0_P0_TX_BUF_C_DP(7)    I15 @T6G_MB_LIB.T6G(SCH_1):PAGE320
    I7 P5E_CPU0_P0_TX_BUF_C_DN<6> @T6G_MB_LIB.T6G(SCH_1):P5E_CPU0_P0_TX_BUF_C_DN(6)    I15 @T6G_MB_LIB.T6G(SCH_1):PAGE320
    I6 P5E_CPU0_P0_TX_BUF_C_DP<5> @T6G_MB_LIB.T6G(SCH_1):P5E_CPU0_P0_TX_BUF_C_DP(5)    I15 @T6G_MB_LIB.T6G(SCH_1):PAGE320
    I5 P5E_CPU0_P0_TX_BUF_C_DN<4> @T6G_MB_LIB.T6G(SCH_1):P5E_CPU0_P0_TX_BUF_C_DN(4)    I15 @T6G_MB_LIB.T6G(SCH_1):PAGE320
    J8    GND @T6G_MB_LIB.T6G(SCH_1):GND    I15 @T6G_MB_LIB.T6G(SCH_1):PAGE320
    J7 P5E_CPU0_P0_TX_BUF_C_DP<6> @T6G_MB_LIB.T6G(SCH_1):P5E_CPU0_P0_TX_BUF_C_DP(6)    I15 @T6G_MB_LIB.T6G(SCH_1):PAGE320
    J6    GND @T6G_MB_LIB.T6G(SCH_1):GND    I15 @T6G_MB_LIB.T6G(SCH_1):PAGE320
    J5 P5E_CPU0_P0_TX_BUF_C_DP<4> @T6G_MB_LIB.T6G(SCH_1):P5E_CPU0_P0_TX_BUF_C_DP(4)    I15 @T6G_MB_LIB.T6G(SCH_1):PAGE320
    K8 P5E_CPU0_P1_TX_BUF_C_DN<7> @T6G_MB_LIB.T6G(SCH_1):P5E_CPU0_P1_TX_BUF_C_DN(7)    I15 @T6G_MB_LIB.T6G(SCH_1):PAGE320
    K7    GND @T6G_MB_LIB.T6G(SCH_1):GND    I15 @T6G_MB_LIB.T6G(SCH_1):PAGE320
    K6 P5E_CPU0_P1_TX_BUF_C_DN<5> @T6G_MB_LIB.T6G(SCH_1):P5E_CPU0_P1_TX_BUF_C_DN(5)    I15 @T6G_MB_LIB.T6G(SCH_1):PAGE320
    K5    GND @T6G_MB_LIB.T6G(SCH_1):GND    I15 @T6G_MB_LIB.T6G(SCH_1):PAGE320
    L8 P5E_CPU0_P1_TX_BUF_C_DP<7> @T6G_MB_LIB.T6G(SCH_1):P5E_CPU0_P1_TX_BUF_C_DP(7)    I15 @T6G_MB_LIB.T6G(SCH_1):PAGE320
    L7 P5E_CPU0_P1_TX_BUF_C_DN<6> @T6G_MB_LIB.T6G(SCH_1):P5E_CPU0_P1_TX_BUF_C_DN(6)    I15 @T6G_MB_LIB.T6G(SCH_1):PAGE320
    L6 P5E_CPU0_P1_TX_BUF_C_DP<5> @T6G_MB_LIB.T6G(SCH_1):P5E_CPU0_P1_TX_BUF_C_DP(5)    I15 @T6G_MB_LIB.T6G(SCH_1):PAGE320
    L5 P5E_CPU0_P1_TX_BUF_C_DN<4> @T6G_MB_LIB.T6G(SCH_1):P5E_CPU0_P1_TX_BUF_C_DN(4)    I15 @T6G_MB_LIB.T6G(SCH_1):PAGE320
    M5 P5E_CPU0_P1_TX_BUF_C_DP<4> @T6G_MB_LIB.T6G(SCH_1):P5E_CPU0_P1_TX_BUF_C_DP(4)    I15 @T6G_MB_LIB.T6G(SCH_1):PAGE320
    N5    GND @T6G_MB_LIB.T6G(SCH_1):GND    I15 @T6G_MB_LIB.T6G(SCH_1):PAGE320
    M6    GND @T6G_MB_LIB.T6G(SCH_1):GND    I15 @T6G_MB_LIB.T6G(SCH_1):PAGE320
    N6 NC_J108_N6 @T6G_MB_LIB.T6G(SCH_1):NC_J108_N6    I15 @T6G_MB_LIB.T6G(SCH_1):PAGE320
    M7 P5E_CPU0_P1_TX_BUF_C_DP<6> @T6G_MB_LIB.T6G(SCH_1):P5E_CPU0_P1_TX_BUF_C_DP(6)    I15 @T6G_MB_LIB.T6G(SCH_1):PAGE320
    N7    GND @T6G_MB_LIB.T6G(SCH_1):GND    I15 @T6G_MB_LIB.T6G(SCH_1):PAGE320
    M8    GND @T6G_MB_LIB.T6G(SCH_1):GND    I15 @T6G_MB_LIB.T6G(SCH_1):PAGE320
    N8 PRSNT_CABLE_GPU_A3_N @T6G_MB_LIB.T6G(SCH_1):PRSNT_CABLE_GPU_A3_N    I15 @T6G_MB_LIB.T6G(SCH_1):PAGE320
    A4    GND @T6G_MB_LIB.T6G(SCH_1):GND    I72 @T6G_MB_LIB.T6G(SCH_1):PAGE320
    A3 PRSNT_CABLE_GPU_A2_N @T6G_MB_LIB.T6G(SCH_1):PRSNT_CABLE_GPU_A2_N    I72 @T6G_MB_LIB.T6G(SCH_1):PAGE320
    A2    GND @T6G_MB_LIB.T6G(SCH_1):GND    I72 @T6G_MB_LIB.T6G(SCH_1):PAGE320
    A1 GPU_3V3IO_RSVD3_FFU @T6G_MB_LIB.T6G(SCH_1):GPU_3V3IO_RSVD3_FFU    I72 @T6G_MB_LIB.T6G(SCH_1):PAGE320
    B4 P5E_CPU0_P0_RX_BUF_DN<3> @T6G_MB_LIB.T6G(SCH_1):P5E_CPU0_P0_RX_BUF_DN(3)    I72 @T6G_MB_LIB.T6G(SCH_1):PAGE320
    B3    GND @T6G_MB_LIB.T6G(SCH_1):GND    I72 @T6G_MB_LIB.T6G(SCH_1):PAGE320
    B2 P5E_CPU0_P0_RX_BUF_DN<1> @T6G_MB_LIB.T6G(SCH_1):P5E_CPU0_P0_RX_BUF_DN(1)    I72 @T6G_MB_LIB.T6G(SCH_1):PAGE320
    B1    GND @T6G_MB_LIB.T6G(SCH_1):GND    I72 @T6G_MB_LIB.T6G(SCH_1):PAGE320
    C4 P5E_CPU0_P0_RX_BUF_DP<3> @T6G_MB_LIB.T6G(SCH_1):P5E_CPU0_P0_RX_BUF_DP(3)    I72 @T6G_MB_LIB.T6G(SCH_1):PAGE320
    C3 P5E_CPU0_P0_RX_BUF_DN<2> @T6G_MB_LIB.T6G(SCH_1):P5E_CPU0_P0_RX_BUF_DN(2)    I72 @T6G_MB_LIB.T6G(SCH_1):PAGE320
    C2 P5E_CPU0_P0_RX_BUF_DP<1> @T6G_MB_LIB.T6G(SCH_1):P5E_CPU0_P0_RX_BUF_DP(1)    I72 @T6G_MB_LIB.T6G(SCH_1):PAGE320
    C1 P5E_CPU0_P0_RX_BUF_DN<0> @T6G_MB_LIB.T6G(SCH_1):P5E_CPU0_P0_RX_BUF_DN(0)    I72 @T6G_MB_LIB.T6G(SCH_1):PAGE320
    D4    GND @T6G_MB_LIB.T6G(SCH_1):GND    I72 @T6G_MB_LIB.T6G(SCH_1):PAGE320
    D3 P5E_CPU0_P0_RX_BUF_DP<2> @T6G_MB_LIB.T6G(SCH_1):P5E_CPU0_P0_RX_BUF_DP(2)    I72 @T6G_MB_LIB.T6G(SCH_1):PAGE320
    D2    GND @T6G_MB_LIB.T6G(SCH_1):GND    I72 @T6G_MB_LIB.T6G(SCH_1):PAGE320
    D1 P5E_CPU0_P0_RX_BUF_DP<0> @T6G_MB_LIB.T6G(SCH_1):P5E_CPU0_P0_RX_BUF_DP(0)    I72 @T6G_MB_LIB.T6G(SCH_1):PAGE320
    E4 P5E_CPU0_P1_RX_BUF_DN<3> @T6G_MB_LIB.T6G(SCH_1):P5E_CPU0_P1_RX_BUF_DN(3)    I72 @T6G_MB_LIB.T6G(SCH_1):PAGE320
    E3    GND @T6G_MB_LIB.T6G(SCH_1):GND    I72 @T6G_MB_LIB.T6G(SCH_1):PAGE320
    E2 P5E_CPU0_P1_RX_BUF_DN<1> @T6G_MB_LIB.T6G(SCH_1):P5E_CPU0_P1_RX_BUF_DN(1)    I72 @T6G_MB_LIB.T6G(SCH_1):PAGE320
    E1    GND @T6G_MB_LIB.T6G(SCH_1):GND    I72 @T6G_MB_LIB.T6G(SCH_1):PAGE320
    F4 P5E_CPU0_P1_RX_BUF_DP<3> @T6G_MB_LIB.T6G(SCH_1):P5E_CPU0_P1_RX_BUF_DP(3)    I72 @T6G_MB_LIB.T6G(SCH_1):PAGE320
    F3 P5E_CPU0_P1_RX_BUF_DN<2> @T6G_MB_LIB.T6G(SCH_1):P5E_CPU0_P1_RX_BUF_DN(2)    I72 @T6G_MB_LIB.T6G(SCH_1):PAGE320
    F2 P5E_CPU0_P1_RX_BUF_DP<1> @T6G_MB_LIB.T6G(SCH_1):P5E_CPU0_P1_RX_BUF_DP(1)    I72 @T6G_MB_LIB.T6G(SCH_1):PAGE320
    F1 P5E_CPU0_P1_RX_BUF_DN<0> @T6G_MB_LIB.T6G(SCH_1):P5E_CPU0_P1_RX_BUF_DN(0)    I72 @T6G_MB_LIB.T6G(SCH_1):PAGE320
    G4    GND @T6G_MB_LIB.T6G(SCH_1):GND    I72 @T6G_MB_LIB.T6G(SCH_1):PAGE320
    G3 P5E_CPU0_P1_RX_BUF_DP<2> @T6G_MB_LIB.T6G(SCH_1):P5E_CPU0_P1_RX_BUF_DP(2)    I72 @T6G_MB_LIB.T6G(SCH_1):PAGE320
    G2    GND @T6G_MB_LIB.T6G(SCH_1):GND    I72 @T6G_MB_LIB.T6G(SCH_1):PAGE320
    G1 P5E_CPU0_P1_RX_BUF_DP<0> @T6G_MB_LIB.T6G(SCH_1):P5E_CPU0_P1_RX_BUF_DP(0)    I72 @T6G_MB_LIB.T6G(SCH_1):PAGE320
    H4 P5E_CPU0_P0_TX_BUF_C_DN<3> @T6G_MB_LIB.T6G(SCH_1):P5E_CPU0_P0_TX_BUF_C_DN(3)    I72 @T6G_MB_LIB.T6G(SCH_1):PAGE320
    H3    GND @T6G_MB_LIB.T6G(SCH_1):GND    I72 @T6G_MB_LIB.T6G(SCH_1):PAGE320
    H2 P5E_CPU0_P0_TX_BUF_C_DN<1> @T6G_MB_LIB.T6G(SCH_1):P5E_CPU0_P0_TX_BUF_C_DN(1)    I72 @T6G_MB_LIB.T6G(SCH_1):PAGE320
    H1    GND @T6G_MB_LIB.T6G(SCH_1):GND    I72 @T6G_MB_LIB.T6G(SCH_1):PAGE320
    I4 P5E_CPU0_P0_TX_BUF_C_DP<3> @T6G_MB_LIB.T6G(SCH_1):P5E_CPU0_P0_TX_BUF_C_DP(3)    I72 @T6G_MB_LIB.T6G(SCH_1):PAGE320
    I3 P5E_CPU0_P0_TX_BUF_C_DN<2> @T6G_MB_LIB.T6G(SCH_1):P5E_CPU0_P0_TX_BUF_C_DN(2)    I72 @T6G_MB_LIB.T6G(SCH_1):PAGE320
    I2 P5E_CPU0_P0_TX_BUF_C_DP<1> @T6G_MB_LIB.T6G(SCH_1):P5E_CPU0_P0_TX_BUF_C_DP(1)    I72 @T6G_MB_LIB.T6G(SCH_1):PAGE320
    I1 P5E_CPU0_P0_TX_BUF_C_DN<0> @T6G_MB_LIB.T6G(SCH_1):P5E_CPU0_P0_TX_BUF_C_DN(0)    I72 @T6G_MB_LIB.T6G(SCH_1):PAGE320
    J4    GND @T6G_MB_LIB.T6G(SCH_1):GND    I72 @T6G_MB_LIB.T6G(SCH_1):PAGE320
    J3 P5E_CPU0_P0_TX_BUF_C_DP<2> @T6G_MB_LIB.T6G(SCH_1):P5E_CPU0_P0_TX_BUF_C_DP(2)    I72 @T6G_MB_LIB.T6G(SCH_1):PAGE320
    J2    GND @T6G_MB_LIB.T6G(SCH_1):GND    I72 @T6G_MB_LIB.T6G(SCH_1):PAGE320
    J1 P5E_CPU0_P0_TX_BUF_C_DP<0> @T6G_MB_LIB.T6G(SCH_1):P5E_CPU0_P0_TX_BUF_C_DP(0)    I72 @T6G_MB_LIB.T6G(SCH_1):PAGE320
    K4 P5E_CPU0_P1_TX_BUF_C_DN<3> @T6G_MB_LIB.T6G(SCH_1):P5E_CPU0_P1_TX_BUF_C_DN(3)    I72 @T6G_MB_LIB.T6G(SCH_1):PAGE320
    K3    GND @T6G_MB_LIB.T6G(SCH_1):GND    I72 @T6G_MB_LIB.T6G(SCH_1):PAGE320
    K2 P5E_CPU0_P1_TX_BUF_C_DN<1> @T6G_MB_LIB.T6G(SCH_1):P5E_CPU0_P1_TX_BUF_C_DN(1)    I72 @T6G_MB_LIB.T6G(SCH_1):PAGE320
    K1    GND @T6G_MB_LIB.T6G(SCH_1):GND    I72 @T6G_MB_LIB.T6G(SCH_1):PAGE320
    L4 P5E_CPU0_P1_TX_BUF_C_DP<3> @T6G_MB_LIB.T6G(SCH_1):P5E_CPU0_P1_TX_BUF_C_DP(3)    I72 @T6G_MB_LIB.T6G(SCH_1):PAGE320
    L3 P5E_CPU0_P1_TX_BUF_C_DN<2> @T6G_MB_LIB.T6G(SCH_1):P5E_CPU0_P1_TX_BUF_C_DN(2)    I72 @T6G_MB_LIB.T6G(SCH_1):PAGE320
    L2 P5E_CPU0_P1_TX_BUF_C_DP<1> @T6G_MB_LIB.T6G(SCH_1):P5E_CPU0_P1_TX_BUF_C_DP(1)    I72 @T6G_MB_LIB.T6G(SCH_1):PAGE320
    L1 P5E_CPU0_P1_TX_BUF_C_DN<0> @T6G_MB_LIB.T6G(SCH_1):P5E_CPU0_P1_TX_BUF_C_DN(0)    I72 @T6G_MB_LIB.T6G(SCH_1):PAGE320
    M1 P5E_CPU0_P1_TX_BUF_C_DP<0> @T6G_MB_LIB.T6G(SCH_1):P5E_CPU0_P1_TX_BUF_C_DP(0)    I72 @T6G_MB_LIB.T6G(SCH_1):PAGE320
    N1    GND @T6G_MB_LIB.T6G(SCH_1):GND    I72 @T6G_MB_LIB.T6G(SCH_1):PAGE320
    M2    GND @T6G_MB_LIB.T6G(SCH_1):GND    I72 @T6G_MB_LIB.T6G(SCH_1):PAGE320
    N2 NC_J108_N2 @T6G_MB_LIB.T6G(SCH_1):NC_J108_N2    I72 @T6G_MB_LIB.T6G(SCH_1):PAGE320
    M3 P5E_CPU0_P1_TX_BUF_C_DP<2> @T6G_MB_LIB.T6G(SCH_1):P5E_CPU0_P1_TX_BUF_C_DP(2)    I72 @T6G_MB_LIB.T6G(SCH_1):PAGE320
    N3    GND @T6G_MB_LIB.T6G(SCH_1):GND    I72 @T6G_MB_LIB.T6G(SCH_1):PAGE320
    M4    GND @T6G_MB_LIB.T6G(SCH_1):GND    I72 @T6G_MB_LIB.T6G(SCH_1):PAGE320
    N4 NC_J108_N4 @T6G_MB_LIB.T6G(SCH_1):NC_J108_N4    I72 @T6G_MB_LIB.T6G(SCH_1):PAGE320

J109 CONN112_10137002101LF-CONN112_10137002-101LF,THLF,A
    A8    GND @T6G_MB_LIB.T6G(SCH_1):GND    I16 @T6G_MB_LIB.T6G(SCH_1):PAGE319
    A7 SMB_BMC_SWB_BUF_SDA @T6G_MB_LIB.T6G(SCH_1):SMB_BMC_SWB_BUF_SDA    I16 @T6G_MB_LIB.T6G(SCH_1):PAGE319
    A6    GND @T6G_MB_LIB.T6G(SCH_1):GND    I16 @T6G_MB_LIB.T6G(SCH_1):PAGE319
    A5 SMB_BMC_SWB_BUF_SCL @T6G_MB_LIB.T6G(SCH_1):SMB_BMC_SWB_BUF_SCL    I16 @T6G_MB_LIB.T6G(SCH_1):PAGE319
    B8 P5E_CPU1_P2_RX_BUF_DN<15> @T6G_MB_LIB.T6G(SCH_1):P5E_CPU1_P2_RX_BUF_DN(15)    I16 @T6G_MB_LIB.T6G(SCH_1):PAGE319
    B7    GND @T6G_MB_LIB.T6G(SCH_1):GND    I16 @T6G_MB_LIB.T6G(SCH_1):PAGE319
    B6 P5E_CPU1_P2_RX_BUF_DN<13> @T6G_MB_LIB.T6G(SCH_1):P5E_CPU1_P2_RX_BUF_DN(13)    I16 @T6G_MB_LIB.T6G(SCH_1):PAGE319
    B5    GND @T6G_MB_LIB.T6G(SCH_1):GND    I16 @T6G_MB_LIB.T6G(SCH_1):PAGE319
    C8 P5E_CPU1_P2_RX_BUF_DP<15> @T6G_MB_LIB.T6G(SCH_1):P5E_CPU1_P2_RX_BUF_DP(15)    I16 @T6G_MB_LIB.T6G(SCH_1):PAGE319
    C7 P5E_CPU1_P2_RX_BUF_DN<14> @T6G_MB_LIB.T6G(SCH_1):P5E_CPU1_P2_RX_BUF_DN(14)    I16 @T6G_MB_LIB.T6G(SCH_1):PAGE319
    C6 P5E_CPU1_P2_RX_BUF_DP<13> @T6G_MB_LIB.T6G(SCH_1):P5E_CPU1_P2_RX_BUF_DP(13)    I16 @T6G_MB_LIB.T6G(SCH_1):PAGE319
    C5 P5E_CPU1_P2_RX_BUF_DN<12> @T6G_MB_LIB.T6G(SCH_1):P5E_CPU1_P2_RX_BUF_DN(12)    I16 @T6G_MB_LIB.T6G(SCH_1):PAGE319
    D8    GND @T6G_MB_LIB.T6G(SCH_1):GND    I16 @T6G_MB_LIB.T6G(SCH_1):PAGE319
    D7 P5E_CPU1_P2_RX_BUF_DP<14> @T6G_MB_LIB.T6G(SCH_1):P5E_CPU1_P2_RX_BUF_DP(14)    I16 @T6G_MB_LIB.T6G(SCH_1):PAGE319
    D6    GND @T6G_MB_LIB.T6G(SCH_1):GND    I16 @T6G_MB_LIB.T6G(SCH_1):PAGE319
    D5 P5E_CPU1_P2_RX_BUF_DP<12> @T6G_MB_LIB.T6G(SCH_1):P5E_CPU1_P2_RX_BUF_DP(12)    I16 @T6G_MB_LIB.T6G(SCH_1):PAGE319
    E8 P5E_CPU1_P3_RX_BUF_DN<15> @T6G_MB_LIB.T6G(SCH_1):P5E_CPU1_P3_RX_BUF_DN(15)    I16 @T6G_MB_LIB.T6G(SCH_1):PAGE319
    E7    GND @T6G_MB_LIB.T6G(SCH_1):GND    I16 @T6G_MB_LIB.T6G(SCH_1):PAGE319
    E6 P5E_CPU1_P3_RX_BUF_DN<13> @T6G_MB_LIB.T6G(SCH_1):P5E_CPU1_P3_RX_BUF_DN(13)    I16 @T6G_MB_LIB.T6G(SCH_1):PAGE319
    E5    GND @T6G_MB_LIB.T6G(SCH_1):GND    I16 @T6G_MB_LIB.T6G(SCH_1):PAGE319
    F8 P5E_CPU1_P3_RX_BUF_DP<15> @T6G_MB_LIB.T6G(SCH_1):P5E_CPU1_P3_RX_BUF_DP(15)    I16 @T6G_MB_LIB.T6G(SCH_1):PAGE319
    F7 P5E_CPU1_P3_RX_BUF_DN<14> @T6G_MB_LIB.T6G(SCH_1):P5E_CPU1_P3_RX_BUF_DN(14)    I16 @T6G_MB_LIB.T6G(SCH_1):PAGE319
    F6 P5E_CPU1_P3_RX_BUF_DP<13> @T6G_MB_LIB.T6G(SCH_1):P5E_CPU1_P3_RX_BUF_DP(13)    I16 @T6G_MB_LIB.T6G(SCH_1):PAGE319
    F5 P5E_CPU1_P3_RX_BUF_DN<12> @T6G_MB_LIB.T6G(SCH_1):P5E_CPU1_P3_RX_BUF_DN(12)    I16 @T6G_MB_LIB.T6G(SCH_1):PAGE319
    G8    GND @T6G_MB_LIB.T6G(SCH_1):GND    I16 @T6G_MB_LIB.T6G(SCH_1):PAGE319
    G7 P5E_CPU1_P3_RX_BUF_DP<14> @T6G_MB_LIB.T6G(SCH_1):P5E_CPU1_P3_RX_BUF_DP(14)    I16 @T6G_MB_LIB.T6G(SCH_1):PAGE319
    G6    GND @T6G_MB_LIB.T6G(SCH_1):GND    I16 @T6G_MB_LIB.T6G(SCH_1):PAGE319
    G5 P5E_CPU1_P3_RX_BUF_DP<12> @T6G_MB_LIB.T6G(SCH_1):P5E_CPU1_P3_RX_BUF_DP(12)    I16 @T6G_MB_LIB.T6G(SCH_1):PAGE319
    H8 P5E_CPU1_P2_TX_BUF_C_DN<15> @T6G_MB_LIB.T6G(SCH_1):P5E_CPU1_P2_TX_BUF_C_DN(15)    I16 @T6G_MB_LIB.T6G(SCH_1):PAGE319
    H7    GND @T6G_MB_LIB.T6G(SCH_1):GND    I16 @T6G_MB_LIB.T6G(SCH_1):PAGE319
    H6 P5E_CPU1_P2_TX_BUF_C_DN<13> @T6G_MB_LIB.T6G(SCH_1):P5E_CPU1_P2_TX_BUF_C_DN(13)    I16 @T6G_MB_LIB.T6G(SCH_1):PAGE319
    H5    GND @T6G_MB_LIB.T6G(SCH_1):GND    I16 @T6G_MB_LIB.T6G(SCH_1):PAGE319
    I8 P5E_CPU1_P2_TX_BUF_C_DP<15> @T6G_MB_LIB.T6G(SCH_1):P5E_CPU1_P2_TX_BUF_C_DP(15)    I16 @T6G_MB_LIB.T6G(SCH_1):PAGE319
    I7 P5E_CPU1_P2_TX_BUF_C_DN<14> @T6G_MB_LIB.T6G(SCH_1):P5E_CPU1_P2_TX_BUF_C_DN(14)    I16 @T6G_MB_LIB.T6G(SCH_1):PAGE319
    I6 P5E_CPU1_P2_TX_BUF_C_DP<13> @T6G_MB_LIB.T6G(SCH_1):P5E_CPU1_P2_TX_BUF_C_DP(13)    I16 @T6G_MB_LIB.T6G(SCH_1):PAGE319
    I5 P5E_CPU1_P2_TX_BUF_C_DN<12> @T6G_MB_LIB.T6G(SCH_1):P5E_CPU1_P2_TX_BUF_C_DN(12)    I16 @T6G_MB_LIB.T6G(SCH_1):PAGE319
    J8    GND @T6G_MB_LIB.T6G(SCH_1):GND    I16 @T6G_MB_LIB.T6G(SCH_1):PAGE319
    J7 P5E_CPU1_P2_TX_BUF_C_DP<14> @T6G_MB_LIB.T6G(SCH_1):P5E_CPU1_P2_TX_BUF_C_DP(14)    I16 @T6G_MB_LIB.T6G(SCH_1):PAGE319
    J6    GND @T6G_MB_LIB.T6G(SCH_1):GND    I16 @T6G_MB_LIB.T6G(SCH_1):PAGE319
    J5 P5E_CPU1_P2_TX_BUF_C_DP<12> @T6G_MB_LIB.T6G(SCH_1):P5E_CPU1_P2_TX_BUF_C_DP(12)    I16 @T6G_MB_LIB.T6G(SCH_1):PAGE319
    K8 P5E_CPU1_P3_TX_BUF_C_DN<15> @T6G_MB_LIB.T6G(SCH_1):P5E_CPU1_P3_TX_BUF_C_DN(15)    I16 @T6G_MB_LIB.T6G(SCH_1):PAGE319
    K7    GND @T6G_MB_LIB.T6G(SCH_1):GND    I16 @T6G_MB_LIB.T6G(SCH_1):PAGE319
    K6 P5E_CPU1_P3_TX_BUF_C_DN<13> @T6G_MB_LIB.T6G(SCH_1):P5E_CPU1_P3_TX_BUF_C_DN(13)    I16 @T6G_MB_LIB.T6G(SCH_1):PAGE319
    K5    GND @T6G_MB_LIB.T6G(SCH_1):GND    I16 @T6G_MB_LIB.T6G(SCH_1):PAGE319
    L8 P5E_CPU1_P3_TX_BUF_C_DP<15> @T6G_MB_LIB.T6G(SCH_1):P5E_CPU1_P3_TX_BUF_C_DP(15)    I16 @T6G_MB_LIB.T6G(SCH_1):PAGE319
    L7 P5E_CPU1_P3_TX_BUF_C_DN<14> @T6G_MB_LIB.T6G(SCH_1):P5E_CPU1_P3_TX_BUF_C_DN(14)    I16 @T6G_MB_LIB.T6G(SCH_1):PAGE319
    L6 P5E_CPU1_P3_TX_BUF_C_DP<13> @T6G_MB_LIB.T6G(SCH_1):P5E_CPU1_P3_TX_BUF_C_DP(13)    I16 @T6G_MB_LIB.T6G(SCH_1):PAGE319
    L5 P5E_CPU1_P3_TX_BUF_C_DN<12> @T6G_MB_LIB.T6G(SCH_1):P5E_CPU1_P3_TX_BUF_C_DN(12)    I16 @T6G_MB_LIB.T6G(SCH_1):PAGE319
    M5 P5E_CPU1_P3_TX_BUF_C_DP<12> @T6G_MB_LIB.T6G(SCH_1):P5E_CPU1_P3_TX_BUF_C_DP(12)    I16 @T6G_MB_LIB.T6G(SCH_1):PAGE319
    N5    GND @T6G_MB_LIB.T6G(SCH_1):GND    I16 @T6G_MB_LIB.T6G(SCH_1):PAGE319
    M6    GND @T6G_MB_LIB.T6G(SCH_1):GND    I16 @T6G_MB_LIB.T6G(SCH_1):PAGE319
    N6 GPU_3V3IO_RSVD1_FFU @T6G_MB_LIB.T6G(SCH_1):GPU_3V3IO_RSVD1_FFU    I16 @T6G_MB_LIB.T6G(SCH_1):PAGE319
    M7 P5E_CPU1_P3_TX_BUF_C_DP<14> @T6G_MB_LIB.T6G(SCH_1):P5E_CPU1_P3_TX_BUF_C_DP(14)    I16 @T6G_MB_LIB.T6G(SCH_1):PAGE319
    N7    GND @T6G_MB_LIB.T6G(SCH_1):GND    I16 @T6G_MB_LIB.T6G(SCH_1):PAGE319
    M8    GND @T6G_MB_LIB.T6G(SCH_1):GND    I16 @T6G_MB_LIB.T6G(SCH_1):PAGE319
    N8 PRSNT_CABLE_GPU_B3_N @T6G_MB_LIB.T6G(SCH_1):PRSNT_CABLE_GPU_B3_N    I16 @T6G_MB_LIB.T6G(SCH_1):PAGE319
    A4    GND @T6G_MB_LIB.T6G(SCH_1):GND    I76 @T6G_MB_LIB.T6G(SCH_1):PAGE319
    A3 BIC_MONITER @T6G_MB_LIB.T6G(SCH_1):BIC_MONITER    I76 @T6G_MB_LIB.T6G(SCH_1):PAGE319
    A2    GND @T6G_MB_LIB.T6G(SCH_1):GND    I76 @T6G_MB_LIB.T6G(SCH_1):PAGE319
    A1 BMC_MONITER_BUF @T6G_MB_LIB.T6G(SCH_1):BMC_MONITER_BUF    I76 @T6G_MB_LIB.T6G(SCH_1):PAGE319
    B4 P5E_CPU1_P2_RX_BUF_DN<11> @T6G_MB_LIB.T6G(SCH_1):P5E_CPU1_P2_RX_BUF_DN(11)    I76 @T6G_MB_LIB.T6G(SCH_1):PAGE319
    B3    GND @T6G_MB_LIB.T6G(SCH_1):GND    I76 @T6G_MB_LIB.T6G(SCH_1):PAGE319
    B2 P5E_CPU1_P2_RX_BUF_DN<9> @T6G_MB_LIB.T6G(SCH_1):P5E_CPU1_P2_RX_BUF_DN(9)    I76 @T6G_MB_LIB.T6G(SCH_1):PAGE319
    B1    GND @T6G_MB_LIB.T6G(SCH_1):GND    I76 @T6G_MB_LIB.T6G(SCH_1):PAGE319
    C4 P5E_CPU1_P2_RX_BUF_DP<11> @T6G_MB_LIB.T6G(SCH_1):P5E_CPU1_P2_RX_BUF_DP(11)    I76 @T6G_MB_LIB.T6G(SCH_1):PAGE319
    C3 P5E_CPU1_P2_RX_BUF_DN<10> @T6G_MB_LIB.T6G(SCH_1):P5E_CPU1_P2_RX_BUF_DN(10)    I76 @T6G_MB_LIB.T6G(SCH_1):PAGE319
    C2 P5E_CPU1_P2_RX_BUF_DP<9> @T6G_MB_LIB.T6G(SCH_1):P5E_CPU1_P2_RX_BUF_DP(9)    I76 @T6G_MB_LIB.T6G(SCH_1):PAGE319
    C1 P5E_CPU1_P2_RX_BUF_DN<8> @T6G_MB_LIB.T6G(SCH_1):P5E_CPU1_P2_RX_BUF_DN(8)    I76 @T6G_MB_LIB.T6G(SCH_1):PAGE319
    D4    GND @T6G_MB_LIB.T6G(SCH_1):GND    I76 @T6G_MB_LIB.T6G(SCH_1):PAGE319
    D3 P5E_CPU1_P2_RX_BUF_DP<10> @T6G_MB_LIB.T6G(SCH_1):P5E_CPU1_P2_RX_BUF_DP(10)    I76 @T6G_MB_LIB.T6G(SCH_1):PAGE319
    D2    GND @T6G_MB_LIB.T6G(SCH_1):GND    I76 @T6G_MB_LIB.T6G(SCH_1):PAGE319
    D1 P5E_CPU1_P2_RX_BUF_DP<8> @T6G_MB_LIB.T6G(SCH_1):P5E_CPU1_P2_RX_BUF_DP(8)    I76 @T6G_MB_LIB.T6G(SCH_1):PAGE319
    E4 P5E_CPU1_P3_RX_BUF_DN<11> @T6G_MB_LIB.T6G(SCH_1):P5E_CPU1_P3_RX_BUF_DN(11)    I76 @T6G_MB_LIB.T6G(SCH_1):PAGE319
    E3    GND @T6G_MB_LIB.T6G(SCH_1):GND    I76 @T6G_MB_LIB.T6G(SCH_1):PAGE319
    E2 P5E_CPU1_P3_RX_BUF_DN<9> @T6G_MB_LIB.T6G(SCH_1):P5E_CPU1_P3_RX_BUF_DN(9)    I76 @T6G_MB_LIB.T6G(SCH_1):PAGE319
    E1    GND @T6G_MB_LIB.T6G(SCH_1):GND    I76 @T6G_MB_LIB.T6G(SCH_1):PAGE319
    F4 P5E_CPU1_P3_RX_BUF_DP<11> @T6G_MB_LIB.T6G(SCH_1):P5E_CPU1_P3_RX_BUF_DP(11)    I76 @T6G_MB_LIB.T6G(SCH_1):PAGE319
    F3 P5E_CPU1_P3_RX_BUF_DN<10> @T6G_MB_LIB.T6G(SCH_1):P5E_CPU1_P3_RX_BUF_DN(10)    I76 @T6G_MB_LIB.T6G(SCH_1):PAGE319
    F2 P5E_CPU1_P3_RX_BUF_DP<9> @T6G_MB_LIB.T6G(SCH_1):P5E_CPU1_P3_RX_BUF_DP(9)    I76 @T6G_MB_LIB.T6G(SCH_1):PAGE319
    F1 P5E_CPU1_P3_RX_BUF_DN<8> @T6G_MB_LIB.T6G(SCH_1):P5E_CPU1_P3_RX_BUF_DN(8)    I76 @T6G_MB_LIB.T6G(SCH_1):PAGE319
    G4    GND @T6G_MB_LIB.T6G(SCH_1):GND    I76 @T6G_MB_LIB.T6G(SCH_1):PAGE319
    G3 P5E_CPU1_P3_RX_BUF_DP<10> @T6G_MB_LIB.T6G(SCH_1):P5E_CPU1_P3_RX_BUF_DP(10)    I76 @T6G_MB_LIB.T6G(SCH_1):PAGE319
    G2    GND @T6G_MB_LIB.T6G(SCH_1):GND    I76 @T6G_MB_LIB.T6G(SCH_1):PAGE319
    G1 P5E_CPU1_P3_RX_BUF_DP<8> @T6G_MB_LIB.T6G(SCH_1):P5E_CPU1_P3_RX_BUF_DP(8)    I76 @T6G_MB_LIB.T6G(SCH_1):PAGE319
    H4 P5E_CPU1_P2_TX_BUF_C_DN<11> @T6G_MB_LIB.T6G(SCH_1):P5E_CPU1_P2_TX_BUF_C_DN(11)    I76 @T6G_MB_LIB.T6G(SCH_1):PAGE319
    H3    GND @T6G_MB_LIB.T6G(SCH_1):GND    I76 @T6G_MB_LIB.T6G(SCH_1):PAGE319
    H2 P5E_CPU1_P2_TX_BUF_C_DN<9> @T6G_MB_LIB.T6G(SCH_1):P5E_CPU1_P2_TX_BUF_C_DN(9)    I76 @T6G_MB_LIB.T6G(SCH_1):PAGE319
    H1    GND @T6G_MB_LIB.T6G(SCH_1):GND    I76 @T6G_MB_LIB.T6G(SCH_1):PAGE319
    I4 P5E_CPU1_P2_TX_BUF_C_DP<11> @T6G_MB_LIB.T6G(SCH_1):P5E_CPU1_P2_TX_BUF_C_DP(11)    I76 @T6G_MB_LIB.T6G(SCH_1):PAGE319
    I3 P5E_CPU1_P2_TX_BUF_C_DN<10> @T6G_MB_LIB.T6G(SCH_1):P5E_CPU1_P2_TX_BUF_C_DN(10)    I76 @T6G_MB_LIB.T6G(SCH_1):PAGE319
    I2 P5E_CPU1_P2_TX_BUF_C_DP<9> @T6G_MB_LIB.T6G(SCH_1):P5E_CPU1_P2_TX_BUF_C_DP(9)    I76 @T6G_MB_LIB.T6G(SCH_1):PAGE319
    I1 P5E_CPU1_P2_TX_BUF_C_DN<8> @T6G_MB_LIB.T6G(SCH_1):P5E_CPU1_P2_TX_BUF_C_DN(8)    I76 @T6G_MB_LIB.T6G(SCH_1):PAGE319
    J4    GND @T6G_MB_LIB.T6G(SCH_1):GND    I76 @T6G_MB_LIB.T6G(SCH_1):PAGE319
    J3 P5E_CPU1_P2_TX_BUF_C_DP<10> @T6G_MB_LIB.T6G(SCH_1):P5E_CPU1_P2_TX_BUF_C_DP(10)    I76 @T6G_MB_LIB.T6G(SCH_1):PAGE319
    J2    GND @T6G_MB_LIB.T6G(SCH_1):GND    I76 @T6G_MB_LIB.T6G(SCH_1):PAGE319
    J1 P5E_CPU1_P2_TX_BUF_C_DP<8> @T6G_MB_LIB.T6G(SCH_1):P5E_CPU1_P2_TX_BUF_C_DP(8)    I76 @T6G_MB_LIB.T6G(SCH_1):PAGE319
    K4 P5E_CPU1_P3_TX_BUF_C_DN<11> @T6G_MB_LIB.T6G(SCH_1):P5E_CPU1_P3_TX_BUF_C_DN(11)    I76 @T6G_MB_LIB.T6G(SCH_1):PAGE319
    K3    GND @T6G_MB_LIB.T6G(SCH_1):GND    I76 @T6G_MB_LIB.T6G(SCH_1):PAGE319
    K2 P5E_CPU1_P3_TX_BUF_C_DN<9> @T6G_MB_LIB.T6G(SCH_1):P5E_CPU1_P3_TX_BUF_C_DN(9)    I76 @T6G_MB_LIB.T6G(SCH_1):PAGE319
    K1    GND @T6G_MB_LIB.T6G(SCH_1):GND    I76 @T6G_MB_LIB.T6G(SCH_1):PAGE319
    L4 P5E_CPU1_P3_TX_BUF_C_DP<11> @T6G_MB_LIB.T6G(SCH_1):P5E_CPU1_P3_TX_BUF_C_DP(11)    I76 @T6G_MB_LIB.T6G(SCH_1):PAGE319
    L3 P5E_CPU1_P3_TX_BUF_C_DN<10> @T6G_MB_LIB.T6G(SCH_1):P5E_CPU1_P3_TX_BUF_C_DN(10)    I76 @T6G_MB_LIB.T6G(SCH_1):PAGE319
    L2 P5E_CPU1_P3_TX_BUF_C_DP<9> @T6G_MB_LIB.T6G(SCH_1):P5E_CPU1_P3_TX_BUF_C_DP(9)    I76 @T6G_MB_LIB.T6G(SCH_1):PAGE319
    L1 P5E_CPU1_P3_TX_BUF_C_DN<8> @T6G_MB_LIB.T6G(SCH_1):P5E_CPU1_P3_TX_BUF_C_DN(8)    I76 @T6G_MB_LIB.T6G(SCH_1):PAGE319
    M1 P5E_CPU1_P3_TX_BUF_C_DP<8> @T6G_MB_LIB.T6G(SCH_1):P5E_CPU1_P3_TX_BUF_C_DP(8)    I76 @T6G_MB_LIB.T6G(SCH_1):PAGE319
    N1    GND @T6G_MB_LIB.T6G(SCH_1):GND    I76 @T6G_MB_LIB.T6G(SCH_1):PAGE319
    M2    GND @T6G_MB_LIB.T6G(SCH_1):GND    I76 @T6G_MB_LIB.T6G(SCH_1):PAGE319
    N2 GPU_FPGA_EROT_FATALERR_N @T6G_MB_LIB.T6G(SCH_1):GPU_FPGA_EROT_FATALERR_N    I76 @T6G_MB_LIB.T6G(SCH_1):PAGE319
    M3 P5E_CPU1_P3_TX_BUF_C_DP<10> @T6G_MB_LIB.T6G(SCH_1):P5E_CPU1_P3_TX_BUF_C_DP(10)    I76 @T6G_MB_LIB.T6G(SCH_1):PAGE319
    N3    GND @T6G_MB_LIB.T6G(SCH_1):GND    I76 @T6G_MB_LIB.T6G(SCH_1):PAGE319
    M4    GND @T6G_MB_LIB.T6G(SCH_1):GND    I76 @T6G_MB_LIB.T6G(SCH_1):PAGE319
    N4 GPU_3V3IO_RSVD0_FFU @T6G_MB_LIB.T6G(SCH_1):GPU_3V3IO_RSVD0_FFU    I76 @T6G_MB_LIB.T6G(SCH_1):PAGE319

J110 CONN112_10137002101LF-CONN112_10137002-101LF,THLF,A
    A8    GND @T6G_MB_LIB.T6G(SCH_1):GND    I16 @T6G_MB_LIB.T6G(SCH_1):PAGE318
    A7 GPU_BASE_STBY_EN_BUF @T6G_MB_LIB.T6G(SCH_1):GPU_BASE_STBY_EN_BUF    I16 @T6G_MB_LIB.T6G(SCH_1):PAGE318
    A6    GND @T6G_MB_LIB.T6G(SCH_1):GND    I16 @T6G_MB_LIB.T6G(SCH_1):PAGE318
    A5 GPU_BASE_HMC_READY @T6G_MB_LIB.T6G(SCH_1):GPU_BASE_HMC_READY    I16 @T6G_MB_LIB.T6G(SCH_1):PAGE318
    B8 P5E_CPU1_P2_RX_BUF_DN<7> @T6G_MB_LIB.T6G(SCH_1):P5E_CPU1_P2_RX_BUF_DN(7)    I16 @T6G_MB_LIB.T6G(SCH_1):PAGE318
    B7    GND @T6G_MB_LIB.T6G(SCH_1):GND    I16 @T6G_MB_LIB.T6G(SCH_1):PAGE318
    B6 P5E_CPU1_P2_RX_BUF_DN<5> @T6G_MB_LIB.T6G(SCH_1):P5E_CPU1_P2_RX_BUF_DN(5)    I16 @T6G_MB_LIB.T6G(SCH_1):PAGE318
    B5    GND @T6G_MB_LIB.T6G(SCH_1):GND    I16 @T6G_MB_LIB.T6G(SCH_1):PAGE318
    C8 P5E_CPU1_P2_RX_BUF_DP<7> @T6G_MB_LIB.T6G(SCH_1):P5E_CPU1_P2_RX_BUF_DP(7)    I16 @T6G_MB_LIB.T6G(SCH_1):PAGE318
    C7 P5E_CPU1_P2_RX_BUF_DN<6> @T6G_MB_LIB.T6G(SCH_1):P5E_CPU1_P2_RX_BUF_DN(6)    I16 @T6G_MB_LIB.T6G(SCH_1):PAGE318
    C6 P5E_CPU1_P2_RX_BUF_DP<5> @T6G_MB_LIB.T6G(SCH_1):P5E_CPU1_P2_RX_BUF_DP(5)    I16 @T6G_MB_LIB.T6G(SCH_1):PAGE318
    C5 P5E_CPU1_P2_RX_BUF_DN<4> @T6G_MB_LIB.T6G(SCH_1):P5E_CPU1_P2_RX_BUF_DN(4)    I16 @T6G_MB_LIB.T6G(SCH_1):PAGE318
    D8    GND @T6G_MB_LIB.T6G(SCH_1):GND    I16 @T6G_MB_LIB.T6G(SCH_1):PAGE318
    D7 P5E_CPU1_P2_RX_BUF_DP<6> @T6G_MB_LIB.T6G(SCH_1):P5E_CPU1_P2_RX_BUF_DP(6)    I16 @T6G_MB_LIB.T6G(SCH_1):PAGE318
    D6    GND @T6G_MB_LIB.T6G(SCH_1):GND    I16 @T6G_MB_LIB.T6G(SCH_1):PAGE318
    D5 P5E_CPU1_P2_RX_BUF_DP<4> @T6G_MB_LIB.T6G(SCH_1):P5E_CPU1_P2_RX_BUF_DP(4)    I16 @T6G_MB_LIB.T6G(SCH_1):PAGE318
    E8 P5E_CPU1_P3_RX_BUF_DN<7> @T6G_MB_LIB.T6G(SCH_1):P5E_CPU1_P3_RX_BUF_DN(7)    I16 @T6G_MB_LIB.T6G(SCH_1):PAGE318
    E7    GND @T6G_MB_LIB.T6G(SCH_1):GND    I16 @T6G_MB_LIB.T6G(SCH_1):PAGE318
    E6 P5E_CPU1_P3_RX_BUF_DN<5> @T6G_MB_LIB.T6G(SCH_1):P5E_CPU1_P3_RX_BUF_DN(5)    I16 @T6G_MB_LIB.T6G(SCH_1):PAGE318
    E5    GND @T6G_MB_LIB.T6G(SCH_1):GND    I16 @T6G_MB_LIB.T6G(SCH_1):PAGE318
    F8 P5E_CPU1_P3_RX_BUF_DP<7> @T6G_MB_LIB.T6G(SCH_1):P5E_CPU1_P3_RX_BUF_DP(7)    I16 @T6G_MB_LIB.T6G(SCH_1):PAGE318
    F7 P5E_CPU1_P3_RX_BUF_DN<6> @T6G_MB_LIB.T6G(SCH_1):P5E_CPU1_P3_RX_BUF_DN(6)    I16 @T6G_MB_LIB.T6G(SCH_1):PAGE318
    F6 P5E_CPU1_P3_RX_BUF_DP<5> @T6G_MB_LIB.T6G(SCH_1):P5E_CPU1_P3_RX_BUF_DP(5)    I16 @T6G_MB_LIB.T6G(SCH_1):PAGE318
    F5 P5E_CPU1_P3_RX_BUF_DN<4> @T6G_MB_LIB.T6G(SCH_1):P5E_CPU1_P3_RX_BUF_DN(4)    I16 @T6G_MB_LIB.T6G(SCH_1):PAGE318
    G8    GND @T6G_MB_LIB.T6G(SCH_1):GND    I16 @T6G_MB_LIB.T6G(SCH_1):PAGE318
    G7 P5E_CPU1_P3_RX_BUF_DP<6> @T6G_MB_LIB.T6G(SCH_1):P5E_CPU1_P3_RX_BUF_DP(6)    I16 @T6G_MB_LIB.T6G(SCH_1):PAGE318
    G6    GND @T6G_MB_LIB.T6G(SCH_1):GND    I16 @T6G_MB_LIB.T6G(SCH_1):PAGE318
    G5 P5E_CPU1_P3_RX_BUF_DP<4> @T6G_MB_LIB.T6G(SCH_1):P5E_CPU1_P3_RX_BUF_DP(4)    I16 @T6G_MB_LIB.T6G(SCH_1):PAGE318
    H8 P5E_CPU1_P2_TX_BUF_C_DN<7> @T6G_MB_LIB.T6G(SCH_1):P5E_CPU1_P2_TX_BUF_C_DN(7)    I16 @T6G_MB_LIB.T6G(SCH_1):PAGE318
    H7    GND @T6G_MB_LIB.T6G(SCH_1):GND    I16 @T6G_MB_LIB.T6G(SCH_1):PAGE318
    H6 P5E_CPU1_P2_TX_BUF_C_DN<5> @T6G_MB_LIB.T6G(SCH_1):P5E_CPU1_P2_TX_BUF_C_DN(5)    I16 @T6G_MB_LIB.T6G(SCH_1):PAGE318
    H5    GND @T6G_MB_LIB.T6G(SCH_1):GND    I16 @T6G_MB_LIB.T6G(SCH_1):PAGE318
    I8 P5E_CPU1_P2_TX_BUF_C_DP<7> @T6G_MB_LIB.T6G(SCH_1):P5E_CPU1_P2_TX_BUF_C_DP(7)    I16 @T6G_MB_LIB.T6G(SCH_1):PAGE318
    I7 P5E_CPU1_P2_TX_BUF_C_DN<6> @T6G_MB_LIB.T6G(SCH_1):P5E_CPU1_P2_TX_BUF_C_DN(6)    I16 @T6G_MB_LIB.T6G(SCH_1):PAGE318
    I6 P5E_CPU1_P2_TX_BUF_C_DP<5> @T6G_MB_LIB.T6G(SCH_1):P5E_CPU1_P2_TX_BUF_C_DP(5)    I16 @T6G_MB_LIB.T6G(SCH_1):PAGE318
    I5 P5E_CPU1_P2_TX_BUF_C_DN<4> @T6G_MB_LIB.T6G(SCH_1):P5E_CPU1_P2_TX_BUF_C_DN(4)    I16 @T6G_MB_LIB.T6G(SCH_1):PAGE318
    J8    GND @T6G_MB_LIB.T6G(SCH_1):GND    I16 @T6G_MB_LIB.T6G(SCH_1):PAGE318
    J7 P5E_CPU1_P2_TX_BUF_C_DP<6> @T6G_MB_LIB.T6G(SCH_1):P5E_CPU1_P2_TX_BUF_C_DP(6)    I16 @T6G_MB_LIB.T6G(SCH_1):PAGE318
    J6    GND @T6G_MB_LIB.T6G(SCH_1):GND    I16 @T6G_MB_LIB.T6G(SCH_1):PAGE318
    J5 P5E_CPU1_P2_TX_BUF_C_DP<4> @T6G_MB_LIB.T6G(SCH_1):P5E_CPU1_P2_TX_BUF_C_DP(4)    I16 @T6G_MB_LIB.T6G(SCH_1):PAGE318
    K8 P5E_CPU1_P3_TX_BUF_C_DN<7> @T6G_MB_LIB.T6G(SCH_1):P5E_CPU1_P3_TX_BUF_C_DN(7)    I16 @T6G_MB_LIB.T6G(SCH_1):PAGE318
    K7    GND @T6G_MB_LIB.T6G(SCH_1):GND    I16 @T6G_MB_LIB.T6G(SCH_1):PAGE318
    K6 P5E_CPU1_P3_TX_BUF_C_DN<5> @T6G_MB_LIB.T6G(SCH_1):P5E_CPU1_P3_TX_BUF_C_DN(5)    I16 @T6G_MB_LIB.T6G(SCH_1):PAGE318
    K5    GND @T6G_MB_LIB.T6G(SCH_1):GND    I16 @T6G_MB_LIB.T6G(SCH_1):PAGE318
    L8 P5E_CPU1_P3_TX_BUF_C_DP<7> @T6G_MB_LIB.T6G(SCH_1):P5E_CPU1_P3_TX_BUF_C_DP(7)    I16 @T6G_MB_LIB.T6G(SCH_1):PAGE318
    L7 P5E_CPU1_P3_TX_BUF_C_DN<6> @T6G_MB_LIB.T6G(SCH_1):P5E_CPU1_P3_TX_BUF_C_DN(6)    I16 @T6G_MB_LIB.T6G(SCH_1):PAGE318
    L6 P5E_CPU1_P3_TX_BUF_C_DP<5> @T6G_MB_LIB.T6G(SCH_1):P5E_CPU1_P3_TX_BUF_C_DP(5)    I16 @T6G_MB_LIB.T6G(SCH_1):PAGE318
    L5 P5E_CPU1_P3_TX_BUF_C_DN<4> @T6G_MB_LIB.T6G(SCH_1):P5E_CPU1_P3_TX_BUF_C_DN(4)    I16 @T6G_MB_LIB.T6G(SCH_1):PAGE318
    M5 P5E_CPU1_P3_TX_BUF_C_DP<4> @T6G_MB_LIB.T6G(SCH_1):P5E_CPU1_P3_TX_BUF_C_DP(4)    I16 @T6G_MB_LIB.T6G(SCH_1):PAGE318
    N5    GND @T6G_MB_LIB.T6G(SCH_1):GND    I16 @T6G_MB_LIB.T6G(SCH_1):PAGE318
    M6    GND @T6G_MB_LIB.T6G(SCH_1):GND    I16 @T6G_MB_LIB.T6G(SCH_1):PAGE318
    N6 FM_SMB_2_ALERT_GPU_N @T6G_MB_LIB.T6G(SCH_1):FM_SMB_2_ALERT_GPU_N    I16 @T6G_MB_LIB.T6G(SCH_1):PAGE318
    M7 P5E_CPU1_P3_TX_BUF_C_DP<6> @T6G_MB_LIB.T6G(SCH_1):P5E_CPU1_P3_TX_BUF_C_DP(6)    I16 @T6G_MB_LIB.T6G(SCH_1):PAGE318
    N7    GND @T6G_MB_LIB.T6G(SCH_1):GND    I16 @T6G_MB_LIB.T6G(SCH_1):PAGE318
    M8    GND @T6G_MB_LIB.T6G(SCH_1):GND    I16 @T6G_MB_LIB.T6G(SCH_1):PAGE318
    N8 GPU_FPGA_EROT_RST_BUF_N @T6G_MB_LIB.T6G(SCH_1):GPU_FPGA_EROT_RST_BUF_N    I16 @T6G_MB_LIB.T6G(SCH_1):PAGE318
    A4    GND @T6G_MB_LIB.T6G(SCH_1):GND    I76 @T6G_MB_LIB.T6G(SCH_1):PAGE318
    A3 GPU_HMC_PRSNT_N @T6G_MB_LIB.T6G(SCH_1):GPU_HMC_PRSNT_N    I76 @T6G_MB_LIB.T6G(SCH_1):PAGE318
    A2    GND @T6G_MB_LIB.T6G(SCH_1):GND    I76 @T6G_MB_LIB.T6G(SCH_1):PAGE318
    A1 GPU_FPGA_EROT_RECOV_BUF_N @T6G_MB_LIB.T6G(SCH_1):GPU_FPGA_EROT_RECOV_BUF_N    I76 @T6G_MB_LIB.T6G(SCH_1):PAGE318
    B4 P5E_CPU1_P2_RX_BUF_DN<3> @T6G_MB_LIB.T6G(SCH_1):P5E_CPU1_P2_RX_BUF_DN(3)    I76 @T6G_MB_LIB.T6G(SCH_1):PAGE318
    B3    GND @T6G_MB_LIB.T6G(SCH_1):GND    I76 @T6G_MB_LIB.T6G(SCH_1):PAGE318
    B2 P5E_CPU1_P2_RX_BUF_DN<1> @T6G_MB_LIB.T6G(SCH_1):P5E_CPU1_P2_RX_BUF_DN(1)    I76 @T6G_MB_LIB.T6G(SCH_1):PAGE318
    B1    GND @T6G_MB_LIB.T6G(SCH_1):GND    I76 @T6G_MB_LIB.T6G(SCH_1):PAGE318
    C4 P5E_CPU1_P2_RX_BUF_DP<3> @T6G_MB_LIB.T6G(SCH_1):P5E_CPU1_P2_RX_BUF_DP(3)    I76 @T6G_MB_LIB.T6G(SCH_1):PAGE318
    C3 P5E_CPU1_P2_RX_BUF_DN<2> @T6G_MB_LIB.T6G(SCH_1):P5E_CPU1_P2_RX_BUF_DN(2)    I76 @T6G_MB_LIB.T6G(SCH_1):PAGE318
    C2 P5E_CPU1_P2_RX_BUF_DP<1> @T6G_MB_LIB.T6G(SCH_1):P5E_CPU1_P2_RX_BUF_DP(1)    I76 @T6G_MB_LIB.T6G(SCH_1):PAGE318
    C1 P5E_CPU1_P2_RX_BUF_DN<0> @T6G_MB_LIB.T6G(SCH_1):P5E_CPU1_P2_RX_BUF_DN(0)    I76 @T6G_MB_LIB.T6G(SCH_1):PAGE318
    D4    GND @T6G_MB_LIB.T6G(SCH_1):GND    I76 @T6G_MB_LIB.T6G(SCH_1):PAGE318
    D3 P5E_CPU1_P2_RX_BUF_DP<2> @T6G_MB_LIB.T6G(SCH_1):P5E_CPU1_P2_RX_BUF_DP(2)    I76 @T6G_MB_LIB.T6G(SCH_1):PAGE318
    D2    GND @T6G_MB_LIB.T6G(SCH_1):GND    I76 @T6G_MB_LIB.T6G(SCH_1):PAGE318
    D1 P5E_CPU1_P2_RX_BUF_DP<0> @T6G_MB_LIB.T6G(SCH_1):P5E_CPU1_P2_RX_BUF_DP(0)    I76 @T6G_MB_LIB.T6G(SCH_1):PAGE318
    E4 P5E_CPU1_P3_RX_BUF_DN<3> @T6G_MB_LIB.T6G(SCH_1):P5E_CPU1_P3_RX_BUF_DN(3)    I76 @T6G_MB_LIB.T6G(SCH_1):PAGE318
    E3    GND @T6G_MB_LIB.T6G(SCH_1):GND    I76 @T6G_MB_LIB.T6G(SCH_1):PAGE318
    E2 P5E_CPU1_P3_RX_BUF_DN<1> @T6G_MB_LIB.T6G(SCH_1):P5E_CPU1_P3_RX_BUF_DN(1)    I76 @T6G_MB_LIB.T6G(SCH_1):PAGE318
    E1    GND @T6G_MB_LIB.T6G(SCH_1):GND    I76 @T6G_MB_LIB.T6G(SCH_1):PAGE318
    F4 P5E_CPU1_P3_RX_BUF_DP<3> @T6G_MB_LIB.T6G(SCH_1):P5E_CPU1_P3_RX_BUF_DP(3)    I76 @T6G_MB_LIB.T6G(SCH_1):PAGE318
    F3 P5E_CPU1_P3_RX_BUF_DN<2> @T6G_MB_LIB.T6G(SCH_1):P5E_CPU1_P3_RX_BUF_DN(2)    I76 @T6G_MB_LIB.T6G(SCH_1):PAGE318
    F2 P5E_CPU1_P3_RX_BUF_DP<1> @T6G_MB_LIB.T6G(SCH_1):P5E_CPU1_P3_RX_BUF_DP(1)    I76 @T6G_MB_LIB.T6G(SCH_1):PAGE318
    F1 P5E_CPU1_P3_RX_BUF_DN<0> @T6G_MB_LIB.T6G(SCH_1):P5E_CPU1_P3_RX_BUF_DN(0)    I76 @T6G_MB_LIB.T6G(SCH_1):PAGE318
    G4    GND @T6G_MB_LIB.T6G(SCH_1):GND    I76 @T6G_MB_LIB.T6G(SCH_1):PAGE318
    G3 P5E_CPU1_P3_RX_BUF_DP<2> @T6G_MB_LIB.T6G(SCH_1):P5E_CPU1_P3_RX_BUF_DP(2)    I76 @T6G_MB_LIB.T6G(SCH_1):PAGE318
    G2    GND @T6G_MB_LIB.T6G(SCH_1):GND    I76 @T6G_MB_LIB.T6G(SCH_1):PAGE318
    G1 P5E_CPU1_P3_RX_BUF_DP<0> @T6G_MB_LIB.T6G(SCH_1):P5E_CPU1_P3_RX_BUF_DP(0)    I76 @T6G_MB_LIB.T6G(SCH_1):PAGE318
    H4 P5E_CPU1_P2_TX_BUF_C_DN<3> @T6G_MB_LIB.T6G(SCH_1):P5E_CPU1_P2_TX_BUF_C_DN(3)    I76 @T6G_MB_LIB.T6G(SCH_1):PAGE318
    H3    GND @T6G_MB_LIB.T6G(SCH_1):GND    I76 @T6G_MB_LIB.T6G(SCH_1):PAGE318
    H2 P5E_CPU1_P2_TX_BUF_C_DN<1> @T6G_MB_LIB.T6G(SCH_1):P5E_CPU1_P2_TX_BUF_C_DN(1)    I76 @T6G_MB_LIB.T6G(SCH_1):PAGE318
    H1    GND @T6G_MB_LIB.T6G(SCH_1):GND    I76 @T6G_MB_LIB.T6G(SCH_1):PAGE318
    I4 P5E_CPU1_P2_TX_BUF_C_DP<3> @T6G_MB_LIB.T6G(SCH_1):P5E_CPU1_P2_TX_BUF_C_DP(3)    I76 @T6G_MB_LIB.T6G(SCH_1):PAGE318
    I3 P5E_CPU1_P2_TX_BUF_C_DN<2> @T6G_MB_LIB.T6G(SCH_1):P5E_CPU1_P2_TX_BUF_C_DN(2)    I76 @T6G_MB_LIB.T6G(SCH_1):PAGE318
    I2 P5E_CPU1_P2_TX_BUF_C_DP<1> @T6G_MB_LIB.T6G(SCH_1):P5E_CPU1_P2_TX_BUF_C_DP(1)    I76 @T6G_MB_LIB.T6G(SCH_1):PAGE318
    I1 P5E_CPU1_P2_TX_BUF_C_DN<0> @T6G_MB_LIB.T6G(SCH_1):P5E_CPU1_P2_TX_BUF_C_DN(0)    I76 @T6G_MB_LIB.T6G(SCH_1):PAGE318
    J4    GND @T6G_MB_LIB.T6G(SCH_1):GND    I76 @T6G_MB_LIB.T6G(SCH_1):PAGE318
    J3 P5E_CPU1_P2_TX_BUF_C_DP<2> @T6G_MB_LIB.T6G(SCH_1):P5E_CPU1_P2_TX_BUF_C_DP(2)    I76 @T6G_MB_LIB.T6G(SCH_1):PAGE318
    J2    GND @T6G_MB_LIB.T6G(SCH_1):GND    I76 @T6G_MB_LIB.T6G(SCH_1):PAGE318
    J1 P5E_CPU1_P2_TX_BUF_C_DP<0> @T6G_MB_LIB.T6G(SCH_1):P5E_CPU1_P2_TX_BUF_C_DP(0)    I76 @T6G_MB_LIB.T6G(SCH_1):PAGE318
    K4 P5E_CPU1_P3_TX_BUF_C_DN<3> @T6G_MB_LIB.T6G(SCH_1):P5E_CPU1_P3_TX_BUF_C_DN(3)    I76 @T6G_MB_LIB.T6G(SCH_1):PAGE318
    K3    GND @T6G_MB_LIB.T6G(SCH_1):GND    I76 @T6G_MB_LIB.T6G(SCH_1):PAGE318
    K2 P5E_CPU1_P3_TX_BUF_C_DN<1> @T6G_MB_LIB.T6G(SCH_1):P5E_CPU1_P3_TX_BUF_C_DN(1)    I76 @T6G_MB_LIB.T6G(SCH_1):PAGE318
    K1    GND @T6G_MB_LIB.T6G(SCH_1):GND    I76 @T6G_MB_LIB.T6G(SCH_1):PAGE318
    L4 P5E_CPU1_P3_TX_BUF_C_DP<3> @T6G_MB_LIB.T6G(SCH_1):P5E_CPU1_P3_TX_BUF_C_DP(3)    I76 @T6G_MB_LIB.T6G(SCH_1):PAGE318
    L3 P5E_CPU1_P3_TX_BUF_C_DN<2> @T6G_MB_LIB.T6G(SCH_1):P5E_CPU1_P3_TX_BUF_C_DN(2)    I76 @T6G_MB_LIB.T6G(SCH_1):PAGE318
    L2 P5E_CPU1_P3_TX_BUF_C_DP<1> @T6G_MB_LIB.T6G(SCH_1):P5E_CPU1_P3_TX_BUF_C_DP(1)    I76 @T6G_MB_LIB.T6G(SCH_1):PAGE318
    L1 P5E_CPU1_P3_TX_BUF_C_DN<0> @T6G_MB_LIB.T6G(SCH_1):P5E_CPU1_P3_TX_BUF_C_DN(0)    I76 @T6G_MB_LIB.T6G(SCH_1):PAGE318
    M1 P5E_CPU1_P3_TX_BUF_C_DP<0> @T6G_MB_LIB.T6G(SCH_1):P5E_CPU1_P3_TX_BUF_C_DP(0)    I76 @T6G_MB_LIB.T6G(SCH_1):PAGE318
    N1    GND @T6G_MB_LIB.T6G(SCH_1):GND    I76 @T6G_MB_LIB.T6G(SCH_1):PAGE318
    M2    GND @T6G_MB_LIB.T6G(SCH_1):GND    I76 @T6G_MB_LIB.T6G(SCH_1):PAGE318
    N2 GPU_FPGA_BOOT_EN_BUF @T6G_MB_LIB.T6G(SCH_1):GPU_FPGA_BOOT_EN_BUF    I76 @T6G_MB_LIB.T6G(SCH_1):PAGE318
    M3 P5E_CPU1_P3_TX_BUF_C_DP<2> @T6G_MB_LIB.T6G(SCH_1):P5E_CPU1_P3_TX_BUF_C_DP(2)    I76 @T6G_MB_LIB.T6G(SCH_1):PAGE318
    N3    GND @T6G_MB_LIB.T6G(SCH_1):GND    I76 @T6G_MB_LIB.T6G(SCH_1):PAGE318
    M4    GND @T6G_MB_LIB.T6G(SCH_1):GND    I76 @T6G_MB_LIB.T6G(SCH_1):PAGE318
    N4 FM_SMB_1_ALERT_GPU_N @T6G_MB_LIB.T6G(SCH_1):FM_SMB_1_ALERT_GPU_N    I76 @T6G_MB_LIB.T6G(SCH_1):PAGE318

J111 CONN112_10137002101LF-CONN112_10137002-101LF,THLF,A
    A8    GND @T6G_MB_LIB.T6G(SCH_1):GND    I38 @T6G_MB_LIB.T6G(SCH_1):PAGE328
    A7 GPU_FPGA_RST_R_BUF_N @T6G_MB_LIB.T6G(SCH_1):GPU_FPGA_RST_R_BUF_N    I38 @T6G_MB_LIB.T6G(SCH_1):PAGE328
    A6    GND @T6G_MB_LIB.T6G(SCH_1):GND    I38 @T6G_MB_LIB.T6G(SCH_1):PAGE328
    A5 GPU_PEX_STRAP0 @T6G_MB_LIB.T6G(SCH_1):GPU_PEX_STRAP0    I38 @T6G_MB_LIB.T6G(SCH_1):PAGE328
    B8 P5E_CPU1_P0_RX_BUF_DN<15> @T6G_MB_LIB.T6G(SCH_1):P5E_CPU1_P0_RX_BUF_DN(15)    I38 @T6G_MB_LIB.T6G(SCH_1):PAGE328
    B7    GND @T6G_MB_LIB.T6G(SCH_1):GND    I38 @T6G_MB_LIB.T6G(SCH_1):PAGE328
    B6 P5E_CPU1_P0_RX_BUF_DN<13> @T6G_MB_LIB.T6G(SCH_1):P5E_CPU1_P0_RX_BUF_DN(13)    I38 @T6G_MB_LIB.T6G(SCH_1):PAGE328
    B5    GND @T6G_MB_LIB.T6G(SCH_1):GND    I38 @T6G_MB_LIB.T6G(SCH_1):PAGE328
    C8 P5E_CPU1_P0_RX_BUF_DP<15> @T6G_MB_LIB.T6G(SCH_1):P5E_CPU1_P0_RX_BUF_DP(15)    I38 @T6G_MB_LIB.T6G(SCH_1):PAGE328
    C7 P5E_CPU1_P0_RX_BUF_DN<14> @T6G_MB_LIB.T6G(SCH_1):P5E_CPU1_P0_RX_BUF_DN(14)    I38 @T6G_MB_LIB.T6G(SCH_1):PAGE328
    C6 P5E_CPU1_P0_RX_BUF_DP<13> @T6G_MB_LIB.T6G(SCH_1):P5E_CPU1_P0_RX_BUF_DP(13)    I38 @T6G_MB_LIB.T6G(SCH_1):PAGE328
    C5 P5E_CPU1_P0_RX_BUF_DN<12> @T6G_MB_LIB.T6G(SCH_1):P5E_CPU1_P0_RX_BUF_DN(12)    I38 @T6G_MB_LIB.T6G(SCH_1):PAGE328
    D8    GND @T6G_MB_LIB.T6G(SCH_1):GND    I38 @T6G_MB_LIB.T6G(SCH_1):PAGE328
    D7 P5E_CPU1_P0_RX_BUF_DP<14> @T6G_MB_LIB.T6G(SCH_1):P5E_CPU1_P0_RX_BUF_DP(14)    I38 @T6G_MB_LIB.T6G(SCH_1):PAGE328
    D6    GND @T6G_MB_LIB.T6G(SCH_1):GND    I38 @T6G_MB_LIB.T6G(SCH_1):PAGE328
    D5 P5E_CPU1_P0_RX_BUF_DP<12> @T6G_MB_LIB.T6G(SCH_1):P5E_CPU1_P0_RX_BUF_DP(12)    I38 @T6G_MB_LIB.T6G(SCH_1):PAGE328
    E8 P5E_CPU1_P1_RX_BUF_DN<15> @T6G_MB_LIB.T6G(SCH_1):P5E_CPU1_P1_RX_BUF_DN(15)    I38 @T6G_MB_LIB.T6G(SCH_1):PAGE328
    E7    GND @T6G_MB_LIB.T6G(SCH_1):GND    I38 @T6G_MB_LIB.T6G(SCH_1):PAGE328
    E6 P5E_CPU1_P1_RX_BUF_DN<13> @T6G_MB_LIB.T6G(SCH_1):P5E_CPU1_P1_RX_BUF_DN(13)    I38 @T6G_MB_LIB.T6G(SCH_1):PAGE328
    E5    GND @T6G_MB_LIB.T6G(SCH_1):GND    I38 @T6G_MB_LIB.T6G(SCH_1):PAGE328
    F8 P5E_CPU1_P1_RX_BUF_DP<15> @T6G_MB_LIB.T6G(SCH_1):P5E_CPU1_P1_RX_BUF_DP(15)    I38 @T6G_MB_LIB.T6G(SCH_1):PAGE328
    F7 P5E_CPU1_P1_RX_BUF_DN<14> @T6G_MB_LIB.T6G(SCH_1):P5E_CPU1_P1_RX_BUF_DN(14)    I38 @T6G_MB_LIB.T6G(SCH_1):PAGE328
    F6 P5E_CPU1_P1_RX_BUF_DP<13> @T6G_MB_LIB.T6G(SCH_1):P5E_CPU1_P1_RX_BUF_DP(13)    I38 @T6G_MB_LIB.T6G(SCH_1):PAGE328
    F5 P5E_CPU1_P1_RX_BUF_DN<12> @T6G_MB_LIB.T6G(SCH_1):P5E_CPU1_P1_RX_BUF_DN(12)    I38 @T6G_MB_LIB.T6G(SCH_1):PAGE328
    G8    GND @T6G_MB_LIB.T6G(SCH_1):GND    I38 @T6G_MB_LIB.T6G(SCH_1):PAGE328
    G7 P5E_CPU1_P1_RX_BUF_DP<14> @T6G_MB_LIB.T6G(SCH_1):P5E_CPU1_P1_RX_BUF_DP(14)    I38 @T6G_MB_LIB.T6G(SCH_1):PAGE328
    G6    GND @T6G_MB_LIB.T6G(SCH_1):GND    I38 @T6G_MB_LIB.T6G(SCH_1):PAGE328
    G5 P5E_CPU1_P1_RX_BUF_DP<12> @T6G_MB_LIB.T6G(SCH_1):P5E_CPU1_P1_RX_BUF_DP(12)    I38 @T6G_MB_LIB.T6G(SCH_1):PAGE328
    H8 P5E_CPU1_P0_TX_BUF_C_DN<15> @T6G_MB_LIB.T6G(SCH_1):P5E_CPU1_P0_TX_BUF_C_DN(15)    I38 @T6G_MB_LIB.T6G(SCH_1):PAGE328
    H7    GND @T6G_MB_LIB.T6G(SCH_1):GND    I38 @T6G_MB_LIB.T6G(SCH_1):PAGE328
    H6 P5E_CPU1_P0_TX_BUF_C_DN<13> @T6G_MB_LIB.T6G(SCH_1):P5E_CPU1_P0_TX_BUF_C_DN(13)    I38 @T6G_MB_LIB.T6G(SCH_1):PAGE328
    H5    GND @T6G_MB_LIB.T6G(SCH_1):GND    I38 @T6G_MB_LIB.T6G(SCH_1):PAGE328
    I8 P5E_CPU1_P0_TX_BUF_C_DP<15> @T6G_MB_LIB.T6G(SCH_1):P5E_CPU1_P0_TX_BUF_C_DP(15)    I38 @T6G_MB_LIB.T6G(SCH_1):PAGE328
    I7 P5E_CPU1_P0_TX_BUF_C_DN<14> @T6G_MB_LIB.T6G(SCH_1):P5E_CPU1_P0_TX_BUF_C_DN(14)    I38 @T6G_MB_LIB.T6G(SCH_1):PAGE328
    I6 P5E_CPU1_P0_TX_BUF_C_DP<13> @T6G_MB_LIB.T6G(SCH_1):P5E_CPU1_P0_TX_BUF_C_DP(13)    I38 @T6G_MB_LIB.T6G(SCH_1):PAGE328
    I5 P5E_CPU1_P0_TX_BUF_C_DN<12> @T6G_MB_LIB.T6G(SCH_1):P5E_CPU1_P0_TX_BUF_C_DN(12)    I38 @T6G_MB_LIB.T6G(SCH_1):PAGE328
    J8    GND @T6G_MB_LIB.T6G(SCH_1):GND    I38 @T6G_MB_LIB.T6G(SCH_1):PAGE328
    J7 P5E_CPU1_P0_TX_BUF_C_DP<14> @T6G_MB_LIB.T6G(SCH_1):P5E_CPU1_P0_TX_BUF_C_DP(14)    I38 @T6G_MB_LIB.T6G(SCH_1):PAGE328
    J6    GND @T6G_MB_LIB.T6G(SCH_1):GND    I38 @T6G_MB_LIB.T6G(SCH_1):PAGE328
    J5 P5E_CPU1_P0_TX_BUF_C_DP<12> @T6G_MB_LIB.T6G(SCH_1):P5E_CPU1_P0_TX_BUF_C_DP(12)    I38 @T6G_MB_LIB.T6G(SCH_1):PAGE328
    K8 P5E_CPU1_P1_TX_BUF_C_DN<15> @T6G_MB_LIB.T6G(SCH_1):P5E_CPU1_P1_TX_BUF_C_DN(15)    I38 @T6G_MB_LIB.T6G(SCH_1):PAGE328
    K7    GND @T6G_MB_LIB.T6G(SCH_1):GND    I38 @T6G_MB_LIB.T6G(SCH_1):PAGE328
    K6 P5E_CPU1_P1_TX_BUF_C_DN<13> @T6G_MB_LIB.T6G(SCH_1):P5E_CPU1_P1_TX_BUF_C_DN(13)    I38 @T6G_MB_LIB.T6G(SCH_1):PAGE328
    K5    GND @T6G_MB_LIB.T6G(SCH_1):GND    I38 @T6G_MB_LIB.T6G(SCH_1):PAGE328
    L8 P5E_CPU1_P1_TX_BUF_C_DP<15> @T6G_MB_LIB.T6G(SCH_1):P5E_CPU1_P1_TX_BUF_C_DP(15)    I38 @T6G_MB_LIB.T6G(SCH_1):PAGE328
    L7 P5E_CPU1_P1_TX_BUF_C_DN<14> @T6G_MB_LIB.T6G(SCH_1):P5E_CPU1_P1_TX_BUF_C_DN(14)    I38 @T6G_MB_LIB.T6G(SCH_1):PAGE328
    L6 P5E_CPU1_P1_TX_BUF_C_DP<13> @T6G_MB_LIB.T6G(SCH_1):P5E_CPU1_P1_TX_BUF_C_DP(13)    I38 @T6G_MB_LIB.T6G(SCH_1):PAGE328
    L5 P5E_CPU1_P1_TX_BUF_C_DN<12> @T6G_MB_LIB.T6G(SCH_1):P5E_CPU1_P1_TX_BUF_C_DN(12)    I38 @T6G_MB_LIB.T6G(SCH_1):PAGE328
    M5 P5E_CPU1_P1_TX_BUF_C_DP<12> @T6G_MB_LIB.T6G(SCH_1):P5E_CPU1_P1_TX_BUF_C_DP(12)    I38 @T6G_MB_LIB.T6G(SCH_1):PAGE328
    N5    GND @T6G_MB_LIB.T6G(SCH_1):GND    I38 @T6G_MB_LIB.T6G(SCH_1):PAGE328
    M6    GND @T6G_MB_LIB.T6G(SCH_1):GND    I38 @T6G_MB_LIB.T6G(SCH_1):PAGE328
    N6 FM_GPU_PWRGD @T6G_MB_LIB.T6G(SCH_1):FM_GPU_PWRGD    I38 @T6G_MB_LIB.T6G(SCH_1):PAGE328
    M7 P5E_CPU1_P1_TX_BUF_C_DP<14> @T6G_MB_LIB.T6G(SCH_1):P5E_CPU1_P1_TX_BUF_C_DP(14)    I38 @T6G_MB_LIB.T6G(SCH_1):PAGE328
    N7    GND @T6G_MB_LIB.T6G(SCH_1):GND    I38 @T6G_MB_LIB.T6G(SCH_1):PAGE328
    M8    GND @T6G_MB_LIB.T6G(SCH_1):GND    I38 @T6G_MB_LIB.T6G(SCH_1):PAGE328
    N8 GPU_BASE_ID1 @T6G_MB_LIB.T6G(SCH_1):GPU_BASE_ID1    I38 @T6G_MB_LIB.T6G(SCH_1):PAGE328
    A4    GND @T6G_MB_LIB.T6G(SCH_1):GND    I76 @T6G_MB_LIB.T6G(SCH_1):PAGE328
    A3 GPU_BASE_ID0 @T6G_MB_LIB.T6G(SCH_1):GPU_BASE_ID0    I76 @T6G_MB_LIB.T6G(SCH_1):PAGE328
    A2    GND @T6G_MB_LIB.T6G(SCH_1):GND    I76 @T6G_MB_LIB.T6G(SCH_1):PAGE328
    A1 GPU_PEX_STRAP1 @T6G_MB_LIB.T6G(SCH_1):GPU_PEX_STRAP1    I76 @T6G_MB_LIB.T6G(SCH_1):PAGE328
    B4 P5E_CPU1_P0_RX_BUF_DN<11> @T6G_MB_LIB.T6G(SCH_1):P5E_CPU1_P0_RX_BUF_DN(11)    I76 @T6G_MB_LIB.T6G(SCH_1):PAGE328
    B3    GND @T6G_MB_LIB.T6G(SCH_1):GND    I76 @T6G_MB_LIB.T6G(SCH_1):PAGE328
    B2 P5E_CPU1_P0_RX_BUF_DN<9> @T6G_MB_LIB.T6G(SCH_1):P5E_CPU1_P0_RX_BUF_DN(9)    I76 @T6G_MB_LIB.T6G(SCH_1):PAGE328
    B1    GND @T6G_MB_LIB.T6G(SCH_1):GND    I76 @T6G_MB_LIB.T6G(SCH_1):PAGE328
    C4 P5E_CPU1_P0_RX_BUF_DP<11> @T6G_MB_LIB.T6G(SCH_1):P5E_CPU1_P0_RX_BUF_DP(11)    I76 @T6G_MB_LIB.T6G(SCH_1):PAGE328
    C3 P5E_CPU1_P0_RX_BUF_DN<10> @T6G_MB_LIB.T6G(SCH_1):P5E_CPU1_P0_RX_BUF_DN(10)    I76 @T6G_MB_LIB.T6G(SCH_1):PAGE328
    C2 P5E_CPU1_P0_RX_BUF_DP<9> @T6G_MB_LIB.T6G(SCH_1):P5E_CPU1_P0_RX_BUF_DP(9)    I76 @T6G_MB_LIB.T6G(SCH_1):PAGE328
    C1 P5E_CPU1_P0_RX_BUF_DN<8> @T6G_MB_LIB.T6G(SCH_1):P5E_CPU1_P0_RX_BUF_DN(8)    I76 @T6G_MB_LIB.T6G(SCH_1):PAGE328
    D4    GND @T6G_MB_LIB.T6G(SCH_1):GND    I76 @T6G_MB_LIB.T6G(SCH_1):PAGE328
    D3 P5E_CPU1_P0_RX_BUF_DP<10> @T6G_MB_LIB.T6G(SCH_1):P5E_CPU1_P0_RX_BUF_DP(10)    I76 @T6G_MB_LIB.T6G(SCH_1):PAGE328
    D2    GND @T6G_MB_LIB.T6G(SCH_1):GND    I76 @T6G_MB_LIB.T6G(SCH_1):PAGE328
    D1 P5E_CPU1_P0_RX_BUF_DP<8> @T6G_MB_LIB.T6G(SCH_1):P5E_CPU1_P0_RX_BUF_DP(8)    I76 @T6G_MB_LIB.T6G(SCH_1):PAGE328
    E4 P5E_CPU1_P1_RX_BUF_DN<11> @T6G_MB_LIB.T6G(SCH_1):P5E_CPU1_P1_RX_BUF_DN(11)    I76 @T6G_MB_LIB.T6G(SCH_1):PAGE328
    E3    GND @T6G_MB_LIB.T6G(SCH_1):GND    I76 @T6G_MB_LIB.T6G(SCH_1):PAGE328
    E2 P5E_CPU1_P1_RX_BUF_DN<9> @T6G_MB_LIB.T6G(SCH_1):P5E_CPU1_P1_RX_BUF_DN(9)    I76 @T6G_MB_LIB.T6G(SCH_1):PAGE328
    E1    GND @T6G_MB_LIB.T6G(SCH_1):GND    I76 @T6G_MB_LIB.T6G(SCH_1):PAGE328
    F4 P5E_CPU1_P1_RX_BUF_DP<11> @T6G_MB_LIB.T6G(SCH_1):P5E_CPU1_P1_RX_BUF_DP(11)    I76 @T6G_MB_LIB.T6G(SCH_1):PAGE328
    F3 P5E_CPU1_P1_RX_BUF_DN<10> @T6G_MB_LIB.T6G(SCH_1):P5E_CPU1_P1_RX_BUF_DN(10)    I76 @T6G_MB_LIB.T6G(SCH_1):PAGE328
    F2 P5E_CPU1_P1_RX_BUF_DP<9> @T6G_MB_LIB.T6G(SCH_1):P5E_CPU1_P1_RX_BUF_DP(9)    I76 @T6G_MB_LIB.T6G(SCH_1):PAGE328
    F1 P5E_CPU1_P1_RX_BUF_DN<8> @T6G_MB_LIB.T6G(SCH_1):P5E_CPU1_P1_RX_BUF_DN(8)    I76 @T6G_MB_LIB.T6G(SCH_1):PAGE328
    G4    GND @T6G_MB_LIB.T6G(SCH_1):GND    I76 @T6G_MB_LIB.T6G(SCH_1):PAGE328
    G3 P5E_CPU1_P1_RX_BUF_DP<10> @T6G_MB_LIB.T6G(SCH_1):P5E_CPU1_P1_RX_BUF_DP(10)    I76 @T6G_MB_LIB.T6G(SCH_1):PAGE328
    G2    GND @T6G_MB_LIB.T6G(SCH_1):GND    I76 @T6G_MB_LIB.T6G(SCH_1):PAGE328
    G1 P5E_CPU1_P1_RX_BUF_DP<8> @T6G_MB_LIB.T6G(SCH_1):P5E_CPU1_P1_RX_BUF_DP(8)    I76 @T6G_MB_LIB.T6G(SCH_1):PAGE328
    H4 P5E_CPU1_P0_TX_BUF_C_DN<11> @T6G_MB_LIB.T6G(SCH_1):P5E_CPU1_P0_TX_BUF_C_DN(11)    I76 @T6G_MB_LIB.T6G(SCH_1):PAGE328
    H3    GND @T6G_MB_LIB.T6G(SCH_1):GND    I76 @T6G_MB_LIB.T6G(SCH_1):PAGE328
    H2 P5E_CPU1_P0_TX_BUF_C_DN<9> @T6G_MB_LIB.T6G(SCH_1):P5E_CPU1_P0_TX_BUF_C_DN(9)    I76 @T6G_MB_LIB.T6G(SCH_1):PAGE328
    H1    GND @T6G_MB_LIB.T6G(SCH_1):GND    I76 @T6G_MB_LIB.T6G(SCH_1):PAGE328
    I4 P5E_CPU1_P0_TX_BUF_C_DP<11> @T6G_MB_LIB.T6G(SCH_1):P5E_CPU1_P0_TX_BUF_C_DP(11)    I76 @T6G_MB_LIB.T6G(SCH_1):PAGE328
    I3 P5E_CPU1_P0_TX_BUF_C_DN<10> @T6G_MB_LIB.T6G(SCH_1):P5E_CPU1_P0_TX_BUF_C_DN(10)    I76 @T6G_MB_LIB.T6G(SCH_1):PAGE328
    I2 P5E_CPU1_P0_TX_BUF_C_DP<9> @T6G_MB_LIB.T6G(SCH_1):P5E_CPU1_P0_TX_BUF_C_DP(9)    I76 @T6G_MB_LIB.T6G(SCH_1):PAGE328
    I1 P5E_CPU1_P0_TX_BUF_C_DN<8> @T6G_MB_LIB.T6G(SCH_1):P5E_CPU1_P0_TX_BUF_C_DN(8)    I76 @T6G_MB_LIB.T6G(SCH_1):PAGE328
    J4    GND @T6G_MB_LIB.T6G(SCH_1):GND    I76 @T6G_MB_LIB.T6G(SCH_1):PAGE328
    J3 P5E_CPU1_P0_TX_BUF_C_DP<10> @T6G_MB_LIB.T6G(SCH_1):P5E_CPU1_P0_TX_BUF_C_DP(10)    I76 @T6G_MB_LIB.T6G(SCH_1):PAGE328
    J2    GND @T6G_MB_LIB.T6G(SCH_1):GND    I76 @T6G_MB_LIB.T6G(SCH_1):PAGE328
    J1 P5E_CPU1_P0_TX_BUF_C_DP<8> @T6G_MB_LIB.T6G(SCH_1):P5E_CPU1_P0_TX_BUF_C_DP(8)    I76 @T6G_MB_LIB.T6G(SCH_1):PAGE328
    K4 P5E_CPU1_P1_TX_BUF_C_DN<11> @T6G_MB_LIB.T6G(SCH_1):P5E_CPU1_P1_TX_BUF_C_DN(11)    I76 @T6G_MB_LIB.T6G(SCH_1):PAGE328
    K3    GND @T6G_MB_LIB.T6G(SCH_1):GND    I76 @T6G_MB_LIB.T6G(SCH_1):PAGE328
    K2 P5E_CPU1_P1_TX_BUF_C_DN<9> @T6G_MB_LIB.T6G(SCH_1):P5E_CPU1_P1_TX_BUF_C_DN(9)    I76 @T6G_MB_LIB.T6G(SCH_1):PAGE328
    K1    GND @T6G_MB_LIB.T6G(SCH_1):GND    I76 @T6G_MB_LIB.T6G(SCH_1):PAGE328
    L4 P5E_CPU1_P1_TX_BUF_C_DP<11> @T6G_MB_LIB.T6G(SCH_1):P5E_CPU1_P1_TX_BUF_C_DP(11)    I76 @T6G_MB_LIB.T6G(SCH_1):PAGE328
    L3 P5E_CPU1_P1_TX_BUF_C_DN<10> @T6G_MB_LIB.T6G(SCH_1):P5E_CPU1_P1_TX_BUF_C_DN(10)    I76 @T6G_MB_LIB.T6G(SCH_1):PAGE328
    L2 P5E_CPU1_P1_TX_BUF_C_DP<9> @T6G_MB_LIB.T6G(SCH_1):P5E_CPU1_P1_TX_BUF_C_DP(9)    I76 @T6G_MB_LIB.T6G(SCH_1):PAGE328
    L1 P5E_CPU1_P1_TX_BUF_C_DN<8> @T6G_MB_LIB.T6G(SCH_1):P5E_CPU1_P1_TX_BUF_C_DN(8)    I76 @T6G_MB_LIB.T6G(SCH_1):PAGE328
    M1 P5E_CPU1_P1_TX_BUF_C_DP<8> @T6G_MB_LIB.T6G(SCH_1):P5E_CPU1_P1_TX_BUF_C_DP(8)    I76 @T6G_MB_LIB.T6G(SCH_1):PAGE328
    N1    GND @T6G_MB_LIB.T6G(SCH_1):GND    I76 @T6G_MB_LIB.T6G(SCH_1):PAGE328
    M2    GND @T6G_MB_LIB.T6G(SCH_1):GND    I76 @T6G_MB_LIB.T6G(SCH_1):PAGE328
    N2 GPU_PRSNT_N @T6G_MB_LIB.T6G(SCH_1):GPU_PRSNT_N    I76 @T6G_MB_LIB.T6G(SCH_1):PAGE328
    M3 P5E_CPU1_P1_TX_BUF_C_DP<10> @T6G_MB_LIB.T6G(SCH_1):P5E_CPU1_P1_TX_BUF_C_DP(10)    I76 @T6G_MB_LIB.T6G(SCH_1):PAGE328
    N3    GND @T6G_MB_LIB.T6G(SCH_1):GND    I76 @T6G_MB_LIB.T6G(SCH_1):PAGE328
    M4    GND @T6G_MB_LIB.T6G(SCH_1):GND    I76 @T6G_MB_LIB.T6G(SCH_1):PAGE328
    N4 FM_GPU_PWR_EN_R_BUF @T6G_MB_LIB.T6G(SCH_1):FM_GPU_PWR_EN_R_BUF    I76 @T6G_MB_LIB.T6G(SCH_1):PAGE328

J112 CONN160_10131762101LF-CONN160_10131762-101LF,THLF,A
    A8    GND @T6G_MB_LIB.T6G(SCH_1):GND     I7 @T6G_MB_LIB.T6G(SCH_1):PAGE329
    A7 PRSNT_SWB_N @T6G_MB_LIB.T6G(SCH_1):PRSNT_SWB_N     I7 @T6G_MB_LIB.T6G(SCH_1):PAGE329
    A6    GND @T6G_MB_LIB.T6G(SCH_1):GND     I7 @T6G_MB_LIB.T6G(SCH_1):PAGE329
    A5 RST_PERST_1_SWB_BUF_N @T6G_MB_LIB.T6G(SCH_1):RST_PERST_1_SWB_BUF_N     I7 @T6G_MB_LIB.T6G(SCH_1):PAGE329
    B8 P5E_CPU1_P0_RX_BUF_DN<7> @T6G_MB_LIB.T6G(SCH_1):P5E_CPU1_P0_RX_BUF_DN(7)     I7 @T6G_MB_LIB.T6G(SCH_1):PAGE329
    B7    GND @T6G_MB_LIB.T6G(SCH_1):GND     I7 @T6G_MB_LIB.T6G(SCH_1):PAGE329
    B6 P5E_CPU1_P0_RX_BUF_DN<5> @T6G_MB_LIB.T6G(SCH_1):P5E_CPU1_P0_RX_BUF_DN(5)     I7 @T6G_MB_LIB.T6G(SCH_1):PAGE329
    B5    GND @T6G_MB_LIB.T6G(SCH_1):GND     I7 @T6G_MB_LIB.T6G(SCH_1):PAGE329
    C8 P5E_CPU1_P0_RX_BUF_DP<7> @T6G_MB_LIB.T6G(SCH_1):P5E_CPU1_P0_RX_BUF_DP(7)     I7 @T6G_MB_LIB.T6G(SCH_1):PAGE329
    C7 P5E_CPU1_P0_RX_BUF_DN<6> @T6G_MB_LIB.T6G(SCH_1):P5E_CPU1_P0_RX_BUF_DN(6)     I7 @T6G_MB_LIB.T6G(SCH_1):PAGE329
    C6 P5E_CPU1_P0_RX_BUF_DP<5> @T6G_MB_LIB.T6G(SCH_1):P5E_CPU1_P0_RX_BUF_DP(5)     I7 @T6G_MB_LIB.T6G(SCH_1):PAGE329
    C5 P5E_CPU1_P0_RX_BUF_DN<4> @T6G_MB_LIB.T6G(SCH_1):P5E_CPU1_P0_RX_BUF_DN(4)     I7 @T6G_MB_LIB.T6G(SCH_1):PAGE329
    D8    GND @T6G_MB_LIB.T6G(SCH_1):GND     I7 @T6G_MB_LIB.T6G(SCH_1):PAGE329
    D7 P5E_CPU1_P0_RX_BUF_DP<6> @T6G_MB_LIB.T6G(SCH_1):P5E_CPU1_P0_RX_BUF_DP(6)     I7 @T6G_MB_LIB.T6G(SCH_1):PAGE329
    D6    GND @T6G_MB_LIB.T6G(SCH_1):GND     I7 @T6G_MB_LIB.T6G(SCH_1):PAGE329
    D5 P5E_CPU1_P0_RX_BUF_DP<4> @T6G_MB_LIB.T6G(SCH_1):P5E_CPU1_P0_RX_BUF_DP(4)     I7 @T6G_MB_LIB.T6G(SCH_1):PAGE329
    E8 P5E_CPU1_P1_RX_BUF_DN<7> @T6G_MB_LIB.T6G(SCH_1):P5E_CPU1_P1_RX_BUF_DN(7)     I7 @T6G_MB_LIB.T6G(SCH_1):PAGE329
    E7    GND @T6G_MB_LIB.T6G(SCH_1):GND     I7 @T6G_MB_LIB.T6G(SCH_1):PAGE329
    E6 P5E_CPU1_P1_RX_BUF_DN<5> @T6G_MB_LIB.T6G(SCH_1):P5E_CPU1_P1_RX_BUF_DN(5)     I7 @T6G_MB_LIB.T6G(SCH_1):PAGE329
    E5    GND @T6G_MB_LIB.T6G(SCH_1):GND     I7 @T6G_MB_LIB.T6G(SCH_1):PAGE329
    F8 P5E_CPU1_P1_RX_BUF_DP<7> @T6G_MB_LIB.T6G(SCH_1):P5E_CPU1_P1_RX_BUF_DP(7)     I7 @T6G_MB_LIB.T6G(SCH_1):PAGE329
    F7 P5E_CPU1_P1_RX_BUF_DN<6> @T6G_MB_LIB.T6G(SCH_1):P5E_CPU1_P1_RX_BUF_DN(6)     I7 @T6G_MB_LIB.T6G(SCH_1):PAGE329
    F6 P5E_CPU1_P1_RX_BUF_DP<5> @T6G_MB_LIB.T6G(SCH_1):P5E_CPU1_P1_RX_BUF_DP(5)     I7 @T6G_MB_LIB.T6G(SCH_1):PAGE329
    F5 P5E_CPU1_P1_RX_BUF_DN<4> @T6G_MB_LIB.T6G(SCH_1):P5E_CPU1_P1_RX_BUF_DN(4)     I7 @T6G_MB_LIB.T6G(SCH_1):PAGE329
    G8    GND @T6G_MB_LIB.T6G(SCH_1):GND     I7 @T6G_MB_LIB.T6G(SCH_1):PAGE329
    G7 P5E_CPU1_P1_RX_BUF_DP<6> @T6G_MB_LIB.T6G(SCH_1):P5E_CPU1_P1_RX_BUF_DP(6)     I7 @T6G_MB_LIB.T6G(SCH_1):PAGE329
    G6    GND @T6G_MB_LIB.T6G(SCH_1):GND     I7 @T6G_MB_LIB.T6G(SCH_1):PAGE329
    G5 P5E_CPU1_P1_RX_BUF_DP<4> @T6G_MB_LIB.T6G(SCH_1):P5E_CPU1_P1_RX_BUF_DP(4)     I7 @T6G_MB_LIB.T6G(SCH_1):PAGE329
    H8 P5E_CPU1_P0_TX_BUF_C_DN<7> @T6G_MB_LIB.T6G(SCH_1):P5E_CPU1_P0_TX_BUF_C_DN(7)     I7 @T6G_MB_LIB.T6G(SCH_1):PAGE329
    H7    GND @T6G_MB_LIB.T6G(SCH_1):GND     I7 @T6G_MB_LIB.T6G(SCH_1):PAGE329
    H6 P5E_CPU1_P0_TX_BUF_C_DN<5> @T6G_MB_LIB.T6G(SCH_1):P5E_CPU1_P0_TX_BUF_C_DN(5)     I7 @T6G_MB_LIB.T6G(SCH_1):PAGE329
    H5    GND @T6G_MB_LIB.T6G(SCH_1):GND     I7 @T6G_MB_LIB.T6G(SCH_1):PAGE329
    I8 P5E_CPU1_P0_TX_BUF_C_DP<7> @T6G_MB_LIB.T6G(SCH_1):P5E_CPU1_P0_TX_BUF_C_DP(7)     I7 @T6G_MB_LIB.T6G(SCH_1):PAGE329
    I7 P5E_CPU1_P0_TX_BUF_C_DN<6> @T6G_MB_LIB.T6G(SCH_1):P5E_CPU1_P0_TX_BUF_C_DN(6)     I7 @T6G_MB_LIB.T6G(SCH_1):PAGE329
    I6 P5E_CPU1_P0_TX_BUF_C_DP<5> @T6G_MB_LIB.T6G(SCH_1):P5E_CPU1_P0_TX_BUF_C_DP(5)     I7 @T6G_MB_LIB.T6G(SCH_1):PAGE329
    I5 P5E_CPU1_P0_TX_BUF_C_DN<4> @T6G_MB_LIB.T6G(SCH_1):P5E_CPU1_P0_TX_BUF_C_DN(4)     I7 @T6G_MB_LIB.T6G(SCH_1):PAGE329
    J8    GND @T6G_MB_LIB.T6G(SCH_1):GND     I7 @T6G_MB_LIB.T6G(SCH_1):PAGE329
    J7 P5E_CPU1_P0_TX_BUF_C_DP<6> @T6G_MB_LIB.T6G(SCH_1):P5E_CPU1_P0_TX_BUF_C_DP(6)     I7 @T6G_MB_LIB.T6G(SCH_1):PAGE329
    J6    GND @T6G_MB_LIB.T6G(SCH_1):GND     I7 @T6G_MB_LIB.T6G(SCH_1):PAGE329
    J5 P5E_CPU1_P0_TX_BUF_C_DP<4> @T6G_MB_LIB.T6G(SCH_1):P5E_CPU1_P0_TX_BUF_C_DP(4)     I7 @T6G_MB_LIB.T6G(SCH_1):PAGE329
    K8 P5E_CPU1_P1_TX_BUF_C_DN<7> @T6G_MB_LIB.T6G(SCH_1):P5E_CPU1_P1_TX_BUF_C_DN(7)     I7 @T6G_MB_LIB.T6G(SCH_1):PAGE329
    K7    GND @T6G_MB_LIB.T6G(SCH_1):GND     I7 @T6G_MB_LIB.T6G(SCH_1):PAGE329
    K6 P5E_CPU1_P1_TX_BUF_C_DN<5> @T6G_MB_LIB.T6G(SCH_1):P5E_CPU1_P1_TX_BUF_C_DN(5)     I7 @T6G_MB_LIB.T6G(SCH_1):PAGE329
    K5    GND @T6G_MB_LIB.T6G(SCH_1):GND     I7 @T6G_MB_LIB.T6G(SCH_1):PAGE329
    L8 P5E_CPU1_P1_TX_BUF_C_DP<7> @T6G_MB_LIB.T6G(SCH_1):P5E_CPU1_P1_TX_BUF_C_DP(7)     I7 @T6G_MB_LIB.T6G(SCH_1):PAGE329
    L7 P5E_CPU1_P1_TX_BUF_C_DN<6> @T6G_MB_LIB.T6G(SCH_1):P5E_CPU1_P1_TX_BUF_C_DN(6)     I7 @T6G_MB_LIB.T6G(SCH_1):PAGE329
    L6 P5E_CPU1_P1_TX_BUF_C_DP<5> @T6G_MB_LIB.T6G(SCH_1):P5E_CPU1_P1_TX_BUF_C_DP(5)     I7 @T6G_MB_LIB.T6G(SCH_1):PAGE329
    L5 P5E_CPU1_P1_TX_BUF_C_DN<4> @T6G_MB_LIB.T6G(SCH_1):P5E_CPU1_P1_TX_BUF_C_DN(4)     I7 @T6G_MB_LIB.T6G(SCH_1):PAGE329
    M5 P5E_CPU1_P1_TX_BUF_C_DP<4> @T6G_MB_LIB.T6G(SCH_1):P5E_CPU1_P1_TX_BUF_C_DP(4)     I7 @T6G_MB_LIB.T6G(SCH_1):PAGE329
    N5    GND @T6G_MB_LIB.T6G(SCH_1):GND     I7 @T6G_MB_LIB.T6G(SCH_1):PAGE329
    M6    GND @T6G_MB_LIB.T6G(SCH_1):GND     I7 @T6G_MB_LIB.T6G(SCH_1):PAGE329
    N6 P2E_MB_BMC_RX_DP<0> @T6G_MB_LIB.T6G(SCH_1):P2E_MB_BMC_RX_DP(0)     I7 @T6G_MB_LIB.T6G(SCH_1):PAGE329
    M7 P5E_CPU1_P1_TX_BUF_C_DP<6> @T6G_MB_LIB.T6G(SCH_1):P5E_CPU1_P1_TX_BUF_C_DP(6)     I7 @T6G_MB_LIB.T6G(SCH_1):PAGE329
    N7    GND @T6G_MB_LIB.T6G(SCH_1):GND     I7 @T6G_MB_LIB.T6G(SCH_1):PAGE329
    M8    GND @T6G_MB_LIB.T6G(SCH_1):GND     I7 @T6G_MB_LIB.T6G(SCH_1):PAGE329
    N8 P3E_CPU1_P5_RX_DN<0> @T6G_MB_LIB.T6G(SCH_1):P3E_CPU1_P5_RX_DN(0)     I7 @T6G_MB_LIB.T6G(SCH_1):PAGE329
    O5 NC_J112_O5 @T6G_MB_LIB.T6G(SCH_1):NC_J112_O5     I7 @T6G_MB_LIB.T6G(SCH_1):PAGE329
    P5 NC_J112_P5 @T6G_MB_LIB.T6G(SCH_1):NC_J112_P5     I7 @T6G_MB_LIB.T6G(SCH_1):PAGE329
    Q5    GND @T6G_MB_LIB.T6G(SCH_1):GND     I7 @T6G_MB_LIB.T6G(SCH_1):PAGE329
    R5 NC_J112_R5 @T6G_MB_LIB.T6G(SCH_1):NC_J112_R5     I7 @T6G_MB_LIB.T6G(SCH_1):PAGE329
    S5 NC_J112_S5 @T6G_MB_LIB.T6G(SCH_1):NC_J112_S5     I7 @T6G_MB_LIB.T6G(SCH_1):PAGE329
    T5    GND @T6G_MB_LIB.T6G(SCH_1):GND     I7 @T6G_MB_LIB.T6G(SCH_1):PAGE329
    O6 P2E_MB_BMC_RX_DN<0> @T6G_MB_LIB.T6G(SCH_1):P2E_MB_BMC_RX_DN(0)     I7 @T6G_MB_LIB.T6G(SCH_1):PAGE329
    P6    GND @T6G_MB_LIB.T6G(SCH_1):GND     I7 @T6G_MB_LIB.T6G(SCH_1):PAGE329
    Q6 P2E_MB_BMC_TX_BUF_C_DP<0> @T6G_MB_LIB.T6G(SCH_1):P2E_MB_BMC_TX_BUF_C_DP(0)     I7 @T6G_MB_LIB.T6G(SCH_1):PAGE329
    R6 P2E_MB_BMC_TX_BUF_C_DN<0> @T6G_MB_LIB.T6G(SCH_1):P2E_MB_BMC_TX_BUF_C_DN(0)     I7 @T6G_MB_LIB.T6G(SCH_1):PAGE329
    S6    GND @T6G_MB_LIB.T6G(SCH_1):GND     I7 @T6G_MB_LIB.T6G(SCH_1):PAGE329
    T6 GPU_FPGA_THERM_OVERT_N @T6G_MB_LIB.T6G(SCH_1):GPU_FPGA_THERM_OVERT_N     I7 @T6G_MB_LIB.T6G(SCH_1):PAGE329
    O7 P3E_CPU1_P5_RX_DN<1> @T6G_MB_LIB.T6G(SCH_1):P3E_CPU1_P5_RX_DN(1)     I7 @T6G_MB_LIB.T6G(SCH_1):PAGE329
    P7 P3E_CPU1_P5_RX_DP<1> @T6G_MB_LIB.T6G(SCH_1):P3E_CPU1_P5_RX_DP(1)     I7 @T6G_MB_LIB.T6G(SCH_1):PAGE329
    Q7    GND @T6G_MB_LIB.T6G(SCH_1):GND     I7 @T6G_MB_LIB.T6G(SCH_1):PAGE329
    R7 P3E_CPU1_P5_TX_C_DP<1> @T6G_MB_LIB.T6G(SCH_1):P3E_CPU1_P5_TX_C_DP(1)     I7 @T6G_MB_LIB.T6G(SCH_1):PAGE329
    S7 P3E_CPU1_P5_TX_C_DN<1> @T6G_MB_LIB.T6G(SCH_1):P3E_CPU1_P5_TX_C_DN(1)     I7 @T6G_MB_LIB.T6G(SCH_1):PAGE329
    T7    GND @T6G_MB_LIB.T6G(SCH_1):GND     I7 @T6G_MB_LIB.T6G(SCH_1):PAGE329
    O8 P3E_CPU1_P5_RX_DP<0> @T6G_MB_LIB.T6G(SCH_1):P3E_CPU1_P5_RX_DP(0)     I7 @T6G_MB_LIB.T6G(SCH_1):PAGE329
    P8    GND @T6G_MB_LIB.T6G(SCH_1):GND     I7 @T6G_MB_LIB.T6G(SCH_1):PAGE329
    Q8 P3E_CPU1_P5_TX_C_DN<0> @T6G_MB_LIB.T6G(SCH_1):P3E_CPU1_P5_TX_C_DN(0)     I7 @T6G_MB_LIB.T6G(SCH_1):PAGE329
    R8 P3E_CPU1_P5_TX_C_DP<0> @T6G_MB_LIB.T6G(SCH_1):P3E_CPU1_P5_TX_C_DP(0)     I7 @T6G_MB_LIB.T6G(SCH_1):PAGE329
    S8    GND @T6G_MB_LIB.T6G(SCH_1):GND     I7 @T6G_MB_LIB.T6G(SCH_1):PAGE329
    T8 RST_PERST_0_SWB_BUF_N @T6G_MB_LIB.T6G(SCH_1):RST_PERST_0_SWB_BUF_N     I7 @T6G_MB_LIB.T6G(SCH_1):PAGE329
    A4    GND @T6G_MB_LIB.T6G(SCH_1):GND   I102 @T6G_MB_LIB.T6G(SCH_1):PAGE329
    A3 HGX_DETECT_N_ISO @T6G_MB_LIB.T6G(SCH_1):HGX_DETECT_N_ISO   I102 @T6G_MB_LIB.T6G(SCH_1):PAGE329
    A2    GND @T6G_MB_LIB.T6G(SCH_1):GND   I102 @T6G_MB_LIB.T6G(SCH_1):PAGE329
    A1 RST_PERST_2_SWB_BUF_N @T6G_MB_LIB.T6G(SCH_1):RST_PERST_2_SWB_BUF_N   I102 @T6G_MB_LIB.T6G(SCH_1):PAGE329
    B4 P5E_CPU1_P0_RX_BUF_DN<3> @T6G_MB_LIB.T6G(SCH_1):P5E_CPU1_P0_RX_BUF_DN(3)   I102 @T6G_MB_LIB.T6G(SCH_1):PAGE329
    B3    GND @T6G_MB_LIB.T6G(SCH_1):GND   I102 @T6G_MB_LIB.T6G(SCH_1):PAGE329
    B2 P5E_CPU1_P0_RX_BUF_DN<1> @T6G_MB_LIB.T6G(SCH_1):P5E_CPU1_P0_RX_BUF_DN(1)   I102 @T6G_MB_LIB.T6G(SCH_1):PAGE329
    B1    GND @T6G_MB_LIB.T6G(SCH_1):GND   I102 @T6G_MB_LIB.T6G(SCH_1):PAGE329
    C4 P5E_CPU1_P0_RX_BUF_DP<3> @T6G_MB_LIB.T6G(SCH_1):P5E_CPU1_P0_RX_BUF_DP(3)   I102 @T6G_MB_LIB.T6G(SCH_1):PAGE329
    C3 P5E_CPU1_P0_RX_BUF_DN<2> @T6G_MB_LIB.T6G(SCH_1):P5E_CPU1_P0_RX_BUF_DN(2)   I102 @T6G_MB_LIB.T6G(SCH_1):PAGE329
    C2 P5E_CPU1_P0_RX_BUF_DP<1> @T6G_MB_LIB.T6G(SCH_1):P5E_CPU1_P0_RX_BUF_DP(1)   I102 @T6G_MB_LIB.T6G(SCH_1):PAGE329
    C1 P5E_CPU1_P0_RX_BUF_DN<0> @T6G_MB_LIB.T6G(SCH_1):P5E_CPU1_P0_RX_BUF_DN(0)   I102 @T6G_MB_LIB.T6G(SCH_1):PAGE329
    D4    GND @T6G_MB_LIB.T6G(SCH_1):GND   I102 @T6G_MB_LIB.T6G(SCH_1):PAGE329
    D3 P5E_CPU1_P0_RX_BUF_DP<2> @T6G_MB_LIB.T6G(SCH_1):P5E_CPU1_P0_RX_BUF_DP(2)   I102 @T6G_MB_LIB.T6G(SCH_1):PAGE329
    D2    GND @T6G_MB_LIB.T6G(SCH_1):GND   I102 @T6G_MB_LIB.T6G(SCH_1):PAGE329
    D1 P5E_CPU1_P0_RX_BUF_DP<0> @T6G_MB_LIB.T6G(SCH_1):P5E_CPU1_P0_RX_BUF_DP(0)   I102 @T6G_MB_LIB.T6G(SCH_1):PAGE329
    E4 P5E_CPU1_P1_RX_BUF_DN<3> @T6G_MB_LIB.T6G(SCH_1):P5E_CPU1_P1_RX_BUF_DN(3)   I102 @T6G_MB_LIB.T6G(SCH_1):PAGE329
    E3    GND @T6G_MB_LIB.T6G(SCH_1):GND   I102 @T6G_MB_LIB.T6G(SCH_1):PAGE329
    E2 P5E_CPU1_P1_RX_BUF_DN<1> @T6G_MB_LIB.T6G(SCH_1):P5E_CPU1_P1_RX_BUF_DN(1)   I102 @T6G_MB_LIB.T6G(SCH_1):PAGE329
    E1    GND @T6G_MB_LIB.T6G(SCH_1):GND   I102 @T6G_MB_LIB.T6G(SCH_1):PAGE329
    F4 P5E_CPU1_P1_RX_BUF_DP<3> @T6G_MB_LIB.T6G(SCH_1):P5E_CPU1_P1_RX_BUF_DP(3)   I102 @T6G_MB_LIB.T6G(SCH_1):PAGE329
    F3 P5E_CPU1_P1_RX_BUF_DN<2> @T6G_MB_LIB.T6G(SCH_1):P5E_CPU1_P1_RX_BUF_DN(2)   I102 @T6G_MB_LIB.T6G(SCH_1):PAGE329
    F2 P5E_CPU1_P1_RX_BUF_DP<1> @T6G_MB_LIB.T6G(SCH_1):P5E_CPU1_P1_RX_BUF_DP(1)   I102 @T6G_MB_LIB.T6G(SCH_1):PAGE329
    F1 P5E_CPU1_P1_RX_BUF_DN<0> @T6G_MB_LIB.T6G(SCH_1):P5E_CPU1_P1_RX_BUF_DN(0)   I102 @T6G_MB_LIB.T6G(SCH_1):PAGE329
    G4    GND @T6G_MB_LIB.T6G(SCH_1):GND   I102 @T6G_MB_LIB.T6G(SCH_1):PAGE329
    G3 P5E_CPU1_P1_RX_BUF_DP<2> @T6G_MB_LIB.T6G(SCH_1):P5E_CPU1_P1_RX_BUF_DP(2)   I102 @T6G_MB_LIB.T6G(SCH_1):PAGE329
    G2    GND @T6G_MB_LIB.T6G(SCH_1):GND   I102 @T6G_MB_LIB.T6G(SCH_1):PAGE329
    G1 P5E_CPU1_P1_RX_BUF_DP<0> @T6G_MB_LIB.T6G(SCH_1):P5E_CPU1_P1_RX_BUF_DP(0)   I102 @T6G_MB_LIB.T6G(SCH_1):PAGE329
    H4 P5E_CPU1_P0_TX_BUF_C_DN<3> @T6G_MB_LIB.T6G(SCH_1):P5E_CPU1_P0_TX_BUF_C_DN(3)   I102 @T6G_MB_LIB.T6G(SCH_1):PAGE329
    H3    GND @T6G_MB_LIB.T6G(SCH_1):GND   I102 @T6G_MB_LIB.T6G(SCH_1):PAGE329
    H2 P5E_CPU1_P0_TX_BUF_C_DN<1> @T6G_MB_LIB.T6G(SCH_1):P5E_CPU1_P0_TX_BUF_C_DN(1)   I102 @T6G_MB_LIB.T6G(SCH_1):PAGE329
    H1    GND @T6G_MB_LIB.T6G(SCH_1):GND   I102 @T6G_MB_LIB.T6G(SCH_1):PAGE329
    I4 P5E_CPU1_P0_TX_BUF_C_DP<3> @T6G_MB_LIB.T6G(SCH_1):P5E_CPU1_P0_TX_BUF_C_DP(3)   I102 @T6G_MB_LIB.T6G(SCH_1):PAGE329
    I3 P5E_CPU1_P0_TX_BUF_C_DN<2> @T6G_MB_LIB.T6G(SCH_1):P5E_CPU1_P0_TX_BUF_C_DN(2)   I102 @T6G_MB_LIB.T6G(SCH_1):PAGE329
    I2 P5E_CPU1_P0_TX_BUF_C_DP<1> @T6G_MB_LIB.T6G(SCH_1):P5E_CPU1_P0_TX_BUF_C_DP(1)   I102 @T6G_MB_LIB.T6G(SCH_1):PAGE329
    I1 P5E_CPU1_P0_TX_BUF_C_DN<0> @T6G_MB_LIB.T6G(SCH_1):P5E_CPU1_P0_TX_BUF_C_DN(0)   I102 @T6G_MB_LIB.T6G(SCH_1):PAGE329
    J4    GND @T6G_MB_LIB.T6G(SCH_1):GND   I102 @T6G_MB_LIB.T6G(SCH_1):PAGE329
    J3 P5E_CPU1_P0_TX_BUF_C_DP<2> @T6G_MB_LIB.T6G(SCH_1):P5E_CPU1_P0_TX_BUF_C_DP(2)   I102 @T6G_MB_LIB.T6G(SCH_1):PAGE329
    J2    GND @T6G_MB_LIB.T6G(SCH_1):GND   I102 @T6G_MB_LIB.T6G(SCH_1):PAGE329
    J1 P5E_CPU1_P0_TX_BUF_C_DP<0> @T6G_MB_LIB.T6G(SCH_1):P5E_CPU1_P0_TX_BUF_C_DP(0)   I102 @T6G_MB_LIB.T6G(SCH_1):PAGE329
    K4 P5E_CPU1_P1_TX_BUF_C_DN<3> @T6G_MB_LIB.T6G(SCH_1):P5E_CPU1_P1_TX_BUF_C_DN(3)   I102 @T6G_MB_LIB.T6G(SCH_1):PAGE329
    K3    GND @T6G_MB_LIB.T6G(SCH_1):GND   I102 @T6G_MB_LIB.T6G(SCH_1):PAGE329
    K2 P5E_CPU1_P1_TX_BUF_C_DN<1> @T6G_MB_LIB.T6G(SCH_1):P5E_CPU1_P1_TX_BUF_C_DN(1)   I102 @T6G_MB_LIB.T6G(SCH_1):PAGE329
    K1    GND @T6G_MB_LIB.T6G(SCH_1):GND   I102 @T6G_MB_LIB.T6G(SCH_1):PAGE329
    L4 P5E_CPU1_P1_TX_BUF_C_DP<3> @T6G_MB_LIB.T6G(SCH_1):P5E_CPU1_P1_TX_BUF_C_DP(3)   I102 @T6G_MB_LIB.T6G(SCH_1):PAGE329
    L3 P5E_CPU1_P1_TX_BUF_C_DN<2> @T6G_MB_LIB.T6G(SCH_1):P5E_CPU1_P1_TX_BUF_C_DN(2)   I102 @T6G_MB_LIB.T6G(SCH_1):PAGE329
    L2 P5E_CPU1_P1_TX_BUF_C_DP<1> @T6G_MB_LIB.T6G(SCH_1):P5E_CPU1_P1_TX_BUF_C_DP(1)   I102 @T6G_MB_LIB.T6G(SCH_1):PAGE329
    L1 P5E_CPU1_P1_TX_BUF_C_DN<0> @T6G_MB_LIB.T6G(SCH_1):P5E_CPU1_P1_TX_BUF_C_DN(0)   I102 @T6G_MB_LIB.T6G(SCH_1):PAGE329
    M1 P5E_CPU1_P1_TX_BUF_C_DP<0> @T6G_MB_LIB.T6G(SCH_1):P5E_CPU1_P1_TX_BUF_C_DP(0)   I102 @T6G_MB_LIB.T6G(SCH_1):PAGE329
    N1    GND @T6G_MB_LIB.T6G(SCH_1):GND   I102 @T6G_MB_LIB.T6G(SCH_1):PAGE329
    M2    GND @T6G_MB_LIB.T6G(SCH_1):GND   I102 @T6G_MB_LIB.T6G(SCH_1):PAGE329
    N2 NC_J112_N2 @T6G_MB_LIB.T6G(SCH_1):NC_J112_N2   I102 @T6G_MB_LIB.T6G(SCH_1):PAGE329
    M3 P5E_CPU1_P1_TX_BUF_C_DP<2> @T6G_MB_LIB.T6G(SCH_1):P5E_CPU1_P1_TX_BUF_C_DP(2)   I102 @T6G_MB_LIB.T6G(SCH_1):PAGE329
    N3    GND @T6G_MB_LIB.T6G(SCH_1):GND   I102 @T6G_MB_LIB.T6G(SCH_1):PAGE329
    M4    GND @T6G_MB_LIB.T6G(SCH_1):GND   I102 @T6G_MB_LIB.T6G(SCH_1):PAGE329
    N4 CLK_100M_CPU0_CLK11_DN @T6G_MB_LIB.T6G(SCH_1):CLK_100M_CPU0_CLK11_DN   I102 @T6G_MB_LIB.T6G(SCH_1):PAGE329
    O1 CLK_100M_CPU1_CLK01_DN @T6G_MB_LIB.T6G(SCH_1):CLK_100M_CPU1_CLK01_DN   I102 @T6G_MB_LIB.T6G(SCH_1):PAGE329
    P1 CLK_100M_CPU1_CLK01_DP @T6G_MB_LIB.T6G(SCH_1):CLK_100M_CPU1_CLK01_DP   I102 @T6G_MB_LIB.T6G(SCH_1):PAGE329
    Q1    GND @T6G_MB_LIB.T6G(SCH_1):GND   I102 @T6G_MB_LIB.T6G(SCH_1):PAGE329
    R1 USB2_HUB_BUF_SWB_DN @T6G_MB_LIB.T6G(SCH_1):USB2_HUB_BUF_SWB_DN   I102 @T6G_MB_LIB.T6G(SCH_1):PAGE329
    S1 USB2_HUB_BUF_SWB_DP @T6G_MB_LIB.T6G(SCH_1):USB2_HUB_BUF_SWB_DP   I102 @T6G_MB_LIB.T6G(SCH_1):PAGE329
    T1    GND @T6G_MB_LIB.T6G(SCH_1):GND   I102 @T6G_MB_LIB.T6G(SCH_1):PAGE329
    O2 NC_J112_O2 @T6G_MB_LIB.T6G(SCH_1):NC_J112_O2   I102 @T6G_MB_LIB.T6G(SCH_1):PAGE329
    P2    GND @T6G_MB_LIB.T6G(SCH_1):GND   I102 @T6G_MB_LIB.T6G(SCH_1):PAGE329
    Q2 CLK_100M_GPU_FPGA_DN @T6G_MB_LIB.T6G(SCH_1):CLK_100M_GPU_FPGA_DN   I102 @T6G_MB_LIB.T6G(SCH_1):PAGE329
    R2 CLK_100M_GPU_FPGA_DP @T6G_MB_LIB.T6G(SCH_1):CLK_100M_GPU_FPGA_DP   I102 @T6G_MB_LIB.T6G(SCH_1):PAGE329
    S2    GND @T6G_MB_LIB.T6G(SCH_1):GND   I102 @T6G_MB_LIB.T6G(SCH_1):PAGE329
    T2 GPU_FPGA_READY @T6G_MB_LIB.T6G(SCH_1):GPU_FPGA_READY   I102 @T6G_MB_LIB.T6G(SCH_1):PAGE329
    O3 CLK_100M_CPU1_CLK11_DN @T6G_MB_LIB.T6G(SCH_1):CLK_100M_CPU1_CLK11_DN   I102 @T6G_MB_LIB.T6G(SCH_1):PAGE329
    P3 CLK_100M_CPU1_CLK11_DP @T6G_MB_LIB.T6G(SCH_1):CLK_100M_CPU1_CLK11_DP   I102 @T6G_MB_LIB.T6G(SCH_1):PAGE329
    Q3    GND @T6G_MB_LIB.T6G(SCH_1):GND   I102 @T6G_MB_LIB.T6G(SCH_1):PAGE329
    R3 SMB_2_BMC_GPU_BUF_SCL @T6G_MB_LIB.T6G(SCH_1):SMB_2_BMC_GPU_BUF_SCL   I102 @T6G_MB_LIB.T6G(SCH_1):PAGE329
    S3 SMB_2_BMC_GPU_BUF_SDA @T6G_MB_LIB.T6G(SCH_1):SMB_2_BMC_GPU_BUF_SDA   I102 @T6G_MB_LIB.T6G(SCH_1):PAGE329
    T3    GND @T6G_MB_LIB.T6G(SCH_1):GND   I102 @T6G_MB_LIB.T6G(SCH_1):PAGE329
    O4 CLK_100M_CPU0_CLK11_DP @T6G_MB_LIB.T6G(SCH_1):CLK_100M_CPU0_CLK11_DP   I102 @T6G_MB_LIB.T6G(SCH_1):PAGE329
    P4    GND @T6G_MB_LIB.T6G(SCH_1):GND   I102 @T6G_MB_LIB.T6G(SCH_1):PAGE329
    Q4 SMB_1_BMC_GPU_BUF_SCL @T6G_MB_LIB.T6G(SCH_1):SMB_1_BMC_GPU_BUF_SCL   I102 @T6G_MB_LIB.T6G(SCH_1):PAGE329
    R4 SMB_1_BMC_GPU_BUF_SDA @T6G_MB_LIB.T6G(SCH_1):SMB_1_BMC_GPU_BUF_SDA   I102 @T6G_MB_LIB.T6G(SCH_1):PAGE329
    S4    GND @T6G_MB_LIB.T6G(SCH_1):GND   I102 @T6G_MB_LIB.T6G(SCH_1):PAGE329
    T4 GPU_NVS_PWR_BRAKE_N_BUF @T6G_MB_LIB.T6G(SCH_1):GPU_NVS_PWR_BRAKE_N_BUF   I102 @T6G_MB_LIB.T6G(SCH_1):PAGE329

J114 PICOPROBE_BXA-DELTA-L 4.0,SMLF,EMPTY,TP33
     2 DELTA_L_85_5INCH_IN5_DN @T6G_MB_LIB.T6G(SCH_1):DELTA_L_85_5INCH_IN5_DN    I77 @T6G_MB_LIB.T6G(SCH_1):PAGE211
     3 DELTA_L_GND_1 @T6G_MB_LIB.T6G(SCH_1):DELTA_L_GND_1    I77 @T6G_MB_LIB.T6G(SCH_1):PAGE211
     1 DELTA_L_85_5INCH_IN5_DP @T6G_MB_LIB.T6G(SCH_1):DELTA_L_85_5INCH_IN5_DP    I77 @T6G_MB_LIB.T6G(SCH_1):PAGE211

J115 PICOPROBE_BXA-DELTA-L 4.0,SMLF,EMPTY,TP33
     2 DELTA_L_85_5INCH_IN6_DN @T6G_MB_LIB.T6G(SCH_1):DELTA_L_85_5INCH_IN6_DN    I79 @T6G_MB_LIB.T6G(SCH_1):PAGE211
     3 DELTA_L_GND_1 @T6G_MB_LIB.T6G(SCH_1):DELTA_L_GND_1    I79 @T6G_MB_LIB.T6G(SCH_1):PAGE211
     1 DELTA_L_85_5INCH_IN6_DP @T6G_MB_LIB.T6G(SCH_1):DELTA_L_85_5INCH_IN6_DP    I79 @T6G_MB_LIB.T6G(SCH_1):PAGE211

J116 PICOPROBE_BXA-DELTA-L 4.0,SMLF,EMPTY,TP33
     2 DELTA_L_85_5INCH_IN5_DP @T6G_MB_LIB.T6G(SCH_1):DELTA_L_85_5INCH_IN5_DP    I78 @T6G_MB_LIB.T6G(SCH_1):PAGE211
     3 DELTA_L_GND_1 @T6G_MB_LIB.T6G(SCH_1):DELTA_L_GND_1    I78 @T6G_MB_LIB.T6G(SCH_1):PAGE211
     1 DELTA_L_85_5INCH_IN5_DN @T6G_MB_LIB.T6G(SCH_1):DELTA_L_85_5INCH_IN5_DN    I78 @T6G_MB_LIB.T6G(SCH_1):PAGE211

J117 PICOPROBE_BXA-DELTA-L 4.0,SMLF,EMPTY,TP33
     2 DELTA_L_85_5INCH_IN6_DP @T6G_MB_LIB.T6G(SCH_1):DELTA_L_85_5INCH_IN6_DP    I80 @T6G_MB_LIB.T6G(SCH_1):PAGE211
     3 DELTA_L_GND_1 @T6G_MB_LIB.T6G(SCH_1):DELTA_L_GND_1    I80 @T6G_MB_LIB.T6G(SCH_1):PAGE211
     1 DELTA_L_85_5INCH_IN6_DN @T6G_MB_LIB.T6G(SCH_1):DELTA_L_85_5INCH_IN6_DN    I80 @T6G_MB_LIB.T6G(SCH_1):PAGE211

J118 PICOPROBE_BXA-DELTA-L 4.0,SMLF,EMPTY,TP33
     2 DELTA_L_85_10INCH_IN5_DN @T6G_MB_LIB.T6G(SCH_1):DELTA_L_85_10INCH_IN5_DN    I93 @T6G_MB_LIB.T6G(SCH_1):PAGE211
     3 DELTA_L_GND_1 @T6G_MB_LIB.T6G(SCH_1):DELTA_L_GND_1    I93 @T6G_MB_LIB.T6G(SCH_1):PAGE211
     1 DELTA_L_85_10INCH_IN5_DP @T6G_MB_LIB.T6G(SCH_1):DELTA_L_85_10INCH_IN5_DP    I93 @T6G_MB_LIB.T6G(SCH_1):PAGE211

J119 PICOPROBE_BXA-DELTA-L 4.0,SMLF,EMPTY,TP33
     2 DELTA_L_85_10INCH_IN6_DN @T6G_MB_LIB.T6G(SCH_1):DELTA_L_85_10INCH_IN6_DN    I95 @T6G_MB_LIB.T6G(SCH_1):PAGE211
     3 DELTA_L_GND_1 @T6G_MB_LIB.T6G(SCH_1):DELTA_L_GND_1    I95 @T6G_MB_LIB.T6G(SCH_1):PAGE211
     1 DELTA_L_85_10INCH_IN6_DP @T6G_MB_LIB.T6G(SCH_1):DELTA_L_85_10INCH_IN6_DP    I95 @T6G_MB_LIB.T6G(SCH_1):PAGE211

J120 PICOPROBE_BXA-DELTA-L 4.0,SMLF,EMPTY,TP33
     2 DELTA_L_85_10INCH_IN5_DP @T6G_MB_LIB.T6G(SCH_1):DELTA_L_85_10INCH_IN5_DP    I94 @T6G_MB_LIB.T6G(SCH_1):PAGE211
     3 DELTA_L_GND_1 @T6G_MB_LIB.T6G(SCH_1):DELTA_L_GND_1    I94 @T6G_MB_LIB.T6G(SCH_1):PAGE211
     1 DELTA_L_85_10INCH_IN5_DN @T6G_MB_LIB.T6G(SCH_1):DELTA_L_85_10INCH_IN5_DN    I94 @T6G_MB_LIB.T6G(SCH_1):PAGE211

J121 PICOPROBE_BXA-DELTA-L 4.0,SMLF,EMPTY,TP33
     2 DELTA_L_85_10INCH_IN6_DP @T6G_MB_LIB.T6G(SCH_1):DELTA_L_85_10INCH_IN6_DP    I96 @T6G_MB_LIB.T6G(SCH_1):PAGE211
     3 DELTA_L_GND_1 @T6G_MB_LIB.T6G(SCH_1):DELTA_L_GND_1    I96 @T6G_MB_LIB.T6G(SCH_1):PAGE211
     1 DELTA_L_85_10INCH_IN6_DN @T6G_MB_LIB.T6G(SCH_1):DELTA_L_85_10INCH_IN6_DN    I96 @T6G_MB_LIB.T6G(SCH_1):PAGE211

J122 CONN1_10165288101LF-CONN1_10165288-101LF,THLF,IO,DA
SCR_H1     NC     NC   I101 @T6G_MB_LIB.T6G(SCH_1):PAGE212

J123 CONN1_10165288101LF-CONN1_10165288-101LF,THLF,IO,DA
SCR_H1     NC     NC   I106 @T6G_MB_LIB.T6G(SCH_1):PAGE212

J212 CONN10_HBC1051L300D8H-CONN10_HBC1051-L300D-8H,THLFA
     1 CPU0_XTRIG_L4 @T6G_MB_LIB.T6G(SCH_1):CPU0_XTRIG_L4   I423 @T6G_MB_LIB.T6G(SCH_1):PAGE27
     2 CPU1_XTRIG_L4 @T6G_MB_LIB.T6G(SCH_1):CPU1_XTRIG_L4   I423 @T6G_MB_LIB.T6G(SCH_1):PAGE27
     3 CPU0_XTRIG_L5 @T6G_MB_LIB.T6G(SCH_1):CPU0_XTRIG_L5   I423 @T6G_MB_LIB.T6G(SCH_1):PAGE27
     4 CPU1_XTRIG_L5 @T6G_MB_LIB.T6G(SCH_1):CPU1_XTRIG_L5   I423 @T6G_MB_LIB.T6G(SCH_1):PAGE27
     5 CPU0_XTRIG_L6 @T6G_MB_LIB.T6G(SCH_1):CPU0_XTRIG_L6   I423 @T6G_MB_LIB.T6G(SCH_1):PAGE27
     6 CPU1_XTRIG_L6 @T6G_MB_LIB.T6G(SCH_1):CPU1_XTRIG_L6   I423 @T6G_MB_LIB.T6G(SCH_1):PAGE27
     7 CPU0_XTRIG_L7 @T6G_MB_LIB.T6G(SCH_1):CPU0_XTRIG_L7   I423 @T6G_MB_LIB.T6G(SCH_1):PAGE27
     9     NC     NC   I423 @T6G_MB_LIB.T6G(SCH_1):PAGE27
     8 CPU1_XTRIG_L7 @T6G_MB_LIB.T6G(SCH_1):CPU1_XTRIG_L7   I423 @T6G_MB_LIB.T6G(SCH_1):PAGE27
    10     NC     NC   I423 @T6G_MB_LIB.T6G(SCH_1):PAGE27

J8067 PICOPROBE_BXA-DELTA-L 4.0,SMLF,EMPTY,TP33
     2 DELTA_L_85_5INCH_IN3_DN @T6G_MB_LIB.T6G(SCH_1):DELTA_L_85_5INCH_IN3_DN    I73 @T6G_MB_LIB.T6G(SCH_1):PAGE211
     3 DELTA_L_GND_1 @T6G_MB_LIB.T6G(SCH_1):DELTA_L_GND_1    I73 @T6G_MB_LIB.T6G(SCH_1):PAGE211
     1 DELTA_L_85_5INCH_IN3_DP @T6G_MB_LIB.T6G(SCH_1):DELTA_L_85_5INCH_IN3_DP    I73 @T6G_MB_LIB.T6G(SCH_1):PAGE211

J8068 PICOPROBE_BXA-DELTA-L 4.0,SMLF,EMPTY,TP33
     2 DELTA_L_85_5INCH_IN4_DN @T6G_MB_LIB.T6G(SCH_1):DELTA_L_85_5INCH_IN4_DN    I75 @T6G_MB_LIB.T6G(SCH_1):PAGE211
     3 DELTA_L_GND_1 @T6G_MB_LIB.T6G(SCH_1):DELTA_L_GND_1    I75 @T6G_MB_LIB.T6G(SCH_1):PAGE211
     1 DELTA_L_85_5INCH_IN4_DP @T6G_MB_LIB.T6G(SCH_1):DELTA_L_85_5INCH_IN4_DP    I75 @T6G_MB_LIB.T6G(SCH_1):PAGE211

J8069 PICOPROBE_BXA-DELTA-L 4.0,SMLF,EMPTY,TP33
     2 DELTA_L_85_5INCH_TOP_DP @T6G_MB_LIB.T6G(SCH_1):DELTA_L_85_5INCH_TOP_DP    I66 @T6G_MB_LIB.T6G(SCH_1):PAGE211
     3 DELTA_L_GND_1 @T6G_MB_LIB.T6G(SCH_1):DELTA_L_GND_1    I66 @T6G_MB_LIB.T6G(SCH_1):PAGE211
     1 DELTA_L_85_5INCH_TOP_DN @T6G_MB_LIB.T6G(SCH_1):DELTA_L_85_5INCH_TOP_DN    I66 @T6G_MB_LIB.T6G(SCH_1):PAGE211

JP10 CONN3_210HP1030BR1-CONN3_210-HP1-030BR1,THLF,IO,DFA
     3    GND @T6G_MB_LIB.T6G(SCH_1):GND   I103 @T6G_MB_LIB.T6G(SCH_1):PAGE372
     2 SMB_SML1_PMBUS_HSC_R1_SDA @T6G_MB_LIB.T6G(SCH_1):SMB_SML1_PMBUS_HSC_R1_SDA   I103 @T6G_MB_LIB.T6G(SCH_1):PAGE372
     1 SMB_SML1_PMBUS_HSC_R1_SCL @T6G_MB_LIB.T6G(SCH_1):SMB_SML1_PMBUS_HSC_R1_SCL   I103 @T6G_MB_LIB.T6G(SCH_1):PAGE372

JP12 CONN3_210HP1030BR1-CONN3_210-HP1-030BR1,THLF,IO,DFA
     3    GND @T6G_MB_LIB.T6G(SCH_1):GND   I128 @T6G_MB_LIB.T6G(SCH_1):PAGE156
     2 P1V5_BAT @T6G_MB_LIB.T6G(SCH_1):P1V5_BAT   I128 @T6G_MB_LIB.T6G(SCH_1):PAGE156
     1 P1V5_BAT_OUT_R @T6G_MB_LIB.T6G(SCH_1):P1V5_BAT_OUT_R   I128 @T6G_MB_LIB.T6G(SCH_1):PAGE156

JP4003 CONN3_210HP1030BR1-CONN3_210-HP1-030BR1,THLF,IO,DFA
     3    GND @T6G_MB_LIB.T6G(SCH_1):GND    I18 @T6G_MB_LIB.T6G(SCH_1):PAGE372
     2 PDB_PRSNT_R_N @T6G_MB_LIB.T6G(SCH_1):PDB_PRSNT_R_N    I18 @T6G_MB_LIB.T6G(SCH_1):PAGE372
     1     NC     NC    I18 @T6G_MB_LIB.T6G(SCH_1):PAGE372

JP6000 CONN3_210HP1030BR1-CONN3_210-HP1-030BR1,THLF,IO,DFA
     3 PD_U212_EN_N @T6G_MB_LIB.T6G(SCH_1):PD_U212_EN_N   I386 @T6G_MB_LIB.T6G(SCH_1):PAGE148
     2 U212_EN_N @T6G_MB_LIB.T6G(SCH_1):U212_EN_N   I386 @T6G_MB_LIB.T6G(SCH_1):PAGE148
     1 PU_U212_EN_N @T6G_MB_LIB.T6G(SCH_1):PU_U212_EN_N   I386 @T6G_MB_LIB.T6G(SCH_1):PAGE148

JP6001 CONN3_210HP1030BR1-CONN3_210-HP1-030BR1,THLF,IO,DFA
     3 PD_U160_EN_N @T6G_MB_LIB.T6G(SCH_1):PD_U160_EN_N   I387 @T6G_MB_LIB.T6G(SCH_1):PAGE148
     2 U160_EN_N @T6G_MB_LIB.T6G(SCH_1):U160_EN_N   I387 @T6G_MB_LIB.T6G(SCH_1):PAGE148
     1 PU_U160_EN_N @T6G_MB_LIB.T6G(SCH_1):PU_U160_EN_N   I387 @T6G_MB_LIB.T6G(SCH_1):PAGE148

JP6500 CONN3_210HP1030BR1-CONN3_210-HP1-030BR1,THLF,IO,DFA
     3    GND @T6G_MB_LIB.T6G(SCH_1):GND   I116 @T6G_MB_LIB.T6G(SCH_1):PAGE378
     2 SMB_MUX_RT_R2_SDA @T6G_MB_LIB.T6G(SCH_1):SMB_MUX_RT_R2_SDA   I116 @T6G_MB_LIB.T6G(SCH_1):PAGE378
     1 SMB_MUX_RT_R2_SCL @T6G_MB_LIB.T6G(SCH_1):SMB_MUX_RT_R2_SCL   I116 @T6G_MB_LIB.T6G(SCH_1):PAGE378

  L1 Q_INDUCTOR_SMLF-FCM2012KF-601T/0.5A,IND,CX601T05003
     2 P3V3_9ZXL045_P1 @T6G_MB_LIB.T6G(SCH_1):P3V3_9ZXL045_P1     I2 @T6G_MB_LIB.T6G(SCH_1):PAGE379
     1 P3V3_AUX @T6G_MB_LIB.T6G(SCH_1):P3V3_AUX     I2 @T6G_MB_LIB.T6G(SCH_1):PAGE379

  L2 Q_INDUCTOR_SMLF-FCM2012KF-601T/0.5A,IND,CX601T05003
     2 P3V3_9ZXL045_P1_VDD @T6G_MB_LIB.T6G(SCH_1):P3V3_9ZXL045_P1_VDD    I32 @T6G_MB_LIB.T6G(SCH_1):PAGE379
     1 P3V3_AUX @T6G_MB_LIB.T6G(SCH_1):P3V3_AUX    I32 @T6G_MB_LIB.T6G(SCH_1):PAGE379

  L3 Q_INDUCTOR_SMLF-BLM21SN300SN1D/5A,IND,CX300SN1000
     2 P1V8_CPU1_RT0_1A @T6G_MB_LIB.T6G(SCH_1):P1V8_CPU1_RT0_1A    I22 @T6G_MB_LIB.T6G(SCH_1):PAGE398
     1 P1V8_CPU1_RT_1D @T6G_MB_LIB.T6G(SCH_1):P1V8_CPU1_RT_1D    I22 @T6G_MB_LIB.T6G(SCH_1):PAGE398

  L4 Q_INDUCTOR_SMLF-100NH/16A,IND,CV+10G0MZ04
     2 P0V9_CPU1_RT0_2A @T6G_MB_LIB.T6G(SCH_1):P0V9_CPU1_RT0_2A    I74 @T6G_MB_LIB.T6G(SCH_1):PAGE398
     1 P0V9_CPU1_RT_2D @T6G_MB_LIB.T6G(SCH_1):P0V9_CPU1_RT_2D    I74 @T6G_MB_LIB.T6G(SCH_1):PAGE398

  L5 Q_INDUCTOR_SMLF-BLM21SN300SN1D/5A,IND,CX300SN1000
     2 P1V8_CPU1_RT1_1A @T6G_MB_LIB.T6G(SCH_1):P1V8_CPU1_RT1_1A    I12 @T6G_MB_LIB.T6G(SCH_1):PAGE443
     1 P1V8_CPU1_RT_1D @T6G_MB_LIB.T6G(SCH_1):P1V8_CPU1_RT_1D    I12 @T6G_MB_LIB.T6G(SCH_1):PAGE443

  L6 Q_INDUCTOR_SMLF-100NH/16A,IND,CV+10G0MZ04
     2 P0V9_CPU1_RT1_2A @T6G_MB_LIB.T6G(SCH_1):P0V9_CPU1_RT1_2A    I30 @T6G_MB_LIB.T6G(SCH_1):PAGE443
     1 P0V9_CPU1_RT_2D @T6G_MB_LIB.T6G(SCH_1):P0V9_CPU1_RT_2D    I30 @T6G_MB_LIB.T6G(SCH_1):PAGE443

  L7 Q_INDUCTOR_SMLF-BLM21SN300SN1D/5A,IND,CX300SN1000
     2 P1V8_CPU1_RT2_1A @T6G_MB_LIB.T6G(SCH_1):P1V8_CPU1_RT2_1A    I21 @T6G_MB_LIB.T6G(SCH_1):PAGE454
     1 P1V8_CPU1_RT_1D @T6G_MB_LIB.T6G(SCH_1):P1V8_CPU1_RT_1D    I21 @T6G_MB_LIB.T6G(SCH_1):PAGE454

  L8 Q_INDUCTOR_SMLF-100NH/16A,IND,CV+10G0MZ04
     2 P0V9_CPU1_RT2_2A @T6G_MB_LIB.T6G(SCH_1):P0V9_CPU1_RT2_2A    I74 @T6G_MB_LIB.T6G(SCH_1):PAGE454
     1 P0V9_CPU1_RT_2D @T6G_MB_LIB.T6G(SCH_1):P0V9_CPU1_RT_2D    I74 @T6G_MB_LIB.T6G(SCH_1):PAGE454

  L9 Q_INDUCTOR_SMLF-BLM21SN300SN1D/5A,IND,CX300SN1000
     2 P1V8_CPU1_RT3_1A @T6G_MB_LIB.T6G(SCH_1):P1V8_CPU1_RT3_1A    I11 @T6G_MB_LIB.T6G(SCH_1):PAGE465
     1 P1V8_CPU1_RT_1D @T6G_MB_LIB.T6G(SCH_1):P1V8_CPU1_RT_1D    I11 @T6G_MB_LIB.T6G(SCH_1):PAGE465

 L10 Q_INDUCTOR_SMLF-100NH/16A,IND,CV+10G0MZ04
     2 P0V9_CPU1_RT3_2A @T6G_MB_LIB.T6G(SCH_1):P0V9_CPU1_RT3_2A    I63 @T6G_MB_LIB.T6G(SCH_1):PAGE465
     1 P0V9_CPU1_RT_2D @T6G_MB_LIB.T6G(SCH_1):P0V9_CPU1_RT_2D    I63 @T6G_MB_LIB.T6G(SCH_1):PAGE465

 L11 Q_INDUCTOR_SMLF-BLM21SN300SN1D/5A,IND,CX300SN1000
     2 P1V8_CPU0_RT0_1A @T6G_MB_LIB.T6G(SCH_1):P1V8_CPU0_RT0_1A    I12 @T6G_MB_LIB.T6G(SCH_1):PAGE388
     1 P1V8_CPU0_RT_1D @T6G_MB_LIB.T6G(SCH_1):P1V8_CPU0_RT_1D    I12 @T6G_MB_LIB.T6G(SCH_1):PAGE388

 L12 Q_INDUCTOR_SMLF-100NH/16A,IND,CV+10G0MZ04
     2 P0V9_CPU0_RT0_2A @T6G_MB_LIB.T6G(SCH_1):P0V9_CPU0_RT0_2A    I30 @T6G_MB_LIB.T6G(SCH_1):PAGE388
     1 P0V9_CPU0_RT_2D @T6G_MB_LIB.T6G(SCH_1):P0V9_CPU0_RT_2D    I30 @T6G_MB_LIB.T6G(SCH_1):PAGE388

 L13 Q_INDUCTOR_SMLF-BLM21SN300SN1D/5A,IND,CX300SN1000
     2 P1V8_CPU0_RT1_1A @T6G_MB_LIB.T6G(SCH_1):P1V8_CPU0_RT1_1A    I11 @T6G_MB_LIB.T6G(SCH_1):PAGE411
     1 P1V8_CPU0_RT_1D @T6G_MB_LIB.T6G(SCH_1):P1V8_CPU0_RT_1D    I11 @T6G_MB_LIB.T6G(SCH_1):PAGE411

 L14 Q_INDUCTOR_SMLF-100NH/16A,IND,CV+10G0MZ04
     2 P0V9_CPU0_RT1_2A @T6G_MB_LIB.T6G(SCH_1):P0V9_CPU0_RT1_2A    I63 @T6G_MB_LIB.T6G(SCH_1):PAGE411
     1 P0V9_CPU0_RT_2D @T6G_MB_LIB.T6G(SCH_1):P0V9_CPU0_RT_2D    I63 @T6G_MB_LIB.T6G(SCH_1):PAGE411

 L15 Q_INDUCTOR_SMLF-BLM18PG300SN1D ,IND,TMP_QCX8PG3000A
     2 P3V3_AUX @T6G_MB_LIB.T6G(SCH_1):P3V3_AUX   I167 @T6G_MB_LIB.T6G(SCH_1):PAGE369
     1 P3V3_MAX11617_VDD @T6G_MB_LIB.T6G(SCH_1):P3V3_MAX11617_VDD   I167 @T6G_MB_LIB.T6G(SCH_1):PAGE369

 L16 Q_INDUCTOR_SMLF-BLM18PG300SN1D ,IND,TMP_QCX8PG3000A
     2 P3V3_ADC128_VCC @T6G_MB_LIB.T6G(SCH_1):P3V3_ADC128_VCC    I69 @T6G_MB_LIB.T6G(SCH_1):PAGE369
     1 P3V3_AUX @T6G_MB_LIB.T6G(SCH_1):P3V3_AUX    I69 @T6G_MB_LIB.T6G(SCH_1):PAGE369

 L17 Q_INDUCTOR_SMLF-FCM2012KF-601T/0.5A,IND,CX601T05003
     2 VFG3P3_CLK_GEN @T6G_MB_LIB.T6G(SCH_1):VFG3P3_CLK_GEN    I33 @T6G_MB_LIB.T6G(SCH_1):PAGE232
     1 P3V3_AUX @T6G_MB_LIB.T6G(SCH_1):P3V3_AUX    I33 @T6G_MB_LIB.T6G(SCH_1):PAGE232

 L18 Q_INDUCTOR_SMLF-BLM21SN300SN1D/5A,IND,CX300SN1000
     2 P1V8_CPU0_RT2_1A @T6G_MB_LIB.T6G(SCH_1):P1V8_CPU0_RT2_1A    I23 @T6G_MB_LIB.T6G(SCH_1):PAGE422
     1 P1V8_CPU0_RT_1D @T6G_MB_LIB.T6G(SCH_1):P1V8_CPU0_RT_1D    I23 @T6G_MB_LIB.T6G(SCH_1):PAGE422

 L19 Q_INDUCTOR_SMLF-FCM2012KF-601T/0.5A,IND,CX601T05003
     2 P3V3_9ZXL045_P0 @T6G_MB_LIB.T6G(SCH_1):P3V3_9ZXL045_P0    I26 @T6G_MB_LIB.T6G(SCH_1):PAGE160
     1 P3V3_AUX @T6G_MB_LIB.T6G(SCH_1):P3V3_AUX    I26 @T6G_MB_LIB.T6G(SCH_1):PAGE160

 L20 Q_INDUCTOR_SMLF-FCM2012KF-601T/0.5A,IND,CX601T05003
     2 P3V3_9ZXL045_P0_VDD @T6G_MB_LIB.T6G(SCH_1):P3V3_9ZXL045_P0_VDD    I24 @T6G_MB_LIB.T6G(SCH_1):PAGE160
     1 P3V3_AUX @T6G_MB_LIB.T6G(SCH_1):P3V3_AUX    I24 @T6G_MB_LIB.T6G(SCH_1):PAGE160

 L21 Q_INDUCTOR_SMLF-100NH/16A,IND,CV+10G0MZ04
     2 P0V9_CPU0_RT2_2A @T6G_MB_LIB.T6G(SCH_1):P0V9_CPU0_RT2_2A    I30 @T6G_MB_LIB.T6G(SCH_1):PAGE422
     1 P0V9_CPU0_RT_2D @T6G_MB_LIB.T6G(SCH_1):P0V9_CPU0_RT_2D    I30 @T6G_MB_LIB.T6G(SCH_1):PAGE422

 L22 Q_INDUCTOR_SMLF-BLM21SN300SN1D/5A,IND,CX300SN1000
     2 P1V8_CPU0_RT3_1A @T6G_MB_LIB.T6G(SCH_1):P1V8_CPU0_RT3_1A    I10 @T6G_MB_LIB.T6G(SCH_1):PAGE433
     1 P1V8_CPU0_RT_1D @T6G_MB_LIB.T6G(SCH_1):P1V8_CPU0_RT_1D    I10 @T6G_MB_LIB.T6G(SCH_1):PAGE433

 L23 Q_INDUCTOR_SMLF-100NH/16A,IND,CV+10G0MZ04
     2 P0V9_CPU0_RT3_2A @T6G_MB_LIB.T6G(SCH_1):P0V9_CPU0_RT3_2A    I65 @T6G_MB_LIB.T6G(SCH_1):PAGE433
     1 P0V9_CPU0_RT_2D @T6G_MB_LIB.T6G(SCH_1):P0V9_CPU0_RT_2D    I65 @T6G_MB_LIB.T6G(SCH_1):PAGE433

 L24 Q_INDUCTOR_SMLF-BLM18PG300SN1D ,IND,TMP_QCX8PG3000A
     2 P3V3_AUX @T6G_MB_LIB.T6G(SCH_1):P3V3_AUX   I168 @T6G_MB_LIB.T6G(SCH_1):PAGE263
     1 P3V3_MAX11617_2_VDD @T6G_MB_LIB.T6G(SCH_1):P3V3_MAX11617_2_VDD   I168 @T6G_MB_LIB.T6G(SCH_1):PAGE263

 L25 Q_INDUCTOR_SMLF-BLM18PG300SN1D ,IND,TMP_QCX8PG3000A
     2 P3V3_ADC128_2_VCC @T6G_MB_LIB.T6G(SCH_1):P3V3_ADC128_2_VCC    I69 @T6G_MB_LIB.T6G(SCH_1):PAGE263
     1 P3V3_AUX @T6G_MB_LIB.T6G(SCH_1):P3V3_AUX    I69 @T6G_MB_LIB.T6G(SCH_1):PAGE263

 L26 Q_INDUCTOR_SMLF-BLM15PD121SN1D/1300MA,IND,CX5PD121A
     2 P1V8_CPU0_RT0_1A_1D @T6G_MB_LIB.T6G(SCH_1):P1V8_CPU0_RT0_1A_1D    I88 @T6G_MB_LIB.T6G(SCH_1):PAGE388
     1 P1V8_CPU0_RT_1D @T6G_MB_LIB.T6G(SCH_1):P1V8_CPU0_RT_1D    I88 @T6G_MB_LIB.T6G(SCH_1):PAGE388

 L27 Q_INDUCTOR_SMLF-BLM15PD121SN1D/1300MA,IND,CX5PD121A
     2 P1V8_CPU1_RT0_1A_1D @T6G_MB_LIB.T6G(SCH_1):P1V8_CPU1_RT0_1A_1D    I97 @T6G_MB_LIB.T6G(SCH_1):PAGE398
     1 P1V8_CPU1_RT_1D @T6G_MB_LIB.T6G(SCH_1):P1V8_CPU1_RT_1D    I97 @T6G_MB_LIB.T6G(SCH_1):PAGE398

 L28 Q_INDUCTOR_SMLF-BLM15PD121SN1D/1300MA,IND,CX5PD121A
     2 P1V8_CPU0_RT1_1A_1D @T6G_MB_LIB.T6G(SCH_1):P1V8_CPU0_RT1_1A_1D    I88 @T6G_MB_LIB.T6G(SCH_1):PAGE411
     1 P1V8_CPU0_RT_1D @T6G_MB_LIB.T6G(SCH_1):P1V8_CPU0_RT_1D    I88 @T6G_MB_LIB.T6G(SCH_1):PAGE411

 L29 Q_INDUCTOR_SMLF-BLM15PD121SN1D/1300MA,IND,CX5PD121A
     2 P1V8_CPU0_RT2_1A_1D @T6G_MB_LIB.T6G(SCH_1):P1V8_CPU0_RT2_1A_1D    I88 @T6G_MB_LIB.T6G(SCH_1):PAGE422
     1 P1V8_CPU0_RT_1D @T6G_MB_LIB.T6G(SCH_1):P1V8_CPU0_RT_1D    I88 @T6G_MB_LIB.T6G(SCH_1):PAGE422

 L30 Q_INDUCTOR_SMLF-BLM15PD121SN1D/1300MA,IND,CX5PD121A
     2 P1V8_CPU0_RT3_1A_1D @T6G_MB_LIB.T6G(SCH_1):P1V8_CPU0_RT3_1A_1D    I88 @T6G_MB_LIB.T6G(SCH_1):PAGE433
     1 P1V8_CPU0_RT_1D @T6G_MB_LIB.T6G(SCH_1):P1V8_CPU0_RT_1D    I88 @T6G_MB_LIB.T6G(SCH_1):PAGE433

 L31 Q_INDUCTOR_SMLF-BLM15PD121SN1D/1300MA,IND,CX5PD121A
     2 P1V8_CPU1_RT1_1A_1D @T6G_MB_LIB.T6G(SCH_1):P1V8_CPU1_RT1_1A_1D    I88 @T6G_MB_LIB.T6G(SCH_1):PAGE443
     1 P1V8_CPU1_RT_1D @T6G_MB_LIB.T6G(SCH_1):P1V8_CPU1_RT_1D    I88 @T6G_MB_LIB.T6G(SCH_1):PAGE443

 L32 Q_INDUCTOR_SMLF-BLM15PD121SN1D/1300MA,IND,CX5PD121A
     2 P1V8_CPU1_RT2_1A_1D @T6G_MB_LIB.T6G(SCH_1):P1V8_CPU1_RT2_1A_1D    I88 @T6G_MB_LIB.T6G(SCH_1):PAGE454
     1 P1V8_CPU1_RT_1D @T6G_MB_LIB.T6G(SCH_1):P1V8_CPU1_RT_1D    I88 @T6G_MB_LIB.T6G(SCH_1):PAGE454

 L33 Q_INDUCTOR_SMLF-BLM15PD121SN1D/1300MA,IND,CX5PD121A
     2 P1V8_CPU1_RT3_1A_1D @T6G_MB_LIB.T6G(SCH_1):P1V8_CPU1_RT3_1A_1D    I88 @T6G_MB_LIB.T6G(SCH_1):PAGE465
     1 P1V8_CPU1_RT_1D @T6G_MB_LIB.T6G(SCH_1):P1V8_CPU1_RT_1D    I88 @T6G_MB_LIB.T6G(SCH_1):PAGE465

L6000 Q_INDUCTOR_SMLF-BLM21PG221SN1D,IND,CX1PG221001
     2 P3V3_AUX_CPU0_USB_AVDD33 @T6G_MB_LIB.T6G(SCH_1):P3V3_AUX_CPU0_USB_AVDD33     I3 @T6G_MB_LIB.T6G(SCH_1):PAGE154
     1 P3V3_AUX @T6G_MB_LIB.T6G(SCH_1):P3V3_AUX     I3 @T6G_MB_LIB.T6G(SCH_1):PAGE154

L6001 Q_INDUCTOR_SMLF-BLM21PG221SN1D,IND,CX1PG221001
     2 P1V2_CPU0_USB_DVDD12 @T6G_MB_LIB.T6G(SCH_1):P1V2_CPU0_USB_DVDD12    I26 @T6G_MB_LIB.T6G(SCH_1):PAGE154
     1 P1V2_AUX @T6G_MB_LIB.T6G(SCH_1):P1V2_AUX    I26 @T6G_MB_LIB.T6G(SCH_1):PAGE154

L6003 Q_INDUCTOR_SMLF-BLM21PG221SN1D,IND,CX1PG221001
     2 P3V3_AUX_CPU0_USB2_AVDD33 @T6G_MB_LIB.T6G(SCH_1):P3V3_AUX_CPU0_USB2_AVDD33    I17 @T6G_MB_LIB.T6G(SCH_1):PAGE157
     1 P3V3_AUX @T6G_MB_LIB.T6G(SCH_1):P3V3_AUX    I17 @T6G_MB_LIB.T6G(SCH_1):PAGE157

L6004 Q_INDUCTOR_SMLF-BLM21PG221SN1D,IND,CX1PG221001
     2 P1V2_CPU0_USB2_DVDD12 @T6G_MB_LIB.T6G(SCH_1):P1V2_CPU0_USB2_DVDD12    I20 @T6G_MB_LIB.T6G(SCH_1):PAGE157
     1 P1V2_AUX @T6G_MB_LIB.T6G(SCH_1):P1V2_AUX    I20 @T6G_MB_LIB.T6G(SCH_1):PAGE157

OSC1 Q_OSC4P_SMLF-50MHZ,OSC,BF650000032
     1 CLK_50M_EN @T6G_MB_LIB.T6G(SCH_1):CLK_50M_EN     I4 @T6G_MB_LIB.T6G(SCH_1):PAGE337
     3 CLK_50M_RMII @T6G_MB_LIB.T6G(SCH_1):CLK_50M_RMII     I4 @T6G_MB_LIB.T6G(SCH_1):PAGE337
     2    GND @T6G_MB_LIB.T6G(SCH_1):GND     I4 @T6G_MB_LIB.T6G(SCH_1):PAGE337
     4 P3V3_AUX @T6G_MB_LIB.T6G(SCH_1):P3V3_AUX     I4 @T6G_MB_LIB.T6G(SCH_1):PAGE337

 PC3 Q_CAPP_THLF-270UF,16V,20%,OSCON,CC72703MD38
     1 SW_P3V3_AUX_FLT @T6G_MB_LIB.T6G(SCH_1):SW_P3V3_AUX_FLT    I29 @T6G_MB_LIB.T6G(SCH_1):PAGE245
     2    GND @T6G_MB_LIB.T6G(SCH_1):GND    I29 @T6G_MB_LIB.T6G(SCH_1):PAGE245

 PC4 Q_CAP_0402-0.1UF,25V,10%,X7R,CH4104K1B00
     1 PVDD11_S3_P0_VCC @T6G_MB_LIB.T6G(SCH_1):PVDD11_S3_P0_VCC    I79 @T6G_MB_LIB.T6G(SCH_1):PAGE182
     2    GND @T6G_MB_LIB.T6G(SCH_1):GND    I79 @T6G_MB_LIB.T6G(SCH_1):PAGE182

 PC5 Q_CAP_0402-0.1UF,25V,10%,X7R,CH4104K1B00
     1 PVDD11_S3_P0_VINSEN @T6G_MB_LIB.T6G(SCH_1):PVDD11_S3_P0_VINSEN    I20 @T6G_MB_LIB.T6G(SCH_1):PAGE182
     2    GND @T6G_MB_LIB.T6G(SCH_1):GND    I20 @T6G_MB_LIB.T6G(SCH_1):PAGE182

 PC6 Q_CAP_0402-0.1UF,25V,10%,X7R,CH4104K1B00
     1 PVDDCR_CPU0_P1_VINSEN @T6G_MB_LIB.T6G(SCH_1):PVDDCR_CPU0_P1_VINSEN    I51 @T6G_MB_LIB.T6G(SCH_1):PAGE185
     2    GND @T6G_MB_LIB.T6G(SCH_1):GND    I51 @T6G_MB_LIB.T6G(SCH_1):PAGE185

 PC7 Q_CAP_0402-0.1UF,25V,10%,X7R,CH4104K1B00
     1 PVDDCR_CPU0_P0_VINSEN @T6G_MB_LIB.T6G(SCH_1):PVDDCR_CPU0_P0_VINSEN    I50 @T6G_MB_LIB.T6G(SCH_1):PAGE168
     2    GND @T6G_MB_LIB.T6G(SCH_1):GND    I50 @T6G_MB_LIB.T6G(SCH_1):PAGE168

 PC8 Q_CAP_0402-0.1UF,25V,10%,X7R,CH4104K1B00
     1 PVDD11_S3_P1_VINSEN @T6G_MB_LIB.T6G(SCH_1):PVDD11_S3_P1_VINSEN    I20 @T6G_MB_LIB.T6G(SCH_1):PAGE199
     2    GND @T6G_MB_LIB.T6G(SCH_1):GND    I20 @T6G_MB_LIB.T6G(SCH_1):PAGE199

 PC9 Q_CAP_0402-0.1UF,25V,10%,X7R,CH4104K1B00
     1 PVDD11_S3_P0_VCCS @T6G_MB_LIB.T6G(SCH_1):PVDD11_S3_P0_VCCS    I77 @T6G_MB_LIB.T6G(SCH_1):PAGE182
     2    GND @T6G_MB_LIB.T6G(SCH_1):GND    I77 @T6G_MB_LIB.T6G(SCH_1):PAGE182

PC10 Q_CAP_0402-0.1UF,25V,10%,X7R,CH4104K1B00
     1 PVDDCR_CPU0_P1_VCC @T6G_MB_LIB.T6G(SCH_1):PVDDCR_CPU0_P1_VCC   I116 @T6G_MB_LIB.T6G(SCH_1):PAGE185
     2    GND @T6G_MB_LIB.T6G(SCH_1):GND   I116 @T6G_MB_LIB.T6G(SCH_1):PAGE185

PC11 Q_CAP_0402-0.1UF,25V,10%,X7R,CH4104K1B00
     1 PVDDCR_CPU0_P1_VCCS @T6G_MB_LIB.T6G(SCH_1):PVDDCR_CPU0_P1_VCCS   I114 @T6G_MB_LIB.T6G(SCH_1):PAGE185
     2    GND @T6G_MB_LIB.T6G(SCH_1):GND   I114 @T6G_MB_LIB.T6G(SCH_1):PAGE185

PC12 Q_CAP_0402-0.1UF,25V,10%,X7R,CH4104K1B00
     1 PVDDCR_CPU0_P0_VCC @T6G_MB_LIB.T6G(SCH_1):PVDDCR_CPU0_P0_VCC   I120 @T6G_MB_LIB.T6G(SCH_1):PAGE168
     2    GND @T6G_MB_LIB.T6G(SCH_1):GND   I120 @T6G_MB_LIB.T6G(SCH_1):PAGE168

PC13 Q_CAP_0402-0.1UF,25V,10%,X7R,CH4104K1B00
     1 PVDDCR_CPU0_P0_VCCS @T6G_MB_LIB.T6G(SCH_1):PVDDCR_CPU0_P0_VCCS   I118 @T6G_MB_LIB.T6G(SCH_1):PAGE168
     2    GND @T6G_MB_LIB.T6G(SCH_1):GND   I118 @T6G_MB_LIB.T6G(SCH_1):PAGE168

PC14 Q_CAP_0402-0.1UF,25V,10%,X7R,CH4104K1B00
     1 PVDDCR_CPU1_P0_VCC @T6G_MB_LIB.T6G(SCH_1):PVDDCR_CPU1_P0_VCC    I96 @T6G_MB_LIB.T6G(SCH_1):PAGE175
     2    GND @T6G_MB_LIB.T6G(SCH_1):GND    I96 @T6G_MB_LIB.T6G(SCH_1):PAGE175

PC15 Q_CAP_0402-0.1UF,25V,10%,X7R,CH4104K1B00
     1 PVDDCR_CPU1_P0_VCCS @T6G_MB_LIB.T6G(SCH_1):PVDDCR_CPU1_P0_VCCS    I94 @T6G_MB_LIB.T6G(SCH_1):PAGE175
     2    GND @T6G_MB_LIB.T6G(SCH_1):GND    I94 @T6G_MB_LIB.T6G(SCH_1):PAGE175

PC19 Q_CAP_0402-0.22UF,16V,10%,X7R,CH4223K1B00
     1 SW_PVDD18_S5_P1_BST_R @T6G_MB_LIB.T6G(SCH_1):SW_PVDD18_S5_P1_BST_R    I25 @T6G_MB_LIB.T6G(SCH_1):PAGE201
     2 SW_PVDD18_S5_P1_SW @T6G_MB_LIB.T6G(SCH_1):SW_PVDD18_S5_P1_SW    I25 @T6G_MB_LIB.T6G(SCH_1):PAGE201

PC20 Q_CAP_C0402-1UF,25V,10%,X6S,CH5104KEB02
     1 PVDD18_S5_P1_VCC @T6G_MB_LIB.T6G(SCH_1):PVDD18_S5_P1_VCC    I53 @T6G_MB_LIB.T6G(SCH_1):PAGE201
     2    GND @T6G_MB_LIB.T6G(SCH_1):GND    I53 @T6G_MB_LIB.T6G(SCH_1):PAGE201

PC21 Q_CAP_0402-0.1UF,25V,10%,X7R,CH4104K1B00
     1 PVDD18_S5_P1 @T6G_MB_LIB.T6G(SCH_1):PVDD18_S5_P1    I47 @T6G_MB_LIB.T6G(SCH_1):PAGE201
     2    GND @T6G_MB_LIB.T6G(SCH_1):GND    I47 @T6G_MB_LIB.T6G(SCH_1):PAGE201

PC22 Q_CAP_C0402-1UF,25V,10%,X6S,CH5104KEB02
     1 SW_P12V_AUX_PVDD18_S5_P1_FLT @T6G_MB_LIB.T6G(SCH_1):SW_P12V_AUX_PVDD18_S5_P1_FLT    I24 @T6G_MB_LIB.T6G(SCH_1):PAGE201
     2    GND @T6G_MB_LIB.T6G(SCH_1):GND    I24 @T6G_MB_LIB.T6G(SCH_1):PAGE201

PC27 Q_CAP_C0805-22UF,16V,20%,X6S,CH6223MEA01
     1 SW_P12V_AUX_PVDD11_S3_P1_FLT @T6G_MB_LIB.T6G(SCH_1):SW_P12V_AUX_PVDD11_S3_P1_FLT    I58 @T6G_MB_LIB.T6G(SCH_1):PAGE200
     2    GND @T6G_MB_LIB.T6G(SCH_1):GND    I58 @T6G_MB_LIB.T6G(SCH_1):PAGE200

PC29 Q_CAP_0402-0.1UF,25V,10%,X7R,CH4104K1B00
     1 PVDDCR_CPU1_P1_VCC @T6G_MB_LIB.T6G(SCH_1):PVDDCR_CPU1_P1_VCC    I95 @T6G_MB_LIB.T6G(SCH_1):PAGE192
     2    GND @T6G_MB_LIB.T6G(SCH_1):GND    I95 @T6G_MB_LIB.T6G(SCH_1):PAGE192

PC60 Q_CAP_C0805-22UF,16V,20%,X6S,CH6223MEA01
     1 SW_P12V_AUX_PVDD18_S5_P1_FLT @T6G_MB_LIB.T6G(SCH_1):SW_P12V_AUX_PVDD18_S5_P1_FLT    I54 @T6G_MB_LIB.T6G(SCH_1):PAGE201
     2    GND @T6G_MB_LIB.T6G(SCH_1):GND    I54 @T6G_MB_LIB.T6G(SCH_1):PAGE201

PC61 Q_CAP_C0805-22UF,16V,20%,X6S,CH6223MEA01
     1 SW_P12V_AUX_PVDD18_S5_P1_FLT @T6G_MB_LIB.T6G(SCH_1):SW_P12V_AUX_PVDD18_S5_P1_FLT    I21 @T6G_MB_LIB.T6G(SCH_1):PAGE201
     2    GND @T6G_MB_LIB.T6G(SCH_1):GND    I21 @T6G_MB_LIB.T6G(SCH_1):PAGE201

PC62 Q_CAP_0402-0.1UF,25V,10%,X7R,CH4104K1B00
     1 PVDD18_S5_P1_REF @T6G_MB_LIB.T6G(SCH_1):PVDD18_S5_P1_REF    I19 @T6G_MB_LIB.T6G(SCH_1):PAGE201
     2 PVDD18_SS_P1_RGND @T6G_MB_LIB.T6G(SCH_1):PVDD18_SS_P1_RGND    I19 @T6G_MB_LIB.T6G(SCH_1):PAGE201

PC64 Q_CAP_0402-220PF,50V,10%,X7R,TMP_QCH12206KB14
     1 PVDD18_S5_P1_FB @T6G_MB_LIB.T6G(SCH_1):PVDD18_S5_P1_FB    I31 @T6G_MB_LIB.T6G(SCH_1):PAGE201
     2 PVDD18_S5_P1_FB_RC @T6G_MB_LIB.T6G(SCH_1):PVDD18_S5_P1_FB_RC    I31 @T6G_MB_LIB.T6G(SCH_1):PAGE201

PC65 Q_CAP_C0805-22UF,4V,20%,X6S,CH622KMEA03
     1 PVDD18_S5_P1 @T6G_MB_LIB.T6G(SCH_1):PVDD18_S5_P1    I37 @T6G_MB_LIB.T6G(SCH_1):PAGE201
     2    GND @T6G_MB_LIB.T6G(SCH_1):GND    I37 @T6G_MB_LIB.T6G(SCH_1):PAGE201

PC67 Q_CAP_0402-0.1UF,25V,10%,X7R,CH4104K1B00
     1 PVDDCR_CPU1_P0_VMON @T6G_MB_LIB.T6G(SCH_1):PVDDCR_CPU1_P0_VMON    I50 @T6G_MB_LIB.T6G(SCH_1):PAGE175
     2    GND @T6G_MB_LIB.T6G(SCH_1):GND    I50 @T6G_MB_LIB.T6G(SCH_1):PAGE175

PC68 Q_CAP_0402-3300PF,50V,10%,X7R,TMP_QCH2336K1B12
     1 VSENSE_PVDDCR_CPU1_P0_VSEN0 @T6G_MB_LIB.T6G(SCH_1):VSENSE_PVDDCR_CPU1_P0_VSEN0    I80 @T6G_MB_LIB.T6G(SCH_1):PAGE175
     2 VSENSE_VSS_SENSE_C_P0 @T6G_MB_LIB.T6G(SCH_1):VSENSE_VSS_SENSE_C_P0    I80 @T6G_MB_LIB.T6G(SCH_1):PAGE175

PC71 Q_CAP_0402-3300PF,50V,10%,X7R,TMP_QCH2336K1B12
     1 VSENSE_PVDDIO_P0_VSEN1 @T6G_MB_LIB.T6G(SCH_1):VSENSE_PVDDIO_P0_VSEN1    I69 @T6G_MB_LIB.T6G(SCH_1):PAGE175
     2 VSENSE_VSS_SENSE_B_P0 @T6G_MB_LIB.T6G(SCH_1):VSENSE_VSS_SENSE_B_P0    I69 @T6G_MB_LIB.T6G(SCH_1):PAGE175

PC73 Q_CAP_0402-1UF,6.3V,10%,X7R,CH5101K1B01
     1 PVDD18_S5_P0 @T6G_MB_LIB.T6G(SCH_1):PVDD18_S5_P0    I63 @T6G_MB_LIB.T6G(SCH_1):PAGE175
     2    GND @T6G_MB_LIB.T6G(SCH_1):GND    I63 @T6G_MB_LIB.T6G(SCH_1):PAGE175

PC74 Q_CAP_0402-0.1UF,25V,10%,X7R,CH4104K1B00
     1 PVDDCR_CPU1_P0_VINSEN @T6G_MB_LIB.T6G(SCH_1):PVDDCR_CPU1_P0_VINSEN    I60 @T6G_MB_LIB.T6G(SCH_1):PAGE175
     2    GND @T6G_MB_LIB.T6G(SCH_1):GND    I60 @T6G_MB_LIB.T6G(SCH_1):PAGE175

PC75 Q_CAP_C0402-1UF,16V,10%,X6S,CH5103KEB01
     1 PVDDCR_CPU1_P0_VCC @T6G_MB_LIB.T6G(SCH_1):PVDDCR_CPU1_P0_VCC   I100 @T6G_MB_LIB.T6G(SCH_1):PAGE175
     2    GND @T6G_MB_LIB.T6G(SCH_1):GND   I100 @T6G_MB_LIB.T6G(SCH_1):PAGE175

PC76 Q_CAP_C0402-10UF,6.3V,20%,X6S,CH6101MEB03
     1 PVDDCR_CPU1_P0_VCCS @T6G_MB_LIB.T6G(SCH_1):PVDDCR_CPU1_P0_VCCS    I98 @T6G_MB_LIB.T6G(SCH_1):PAGE175
     2    GND @T6G_MB_LIB.T6G(SCH_1):GND    I98 @T6G_MB_LIB.T6G(SCH_1):PAGE175

PC77 Q_CAP_0402-470PF,50V,10%,X7R,TMP_QCH14706KB18
     1 PVDDIO_P0_TEMP1 @T6G_MB_LIB.T6G(SCH_1):PVDDIO_P0_TEMP1    I75 @T6G_MB_LIB.T6G(SCH_1):PAGE175
     2    GND @T6G_MB_LIB.T6G(SCH_1):GND    I75 @T6G_MB_LIB.T6G(SCH_1):PAGE175

PC78 Q_CAP_0402-470PF,50V,10%,X7R,TMP_QCH14706KB18
     1 PVDDCR_CPU1_P0_TEMP0 @T6G_MB_LIB.T6G(SCH_1):PVDDCR_CPU1_P0_TEMP0    I73 @T6G_MB_LIB.T6G(SCH_1):PAGE175
     2    GND @T6G_MB_LIB.T6G(SCH_1):GND    I73 @T6G_MB_LIB.T6G(SCH_1):PAGE175

PC79 Q_CAP_C0402-2.2UF,10V,10%,X6S,CH5222KEB01
     1 PVDDCR_CPU1_P0_VCC1 @T6G_MB_LIB.T6G(SCH_1):PVDDCR_CPU1_P0_VCC1    I24 @T6G_MB_LIB.T6G(SCH_1):PAGE176
     2    GND @T6G_MB_LIB.T6G(SCH_1):GND    I24 @T6G_MB_LIB.T6G(SCH_1):PAGE176

PC80 Q_CAP_C0402-2.2UF,10V,10%,X6S,CH5222KEB01
     1 PVDDCR_CPU1_P0_VCC2 @T6G_MB_LIB.T6G(SCH_1):PVDDCR_CPU1_P0_VCC2    I10 @T6G_MB_LIB.T6G(SCH_1):PAGE176
     2    GND @T6G_MB_LIB.T6G(SCH_1):GND    I10 @T6G_MB_LIB.T6G(SCH_1):PAGE176

PC81 Q_CAP_C0805-22UF,16V,20%,X6S,CH6223MEA01
     1 SW_P12V_AUX_PVDD18_S5_P0_FLT @T6G_MB_LIB.T6G(SCH_1):SW_P12V_AUX_PVDD18_S5_P0_FLT    I27 @T6G_MB_LIB.T6G(SCH_1):PAGE184
     2    GND @T6G_MB_LIB.T6G(SCH_1):GND    I27 @T6G_MB_LIB.T6G(SCH_1):PAGE184

PC81_C1P0_1 Q_CAP_C0402-2.2UF,10V,10%,X6S,CH5222KEB01
     1 PVDDCR_CPU1_P0_PVCC @T6G_MB_LIB.T6G(SCH_1):PVDDCR_CPU1_P0_PVCC    I30 @T6G_MB_LIB.T6G(SCH_1):PAGE176
     2    GND @T6G_MB_LIB.T6G(SCH_1):GND    I30 @T6G_MB_LIB.T6G(SCH_1):PAGE176

PC82_C1P0_2 Q_CAP_C0402-2.2UF,10V,10%,X6S,CH5222KEB01
     1 PVDDCR_CPU1_P0_PVCC @T6G_MB_LIB.T6G(SCH_1):PVDDCR_CPU1_P0_PVCC    I15 @T6G_MB_LIB.T6G(SCH_1):PAGE176
     2    GND @T6G_MB_LIB.T6G(SCH_1):GND    I15 @T6G_MB_LIB.T6G(SCH_1):PAGE176

PC83 Q_CAP_C0805-22UF,4V,20%,X6S,CH622KMEA03
     1 PVDD18_S5_P1 @T6G_MB_LIB.T6G(SCH_1):PVDD18_S5_P1    I38 @T6G_MB_LIB.T6G(SCH_1):PAGE201
     2    GND @T6G_MB_LIB.T6G(SCH_1):GND    I38 @T6G_MB_LIB.T6G(SCH_1):PAGE201

PC83_2 Q_CAP_0402-0.1UF,25V,10%,X7R,CH4104K1B00
     1 PVDDCR_CPU1_P0_VCCS @T6G_MB_LIB.T6G(SCH_1):PVDDCR_CPU1_P0_VCCS     I2 @T6G_MB_LIB.T6G(SCH_1):PAGE176
     2    GND @T6G_MB_LIB.T6G(SCH_1):GND     I2 @T6G_MB_LIB.T6G(SCH_1):PAGE176

PC84 Q_CAP_C0805-22UF,4V,20%,X6S,CH622KMEA03
     1 PVDD18_S5_P1 @T6G_MB_LIB.T6G(SCH_1):PVDD18_S5_P1    I40 @T6G_MB_LIB.T6G(SCH_1):PAGE201
     2    GND @T6G_MB_LIB.T6G(SCH_1):GND    I40 @T6G_MB_LIB.T6G(SCH_1):PAGE201

PC84_1 Q_CAP_0402-0.1UF,25V,10%,X7R,CH4104K1B00
     1 PVDDCR_CPU1_P0_VCCS @T6G_MB_LIB.T6G(SCH_1):PVDDCR_CPU1_P0_VCCS    I12 @T6G_MB_LIB.T6G(SCH_1):PAGE176
     2    GND @T6G_MB_LIB.T6G(SCH_1):GND    I12 @T6G_MB_LIB.T6G(SCH_1):PAGE176

PC85 Q_CAP_0402-0.1UF,25V,10%,X7R,CH4104K1B00
     1 P12V_AUX @T6G_MB_LIB.T6G(SCH_1):P12V_AUX    I87 @T6G_MB_LIB.T6G(SCH_1):PAGE176
     2    GND @T6G_MB_LIB.T6G(SCH_1):GND    I87 @T6G_MB_LIB.T6G(SCH_1):PAGE176

PC85_1 Q_CAP_0402-0.1UF,25V,10%,X7R,CH4104K1B00
     1 SW_P12V_AUX_PVDDCR_CPU1_P0_FLT @T6G_MB_LIB.T6G(SCH_1):SW_P12V_AUX_PVDDCR_CPU1_P0_FLT    I55 @T6G_MB_LIB.T6G(SCH_1):PAGE176
     2    GND @T6G_MB_LIB.T6G(SCH_1):GND    I55 @T6G_MB_LIB.T6G(SCH_1):PAGE176

PC86_2 Q_CAP_0402-0.1UF,25V,10%,X7R,CH4104K1B00
     1 SW_P12V_AUX_PVDDCR_CPU1_P0_FLT @T6G_MB_LIB.T6G(SCH_1):SW_P12V_AUX_PVDDCR_CPU1_P0_FLT    I37 @T6G_MB_LIB.T6G(SCH_1):PAGE176
     2    GND @T6G_MB_LIB.T6G(SCH_1):GND    I37 @T6G_MB_LIB.T6G(SCH_1):PAGE176

PC87 Q_CAP_C0805-22UF,4V,20%,EMPTY,CH622KMEA03
     1 PVDD18_S5_P1 @T6G_MB_LIB.T6G(SCH_1):PVDD18_S5_P1    I41 @T6G_MB_LIB.T6G(SCH_1):PAGE201
     2    GND @T6G_MB_LIB.T6G(SCH_1):GND    I41 @T6G_MB_LIB.T6G(SCH_1):PAGE201

PC87_1 Q_CAP_C0402-1UF,25V,10%,X6S,CH5104KEB02
     1 SW_P12V_AUX_PVDDCR_CPU1_P0_FLT @T6G_MB_LIB.T6G(SCH_1):SW_P12V_AUX_PVDDCR_CPU1_P0_FLT    I59 @T6G_MB_LIB.T6G(SCH_1):PAGE176
     2    GND @T6G_MB_LIB.T6G(SCH_1):GND    I59 @T6G_MB_LIB.T6G(SCH_1):PAGE176

PC88 Q_CAP_C0805-22UF,4V,20%,EMPTY,CH622KMEA03
     1 PVDD18_S5_P1 @T6G_MB_LIB.T6G(SCH_1):PVDD18_S5_P1    I42 @T6G_MB_LIB.T6G(SCH_1):PAGE201
     2    GND @T6G_MB_LIB.T6G(SCH_1):GND    I42 @T6G_MB_LIB.T6G(SCH_1):PAGE201

PC88_2 Q_CAP_C0402-1UF,25V,10%,X6S,CH5104KEB02
     1 SW_P12V_AUX_PVDDCR_CPU1_P0_FLT @T6G_MB_LIB.T6G(SCH_1):SW_P12V_AUX_PVDDCR_CPU1_P0_FLT    I47 @T6G_MB_LIB.T6G(SCH_1):PAGE176
     2    GND @T6G_MB_LIB.T6G(SCH_1):GND    I47 @T6G_MB_LIB.T6G(SCH_1):PAGE176

PC89 Q_CAPP_SMLF-390UF,2.5V,20%,ALUM,CC7390JMZ13
     1 PVDD18_S5_P1 @T6G_MB_LIB.T6G(SCH_1):PVDD18_S5_P1    I43 @T6G_MB_LIB.T6G(SCH_1):PAGE201
     2    GND @T6G_MB_LIB.T6G(SCH_1):GND    I43 @T6G_MB_LIB.T6G(SCH_1):PAGE201

PC89_1 Q_CAP_C0805-22UF,16V,20%,X6S,CH6223MEA01
     1 SW_P12V_AUX_PVDDCR_CPU1_P0_FLT @T6G_MB_LIB.T6G(SCH_1):SW_P12V_AUX_PVDDCR_CPU1_P0_FLT    I60 @T6G_MB_LIB.T6G(SCH_1):PAGE176
     2    GND @T6G_MB_LIB.T6G(SCH_1):GND    I60 @T6G_MB_LIB.T6G(SCH_1):PAGE176

PC90_2 Q_CAP_C0805-22UF,16V,20%,X6S,CH6223MEA01
     1 SW_P12V_AUX_PVDDCR_CPU1_P0_FLT @T6G_MB_LIB.T6G(SCH_1):SW_P12V_AUX_PVDDCR_CPU1_P0_FLT    I48 @T6G_MB_LIB.T6G(SCH_1):PAGE176
     2    GND @T6G_MB_LIB.T6G(SCH_1):GND    I48 @T6G_MB_LIB.T6G(SCH_1):PAGE176

PC91_1 Q_CAP_C0805-22UF,16V,20%,X6S,CH6223MEA01
     1 SW_P12V_AUX_PVDDCR_CPU1_P0_FLT @T6G_MB_LIB.T6G(SCH_1):SW_P12V_AUX_PVDDCR_CPU1_P0_FLT    I64 @T6G_MB_LIB.T6G(SCH_1):PAGE176
     2    GND @T6G_MB_LIB.T6G(SCH_1):GND    I64 @T6G_MB_LIB.T6G(SCH_1):PAGE176

PC92 Q_CAP_0402-0.22UF,16V,10%,X7R,CH4223K1B00
     1 SW_PVDDCR_CPU1_P0_BOOT1_R @T6G_MB_LIB.T6G(SCH_1):SW_PVDDCR_CPU1_P0_BOOT1_R    I61 @T6G_MB_LIB.T6G(SCH_1):PAGE176
     2 SW_PVDDCR_CPU1_P0_BOOTR1 @T6G_MB_LIB.T6G(SCH_1):SW_PVDDCR_CPU1_P0_BOOTR1    I61 @T6G_MB_LIB.T6G(SCH_1):PAGE176

PC93 Q_CAP_0402-0.1UF,25V,10%,X7R,CH4104K1B00
     1 PVDDCR_CPU1_P1_VCCS @T6G_MB_LIB.T6G(SCH_1):PVDDCR_CPU1_P1_VCCS    I93 @T6G_MB_LIB.T6G(SCH_1):PAGE192
     2    GND @T6G_MB_LIB.T6G(SCH_1):GND    I93 @T6G_MB_LIB.T6G(SCH_1):PAGE192

PC93_2 Q_CAP_C0805-22UF,16V,20%,X6S,CH6223MEA01
     1 SW_P12V_AUX_PVDDCR_CPU1_P0_FLT @T6G_MB_LIB.T6G(SCH_1):SW_P12V_AUX_PVDDCR_CPU1_P0_FLT    I51 @T6G_MB_LIB.T6G(SCH_1):PAGE176
     2    GND @T6G_MB_LIB.T6G(SCH_1):GND    I51 @T6G_MB_LIB.T6G(SCH_1):PAGE176

PC94 Q_CAP_0402-0.22UF,16V,10%,X7R,CH4223K1B00
     1 SW_PVDDCR_CPU1_P0_BOOT2_R @T6G_MB_LIB.T6G(SCH_1):SW_PVDDCR_CPU1_P0_BOOT2_R    I44 @T6G_MB_LIB.T6G(SCH_1):PAGE176
     2 SW_PVDDCR_CPU1_P0_BOOTR2 @T6G_MB_LIB.T6G(SCH_1):SW_PVDDCR_CPU1_P0_BOOTR2    I44 @T6G_MB_LIB.T6G(SCH_1):PAGE176

PC95 Q_CAP_0402-0.1UF,25V,10%,X7R,CH4104K1B00
     1 PVDD11_S3_P1_VCC @T6G_MB_LIB.T6G(SCH_1):PVDD11_S3_P1_VCC    I73 @T6G_MB_LIB.T6G(SCH_1):PAGE199
     2    GND @T6G_MB_LIB.T6G(SCH_1):GND    I73 @T6G_MB_LIB.T6G(SCH_1):PAGE199

PC95_1 Q_CAP_C0805-22UF,16V,20%,X6S,CH6223MEA01
     1 SW_P12V_AUX_PVDDCR_CPU1_P0_FLT @T6G_MB_LIB.T6G(SCH_1):SW_P12V_AUX_PVDDCR_CPU1_P0_FLT    I65 @T6G_MB_LIB.T6G(SCH_1):PAGE176
     2    GND @T6G_MB_LIB.T6G(SCH_1):GND    I65 @T6G_MB_LIB.T6G(SCH_1):PAGE176

PC96 Q_CAP_0402-0.1UF,25V,10%,X7R,CH4104K1B00
     1 PVDD11_S3_P1_VCCS @T6G_MB_LIB.T6G(SCH_1):PVDD11_S3_P1_VCCS    I72 @T6G_MB_LIB.T6G(SCH_1):PAGE199
     2    GND @T6G_MB_LIB.T6G(SCH_1):GND    I72 @T6G_MB_LIB.T6G(SCH_1):PAGE199

PC96_2 Q_CAP_C0805-22UF,16V,20%,X6S,CH6223MEA01
     1 SW_P12V_AUX_PVDDCR_CPU1_P0_FLT @T6G_MB_LIB.T6G(SCH_1):SW_P12V_AUX_PVDDCR_CPU1_P0_FLT    I52 @T6G_MB_LIB.T6G(SCH_1):PAGE176
     2    GND @T6G_MB_LIB.T6G(SCH_1):GND    I52 @T6G_MB_LIB.T6G(SCH_1):PAGE176

PC97 Q_CAPP_SMLF-220UF,4V,20%,SPCAP,CH122KM8801
     1 PVDDCR_CPU1_P0 @T6G_MB_LIB.T6G(SCH_1):PVDDCR_CPU1_P0    I71 @T6G_MB_LIB.T6G(SCH_1):PAGE176
     2    GND @T6G_MB_LIB.T6G(SCH_1):GND    I71 @T6G_MB_LIB.T6G(SCH_1):PAGE176

PC98 Q_CAPP_SMLF-220UF,4V,20%,SPCAP,CH122KM8801
     1 PVDDCR_CPU1_P0 @T6G_MB_LIB.T6G(SCH_1):PVDDCR_CPU1_P0    I72 @T6G_MB_LIB.T6G(SCH_1):PAGE176
     2    GND @T6G_MB_LIB.T6G(SCH_1):GND    I72 @T6G_MB_LIB.T6G(SCH_1):PAGE176

PC99 Q_CAP_0402-0.1UF,25V,10%,X7R,CH4104K1B00
     1 PVDDCR_CPU1_P0 @T6G_MB_LIB.T6G(SCH_1):PVDDCR_CPU1_P0    I84 @T6G_MB_LIB.T6G(SCH_1):PAGE176
     2    GND @T6G_MB_LIB.T6G(SCH_1):GND    I84 @T6G_MB_LIB.T6G(SCH_1):PAGE176

PC100 Q_CAPP_SMLF-220UF,4V,20%,SPCAP,CH122KM8801
     1 PVDDCR_CPU1_P0 @T6G_MB_LIB.T6G(SCH_1):PVDDCR_CPU1_P0    I73 @T6G_MB_LIB.T6G(SCH_1):PAGE176
     2    GND @T6G_MB_LIB.T6G(SCH_1):GND    I73 @T6G_MB_LIB.T6G(SCH_1):PAGE176

PC101 Q_CAPP_THLF-270UF,16V,20%,OSCON,CC72703MD38
     1 SW_P12V_AUX_PVDDCR_CPU1_P0_FLT @T6G_MB_LIB.T6G(SCH_1):SW_P12V_AUX_PVDDCR_CPU1_P0_FLT    I66 @T6G_MB_LIB.T6G(SCH_1):PAGE176
     2    GND @T6G_MB_LIB.T6G(SCH_1):GND    I66 @T6G_MB_LIB.T6G(SCH_1):PAGE176

PC102 Q_CAPP_SMLF-220UF,4V,20%,SPCAP,CH122KM8801
     1 PVDDCR_CPU1_P0 @T6G_MB_LIB.T6G(SCH_1):PVDDCR_CPU1_P0    I70 @T6G_MB_LIB.T6G(SCH_1):PAGE176
     2    GND @T6G_MB_LIB.T6G(SCH_1):GND    I70 @T6G_MB_LIB.T6G(SCH_1):PAGE176

PC102_1 Q_CAP_C0805-22UF,4V,20%,X6S,CH622KMEA03
     1 PVDDCR_CPU1_P0 @T6G_MB_LIB.T6G(SCH_1):PVDDCR_CPU1_P0    I86 @T6G_MB_LIB.T6G(SCH_1):PAGE176
     2    GND @T6G_MB_LIB.T6G(SCH_1):GND    I86 @T6G_MB_LIB.T6G(SCH_1):PAGE176

PC103 Q_CAPP_SMLF-220UF,4V,20%,SPCAP,CH122KM8801
     1 PVDDCR_CPU1_P0 @T6G_MB_LIB.T6G(SCH_1):PVDDCR_CPU1_P0    I75 @T6G_MB_LIB.T6G(SCH_1):PAGE176
     2    GND @T6G_MB_LIB.T6G(SCH_1):GND    I75 @T6G_MB_LIB.T6G(SCH_1):PAGE176

PC104 Q_CAPP_THLF-270UF,16V,20%,OSCON,CC72703MD38
     1 SW_P12V_AUX_PVDDCR_CPU1_P0_FLT @T6G_MB_LIB.T6G(SCH_1):SW_P12V_AUX_PVDDCR_CPU1_P0_FLT    I82 @T6G_MB_LIB.T6G(SCH_1):PAGE176
     2    GND @T6G_MB_LIB.T6G(SCH_1):GND    I82 @T6G_MB_LIB.T6G(SCH_1):PAGE176

PC105 Q_CAPP_SMLF-220UF,4V,20%,SPCAP,CH122KM8801
     1 PVDDCR_CPU0_P1 @T6G_MB_LIB.T6G(SCH_1):PVDDCR_CPU0_P1    I84 @T6G_MB_LIB.T6G(SCH_1):PAGE186
     2    GND @T6G_MB_LIB.T6G(SCH_1):GND    I84 @T6G_MB_LIB.T6G(SCH_1):PAGE186

PC105_1 Q_CAP_C0805-22UF,4V,20%,X6S,CH622KMEA03
     1 PVDDCR_CPU1_P0 @T6G_MB_LIB.T6G(SCH_1):PVDDCR_CPU1_P0    I89 @T6G_MB_LIB.T6G(SCH_1):PAGE176
     2    GND @T6G_MB_LIB.T6G(SCH_1):GND    I89 @T6G_MB_LIB.T6G(SCH_1):PAGE176

PC106 Q_CAPP_SMLF-220UF,4V,20%,SPCAP,CH122KM8801
     1 PVDDCR_CPU1_P1 @T6G_MB_LIB.T6G(SCH_1):PVDDCR_CPU1_P1    I65 @T6G_MB_LIB.T6G(SCH_1):PAGE193
     2    GND @T6G_MB_LIB.T6G(SCH_1):GND    I65 @T6G_MB_LIB.T6G(SCH_1):PAGE193

PC106_2 Q_CAP_C0805-22UF,4V,20%,X6S,CH622KMEA03
     1 PVDDCR_CPU1_P0 @T6G_MB_LIB.T6G(SCH_1):PVDDCR_CPU1_P0    I69 @T6G_MB_LIB.T6G(SCH_1):PAGE176
     2    GND @T6G_MB_LIB.T6G(SCH_1):GND    I69 @T6G_MB_LIB.T6G(SCH_1):PAGE176

PC107 Q_CAP_0402-0.1UF,25V,10%,X7R,CH4104K1B00
     1 PVDDIO_P0 @T6G_MB_LIB.T6G(SCH_1):PVDDIO_P0    I73 @T6G_MB_LIB.T6G(SCH_1):PAGE180
     2    GND @T6G_MB_LIB.T6G(SCH_1):GND    I73 @T6G_MB_LIB.T6G(SCH_1):PAGE180

PC108 Q_CAPP_SMLF-220UF,4V,20%,SPCAP,CH122KM8801
     1 PVDDCR_CPU0_P0 @T6G_MB_LIB.T6G(SCH_1):PVDDCR_CPU0_P0    I64 @T6G_MB_LIB.T6G(SCH_1):PAGE169
     2    GND @T6G_MB_LIB.T6G(SCH_1):GND    I64 @T6G_MB_LIB.T6G(SCH_1):PAGE169

PC108_2 Q_CAP_C0805-22UF,4V,20%,X6S,CH622KMEA03
     1 PVDDCR_CPU1_P0 @T6G_MB_LIB.T6G(SCH_1):PVDDCR_CPU1_P0    I77 @T6G_MB_LIB.T6G(SCH_1):PAGE176
     2    GND @T6G_MB_LIB.T6G(SCH_1):GND    I77 @T6G_MB_LIB.T6G(SCH_1):PAGE176

PC109 Q_CAP_C0402-2.2UF,10V,10%,X6S,CH5222KEB01
     1 PVDDCR_CPU1_P0_VCC4 @T6G_MB_LIB.T6G(SCH_1):PVDDCR_CPU1_P0_VCC4     I7 @T6G_MB_LIB.T6G(SCH_1):PAGE177
     2    GND @T6G_MB_LIB.T6G(SCH_1):GND     I7 @T6G_MB_LIB.T6G(SCH_1):PAGE177

PC110 Q_CAP_C0402-2.2UF,10V,10%,X6S,CH5222KEB01
     1 PVDDCR_CPU1_P0_VCC3 @T6G_MB_LIB.T6G(SCH_1):PVDDCR_CPU1_P0_VCC3    I28 @T6G_MB_LIB.T6G(SCH_1):PAGE177
     2    GND @T6G_MB_LIB.T6G(SCH_1):GND    I28 @T6G_MB_LIB.T6G(SCH_1):PAGE177

PC111 Q_CAP_C0805-22UF,16V,20%,X6S,CH6223MEA01
     1 SW_P12V_AUX_PVDD18_S5_P0_FLT @T6G_MB_LIB.T6G(SCH_1):SW_P12V_AUX_PVDD18_S5_P0_FLT     I8 @T6G_MB_LIB.T6G(SCH_1):PAGE184
     2    GND @T6G_MB_LIB.T6G(SCH_1):GND     I8 @T6G_MB_LIB.T6G(SCH_1):PAGE184

PC111_6 Q_CAP_0402-0.1UF,25V,10%,X7R,CH4104K1B00
     1 PVDDCR_CPU1_P0_VCCS @T6G_MB_LIB.T6G(SCH_1):PVDDCR_CPU1_P0_VCCS     I2 @T6G_MB_LIB.T6G(SCH_1):PAGE178
     2    GND @T6G_MB_LIB.T6G(SCH_1):GND     I2 @T6G_MB_LIB.T6G(SCH_1):PAGE178

PC111_C1P0_4 Q_CAP_C0402-2.2UF,10V,10%,X6S,CH5222KEB01
     1 PVDDCR_CPU1_P0_PVCC @T6G_MB_LIB.T6G(SCH_1):PVDDCR_CPU1_P0_PVCC    I16 @T6G_MB_LIB.T6G(SCH_1):PAGE177
     2    GND @T6G_MB_LIB.T6G(SCH_1):GND    I16 @T6G_MB_LIB.T6G(SCH_1):PAGE177

PC112 Q_CAP_C0402-2.2UF,10V,10%,X6S,CH5222KEB01
     1 PVDDCR_CPU1_P0_VCC6 @T6G_MB_LIB.T6G(SCH_1):PVDDCR_CPU1_P0_VCC6    I11 @T6G_MB_LIB.T6G(SCH_1):PAGE178
     2    GND @T6G_MB_LIB.T6G(SCH_1):GND    I11 @T6G_MB_LIB.T6G(SCH_1):PAGE178

PC112_C1P0_3 Q_CAP_C0402-2.2UF,10V,10%,X6S,CH5222KEB01
     1 PVDDCR_CPU1_P0_PVCC @T6G_MB_LIB.T6G(SCH_1):PVDDCR_CPU1_P0_PVCC    I32 @T6G_MB_LIB.T6G(SCH_1):PAGE177
     2    GND @T6G_MB_LIB.T6G(SCH_1):GND    I32 @T6G_MB_LIB.T6G(SCH_1):PAGE177

PC113 Q_CAP_0402-0.1UF,25V,10%,X7R,CH4104K1B00
     1 PVDD18_S5_P0_REF @T6G_MB_LIB.T6G(SCH_1):PVDD18_S5_P0_REF    I22 @T6G_MB_LIB.T6G(SCH_1):PAGE184
     2 PVDD18_S5_P0_RGND @T6G_MB_LIB.T6G(SCH_1):PVDD18_S5_P0_RGND    I22 @T6G_MB_LIB.T6G(SCH_1):PAGE184

PC113_4 Q_CAP_0402-0.1UF,25V,10%,X7R,CH4104K1B00
     1 PVDDCR_CPU1_P0_VCCS @T6G_MB_LIB.T6G(SCH_1):PVDDCR_CPU1_P0_VCCS     I2 @T6G_MB_LIB.T6G(SCH_1):PAGE177
     2    GND @T6G_MB_LIB.T6G(SCH_1):GND     I2 @T6G_MB_LIB.T6G(SCH_1):PAGE177

PC113_C1P0_6 Q_CAP_C0402-2.2UF,10V,10%,X6S,CH5222KEB01
     1 PVDDCR_CPU1_P0_PVCC @T6G_MB_LIB.T6G(SCH_1):PVDDCR_CPU1_P0_PVCC    I20 @T6G_MB_LIB.T6G(SCH_1):PAGE178
     2    GND @T6G_MB_LIB.T6G(SCH_1):GND    I20 @T6G_MB_LIB.T6G(SCH_1):PAGE178

PC114 Q_CAP_C0805-22UF,4V,20%,X6S,CH622KMEA03
     1 PVDD18_S5_P0 @T6G_MB_LIB.T6G(SCH_1):PVDD18_S5_P0    I39 @T6G_MB_LIB.T6G(SCH_1):PAGE184
     2    GND @T6G_MB_LIB.T6G(SCH_1):GND    I39 @T6G_MB_LIB.T6G(SCH_1):PAGE184

PC114_3 Q_CAP_0402-0.1UF,25V,10%,X7R,CH4104K1B00
     1 PVDDCR_CPU1_P0_VCCS @T6G_MB_LIB.T6G(SCH_1):PVDDCR_CPU1_P0_VCCS    I12 @T6G_MB_LIB.T6G(SCH_1):PAGE177
     2    GND @T6G_MB_LIB.T6G(SCH_1):GND    I12 @T6G_MB_LIB.T6G(SCH_1):PAGE177

PC114_6 Q_CAP_0402-0.1UF,25V,10%,X7R,CH4104K1B00
     1 SW_P12V_AUX_PVDDCR_CPU1_P0_FLT @T6G_MB_LIB.T6G(SCH_1):SW_P12V_AUX_PVDDCR_CPU1_P0_FLT    I40 @T6G_MB_LIB.T6G(SCH_1):PAGE178
     2    GND @T6G_MB_LIB.T6G(SCH_1):GND    I40 @T6G_MB_LIB.T6G(SCH_1):PAGE178

PC115 Q_CAPP_SMLF-390UF,2.5V,20%,ALUM,CC7390JMZ13
     1 PVDD18_S5_P0 @T6G_MB_LIB.T6G(SCH_1):PVDD18_S5_P0    I47 @T6G_MB_LIB.T6G(SCH_1):PAGE184
     2    GND @T6G_MB_LIB.T6G(SCH_1):GND    I47 @T6G_MB_LIB.T6G(SCH_1):PAGE184

PC115_4 Q_CAP_0402-0.1UF,25V,10%,X7R,CH4104K1B00
     1 SW_P12V_AUX_PVDDCR_CPU1_P0_FLT @T6G_MB_LIB.T6G(SCH_1):SW_P12V_AUX_PVDDCR_CPU1_P0_FLT    I24 @T6G_MB_LIB.T6G(SCH_1):PAGE177
     2    GND @T6G_MB_LIB.T6G(SCH_1):GND    I24 @T6G_MB_LIB.T6G(SCH_1):PAGE177

PC115_6 Q_CAP_C0402-1UF,25V,10%,X6S,CH5104KEB02
     1 SW_P12V_AUX_PVDDCR_CPU1_P0_FLT @T6G_MB_LIB.T6G(SCH_1):SW_P12V_AUX_PVDDCR_CPU1_P0_FLT    I41 @T6G_MB_LIB.T6G(SCH_1):PAGE178
     2    GND @T6G_MB_LIB.T6G(SCH_1):GND    I41 @T6G_MB_LIB.T6G(SCH_1):PAGE178

PC116_3 Q_CAP_0402-0.1UF,25V,10%,X7R,CH4104K1B00
     1 SW_P12V_AUX_PVDDCR_CPU1_P0_FLT @T6G_MB_LIB.T6G(SCH_1):SW_P12V_AUX_PVDDCR_CPU1_P0_FLT    I34 @T6G_MB_LIB.T6G(SCH_1):PAGE177
     2    GND @T6G_MB_LIB.T6G(SCH_1):GND    I34 @T6G_MB_LIB.T6G(SCH_1):PAGE177

PC116_6 Q_CAP_C0805-22UF,16V,20%,X6S,CH6223MEA01
     1 SW_P12V_AUX_PVDDCR_CPU1_P0_FLT @T6G_MB_LIB.T6G(SCH_1):SW_P12V_AUX_PVDDCR_CPU1_P0_FLT    I42 @T6G_MB_LIB.T6G(SCH_1):PAGE178
     2    GND @T6G_MB_LIB.T6G(SCH_1):GND    I42 @T6G_MB_LIB.T6G(SCH_1):PAGE178

PC117 Q_CAP_0402-0.22UF,16V,10%,X7R,CH4223K1B00
     1 SW_PVDDCR_CPU1_P0_BOOT6_R @T6G_MB_LIB.T6G(SCH_1):SW_PVDDCR_CPU1_P0_BOOT6_R    I37 @T6G_MB_LIB.T6G(SCH_1):PAGE178
     2 SW_PVDDCR_CPU1_P0_BOOTR6 @T6G_MB_LIB.T6G(SCH_1):SW_PVDDCR_CPU1_P0_BOOTR6    I37 @T6G_MB_LIB.T6G(SCH_1):PAGE178

PC117_4 Q_CAP_C0402-1UF,25V,10%,X6S,CH5104KEB02
     1 SW_P12V_AUX_PVDDCR_CPU1_P0_FLT @T6G_MB_LIB.T6G(SCH_1):SW_P12V_AUX_PVDDCR_CPU1_P0_FLT    I43 @T6G_MB_LIB.T6G(SCH_1):PAGE177
     2    GND @T6G_MB_LIB.T6G(SCH_1):GND    I43 @T6G_MB_LIB.T6G(SCH_1):PAGE177

PC118 Q_CAP_C0402-1UF,25V,10%,X6S,CH5104KEB02
     1 PVDD_33_S5_VCC @T6G_MB_LIB.T6G(SCH_1):PVDD_33_S5_VCC     I2 @T6G_MB_LIB.T6G(SCH_1):PAGE167
     2    GND @T6G_MB_LIB.T6G(SCH_1):GND     I2 @T6G_MB_LIB.T6G(SCH_1):PAGE167

PC118_3 Q_CAP_C0402-1UF,25V,10%,X6S,CH5104KEB02
     1 SW_P12V_AUX_PVDDCR_CPU1_P0_FLT @T6G_MB_LIB.T6G(SCH_1):SW_P12V_AUX_PVDDCR_CPU1_P0_FLT    I60 @T6G_MB_LIB.T6G(SCH_1):PAGE177
     2    GND @T6G_MB_LIB.T6G(SCH_1):GND    I60 @T6G_MB_LIB.T6G(SCH_1):PAGE177

PC118_6 Q_CAP_C0805-22UF,16V,20%,X6S,CH6223MEA01
     1 SW_P12V_AUX_PVDDCR_CPU1_P0_FLT @T6G_MB_LIB.T6G(SCH_1):SW_P12V_AUX_PVDDCR_CPU1_P0_FLT    I45 @T6G_MB_LIB.T6G(SCH_1):PAGE178
     2    GND @T6G_MB_LIB.T6G(SCH_1):GND    I45 @T6G_MB_LIB.T6G(SCH_1):PAGE178

PC119 Q_CAP_C0805-22UF,16V,20%,X6S,CH6223MEA01
     1 SW_P12V_AUX_PVDD_33_S5_FLT @T6G_MB_LIB.T6G(SCH_1):SW_P12V_AUX_PVDD_33_S5_FLT    I12 @T6G_MB_LIB.T6G(SCH_1):PAGE167
     2    GND @T6G_MB_LIB.T6G(SCH_1):GND    I12 @T6G_MB_LIB.T6G(SCH_1):PAGE167

PC119_4 Q_CAP_C0805-22UF,16V,20%,X6S,CH6223MEA01
     1 SW_P12V_AUX_PVDDCR_CPU1_P0_FLT @T6G_MB_LIB.T6G(SCH_1):SW_P12V_AUX_PVDDCR_CPU1_P0_FLT    I44 @T6G_MB_LIB.T6G(SCH_1):PAGE177
     2    GND @T6G_MB_LIB.T6G(SCH_1):GND    I44 @T6G_MB_LIB.T6G(SCH_1):PAGE177

PC119_6 Q_CAP_C0805-22UF,16V,20%,X6S,CH6223MEA01
     1 SW_P12V_AUX_PVDDCR_CPU1_P0_FLT @T6G_MB_LIB.T6G(SCH_1):SW_P12V_AUX_PVDDCR_CPU1_P0_FLT    I47 @T6G_MB_LIB.T6G(SCH_1):PAGE178
     2    GND @T6G_MB_LIB.T6G(SCH_1):GND    I47 @T6G_MB_LIB.T6G(SCH_1):PAGE178

PC120 Q_CAP_C0805-22UF,16V,20%,X6S,CH6223MEA01
     1 SW_P12V_AUX_PVDD_33_S5_FLT @T6G_MB_LIB.T6G(SCH_1):SW_P12V_AUX_PVDD_33_S5_FLT    I13 @T6G_MB_LIB.T6G(SCH_1):PAGE167
     2    GND @T6G_MB_LIB.T6G(SCH_1):GND    I13 @T6G_MB_LIB.T6G(SCH_1):PAGE167

PC120_3 Q_CAP_C0805-22UF,16V,20%,X6S,CH6223MEA01
     1 SW_P12V_AUX_PVDDCR_CPU1_P0_FLT @T6G_MB_LIB.T6G(SCH_1):SW_P12V_AUX_PVDDCR_CPU1_P0_FLT    I61 @T6G_MB_LIB.T6G(SCH_1):PAGE177
     2    GND @T6G_MB_LIB.T6G(SCH_1):GND    I61 @T6G_MB_LIB.T6G(SCH_1):PAGE177

PC120_6 Q_CAP_C0805-22UF,4V,20%,X6S,CH622KMEA03
     1 PVDDCR_CPU1_P0 @T6G_MB_LIB.T6G(SCH_1):PVDDCR_CPU1_P0    I51 @T6G_MB_LIB.T6G(SCH_1):PAGE178
     2    GND @T6G_MB_LIB.T6G(SCH_1):GND    I51 @T6G_MB_LIB.T6G(SCH_1):PAGE178

PC121 Q_CAP_0402-0.22UF,16V,10%,X7R,CH4223K1B00
     1 SW_PVDDCR_CPU1_P0_BOOT4_R @T6G_MB_LIB.T6G(SCH_1):SW_PVDDCR_CPU1_P0_BOOT4_R    I41 @T6G_MB_LIB.T6G(SCH_1):PAGE177
     2 SW_PVDDCR_CPU1_P0_BOOTR4 @T6G_MB_LIB.T6G(SCH_1):SW_PVDDCR_CPU1_P0_BOOTR4    I41 @T6G_MB_LIB.T6G(SCH_1):PAGE177

PC122 Q_CAP_0402-0.22UF,16V,10%,X7R,CH4223K1B00
     1 SW_PVDDCR_CPU1_P0_BOOT3_R @T6G_MB_LIB.T6G(SCH_1):SW_PVDDCR_CPU1_P0_BOOT3_R    I62 @T6G_MB_LIB.T6G(SCH_1):PAGE177
     2 SW_PVDDCR_CPU1_P0_BOOTR3 @T6G_MB_LIB.T6G(SCH_1):SW_PVDDCR_CPU1_P0_BOOTR3    I62 @T6G_MB_LIB.T6G(SCH_1):PAGE177

PC123 Q_CAP_C0805-22UF,16V,20%,X6S,CH6223MEA01
     1 SW_P12V_AUX_PVDD_33_S5_FLT @T6G_MB_LIB.T6G(SCH_1):SW_P12V_AUX_PVDD_33_S5_FLT    I29 @T6G_MB_LIB.T6G(SCH_1):PAGE167
     2    GND @T6G_MB_LIB.T6G(SCH_1):GND    I29 @T6G_MB_LIB.T6G(SCH_1):PAGE167

PC123_4 Q_CAP_C0805-22UF,16V,20%,X6S,CH6223MEA01
     1 SW_P12V_AUX_PVDDCR_CPU1_P0_FLT @T6G_MB_LIB.T6G(SCH_1):SW_P12V_AUX_PVDDCR_CPU1_P0_FLT    I47 @T6G_MB_LIB.T6G(SCH_1):PAGE177
     2    GND @T6G_MB_LIB.T6G(SCH_1):GND    I47 @T6G_MB_LIB.T6G(SCH_1):PAGE177

PC123_6 Q_CAP_C0805-22UF,4V,20%,X6S,CH622KMEA03
     1 PVDDCR_CPU1_P0 @T6G_MB_LIB.T6G(SCH_1):PVDDCR_CPU1_P0    I53 @T6G_MB_LIB.T6G(SCH_1):PAGE178
     2    GND @T6G_MB_LIB.T6G(SCH_1):GND    I53 @T6G_MB_LIB.T6G(SCH_1):PAGE178

PC124_3 Q_CAP_C0805-22UF,16V,20%,X6S,CH6223MEA01
     1 SW_P12V_AUX_PVDDCR_CPU1_P0_FLT @T6G_MB_LIB.T6G(SCH_1):SW_P12V_AUX_PVDDCR_CPU1_P0_FLT    I65 @T6G_MB_LIB.T6G(SCH_1):PAGE177
     2    GND @T6G_MB_LIB.T6G(SCH_1):GND    I65 @T6G_MB_LIB.T6G(SCH_1):PAGE177

PC124_6 Q_CAP_0402-0.1UF,25V,10%,X7R,CH4104K1B00
     1 PVDDCR_CPU0_P1_VCCS @T6G_MB_LIB.T6G(SCH_1):PVDDCR_CPU0_P1_VCCS     I4 @T6G_MB_LIB.T6G(SCH_1):PAGE188
     2    GND @T6G_MB_LIB.T6G(SCH_1):GND     I4 @T6G_MB_LIB.T6G(SCH_1):PAGE188

PC125 Q_CAP_C0402-2.2UF,10V,10%,X6S,CH5222KEB01
     1 PVDDCR_CPU0_P1_VCC6 @T6G_MB_LIB.T6G(SCH_1):PVDDCR_CPU0_P1_VCC6    I10 @T6G_MB_LIB.T6G(SCH_1):PAGE188
     2    GND @T6G_MB_LIB.T6G(SCH_1):GND    I10 @T6G_MB_LIB.T6G(SCH_1):PAGE188

PC125_4 Q_CAP_C0805-22UF,16V,20%,X6S,CH6223MEA01
     1 SW_P12V_AUX_PVDDCR_CPU1_P0_FLT @T6G_MB_LIB.T6G(SCH_1):SW_P12V_AUX_PVDDCR_CPU1_P0_FLT    I49 @T6G_MB_LIB.T6G(SCH_1):PAGE177
     2    GND @T6G_MB_LIB.T6G(SCH_1):GND    I49 @T6G_MB_LIB.T6G(SCH_1):PAGE177

PC126 Q_CAP_C0402-1UF,25V,10%,X6S,CH5104KEB02
     1 SW_P12V_AUX_PVDD_33_S5_FLT @T6G_MB_LIB.T6G(SCH_1):SW_P12V_AUX_PVDD_33_S5_FLT    I30 @T6G_MB_LIB.T6G(SCH_1):PAGE167
     2    GND @T6G_MB_LIB.T6G(SCH_1):GND    I30 @T6G_MB_LIB.T6G(SCH_1):PAGE167

PC126_3 Q_CAP_C0805-22UF,16V,20%,X6S,CH6223MEA01
     1 SW_P12V_AUX_PVDDCR_CPU1_P0_FLT @T6G_MB_LIB.T6G(SCH_1):SW_P12V_AUX_PVDDCR_CPU1_P0_FLT    I66 @T6G_MB_LIB.T6G(SCH_1):PAGE177
     2    GND @T6G_MB_LIB.T6G(SCH_1):GND    I66 @T6G_MB_LIB.T6G(SCH_1):PAGE177

PC126_C0P1_6 Q_CAP_C0402-2.2UF,10V,10%,X6S,CH5222KEB01
     1 PVDDCR_CPU0_P1_PVCC @T6G_MB_LIB.T6G(SCH_1):PVDDCR_CPU0_P1_PVCC    I15 @T6G_MB_LIB.T6G(SCH_1):PAGE188
     2    GND @T6G_MB_LIB.T6G(SCH_1):GND    I15 @T6G_MB_LIB.T6G(SCH_1):PAGE188

PC127 Q_CAP_0402-0.1UF,25V,10%,X7R,CH4104K1B00
     1 PVDD_33_S5_REF @T6G_MB_LIB.T6G(SCH_1):PVDD_33_S5_REF    I19 @T6G_MB_LIB.T6G(SCH_1):PAGE167
     2    GND @T6G_MB_LIB.T6G(SCH_1):GND    I19 @T6G_MB_LIB.T6G(SCH_1):PAGE167

PC127_4 Q_CAP_C0805-22UF,4V,20%,X6S,CH622KMEA03
     1 PVDDCR_CPU1_P0 @T6G_MB_LIB.T6G(SCH_1):PVDDCR_CPU1_P0    I54 @T6G_MB_LIB.T6G(SCH_1):PAGE177
     2    GND @T6G_MB_LIB.T6G(SCH_1):GND    I54 @T6G_MB_LIB.T6G(SCH_1):PAGE177

PC127_6 Q_CAP_0402-0.1UF,25V,10%,X7R,CH4104K1B00
     1 SW_P12V_AUX_PVDDCR_CPU0_P1_FLT @T6G_MB_LIB.T6G(SCH_1):SW_P12V_AUX_PVDDCR_CPU0_P1_FLT    I25 @T6G_MB_LIB.T6G(SCH_1):PAGE188
     2    GND @T6G_MB_LIB.T6G(SCH_1):GND    I25 @T6G_MB_LIB.T6G(SCH_1):PAGE188

PC128 Q_CAP_0402-0.1UF,25V,10%,X7R,CH4104K1B00
     1 SW_PVDD_33_S5_BST_R @T6G_MB_LIB.T6G(SCH_1):SW_PVDD_33_S5_BST_R    I40 @T6G_MB_LIB.T6G(SCH_1):PAGE167
     2 SW_PVDD_33_S5_SW @T6G_MB_LIB.T6G(SCH_1):SW_PVDD_33_S5_SW    I40 @T6G_MB_LIB.T6G(SCH_1):PAGE167

PC128_4 Q_CAP_C0805-22UF,4V,20%,X6S,CH622KMEA03
     1 PVDDCR_CPU1_P0 @T6G_MB_LIB.T6G(SCH_1):PVDDCR_CPU1_P0    I55 @T6G_MB_LIB.T6G(SCH_1):PAGE177
     2    GND @T6G_MB_LIB.T6G(SCH_1):GND    I55 @T6G_MB_LIB.T6G(SCH_1):PAGE177

PC128_6 Q_CAP_C0402-1UF,25V,10%,X6S,CH5104KEB02
     1 SW_P12V_AUX_PVDDCR_CPU0_P1_FLT @T6G_MB_LIB.T6G(SCH_1):SW_P12V_AUX_PVDDCR_CPU0_P1_FLT    I27 @T6G_MB_LIB.T6G(SCH_1):PAGE188
     2    GND @T6G_MB_LIB.T6G(SCH_1):GND    I27 @T6G_MB_LIB.T6G(SCH_1):PAGE188

PC129 Q_CAP_C0805-22UF,16V,20%,X6S,CH6223MEA01
     1 PVDD_33_S5 @T6G_MB_LIB.T6G(SCH_1):PVDD_33_S5    I27 @T6G_MB_LIB.T6G(SCH_1):PAGE167
     2    GND @T6G_MB_LIB.T6G(SCH_1):GND    I27 @T6G_MB_LIB.T6G(SCH_1):PAGE167

PC129_3 Q_CAP_C0805-22UF,4V,20%,X6S,CH622KMEA03
     1 PVDDCR_CPU1_P0 @T6G_MB_LIB.T6G(SCH_1):PVDDCR_CPU1_P0    I69 @T6G_MB_LIB.T6G(SCH_1):PAGE177
     2    GND @T6G_MB_LIB.T6G(SCH_1):GND    I69 @T6G_MB_LIB.T6G(SCH_1):PAGE177

PC129_6 Q_CAP_C0805-22UF,16V,20%,X6S,CH6223MEA01
     1 SW_P12V_AUX_PVDDCR_CPU0_P1_FLT @T6G_MB_LIB.T6G(SCH_1):SW_P12V_AUX_PVDDCR_CPU0_P1_FLT    I29 @T6G_MB_LIB.T6G(SCH_1):PAGE188
     2    GND @T6G_MB_LIB.T6G(SCH_1):GND    I29 @T6G_MB_LIB.T6G(SCH_1):PAGE188

PC130 Q_CAP_C0805-22UF,16V,20%,X6S,CH6223MEA01
     1 PVDD_33_S5 @T6G_MB_LIB.T6G(SCH_1):PVDD_33_S5    I28 @T6G_MB_LIB.T6G(SCH_1):PAGE167
     2    GND @T6G_MB_LIB.T6G(SCH_1):GND    I28 @T6G_MB_LIB.T6G(SCH_1):PAGE167

PC130_3 Q_CAP_C0805-22UF,4V,20%,X6S,CH622KMEA03
     1 PVDDCR_CPU1_P0 @T6G_MB_LIB.T6G(SCH_1):PVDDCR_CPU1_P0    I71 @T6G_MB_LIB.T6G(SCH_1):PAGE177
     2    GND @T6G_MB_LIB.T6G(SCH_1):GND    I71 @T6G_MB_LIB.T6G(SCH_1):PAGE177

PC130_6 Q_CAP_C0805-22UF,16V,20%,X6S,CH6223MEA01
     1 SW_P12V_AUX_PVDDCR_CPU0_P1_FLT @T6G_MB_LIB.T6G(SCH_1):SW_P12V_AUX_PVDDCR_CPU0_P1_FLT    I30 @T6G_MB_LIB.T6G(SCH_1):PAGE188
     2    GND @T6G_MB_LIB.T6G(SCH_1):GND    I30 @T6G_MB_LIB.T6G(SCH_1):PAGE188

PC131 Q_CAP_C0402-2.2UF,10V,10%,X6S,CH5222KEB01
     1 PVDDCR_CPU1_P0_VCC5 @T6G_MB_LIB.T6G(SCH_1):PVDDCR_CPU1_P0_VCC5    I27 @T6G_MB_LIB.T6G(SCH_1):PAGE178
     2    GND @T6G_MB_LIB.T6G(SCH_1):GND    I27 @T6G_MB_LIB.T6G(SCH_1):PAGE178

PC132 Q_CAP_0402-100PF,50V,5%,NPO,CH11006JB00
     1 PVDD_33_S5_FB @T6G_MB_LIB.T6G(SCH_1):PVDD_33_S5_FB    I24 @T6G_MB_LIB.T6G(SCH_1):PAGE167
     2 PVDD_33_S5 @T6G_MB_LIB.T6G(SCH_1):PVDD_33_S5    I24 @T6G_MB_LIB.T6G(SCH_1):PAGE167

PC132_5 Q_CAP_0402-0.1UF,25V,10%,X7R,CH4104K1B00
     1 PVDDCR_CPU1_P0_VCCS @T6G_MB_LIB.T6G(SCH_1):PVDDCR_CPU1_P0_VCCS    I10 @T6G_MB_LIB.T6G(SCH_1):PAGE178
     2    GND @T6G_MB_LIB.T6G(SCH_1):GND    I10 @T6G_MB_LIB.T6G(SCH_1):PAGE178

PC132_6 Q_CAP_C0805-22UF,16V,20%,X6S,CH6223MEA01
     1 SW_P12V_AUX_PVDDCR_CPU0_P1_FLT @T6G_MB_LIB.T6G(SCH_1):SW_P12V_AUX_PVDDCR_CPU0_P1_FLT    I55 @T6G_MB_LIB.T6G(SCH_1):PAGE188
     2    GND @T6G_MB_LIB.T6G(SCH_1):GND    I55 @T6G_MB_LIB.T6G(SCH_1):PAGE188

PC133 Q_CAP_0402-0.22UF,16V,10%,X7R,CH4223K1B00
     1 SW_PVDDCR_CPU0_P1_BOOT6_RC @T6G_MB_LIB.T6G(SCH_1):SW_PVDDCR_CPU0_P1_BOOT6_RC    I52 @T6G_MB_LIB.T6G(SCH_1):PAGE188
     2 SW_PVDDCR_CPU0_P1_PH6 @T6G_MB_LIB.T6G(SCH_1):SW_PVDDCR_CPU0_P1_PH6    I52 @T6G_MB_LIB.T6G(SCH_1):PAGE188

PC133_C1P0_5 Q_CAP_C0402-2.2UF,10V,10%,X6S,CH5222KEB01
     1 PVDDCR_CPU1_P0_PVCC @T6G_MB_LIB.T6G(SCH_1):PVDDCR_CPU1_P0_PVCC    I31 @T6G_MB_LIB.T6G(SCH_1):PAGE178
     2    GND @T6G_MB_LIB.T6G(SCH_1):GND    I31 @T6G_MB_LIB.T6G(SCH_1):PAGE178

PC134 Q_CAP_C0805-22UF,16V,20%,X6S,CH6223MEA01
     1 PVDD_33_S5 @T6G_MB_LIB.T6G(SCH_1):PVDD_33_S5    I35 @T6G_MB_LIB.T6G(SCH_1):PAGE167
     2    GND @T6G_MB_LIB.T6G(SCH_1):GND    I35 @T6G_MB_LIB.T6G(SCH_1):PAGE167

PC134_5 Q_CAP_0402-0.1UF,25V,10%,X7R,CH4104K1B00
     1 SW_P12V_AUX_PVDDCR_CPU1_P0_FLT @T6G_MB_LIB.T6G(SCH_1):SW_P12V_AUX_PVDDCR_CPU1_P0_FLT    I58 @T6G_MB_LIB.T6G(SCH_1):PAGE178
     2    GND @T6G_MB_LIB.T6G(SCH_1):GND    I58 @T6G_MB_LIB.T6G(SCH_1):PAGE178

PC134_6 Q_CAP_C0805-22UF,4V,20%,X6S,CH622KMEA03
     1 PVDDCR_CPU0_P1 @T6G_MB_LIB.T6G(SCH_1):PVDDCR_CPU0_P1    I58 @T6G_MB_LIB.T6G(SCH_1):PAGE188
     2    GND @T6G_MB_LIB.T6G(SCH_1):GND    I58 @T6G_MB_LIB.T6G(SCH_1):PAGE188

PC135 Q_CAP_C0805-22UF,16V,20%,X6S,CH6223MEA01
     1 PVDD_33_S5 @T6G_MB_LIB.T6G(SCH_1):PVDD_33_S5    I36 @T6G_MB_LIB.T6G(SCH_1):PAGE167
     2    GND @T6G_MB_LIB.T6G(SCH_1):GND    I36 @T6G_MB_LIB.T6G(SCH_1):PAGE167

PC135_5 Q_CAP_C0402-1UF,25V,10%,X6S,CH5104KEB02
     1 SW_P12V_AUX_PVDDCR_CPU1_P0_FLT @T6G_MB_LIB.T6G(SCH_1):SW_P12V_AUX_PVDDCR_CPU1_P0_FLT    I59 @T6G_MB_LIB.T6G(SCH_1):PAGE178
     2    GND @T6G_MB_LIB.T6G(SCH_1):GND    I59 @T6G_MB_LIB.T6G(SCH_1):PAGE178

PC135_6 Q_CAP_C0805-22UF,4V,20%,X6S,CH622KMEA03
     1 PVDDCR_CPU0_P1 @T6G_MB_LIB.T6G(SCH_1):PVDDCR_CPU0_P1    I60 @T6G_MB_LIB.T6G(SCH_1):PAGE188
     2    GND @T6G_MB_LIB.T6G(SCH_1):GND    I60 @T6G_MB_LIB.T6G(SCH_1):PAGE188

PC136 Q_CAP_0402-0.1UF,25V,10%,X7R,CH4104K1B00
     1 PVDD_33_S5 @T6G_MB_LIB.T6G(SCH_1):PVDD_33_S5    I37 @T6G_MB_LIB.T6G(SCH_1):PAGE167
     2    GND @T6G_MB_LIB.T6G(SCH_1):GND    I37 @T6G_MB_LIB.T6G(SCH_1):PAGE167

PC136_5 Q_CAP_C0805-22UF,16V,20%,X6S,CH6223MEA01
     1 SW_P12V_AUX_PVDDCR_CPU1_P0_FLT @T6G_MB_LIB.T6G(SCH_1):SW_P12V_AUX_PVDDCR_CPU1_P0_FLT    I60 @T6G_MB_LIB.T6G(SCH_1):PAGE178
     2    GND @T6G_MB_LIB.T6G(SCH_1):GND    I60 @T6G_MB_LIB.T6G(SCH_1):PAGE178

PC136_6 Q_CAP_0402-0.1UF,25V,10%,X7R,CH4104K1B00
     1 PVDDCR_CPU1_P1_VCCS @T6G_MB_LIB.T6G(SCH_1):PVDDCR_CPU1_P1_VCCS     I1 @T6G_MB_LIB.T6G(SCH_1):PAGE195
     2    GND @T6G_MB_LIB.T6G(SCH_1):GND     I1 @T6G_MB_LIB.T6G(SCH_1):PAGE195

PC137 Q_CAP_0402-0.22UF,16V,10%,X7R,CH4223K1B00
     1 SW_PVDDCR_CPU1_P0_BOOT5_R @T6G_MB_LIB.T6G(SCH_1):SW_PVDDCR_CPU1_P0_BOOT5_R    I62 @T6G_MB_LIB.T6G(SCH_1):PAGE178
     2 SW_PVDDCR_CPU1_P0_BOOTR5 @T6G_MB_LIB.T6G(SCH_1):SW_PVDDCR_CPU1_P0_BOOTR5    I62 @T6G_MB_LIB.T6G(SCH_1):PAGE178

PC138 Q_CAP_C0402-2.2UF,10V,10%,X6S,CH5222KEB01
     1 PVDDCR_CPU1_P1_VCC6 @T6G_MB_LIB.T6G(SCH_1):PVDDCR_CPU1_P1_VCC6    I12 @T6G_MB_LIB.T6G(SCH_1):PAGE195
     2    GND @T6G_MB_LIB.T6G(SCH_1):GND    I12 @T6G_MB_LIB.T6G(SCH_1):PAGE195

PC138_5 Q_CAP_C0805-22UF,16V,20%,X6S,CH6223MEA01
     1 SW_P12V_AUX_PVDDCR_CPU1_P0_FLT @T6G_MB_LIB.T6G(SCH_1):SW_P12V_AUX_PVDDCR_CPU1_P0_FLT    I65 @T6G_MB_LIB.T6G(SCH_1):PAGE178
     2    GND @T6G_MB_LIB.T6G(SCH_1):GND    I65 @T6G_MB_LIB.T6G(SCH_1):PAGE178

PC139_5 Q_CAP_C0805-22UF,16V,20%,X6S,CH6223MEA01
     1 SW_P12V_AUX_PVDDCR_CPU1_P0_FLT @T6G_MB_LIB.T6G(SCH_1):SW_P12V_AUX_PVDDCR_CPU1_P0_FLT    I66 @T6G_MB_LIB.T6G(SCH_1):PAGE178
     2    GND @T6G_MB_LIB.T6G(SCH_1):GND    I66 @T6G_MB_LIB.T6G(SCH_1):PAGE178

PC139_C1P1_6 Q_CAP_C0402-2.2UF,10V,10%,X6S,CH5222KEB01
     1 PVDDCR_CPU1_P1_PVCC @T6G_MB_LIB.T6G(SCH_1):PVDDCR_CPU1_P1_PVCC    I22 @T6G_MB_LIB.T6G(SCH_1):PAGE195
     2    GND @T6G_MB_LIB.T6G(SCH_1):GND    I22 @T6G_MB_LIB.T6G(SCH_1):PAGE195

PC140_5 Q_CAP_C0805-22UF,4V,20%,X6S,CH622KMEA03
     1 PVDDCR_CPU1_P0 @T6G_MB_LIB.T6G(SCH_1):PVDDCR_CPU1_P0    I69 @T6G_MB_LIB.T6G(SCH_1):PAGE178
     2    GND @T6G_MB_LIB.T6G(SCH_1):GND    I69 @T6G_MB_LIB.T6G(SCH_1):PAGE178

PC140_6 Q_CAP_C0402-1UF,25V,10%,X6S,CH5104KEB02
     1 SW_P12V_AUX_PVDDCR_CPU1_P1_FLT @T6G_MB_LIB.T6G(SCH_1):SW_P12V_AUX_PVDDCR_CPU1_P1_FLT    I40 @T6G_MB_LIB.T6G(SCH_1):PAGE195
     2    GND @T6G_MB_LIB.T6G(SCH_1):GND    I40 @T6G_MB_LIB.T6G(SCH_1):PAGE195

PC141 Q_CAP_C0402-560PF,50V,10%,EMPTY,CH1566K1B09
     1 SW_PVDDCR_SOC_P1_SW1 @T6G_MB_LIB.T6G(SCH_1):SW_PVDDCR_SOC_P1_SW1    I45 @T6G_MB_LIB.T6G(SCH_1):PAGE190
     2 SW_PVDDCR_SOC_P1_SW1_RC @T6G_MB_LIB.T6G(SCH_1):SW_PVDDCR_SOC_P1_SW1_RC    I45 @T6G_MB_LIB.T6G(SCH_1):PAGE190

PC141_5 Q_CAP_C0805-22UF,4V,20%,X6S,CH622KMEA03
     1 PVDDCR_CPU1_P0 @T6G_MB_LIB.T6G(SCH_1):PVDDCR_CPU1_P0    I70 @T6G_MB_LIB.T6G(SCH_1):PAGE178
     2    GND @T6G_MB_LIB.T6G(SCH_1):GND    I70 @T6G_MB_LIB.T6G(SCH_1):PAGE178

PC141_6 Q_CAP_0402-0.1UF,25V,10%,X7R,CH4104K1B00
     1 SW_P12V_AUX_PVDDCR_CPU1_P1_FLT @T6G_MB_LIB.T6G(SCH_1):SW_P12V_AUX_PVDDCR_CPU1_P1_FLT    I38 @T6G_MB_LIB.T6G(SCH_1):PAGE195
     2    GND @T6G_MB_LIB.T6G(SCH_1):GND    I38 @T6G_MB_LIB.T6G(SCH_1):PAGE195

PC142 Q_CAP_C0402-2.2UF,10V,10%,X6S,CH5222KEB01
     1 PVDDIO_P0_VCC2 @T6G_MB_LIB.T6G(SCH_1):PVDDIO_P0_VCC2    I10 @T6G_MB_LIB.T6G(SCH_1):PAGE180
     2    GND @T6G_MB_LIB.T6G(SCH_1):GND    I10 @T6G_MB_LIB.T6G(SCH_1):PAGE180

PC143 Q_CAP_C0402-2.2UF,10V,10%,X6S,CH5222KEB01
     1 PVDDIO_P0_VCC1 @T6G_MB_LIB.T6G(SCH_1):PVDDIO_P0_VCC1    I28 @T6G_MB_LIB.T6G(SCH_1):PAGE180
     2    GND @T6G_MB_LIB.T6G(SCH_1):GND    I28 @T6G_MB_LIB.T6G(SCH_1):PAGE180

PC144_6 Q_CAP_C0805-22UF,16V,20%,X6S,CH6223MEA01
     1 SW_P12V_AUX_PVDDCR_CPU1_P1_FLT @T6G_MB_LIB.T6G(SCH_1):SW_P12V_AUX_PVDDCR_CPU1_P1_FLT    I41 @T6G_MB_LIB.T6G(SCH_1):PAGE195
     2    GND @T6G_MB_LIB.T6G(SCH_1):GND    I41 @T6G_MB_LIB.T6G(SCH_1):PAGE195

PC144_IOP0_2 Q_CAP_C0402-2.2UF,10V,10%,X6S,CH5222KEB01
     1 PVDDCR_CPU1_P0_PVCC @T6G_MB_LIB.T6G(SCH_1):PVDDCR_CPU1_P0_PVCC    I13 @T6G_MB_LIB.T6G(SCH_1):PAGE180
     2    GND @T6G_MB_LIB.T6G(SCH_1):GND    I13 @T6G_MB_LIB.T6G(SCH_1):PAGE180

PC145_6 Q_CAP_C0805-22UF,16V,20%,X6S,CH6223MEA01
     1 SW_P12V_AUX_PVDDCR_CPU1_P1_FLT @T6G_MB_LIB.T6G(SCH_1):SW_P12V_AUX_PVDDCR_CPU1_P1_FLT    I44 @T6G_MB_LIB.T6G(SCH_1):PAGE195
     2    GND @T6G_MB_LIB.T6G(SCH_1):GND    I44 @T6G_MB_LIB.T6G(SCH_1):PAGE195

PC145_7 Q_CAP_0402-0.1UF,25V,10%,X7R,CH4104K1B00
     1 PVDDCR_CPU1_P0_VCCS @T6G_MB_LIB.T6G(SCH_1):PVDDCR_CPU1_P0_VCCS    I20 @T6G_MB_LIB.T6G(SCH_1):PAGE180
     2    GND @T6G_MB_LIB.T6G(SCH_1):GND    I20 @T6G_MB_LIB.T6G(SCH_1):PAGE180

PC146 Q_CAP_0402-0.22UF,16V,10%,X7R,CH4223K1B00
     1 SW_PVDDCR_CPU1_P1_BOOT6_R @T6G_MB_LIB.T6G(SCH_1):SW_PVDDCR_CPU1_P1_BOOT6_R    I45 @T6G_MB_LIB.T6G(SCH_1):PAGE195
     2 SW_PVDDCR_CPU1_P1_BOOTR6 @T6G_MB_LIB.T6G(SCH_1):SW_PVDDCR_CPU1_P1_BOOTR6    I45 @T6G_MB_LIB.T6G(SCH_1):PAGE195

PC146_8 Q_CAP_0402-0.1UF,25V,10%,X7R,CH4104K1B00
     1 PVDDCR_CPU1_P0_VCCS @T6G_MB_LIB.T6G(SCH_1):PVDDCR_CPU1_P0_VCCS     I2 @T6G_MB_LIB.T6G(SCH_1):PAGE180
     2    GND @T6G_MB_LIB.T6G(SCH_1):GND     I2 @T6G_MB_LIB.T6G(SCH_1):PAGE180

PC147_6 Q_CAP_C0805-22UF,16V,20%,X6S,CH6223MEA01
     1 SW_P12V_AUX_PVDDCR_CPU1_P1_FLT @T6G_MB_LIB.T6G(SCH_1):SW_P12V_AUX_PVDDCR_CPU1_P1_FLT    I47 @T6G_MB_LIB.T6G(SCH_1):PAGE195
     2    GND @T6G_MB_LIB.T6G(SCH_1):GND    I47 @T6G_MB_LIB.T6G(SCH_1):PAGE195

PC147_IOP0_1 Q_CAP_C0402-2.2UF,10V,10%,X6S,CH5222KEB01
     1 PVDDCR_CPU1_P0_PVCC @T6G_MB_LIB.T6G(SCH_1):PVDDCR_CPU1_P0_PVCC    I31 @T6G_MB_LIB.T6G(SCH_1):PAGE180
     2    GND @T6G_MB_LIB.T6G(SCH_1):GND    I31 @T6G_MB_LIB.T6G(SCH_1):PAGE180

PC148 Q_CAP_0402-0.1UF,25V,10%,X7R,CH4104K1B00
     1 P12V_AUX @T6G_MB_LIB.T6G(SCH_1):P12V_AUX    I72 @T6G_MB_LIB.T6G(SCH_1):PAGE180
     2    GND @T6G_MB_LIB.T6G(SCH_1):GND    I72 @T6G_MB_LIB.T6G(SCH_1):PAGE180

PC148_1 Q_CAP_0402-0.1UF,25V,10%,X7R,CH4104K1B00
     1 SW_P12V_AUX_PVDDIO_P0_FLT @T6G_MB_LIB.T6G(SCH_1):SW_P12V_AUX_PVDDIO_P0_FLT    I83 @T6G_MB_LIB.T6G(SCH_1):PAGE180
     2    GND @T6G_MB_LIB.T6G(SCH_1):GND    I83 @T6G_MB_LIB.T6G(SCH_1):PAGE180

PC148_6 Q_CAP_C0805-22UF,4V,20%,X6S,CH622KMEA03
     1 PVDDCR_CPU1_P1 @T6G_MB_LIB.T6G(SCH_1):PVDDCR_CPU1_P1    I65 @T6G_MB_LIB.T6G(SCH_1):PAGE195
     2    GND @T6G_MB_LIB.T6G(SCH_1):GND    I65 @T6G_MB_LIB.T6G(SCH_1):PAGE195

PC149 Q_CAP_C0402-560PF,50V,10%,EMPTY,CH1566K1B09
     1 SW_PVDDCR_SOC_P1_SW2 @T6G_MB_LIB.T6G(SCH_1):SW_PVDDCR_SOC_P1_SW2    I20 @T6G_MB_LIB.T6G(SCH_1):PAGE190
     2 SW_PVDDCR_SOC_P1_SW2_RC @T6G_MB_LIB.T6G(SCH_1):SW_PVDDCR_SOC_P1_SW2_RC    I20 @T6G_MB_LIB.T6G(SCH_1):PAGE190

PC149_2 Q_CAP_0402-0.1UF,25V,10%,X7R,CH4104K1B00
     1 SW_P12V_AUX_PVDDIO_P0_FLT @T6G_MB_LIB.T6G(SCH_1):SW_P12V_AUX_PVDDIO_P0_FLT    I18 @T6G_MB_LIB.T6G(SCH_1):PAGE180
     2    GND @T6G_MB_LIB.T6G(SCH_1):GND    I18 @T6G_MB_LIB.T6G(SCH_1):PAGE180

PC149_6 Q_CAP_C0805-22UF,4V,20%,X6S,CH622KMEA03
     1 PVDDCR_CPU1_P1 @T6G_MB_LIB.T6G(SCH_1):PVDDCR_CPU1_P1    I67 @T6G_MB_LIB.T6G(SCH_1):PAGE195
     2    GND @T6G_MB_LIB.T6G(SCH_1):GND    I67 @T6G_MB_LIB.T6G(SCH_1):PAGE195

PC150 Q_CAP_C0805-22UF,16V,20%,X6S,CH6223MEA01
     1 SW_P12V_AUX_PVDD18_S5_P1_FLT @T6G_MB_LIB.T6G(SCH_1):SW_P12V_AUX_PVDD18_S5_P1_FLT    I22 @T6G_MB_LIB.T6G(SCH_1):PAGE201
     2    GND @T6G_MB_LIB.T6G(SCH_1):GND    I22 @T6G_MB_LIB.T6G(SCH_1):PAGE201

PC150_1 Q_CAP_C0402-1UF,25V,10%,X6S,CH5104KEB02
     1 SW_P12V_AUX_PVDDIO_P0_FLT @T6G_MB_LIB.T6G(SCH_1):SW_P12V_AUX_PVDDIO_P0_FLT    I82 @T6G_MB_LIB.T6G(SCH_1):PAGE180
     2    GND @T6G_MB_LIB.T6G(SCH_1):GND    I82 @T6G_MB_LIB.T6G(SCH_1):PAGE180

PC150_6 Q_CAP_0402-0.1UF,25V,10%,X7R,CH4104K1B00
     1 PVDDCR_CPU0_P0_VCCS @T6G_MB_LIB.T6G(SCH_1):PVDDCR_CPU0_P0_VCCS     I4 @T6G_MB_LIB.T6G(SCH_1):PAGE171
     2    GND @T6G_MB_LIB.T6G(SCH_1):GND     I4 @T6G_MB_LIB.T6G(SCH_1):PAGE171

PC151 Q_CAP_C0402-2.2UF,10V,10%,X6S,CH5222KEB01
     1 PVDDCR_CPU0_P0_VCC6 @T6G_MB_LIB.T6G(SCH_1):PVDDCR_CPU0_P0_VCC6    I11 @T6G_MB_LIB.T6G(SCH_1):PAGE171
     2    GND @T6G_MB_LIB.T6G(SCH_1):GND    I11 @T6G_MB_LIB.T6G(SCH_1):PAGE171

PC151_2 Q_CAP_C0402-1UF,25V,10%,X6S,CH5104KEB02
     1 SW_P12V_AUX_PVDDIO_P0_FLT @T6G_MB_LIB.T6G(SCH_1):SW_P12V_AUX_PVDDIO_P0_FLT    I42 @T6G_MB_LIB.T6G(SCH_1):PAGE180
     2    GND @T6G_MB_LIB.T6G(SCH_1):GND    I42 @T6G_MB_LIB.T6G(SCH_1):PAGE180

PC152 Q_CAP_C0805-22UF,16V,20%,X6S,CH6223MEA01
     1 SW_P12V_AUX_PVDD18_S5_P1_FLT @T6G_MB_LIB.T6G(SCH_1):SW_P12V_AUX_PVDD18_S5_P1_FLT    I23 @T6G_MB_LIB.T6G(SCH_1):PAGE201
     2    GND @T6G_MB_LIB.T6G(SCH_1):GND    I23 @T6G_MB_LIB.T6G(SCH_1):PAGE201

PC152_1 Q_CAP_C0805-22UF,16V,20%,X6S,CH6223MEA01
     1 SW_P12V_AUX_PVDDIO_P0_FLT @T6G_MB_LIB.T6G(SCH_1):SW_P12V_AUX_PVDDIO_P0_FLT    I81 @T6G_MB_LIB.T6G(SCH_1):PAGE180
     2    GND @T6G_MB_LIB.T6G(SCH_1):GND    I81 @T6G_MB_LIB.T6G(SCH_1):PAGE180

PC152_C0P0_6 Q_CAP_C0402-2.2UF,10V,10%,X6S,CH5222KEB01
     1 PVDDCR_CPU0_P0_PVCC @T6G_MB_LIB.T6G(SCH_1):PVDDCR_CPU0_P0_PVCC    I14 @T6G_MB_LIB.T6G(SCH_1):PAGE171
     2    GND @T6G_MB_LIB.T6G(SCH_1):GND    I14 @T6G_MB_LIB.T6G(SCH_1):PAGE171

PC153 Q_CAP_0402-0.022UF,25V,10%,X7R,CH3224K1B01
     1 PVDD18_S5_P1_REF @T6G_MB_LIB.T6G(SCH_1):PVDD18_S5_P1_REF    I18 @T6G_MB_LIB.T6G(SCH_1):PAGE201
     2    GND @T6G_MB_LIB.T6G(SCH_1):GND    I18 @T6G_MB_LIB.T6G(SCH_1):PAGE201

PC153_2 Q_CAP_C0805-22UF,16V,20%,X6S,CH6223MEA01
     1 SW_P12V_AUX_PVDDIO_P0_FLT @T6G_MB_LIB.T6G(SCH_1):SW_P12V_AUX_PVDDIO_P0_FLT    I43 @T6G_MB_LIB.T6G(SCH_1):PAGE180
     2    GND @T6G_MB_LIB.T6G(SCH_1):GND    I43 @T6G_MB_LIB.T6G(SCH_1):PAGE180

PC153_6 Q_CAP_0402-0.1UF,25V,10%,X7R,CH4104K1B00
     1 SW_P12V_AUX_PVDDCR_CPU0_P0_FLT @T6G_MB_LIB.T6G(SCH_1):SW_P12V_AUX_PVDDCR_CPU0_P0_FLT    I24 @T6G_MB_LIB.T6G(SCH_1):PAGE171
     2    GND @T6G_MB_LIB.T6G(SCH_1):GND    I24 @T6G_MB_LIB.T6G(SCH_1):PAGE171

PC154 Q_CAP_C0402-560PF,50V,10%,EMPTY,CH1566K1B09
     1 SW_PVDDCR_CPU1_P0_SW6 @T6G_MB_LIB.T6G(SCH_1):SW_PVDDCR_CPU1_P0_SW6    I72 @T6G_MB_LIB.T6G(SCH_1):PAGE178
     2 SW_PVDDCR_CPU1_P0_SW6_RC @T6G_MB_LIB.T6G(SCH_1):SW_PVDDCR_CPU1_P0_SW6_RC    I72 @T6G_MB_LIB.T6G(SCH_1):PAGE178

PC154_1 Q_CAP_C0805-22UF,16V,20%,X6S,CH6223MEA01
     1 SW_P12V_AUX_PVDDIO_P0_FLT @T6G_MB_LIB.T6G(SCH_1):SW_P12V_AUX_PVDDIO_P0_FLT    I80 @T6G_MB_LIB.T6G(SCH_1):PAGE180
     2    GND @T6G_MB_LIB.T6G(SCH_1):GND    I80 @T6G_MB_LIB.T6G(SCH_1):PAGE180

PC154_6 Q_CAP_C0402-1UF,25V,10%,X6S,CH5104KEB02
     1 SW_P12V_AUX_PVDDCR_CPU0_P0_FLT @T6G_MB_LIB.T6G(SCH_1):SW_P12V_AUX_PVDDCR_CPU0_P0_FLT    I27 @T6G_MB_LIB.T6G(SCH_1):PAGE171
     2    GND @T6G_MB_LIB.T6G(SCH_1):GND    I27 @T6G_MB_LIB.T6G(SCH_1):PAGE171

PC155 Q_CAP_0402-0.22UF,16V,10%,X7R,CH4223K1B00
     1 SW_PVDDIO_P0_BOOT1_R @T6G_MB_LIB.T6G(SCH_1):SW_PVDDIO_P0_BOOT1_R    I63 @T6G_MB_LIB.T6G(SCH_1):PAGE180
     2 SW_PVDDIO_P0_BOOTR1 @T6G_MB_LIB.T6G(SCH_1):SW_PVDDIO_P0_BOOTR1    I63 @T6G_MB_LIB.T6G(SCH_1):PAGE180

PC156 Q_CAP_0402-0.22UF,16V,10%,X7R,CH4223K1B00
     1 SW_PVDDIO_P0_BOOT2_R @T6G_MB_LIB.T6G(SCH_1):SW_PVDDIO_P0_BOOT2_R    I41 @T6G_MB_LIB.T6G(SCH_1):PAGE180
     2 SW_PVDDIO_P0_BOOTR2 @T6G_MB_LIB.T6G(SCH_1):SW_PVDDIO_P0_BOOTR2    I41 @T6G_MB_LIB.T6G(SCH_1):PAGE180

PC157 Q_CAP_C0402-560PF,50V,10%,EMPTY,CH1566K1B09
     1 SW_PVDDCR_CPU1_P0_SW5 @T6G_MB_LIB.T6G(SCH_1):SW_PVDDCR_CPU1_P0_SW5    I57 @T6G_MB_LIB.T6G(SCH_1):PAGE178
     2 SW_PVDDCR_CPU1_P0_SW5_RC @T6G_MB_LIB.T6G(SCH_1):SW_PVDDCR_CPU1_P0_SW5_RC    I57 @T6G_MB_LIB.T6G(SCH_1):PAGE178

PC157_2 Q_CAP_C0805-22UF,16V,20%,X6S,CH6223MEA01
     1 SW_P12V_AUX_PVDDIO_P0_FLT @T6G_MB_LIB.T6G(SCH_1):SW_P12V_AUX_PVDDIO_P0_FLT    I45 @T6G_MB_LIB.T6G(SCH_1):PAGE180
     2    GND @T6G_MB_LIB.T6G(SCH_1):GND    I45 @T6G_MB_LIB.T6G(SCH_1):PAGE180

PC157_6 Q_CAP_C0805-22UF,16V,20%,X6S,CH6223MEA01
     1 SW_P12V_AUX_PVDDCR_CPU0_P0_FLT @T6G_MB_LIB.T6G(SCH_1):SW_P12V_AUX_PVDDCR_CPU0_P0_FLT    I28 @T6G_MB_LIB.T6G(SCH_1):PAGE171
     2    GND @T6G_MB_LIB.T6G(SCH_1):GND    I28 @T6G_MB_LIB.T6G(SCH_1):PAGE171

PC158 Q_CAP_C0402-560PF,50V,10%,EMPTY,CH1566K1B09
     1 SW_PVDDIO_P0_SW1 @T6G_MB_LIB.T6G(SCH_1):SW_PVDDIO_P0_SW1    I61 @T6G_MB_LIB.T6G(SCH_1):PAGE180
     2 SW_PVDDIO_P0_SW1_RC @T6G_MB_LIB.T6G(SCH_1):SW_PVDDIO_P0_SW1_RC    I61 @T6G_MB_LIB.T6G(SCH_1):PAGE180

PC158_1 Q_CAP_C0805-22UF,16V,20%,X6S,CH6223MEA01
     1 SW_P12V_AUX_PVDDIO_P0_FLT @T6G_MB_LIB.T6G(SCH_1):SW_P12V_AUX_PVDDIO_P0_FLT    I66 @T6G_MB_LIB.T6G(SCH_1):PAGE180
     2    GND @T6G_MB_LIB.T6G(SCH_1):GND    I66 @T6G_MB_LIB.T6G(SCH_1):PAGE180

PC158_6 Q_CAP_C0805-22UF,16V,20%,X6S,CH6223MEA01
     1 SW_P12V_AUX_PVDDCR_CPU0_P0_FLT @T6G_MB_LIB.T6G(SCH_1):SW_P12V_AUX_PVDDCR_CPU0_P0_FLT    I29 @T6G_MB_LIB.T6G(SCH_1):PAGE171
     2    GND @T6G_MB_LIB.T6G(SCH_1):GND    I29 @T6G_MB_LIB.T6G(SCH_1):PAGE171

PC159 Q_CAP_C0402-560PF,50V,10%,EMPTY,CH1566K1B09
     1 SW_PVDDIO_P0_SW2 @T6G_MB_LIB.T6G(SCH_1):SW_PVDDIO_P0_SW2    I37 @T6G_MB_LIB.T6G(SCH_1):PAGE180
     2 SW_PVDDIO_P0_SW2_RC @T6G_MB_LIB.T6G(SCH_1):SW_PVDDIO_P0_SW2_RC    I37 @T6G_MB_LIB.T6G(SCH_1):PAGE180

PC159_2 Q_CAP_C0805-22UF,16V,20%,X6S,CH6223MEA01
     1 SW_P12V_AUX_PVDDIO_P0_FLT @T6G_MB_LIB.T6G(SCH_1):SW_P12V_AUX_PVDDIO_P0_FLT    I47 @T6G_MB_LIB.T6G(SCH_1):PAGE180
     2    GND @T6G_MB_LIB.T6G(SCH_1):GND    I47 @T6G_MB_LIB.T6G(SCH_1):PAGE180

PC159_6 Q_CAP_C0805-22UF,16V,20%,X6S,CH6223MEA01
     1 SW_P12V_AUX_PVDDCR_CPU0_P0_FLT @T6G_MB_LIB.T6G(SCH_1):SW_P12V_AUX_PVDDCR_CPU0_P0_FLT    I55 @T6G_MB_LIB.T6G(SCH_1):PAGE171
     2    GND @T6G_MB_LIB.T6G(SCH_1):GND    I55 @T6G_MB_LIB.T6G(SCH_1):PAGE171

PC160 Q_CAPP_SMLF-470UF,2.5V,20%,EMPTY,CH747LM8825
     1 PVDDIO_P0 @T6G_MB_LIB.T6G(SCH_1):PVDDIO_P0    I54 @T6G_MB_LIB.T6G(SCH_1):PAGE180
     2    GND @T6G_MB_LIB.T6G(SCH_1):GND    I54 @T6G_MB_LIB.T6G(SCH_1):PAGE180

PC161 Q_CAP_0402-0.22UF,16V,10%,X7R,CH4223K1B00
     1 SW_PVDDCR_CPU0_P0_BOOT6_RC @T6G_MB_LIB.T6G(SCH_1):SW_PVDDCR_CPU0_P0_BOOT6_RC    I54 @T6G_MB_LIB.T6G(SCH_1):PAGE171
     2 SW_PVDDCR_CPU0_P0_PH6 @T6G_MB_LIB.T6G(SCH_1):SW_PVDDCR_CPU0_P0_PH6    I54 @T6G_MB_LIB.T6G(SCH_1):PAGE171

PC162 Q_CAPP_SMLF-470UF,2.5V,20%,SPCAP,CH747LM8825
     1 PVDDIO_P0 @T6G_MB_LIB.T6G(SCH_1):PVDDIO_P0    I57 @T6G_MB_LIB.T6G(SCH_1):PAGE180
     2    GND @T6G_MB_LIB.T6G(SCH_1):GND    I57 @T6G_MB_LIB.T6G(SCH_1):PAGE180

PC163 Q_CAP_C0402-560PF,50V,10%,EMPTY,CH1566K1B09
     1 SW_PVDDIO_P0_SW4 @T6G_MB_LIB.T6G(SCH_1):SW_PVDDIO_P0_SW4    I39 @T6G_MB_LIB.T6G(SCH_1):PAGE181
     2 SW_PVDDIO_P0_SW4_RC @T6G_MB_LIB.T6G(SCH_1):SW_PVDDIO_P0_SW4_RC    I39 @T6G_MB_LIB.T6G(SCH_1):PAGE181

PC163_6 Q_CAP_C0805-22UF,4V,20%,X6S,CH622KMEA03
     1 PVDDCR_CPU0_P0 @T6G_MB_LIB.T6G(SCH_1):PVDDCR_CPU0_P0    I59 @T6G_MB_LIB.T6G(SCH_1):PAGE171
     2    GND @T6G_MB_LIB.T6G(SCH_1):GND    I59 @T6G_MB_LIB.T6G(SCH_1):PAGE171

PC164 Q_CAPP_THLF-270UF,16V,20%,OSCON,CC72703MD38
     1 SW_P12V_AUX_PVDDIO_P0_FLT @T6G_MB_LIB.T6G(SCH_1):SW_P12V_AUX_PVDDIO_P0_FLT    I67 @T6G_MB_LIB.T6G(SCH_1):PAGE180
     2    GND @T6G_MB_LIB.T6G(SCH_1):GND    I67 @T6G_MB_LIB.T6G(SCH_1):PAGE180

PC165 Q_CAPP_SMLF-470UF,2.5V,20%,SPCAP,CH747LM8825
     1 PVDDIO_P0 @T6G_MB_LIB.T6G(SCH_1):PVDDIO_P0    I58 @T6G_MB_LIB.T6G(SCH_1):PAGE180
     2    GND @T6G_MB_LIB.T6G(SCH_1):GND    I58 @T6G_MB_LIB.T6G(SCH_1):PAGE180

PC166 Q_CAP_C0402-560PF,50V,10%,EMPTY,CH1566K1B09
     1 SW_PVDDIO_P0_SW3 @T6G_MB_LIB.T6G(SCH_1):SW_PVDDIO_P0_SW3    I56 @T6G_MB_LIB.T6G(SCH_1):PAGE181
     2 SW_PVDDIO_P0_SW3_RC @T6G_MB_LIB.T6G(SCH_1):SW_PVDDIO_P0_SW3_RC    I56 @T6G_MB_LIB.T6G(SCH_1):PAGE181

PC166_1 Q_CAP_C0805-22UF,4V,20%,X6S,CH622KMEA03
     1 PVDDIO_P0 @T6G_MB_LIB.T6G(SCH_1):PVDDIO_P0    I74 @T6G_MB_LIB.T6G(SCH_1):PAGE180
     2    GND @T6G_MB_LIB.T6G(SCH_1):GND    I74 @T6G_MB_LIB.T6G(SCH_1):PAGE180

PC166_6 Q_CAP_C0805-22UF,4V,20%,X6S,CH622KMEA03
     1 PVDDCR_CPU0_P0 @T6G_MB_LIB.T6G(SCH_1):PVDDCR_CPU0_P0    I60 @T6G_MB_LIB.T6G(SCH_1):PAGE171
     2    GND @T6G_MB_LIB.T6G(SCH_1):GND    I60 @T6G_MB_LIB.T6G(SCH_1):PAGE171

PC168 Q_CAP_C0402-560PF,50V,10%,EMPTY,CH1566K1B09
     1 SW_PVDD11_S3_P0_SW2 @T6G_MB_LIB.T6G(SCH_1):SW_PVDD11_S3_P0_SW2    I26 @T6G_MB_LIB.T6G(SCH_1):PAGE183
     2 SW_PVDD11_S3_P0_SW2_RC @T6G_MB_LIB.T6G(SCH_1):SW_PVDD11_S3_P0_SW2_RC    I26 @T6G_MB_LIB.T6G(SCH_1):PAGE183

PC168_2 Q_CAP_C0805-22UF,4V,20%,X6S,CH622KMEA03
     1 PVDDIO_P0 @T6G_MB_LIB.T6G(SCH_1):PVDDIO_P0    I51 @T6G_MB_LIB.T6G(SCH_1):PAGE180
     2    GND @T6G_MB_LIB.T6G(SCH_1):GND    I51 @T6G_MB_LIB.T6G(SCH_1):PAGE180

PC169 Q_CAP_C0402-560PF,50V,10%,EMPTY,CH1566K1B09
     1 SW_PVDD11_S3_P0_SW1 @T6G_MB_LIB.T6G(SCH_1):SW_PVDD11_S3_P0_SW1    I45 @T6G_MB_LIB.T6G(SCH_1):PAGE183
     2 SW_PVDD11_S3_P0_SW1_RC @T6G_MB_LIB.T6G(SCH_1):SW_PVDD11_S3_P0_SW1_RC    I45 @T6G_MB_LIB.T6G(SCH_1):PAGE183

PC169_1 Q_CAP_C0805-22UF,4V,20%,X6S,CH622KMEA03
     1 PVDDIO_P0 @T6G_MB_LIB.T6G(SCH_1):PVDDIO_P0    I75 @T6G_MB_LIB.T6G(SCH_1):PAGE180
     2    GND @T6G_MB_LIB.T6G(SCH_1):GND    I75 @T6G_MB_LIB.T6G(SCH_1):PAGE180

PC170 Q_CAP_C0402-560PF,50V,10%,EMPTY,CH1566K1B09
     1 SW_PVDDCR_CPU0_P1_SW1 @T6G_MB_LIB.T6G(SCH_1):SW_PVDDCR_CPU0_P1_SW1    I48 @T6G_MB_LIB.T6G(SCH_1):PAGE186
     2 SW_PVDDCR_CPU0_P1_SW1_RC @T6G_MB_LIB.T6G(SCH_1):SW_PVDDCR_CPU0_P1_SW1_RC    I48 @T6G_MB_LIB.T6G(SCH_1):PAGE186

PC170_2 Q_CAP_C0805-22UF,4V,20%,X6S,CH622KMEA03
     1 PVDDIO_P0 @T6G_MB_LIB.T6G(SCH_1):PVDDIO_P0    I53 @T6G_MB_LIB.T6G(SCH_1):PAGE180
     2    GND @T6G_MB_LIB.T6G(SCH_1):GND    I53 @T6G_MB_LIB.T6G(SCH_1):PAGE180

PC171 Q_CAP_C0402-2.2UF,10V,10%,X6S,CH5222KEB01
     1 PVDDIO_P0_VCC4 @T6G_MB_LIB.T6G(SCH_1):PVDDIO_P0_VCC4    I10 @T6G_MB_LIB.T6G(SCH_1):PAGE181
     2    GND @T6G_MB_LIB.T6G(SCH_1):GND    I10 @T6G_MB_LIB.T6G(SCH_1):PAGE181

PC172 Q_CAP_C0402-2.2UF,10V,10%,X6S,CH5222KEB01
     1 PVDDIO_P0_VCC3 @T6G_MB_LIB.T6G(SCH_1):PVDDIO_P0_VCC3    I27 @T6G_MB_LIB.T6G(SCH_1):PAGE181
     2    GND @T6G_MB_LIB.T6G(SCH_1):GND    I27 @T6G_MB_LIB.T6G(SCH_1):PAGE181

PC173 Q_CAP_C0402-560PF,50V,10%,EMPTY,CH1566K1B09
     1 SW_PVDDCR_CPU0_P1_SW2 @T6G_MB_LIB.T6G(SCH_1):SW_PVDDCR_CPU0_P1_SW2    I24 @T6G_MB_LIB.T6G(SCH_1):PAGE186
     2 SW_PVDDCR_CPU0_P1_SW2_RC @T6G_MB_LIB.T6G(SCH_1):SW_PVDDCR_CPU0_P1_SW2_RC    I24 @T6G_MB_LIB.T6G(SCH_1):PAGE186

PC173_IOP0_4 Q_CAP_C0402-2.2UF,10V,10%,X6S,CH5222KEB01
     1 PVDDCR_CPU1_P0_PVCC @T6G_MB_LIB.T6G(SCH_1):PVDDCR_CPU1_P0_PVCC    I13 @T6G_MB_LIB.T6G(SCH_1):PAGE181
     2    GND @T6G_MB_LIB.T6G(SCH_1):GND    I13 @T6G_MB_LIB.T6G(SCH_1):PAGE181

PC174 Q_CAP_C0402-560PF,50V,10%,EMPTY,CH1566K1B09
     1 SW_PVDDIO_P1_SW1 @T6G_MB_LIB.T6G(SCH_1):SW_PVDDIO_P1_SW1    I40 @T6G_MB_LIB.T6G(SCH_1):PAGE197
     2 SW_PVDDIO_P1_SW1_RC @T6G_MB_LIB.T6G(SCH_1):SW_PVDDIO_P1_SW1_RC    I40 @T6G_MB_LIB.T6G(SCH_1):PAGE197

PC174_IOP0_3 Q_CAP_C0402-2.2UF,10V,10%,X6S,CH5222KEB01
     1 PVDDCR_CPU1_P0_PVCC @T6G_MB_LIB.T6G(SCH_1):PVDDCR_CPU1_P0_PVCC    I30 @T6G_MB_LIB.T6G(SCH_1):PAGE181
     2    GND @T6G_MB_LIB.T6G(SCH_1):GND    I30 @T6G_MB_LIB.T6G(SCH_1):PAGE181

PC175 Q_CAP_C0402-560PF,50V,10%,EMPTY,CH1566K1B09
     1 SW_PVDDIO_P1_SW2 @T6G_MB_LIB.T6G(SCH_1):SW_PVDDIO_P1_SW2    I20 @T6G_MB_LIB.T6G(SCH_1):PAGE197
     2 SW_PVDDIO_P1_SW2_RC @T6G_MB_LIB.T6G(SCH_1):SW_PVDDIO_P1_SW2_RC    I20 @T6G_MB_LIB.T6G(SCH_1):PAGE197

PC175_9 Q_CAP_0402-0.1UF,25V,10%,X7R,CH4104K1B00
     1 PVDDCR_CPU1_P0_VCCS @T6G_MB_LIB.T6G(SCH_1):PVDDCR_CPU1_P0_VCCS    I19 @T6G_MB_LIB.T6G(SCH_1):PAGE181
     2    GND @T6G_MB_LIB.T6G(SCH_1):GND    I19 @T6G_MB_LIB.T6G(SCH_1):PAGE181

PC176 Q_CAP_C0402-560PF,50V,10%,EMPTY,CH1566K1B09
     1 SW_PVDDIO_P1_SW4 @T6G_MB_LIB.T6G(SCH_1):SW_PVDDIO_P1_SW4    I37 @T6G_MB_LIB.T6G(SCH_1):PAGE198
     2 SW_PVDDIO_P1_SW4_RC @T6G_MB_LIB.T6G(SCH_1):SW_PVDDIO_P1_SW4_RC    I37 @T6G_MB_LIB.T6G(SCH_1):PAGE198

PC176_10 Q_CAP_0402-0.1UF,25V,10%,X7R,CH4104K1B00
     1 PVDDCR_CPU1_P0_VCCS @T6G_MB_LIB.T6G(SCH_1):PVDDCR_CPU1_P0_VCCS     I1 @T6G_MB_LIB.T6G(SCH_1):PAGE181
     2    GND @T6G_MB_LIB.T6G(SCH_1):GND     I1 @T6G_MB_LIB.T6G(SCH_1):PAGE181

PC177 Q_CAP_C0402-560PF,50V,10%,EMPTY,CH1566K1B09
     1 SW_PVDDIO_P1_SW3 @T6G_MB_LIB.T6G(SCH_1):SW_PVDDIO_P1_SW3    I58 @T6G_MB_LIB.T6G(SCH_1):PAGE198
     2 SW_PVDDIO_P1_SW3_RC @T6G_MB_LIB.T6G(SCH_1):SW_PVDDIO_P1_SW3_RC    I58 @T6G_MB_LIB.T6G(SCH_1):PAGE198

PC177_3 Q_CAP_0402-0.1UF,25V,10%,X7R,CH4104K1B00
     1 SW_P12V_AUX_PVDDIO_P0_FLT @T6G_MB_LIB.T6G(SCH_1):SW_P12V_AUX_PVDDIO_P0_FLT    I35 @T6G_MB_LIB.T6G(SCH_1):PAGE181
     2    GND @T6G_MB_LIB.T6G(SCH_1):GND    I35 @T6G_MB_LIB.T6G(SCH_1):PAGE181

PC178 Q_CAP_C0402-560PF,50V,10%,EMPTY,CH1566K1B09
     1 SW_PVDDCR_CPU0_P0_SW1 @T6G_MB_LIB.T6G(SCH_1):SW_PVDDCR_CPU0_P0_SW1    I54 @T6G_MB_LIB.T6G(SCH_1):PAGE169
     2 SW_PVDDCR_CPU0_P0_SW1_RC @T6G_MB_LIB.T6G(SCH_1):SW_PVDDCR_CPU0_P0_SW1_RC    I54 @T6G_MB_LIB.T6G(SCH_1):PAGE169

PC178_4 Q_CAP_0402-0.1UF,25V,10%,X7R,CH4104K1B00
     1 SW_P12V_AUX_PVDDIO_P0_FLT @T6G_MB_LIB.T6G(SCH_1):SW_P12V_AUX_PVDDIO_P0_FLT    I17 @T6G_MB_LIB.T6G(SCH_1):PAGE181
     2    GND @T6G_MB_LIB.T6G(SCH_1):GND    I17 @T6G_MB_LIB.T6G(SCH_1):PAGE181

PC179 Q_CAP_C0402-560PF,50V,10%,EMPTY,CH1566K1B09
     1 SW_PVDDCR_CPU0_P0_SW2 @T6G_MB_LIB.T6G(SCH_1):SW_PVDDCR_CPU0_P0_SW2    I31 @T6G_MB_LIB.T6G(SCH_1):PAGE169
     2 SW_PVDDCR_CPU0_P0_SW2_RC @T6G_MB_LIB.T6G(SCH_1):SW_PVDDCR_CPU0_P0_SW2_RC    I31 @T6G_MB_LIB.T6G(SCH_1):PAGE169

PC179_3 Q_CAP_C0402-1UF,25V,10%,X6S,CH5104KEB02
     1 SW_P12V_AUX_PVDDIO_P0_FLT @T6G_MB_LIB.T6G(SCH_1):SW_P12V_AUX_PVDDIO_P0_FLT    I36 @T6G_MB_LIB.T6G(SCH_1):PAGE181
     2    GND @T6G_MB_LIB.T6G(SCH_1):GND    I36 @T6G_MB_LIB.T6G(SCH_1):PAGE181

PC180 Q_CAP_C0402-560PF,50V,10%,EMPTY,CH1566K1B09
     1 SW_PVDDCR_CPU0_P0_SW3 @T6G_MB_LIB.T6G(SCH_1):SW_PVDDCR_CPU0_P0_SW3    I45 @T6G_MB_LIB.T6G(SCH_1):PAGE170
     2 SW_PVDDCR_CPU0_P0_SW3_RC @T6G_MB_LIB.T6G(SCH_1):SW_PVDDCR_CPU0_P0_SW3_RC    I45 @T6G_MB_LIB.T6G(SCH_1):PAGE170

PC180_4 Q_CAP_C0402-1UF,25V,10%,X6S,CH5104KEB02
     1 SW_P12V_AUX_PVDDIO_P0_FLT @T6G_MB_LIB.T6G(SCH_1):SW_P12V_AUX_PVDDIO_P0_FLT    I45 @T6G_MB_LIB.T6G(SCH_1):PAGE181
     2    GND @T6G_MB_LIB.T6G(SCH_1):GND    I45 @T6G_MB_LIB.T6G(SCH_1):PAGE181

PC181 Q_CAP_C0402-560PF,50V,10%,EMPTY,CH1566K1B09
     1 SW_PVDDCR_CPU0_P0_SW4 @T6G_MB_LIB.T6G(SCH_1):SW_PVDDCR_CPU0_P0_SW4    I19 @T6G_MB_LIB.T6G(SCH_1):PAGE170
     2 SW_PVDDCR_CPU0_P0_SW4_RC @T6G_MB_LIB.T6G(SCH_1):SW_PVDDCR_CPU0_P0_SW4_RC    I19 @T6G_MB_LIB.T6G(SCH_1):PAGE170

PC181_3 Q_CAP_C0805-22UF,16V,20%,X6S,CH6223MEA01
     1 SW_P12V_AUX_PVDDIO_P0_FLT @T6G_MB_LIB.T6G(SCH_1):SW_P12V_AUX_PVDDIO_P0_FLT    I58 @T6G_MB_LIB.T6G(SCH_1):PAGE181
     2    GND @T6G_MB_LIB.T6G(SCH_1):GND    I58 @T6G_MB_LIB.T6G(SCH_1):PAGE181

PC182 Q_CAP_C0402-560PF,50V,10%,EMPTY,CH1566K1B09
     1 SW_PVDDCR_CPU0_P0_SW6 @T6G_MB_LIB.T6G(SCH_1):SW_PVDDCR_CPU0_P0_SW6    I23 @T6G_MB_LIB.T6G(SCH_1):PAGE171
     2 SW_PVDDCR_CPU0_P0_SW6_RC @T6G_MB_LIB.T6G(SCH_1):SW_PVDDCR_CPU0_P0_SW6_RC    I23 @T6G_MB_LIB.T6G(SCH_1):PAGE171

PC182_4 Q_CAP_C0805-22UF,16V,20%,X6S,CH6223MEA01
     1 SW_P12V_AUX_PVDDIO_P0_FLT @T6G_MB_LIB.T6G(SCH_1):SW_P12V_AUX_PVDDIO_P0_FLT    I46 @T6G_MB_LIB.T6G(SCH_1):PAGE181
     2    GND @T6G_MB_LIB.T6G(SCH_1):GND    I46 @T6G_MB_LIB.T6G(SCH_1):PAGE181

PC183 Q_CAP_0402-0.22UF,16V,10%,X7R,CH4223K1B00
     1 SW_PVDDIO_P0_BOOT4_R @T6G_MB_LIB.T6G(SCH_1):SW_PVDDIO_P0_BOOT4_R    I44 @T6G_MB_LIB.T6G(SCH_1):PAGE181
     2 SW_PVDDIO_P0_BOOTR4 @T6G_MB_LIB.T6G(SCH_1):SW_PVDDIO_P0_BOOTR4    I44 @T6G_MB_LIB.T6G(SCH_1):PAGE181

PC184 Q_CAP_C0402-560PF,50V,10%,EMPTY,CH1566K1B09
     1 SW_PVDDCR_CPU0_P0_SW5 @T6G_MB_LIB.T6G(SCH_1):SW_PVDDCR_CPU0_P0_SW5    I46 @T6G_MB_LIB.T6G(SCH_1):PAGE171
     2 SW_PVDDCR_CPU0_P0_SW5_RC @T6G_MB_LIB.T6G(SCH_1):SW_PVDDCR_CPU0_P0_SW5_RC    I46 @T6G_MB_LIB.T6G(SCH_1):PAGE171

PC184_3 Q_CAP_C0805-22UF,16V,20%,X6S,CH6223MEA01
     1 SW_P12V_AUX_PVDDIO_P0_FLT @T6G_MB_LIB.T6G(SCH_1):SW_P12V_AUX_PVDDIO_P0_FLT    I60 @T6G_MB_LIB.T6G(SCH_1):PAGE181
     2    GND @T6G_MB_LIB.T6G(SCH_1):GND    I60 @T6G_MB_LIB.T6G(SCH_1):PAGE181

PC185 Q_CAP_C0402-560PF,50V,10%,EMPTY,CH1566K1B09
     1 SW_PVDDCR_SOC_P0_SW1 @T6G_MB_LIB.T6G(SCH_1):SW_PVDDCR_SOC_P0_SW1    I46 @T6G_MB_LIB.T6G(SCH_1):PAGE173
     2 SW_PVDDCR_SOC_P0_SW1_RC @T6G_MB_LIB.T6G(SCH_1):SW_PVDDCR_SOC_P0_SW1_RC    I46 @T6G_MB_LIB.T6G(SCH_1):PAGE173

PC185_4 Q_CAP_C0805-22UF,16V,20%,X6S,CH6223MEA01
     1 SW_P12V_AUX_PVDDIO_P0_FLT @T6G_MB_LIB.T6G(SCH_1):SW_P12V_AUX_PVDDIO_P0_FLT    I47 @T6G_MB_LIB.T6G(SCH_1):PAGE181
     2    GND @T6G_MB_LIB.T6G(SCH_1):GND    I47 @T6G_MB_LIB.T6G(SCH_1):PAGE181

PC186 Q_CAP_0402-0.22UF,16V,10%,X7R,CH4223K1B00
     1 SW_PVDDIO_P0_BOOT3_R @T6G_MB_LIB.T6G(SCH_1):SW_PVDDIO_P0_BOOT3_R    I59 @T6G_MB_LIB.T6G(SCH_1):PAGE181
     2 SW_PVDDIO_P0_BOOTR3 @T6G_MB_LIB.T6G(SCH_1):SW_PVDDIO_P0_BOOTR3    I59 @T6G_MB_LIB.T6G(SCH_1):PAGE181

PC187 Q_CAP_C0402-560PF,50V,10%,EMPTY,CH1566K1B09
     1 SW_PVDDCR_SOC_P0_SW2 @T6G_MB_LIB.T6G(SCH_1):SW_PVDDCR_SOC_P0_SW2    I85 @T6G_MB_LIB.T6G(SCH_1):PAGE173
     2 SW_PVDDCR_SOC_P0_SW2_RC @T6G_MB_LIB.T6G(SCH_1):SW_PVDDCR_SOC_P0_SW2_RC    I85 @T6G_MB_LIB.T6G(SCH_1):PAGE173

PC187_3 Q_CAP_C0805-22UF,16V,20%,X6S,CH6223MEA01
     1 SW_P12V_AUX_PVDDIO_P0_FLT @T6G_MB_LIB.T6G(SCH_1):SW_P12V_AUX_PVDDIO_P0_FLT    I63 @T6G_MB_LIB.T6G(SCH_1):PAGE181
     2    GND @T6G_MB_LIB.T6G(SCH_1):GND    I63 @T6G_MB_LIB.T6G(SCH_1):PAGE181

PC188 Q_CAP_C0402-560PF,50V,10%,EMPTY,CH1566K1B09
     1 SW_PVDDCR_SOC_P0_SW3 @T6G_MB_LIB.T6G(SCH_1):SW_PVDDCR_SOC_P0_SW3    I12 @T6G_MB_LIB.T6G(SCH_1):PAGE174
     2 SW_PVDDCR_SOC_P0_SW3_RC @T6G_MB_LIB.T6G(SCH_1):SW_PVDDCR_SOC_P0_SW3_RC    I12 @T6G_MB_LIB.T6G(SCH_1):PAGE174

PC188_4 Q_CAP_C0805-22UF,16V,20%,X6S,CH6223MEA01
     1 SW_P12V_AUX_PVDDIO_P0_FLT @T6G_MB_LIB.T6G(SCH_1):SW_P12V_AUX_PVDDIO_P0_FLT    I49 @T6G_MB_LIB.T6G(SCH_1):PAGE181
     2    GND @T6G_MB_LIB.T6G(SCH_1):GND    I49 @T6G_MB_LIB.T6G(SCH_1):PAGE181

PC189 Q_CAP_C0402-560PF,50V,10%,EMPTY,CH1566K1B09
     1 SW_PVDDCR_CPU1_P0_SW1 @T6G_MB_LIB.T6G(SCH_1):SW_PVDDCR_CPU1_P0_SW1    I57 @T6G_MB_LIB.T6G(SCH_1):PAGE176
     2 SW_PVDDCR_CPU1_P0_SW1_RC @T6G_MB_LIB.T6G(SCH_1):SW_PVDDCR_CPU1_P0_SW1_RC    I57 @T6G_MB_LIB.T6G(SCH_1):PAGE176

PC189_4 Q_CAP_C0805-22UF,4V,20%,X6S,CH622KMEA03
     1 PVDDIO_P0 @T6G_MB_LIB.T6G(SCH_1):PVDDIO_P0    I53 @T6G_MB_LIB.T6G(SCH_1):PAGE181
     2    GND @T6G_MB_LIB.T6G(SCH_1):GND    I53 @T6G_MB_LIB.T6G(SCH_1):PAGE181

PC190 Q_CAP_C0402-560PF,50V,10%,EMPTY,CH1566K1B09
     1 SW_PVDDCR_CPU1_P0_SW2 @T6G_MB_LIB.T6G(SCH_1):SW_PVDDCR_CPU1_P0_SW2    I41 @T6G_MB_LIB.T6G(SCH_1):PAGE176
     2 SW_PVDDCR_CPU1_P0_SW2_RC @T6G_MB_LIB.T6G(SCH_1):SW_PVDDCR_CPU1_P0_SW2_RC    I41 @T6G_MB_LIB.T6G(SCH_1):PAGE176

PC190_3 Q_CAP_C0805-22UF,4V,20%,X6S,CH622KMEA03
     1 PVDDIO_P0 @T6G_MB_LIB.T6G(SCH_1):PVDDIO_P0    I66 @T6G_MB_LIB.T6G(SCH_1):PAGE181
     2    GND @T6G_MB_LIB.T6G(SCH_1):GND    I66 @T6G_MB_LIB.T6G(SCH_1):PAGE181

PC191 Q_CAP_C0402-560PF,50V,10%,EMPTY,CH1566K1B09
     1 SW_PVDDCR_CPU1_P0_SW4 @T6G_MB_LIB.T6G(SCH_1):SW_PVDDCR_CPU1_P0_SW4    I38 @T6G_MB_LIB.T6G(SCH_1):PAGE177
     2 SW_PVDDCR_CPU1_P0_SW4_RC @T6G_MB_LIB.T6G(SCH_1):SW_PVDDCR_CPU1_P0_SW4_RC    I38 @T6G_MB_LIB.T6G(SCH_1):PAGE177

PC191_4 Q_CAP_C0805-22UF,4V,20%,X6S,CH622KMEA03
     1 PVDDIO_P0 @T6G_MB_LIB.T6G(SCH_1):PVDDIO_P0    I68 @T6G_MB_LIB.T6G(SCH_1):PAGE181
     2    GND @T6G_MB_LIB.T6G(SCH_1):GND    I68 @T6G_MB_LIB.T6G(SCH_1):PAGE181

PC192 Q_CAP_C0402-560PF,50V,10%,EMPTY,CH1566K1B09
     1 SW_PVDDCR_CPU1_P0_SW3 @T6G_MB_LIB.T6G(SCH_1):SW_PVDDCR_CPU1_P0_SW3    I58 @T6G_MB_LIB.T6G(SCH_1):PAGE177
     2 SW_PVDDCR_CPU1_P0_SW3_RC @T6G_MB_LIB.T6G(SCH_1):SW_PVDDCR_CPU1_P0_SW3_RC    I58 @T6G_MB_LIB.T6G(SCH_1):PAGE177

PC192_3 Q_CAP_C0805-22UF,4V,20%,X6S,CH622KMEA03
     1 PVDDIO_P0 @T6G_MB_LIB.T6G(SCH_1):PVDDIO_P0    I71 @T6G_MB_LIB.T6G(SCH_1):PAGE181
     2    GND @T6G_MB_LIB.T6G(SCH_1):GND    I71 @T6G_MB_LIB.T6G(SCH_1):PAGE181

PC193 Q_CAP_0402-0.1UF,25V,10%,X7R,CH4104K1B00
     1 PVDD11_S3_P0_VMON @T6G_MB_LIB.T6G(SCH_1):PVDD11_S3_P0_VMON     I4 @T6G_MB_LIB.T6G(SCH_1):PAGE182
     2    GND @T6G_MB_LIB.T6G(SCH_1):GND     I4 @T6G_MB_LIB.T6G(SCH_1):PAGE182

PC194 Q_CAP_0402-3300PF,50V,10%,X7R,TMP_QCH2336K1B12
     1 VSENSE_PVDD11_S3_P0_R @T6G_MB_LIB.T6G(SCH_1):VSENSE_PVDD11_S3_P0_R    I29 @T6G_MB_LIB.T6G(SCH_1):PAGE182
     2 VSENSE_VSS_SENSE_C_P0 @T6G_MB_LIB.T6G(SCH_1):VSENSE_VSS_SENSE_C_P0    I29 @T6G_MB_LIB.T6G(SCH_1):PAGE182

PC195 Q_CAP_C0402-560PF,50V,10%,EMPTY,CH1566K1B09
     1 SW_PVDDCR_SOC_P1_SW3 @T6G_MB_LIB.T6G(SCH_1):SW_PVDDCR_SOC_P1_SW3    I11 @T6G_MB_LIB.T6G(SCH_1):PAGE191
     2 SW_PVDDCR_SOC_P1_SW3_RC @T6G_MB_LIB.T6G(SCH_1):SW_PVDDCR_SOC_P1_SW3_RC    I11 @T6G_MB_LIB.T6G(SCH_1):PAGE191

PC198 Q_CAP_0402-470PF,50V,10%,X7R,TMP_QCH14706KB18
     1 PVDD11_S3_P0_TEMP0 @T6G_MB_LIB.T6G(SCH_1):PVDD11_S3_P0_TEMP0    I50 @T6G_MB_LIB.T6G(SCH_1):PAGE182
     2    GND @T6G_MB_LIB.T6G(SCH_1):GND    I50 @T6G_MB_LIB.T6G(SCH_1):PAGE182

PC199 Q_CAP_C0402-10UF,6.3V,20%,X6S,CH6101MEB03
     1 PVDD11_S3_P0_VCCS @T6G_MB_LIB.T6G(SCH_1):PVDD11_S3_P0_VCCS    I80 @T6G_MB_LIB.T6G(SCH_1):PAGE182
     2    GND @T6G_MB_LIB.T6G(SCH_1):GND    I80 @T6G_MB_LIB.T6G(SCH_1):PAGE182

PC200 Q_CAP_C0402-1UF,16V,10%,X6S,CH5103KEB01
     1 PVDD11_S3_P0_VCC @T6G_MB_LIB.T6G(SCH_1):PVDD11_S3_P0_VCC    I82 @T6G_MB_LIB.T6G(SCH_1):PAGE182
     2    GND @T6G_MB_LIB.T6G(SCH_1):GND    I82 @T6G_MB_LIB.T6G(SCH_1):PAGE182

PC201 Q_CAP_C0402-560PF,50V,10%,EMPTY,CH1566K1B09
     1 SW_PVDDCR_CPU1_P1_SW1 @T6G_MB_LIB.T6G(SCH_1):SW_PVDDCR_CPU1_P1_SW1    I52 @T6G_MB_LIB.T6G(SCH_1):PAGE193
     2 SW_PVDDCR_CPU1_P1_SW1_RC @T6G_MB_LIB.T6G(SCH_1):SW_PVDDCR_CPU1_P1_SW1_RC    I52 @T6G_MB_LIB.T6G(SCH_1):PAGE193

PC201_1 Q_CAP_0402-0.1UF,25V,10%,X7R,CH4104K1B00
     1 PVDD11_S3_P0_VCCS @T6G_MB_LIB.T6G(SCH_1):PVDD11_S3_P0_VCCS    I34 @T6G_MB_LIB.T6G(SCH_1):PAGE183
     2    GND @T6G_MB_LIB.T6G(SCH_1):GND    I34 @T6G_MB_LIB.T6G(SCH_1):PAGE183

PC202 Q_CAP_C0402-560PF,50V,10%,EMPTY,CH1566K1B09
     1 SW_PVDDCR_CPU1_P1_SW2 @T6G_MB_LIB.T6G(SCH_1):SW_PVDDCR_CPU1_P1_SW2    I37 @T6G_MB_LIB.T6G(SCH_1):PAGE193
     2 SW_PVDDCR_CPU1_P1_SW2_RC @T6G_MB_LIB.T6G(SCH_1):SW_PVDDCR_CPU1_P1_SW2_RC    I37 @T6G_MB_LIB.T6G(SCH_1):PAGE193

PC202_2 Q_CAP_0402-0.1UF,25V,10%,X7R,CH4104K1B00
     1 PVDD11_S3_P0_VCCS @T6G_MB_LIB.T6G(SCH_1):PVDD11_S3_P0_VCCS     I7 @T6G_MB_LIB.T6G(SCH_1):PAGE183
     2    GND @T6G_MB_LIB.T6G(SCH_1):GND     I7 @T6G_MB_LIB.T6G(SCH_1):PAGE183

PC203 Q_CAP_C0402-2.2UF,10V,10%,X6S,CH5222KEB01
     1 PVDD11_S3_P0_VCC1 @T6G_MB_LIB.T6G(SCH_1):PVDD11_S3_P0_VCC1    I36 @T6G_MB_LIB.T6G(SCH_1):PAGE183
     2    GND @T6G_MB_LIB.T6G(SCH_1):GND    I36 @T6G_MB_LIB.T6G(SCH_1):PAGE183

PC204 Q_CAP_C0402-2.2UF,10V,10%,X6S,CH5222KEB01
     1 PVDD11_S3_P0_VCC2 @T6G_MB_LIB.T6G(SCH_1):PVDD11_S3_P0_VCC2     I9 @T6G_MB_LIB.T6G(SCH_1):PAGE183
     2    GND @T6G_MB_LIB.T6G(SCH_1):GND     I9 @T6G_MB_LIB.T6G(SCH_1):PAGE183

PC205 Q_CAP_C0402-560PF,50V,10%,EMPTY,CH1566K1B09
     1 SW_PVDDCR_CPU1_P1_SW4 @T6G_MB_LIB.T6G(SCH_1):SW_PVDDCR_CPU1_P1_SW4    I37 @T6G_MB_LIB.T6G(SCH_1):PAGE194
     2 SW_PVDDCR_CPU1_P1_SW4_RC @T6G_MB_LIB.T6G(SCH_1):SW_PVDDCR_CPU1_P1_SW4_RC    I37 @T6G_MB_LIB.T6G(SCH_1):PAGE194

PC205_11P0_1 Q_CAP_C0402-2.2UF,10V,10%,X6S,CH5222KEB01
     1 PVDD11_S3_P0_PVCC @T6G_MB_LIB.T6G(SCH_1):PVDD11_S3_P0_PVCC    I42 @T6G_MB_LIB.T6G(SCH_1):PAGE183
     2    GND @T6G_MB_LIB.T6G(SCH_1):GND    I42 @T6G_MB_LIB.T6G(SCH_1):PAGE183

PC206 Q_CAP_C0402-560PF,50V,10%,EMPTY,CH1566K1B09
     1 SW_PVDDCR_CPU1_P1_SW3 @T6G_MB_LIB.T6G(SCH_1):SW_PVDDCR_CPU1_P1_SW3    I53 @T6G_MB_LIB.T6G(SCH_1):PAGE194
     2 SW_PVDDCR_CPU1_P1_SW3_RC @T6G_MB_LIB.T6G(SCH_1):SW_PVDDCR_CPU1_P1_SW3_RC    I53 @T6G_MB_LIB.T6G(SCH_1):PAGE194

PC206_11P0_2 Q_CAP_C0402-2.2UF,10V,10%,X6S,CH5222KEB01
     1 PVDD11_S3_P0_PVCC @T6G_MB_LIB.T6G(SCH_1):PVDD11_S3_P0_PVCC    I17 @T6G_MB_LIB.T6G(SCH_1):PAGE183
     2    GND @T6G_MB_LIB.T6G(SCH_1):GND    I17 @T6G_MB_LIB.T6G(SCH_1):PAGE183

PC207 Q_CAP_C0402-560PF,50V,10%,EMPTY,CH1566K1B09
     1 SW_PVDDCR_CPU1_P1_SW5 @T6G_MB_LIB.T6G(SCH_1):SW_PVDDCR_CPU1_P1_SW5    I53 @T6G_MB_LIB.T6G(SCH_1):PAGE195
     2 SW_PVDDCR_CPU1_P1_SW5_RC @T6G_MB_LIB.T6G(SCH_1):SW_PVDDCR_CPU1_P1_SW5_RC    I53 @T6G_MB_LIB.T6G(SCH_1):PAGE195

PC207_1 Q_CAP_0402-0.1UF,25V,10%,X7R,CH4104K1B00
     1 SW_P12V_AUX_PVDD11_S3_P0_FLT @T6G_MB_LIB.T6G(SCH_1):SW_P12V_AUX_PVDD11_S3_P0_FLT    I47 @T6G_MB_LIB.T6G(SCH_1):PAGE183
     2    GND @T6G_MB_LIB.T6G(SCH_1):GND    I47 @T6G_MB_LIB.T6G(SCH_1):PAGE183

PC208 Q_CAP_C0402-560PF,50V,10%,EMPTY,CH1566K1B09
     1 SW_PVDDCR_CPU1_P1_SW6 @T6G_MB_LIB.T6G(SCH_1):SW_PVDDCR_CPU1_P1_SW6    I34 @T6G_MB_LIB.T6G(SCH_1):PAGE195
     2 SW_PVDDCR_CPU1_P1_SW6_RC @T6G_MB_LIB.T6G(SCH_1):SW_PVDDCR_CPU1_P1_SW6_RC    I34 @T6G_MB_LIB.T6G(SCH_1):PAGE195

PC208_2 Q_CAP_0402-0.1UF,25V,10%,X7R,CH4104K1B00
     1 SW_P12V_AUX_PVDD11_S3_P0_FLT @T6G_MB_LIB.T6G(SCH_1):SW_P12V_AUX_PVDD11_S3_P0_FLT    I29 @T6G_MB_LIB.T6G(SCH_1):PAGE183
     2    GND @T6G_MB_LIB.T6G(SCH_1):GND    I29 @T6G_MB_LIB.T6G(SCH_1):PAGE183

PC209 Q_CAP_0402-0.22UF,16V,10%,X7R,CH4223K1B00
     1 SW_PVDD18_S5_P0_BST_R @T6G_MB_LIB.T6G(SCH_1):SW_PVDD18_S5_P0_BST_R    I24 @T6G_MB_LIB.T6G(SCH_1):PAGE184
     2 SW_PVDD18_S5_P0_SW @T6G_MB_LIB.T6G(SCH_1):SW_PVDD18_S5_P0_SW    I24 @T6G_MB_LIB.T6G(SCH_1):PAGE184

PC209_1 Q_CAP_C0402-1UF,25V,10%,X6S,CH5104KEB02
     1 SW_P12V_AUX_PVDD11_S3_P0_FLT @T6G_MB_LIB.T6G(SCH_1):SW_P12V_AUX_PVDD11_S3_P0_FLT    I44 @T6G_MB_LIB.T6G(SCH_1):PAGE183
     2    GND @T6G_MB_LIB.T6G(SCH_1):GND    I44 @T6G_MB_LIB.T6G(SCH_1):PAGE183

PC210_2 Q_CAP_C0402-1UF,25V,10%,X6S,CH5104KEB02
     1 SW_P12V_AUX_PVDD11_S3_P0_FLT @T6G_MB_LIB.T6G(SCH_1):SW_P12V_AUX_PVDD11_S3_P0_FLT    I27 @T6G_MB_LIB.T6G(SCH_1):PAGE183
     2    GND @T6G_MB_LIB.T6G(SCH_1):GND    I27 @T6G_MB_LIB.T6G(SCH_1):PAGE183

PC211_1 Q_CAP_C0805-22UF,16V,20%,X6S,CH6223MEA01
     1 SW_P12V_AUX_PVDD11_S3_P0_FLT @T6G_MB_LIB.T6G(SCH_1):SW_P12V_AUX_PVDD11_S3_P0_FLT    I48 @T6G_MB_LIB.T6G(SCH_1):PAGE183
     2    GND @T6G_MB_LIB.T6G(SCH_1):GND    I48 @T6G_MB_LIB.T6G(SCH_1):PAGE183

PC212 Q_CAP_C0402-1UF,25V,10%,X6S,CH5104KEB02
     1 PVDD18_S5_P0_VCC @T6G_MB_LIB.T6G(SCH_1):PVDD18_S5_P0_VCC    I11 @T6G_MB_LIB.T6G(SCH_1):PAGE184
     2    GND @T6G_MB_LIB.T6G(SCH_1):GND    I11 @T6G_MB_LIB.T6G(SCH_1):PAGE184

PC212_2 Q_CAP_C0805-22UF,16V,20%,X6S,CH6223MEA01
     1 SW_P12V_AUX_PVDD11_S3_P0_FLT @T6G_MB_LIB.T6G(SCH_1):SW_P12V_AUX_PVDD11_S3_P0_FLT    I30 @T6G_MB_LIB.T6G(SCH_1):PAGE183
     2    GND @T6G_MB_LIB.T6G(SCH_1):GND    I30 @T6G_MB_LIB.T6G(SCH_1):PAGE183

PC213_1 Q_CAP_C0805-22UF,16V,20%,X6S,CH6223MEA01
     1 SW_P12V_AUX_PVDD11_S3_P0_FLT @T6G_MB_LIB.T6G(SCH_1):SW_P12V_AUX_PVDD11_S3_P0_FLT    I49 @T6G_MB_LIB.T6G(SCH_1):PAGE183
     2    GND @T6G_MB_LIB.T6G(SCH_1):GND    I49 @T6G_MB_LIB.T6G(SCH_1):PAGE183

PC214_2 Q_CAP_C0805-22UF,16V,20%,X6S,CH6223MEA01
     1 SW_P12V_AUX_PVDD11_S3_P0_FLT @T6G_MB_LIB.T6G(SCH_1):SW_P12V_AUX_PVDD11_S3_P0_FLT    I31 @T6G_MB_LIB.T6G(SCH_1):PAGE183
     2    GND @T6G_MB_LIB.T6G(SCH_1):GND    I31 @T6G_MB_LIB.T6G(SCH_1):PAGE183

PC215 Q_CAP_0402-0.1UF,25V,10%,X7R,CH4104K1B00
     1 PVDD18_S5_P0 @T6G_MB_LIB.T6G(SCH_1):PVDD18_S5_P0    I48 @T6G_MB_LIB.T6G(SCH_1):PAGE184
     2    GND @T6G_MB_LIB.T6G(SCH_1):GND    I48 @T6G_MB_LIB.T6G(SCH_1):PAGE184

PC215_1 Q_CAP_C0805-22UF,16V,20%,X6S,CH6223MEA01
     1 SW_P12V_AUX_PVDD11_S3_P0_FLT @T6G_MB_LIB.T6G(SCH_1):SW_P12V_AUX_PVDD11_S3_P0_FLT    I87 @T6G_MB_LIB.T6G(SCH_1):PAGE183
     2    GND @T6G_MB_LIB.T6G(SCH_1):GND    I87 @T6G_MB_LIB.T6G(SCH_1):PAGE183

PC216_2 Q_CAP_C0805-22UF,16V,20%,X6S,CH6223MEA01
     1 SW_P12V_AUX_PVDD11_S3_P0_FLT @T6G_MB_LIB.T6G(SCH_1):SW_P12V_AUX_PVDD11_S3_P0_FLT    I50 @T6G_MB_LIB.T6G(SCH_1):PAGE183
     2    GND @T6G_MB_LIB.T6G(SCH_1):GND    I50 @T6G_MB_LIB.T6G(SCH_1):PAGE183

PC217 Q_CAP_0402-0.22UF,16V,10%,X7R,CH4223K1B00
     1 SW_PVDD11_S3_P0_BOOT1_RC @T6G_MB_LIB.T6G(SCH_1):SW_PVDD11_S3_P0_BOOT1_RC    I71 @T6G_MB_LIB.T6G(SCH_1):PAGE183
     2 SW_PVDD11_S3_P0_PH1 @T6G_MB_LIB.T6G(SCH_1):SW_PVDD11_S3_P0_PH1    I71 @T6G_MB_LIB.T6G(SCH_1):PAGE183

PC218 Q_CAP_0402-0.22UF,16V,10%,X7R,CH4223K1B00
     1 SW_PVDD11_S3_P0_BOOT2_RC @T6G_MB_LIB.T6G(SCH_1):SW_PVDD11_S3_P0_BOOT2_RC    I51 @T6G_MB_LIB.T6G(SCH_1):PAGE183
     2 SW_PVDD11_S3_P0_PH2 @T6G_MB_LIB.T6G(SCH_1):SW_PVDD11_S3_P0_PH2    I51 @T6G_MB_LIB.T6G(SCH_1):PAGE183

PC218_2 Q_CAP_C0805-22UF,16V,20%,X6S,CH6223MEA01
     1 SW_P12V_AUX_PVDD11_S3_P0_FLT @T6G_MB_LIB.T6G(SCH_1):SW_P12V_AUX_PVDD11_S3_P0_FLT    I54 @T6G_MB_LIB.T6G(SCH_1):PAGE183
     2    GND @T6G_MB_LIB.T6G(SCH_1):GND    I54 @T6G_MB_LIB.T6G(SCH_1):PAGE183

PC219_1 Q_CAP_C0805-22UF,16V,20%,X6S,CH6223MEA01
     1 SW_P12V_AUX_PVDD11_S3_P0_FLT @T6G_MB_LIB.T6G(SCH_1):SW_P12V_AUX_PVDD11_S3_P0_FLT    I88 @T6G_MB_LIB.T6G(SCH_1):PAGE183
     2    GND @T6G_MB_LIB.T6G(SCH_1):GND    I88 @T6G_MB_LIB.T6G(SCH_1):PAGE183

PC220 Q_CAPP_THLF-270UF,16V,20%,OSCON,CC72703MD38
     1 SW_P12V_AUX_PVDD11_S3_P0_FLT @T6G_MB_LIB.T6G(SCH_1):SW_P12V_AUX_PVDD11_S3_P0_FLT    I75 @T6G_MB_LIB.T6G(SCH_1):PAGE183
     2    GND @T6G_MB_LIB.T6G(SCH_1):GND    I75 @T6G_MB_LIB.T6G(SCH_1):PAGE183

PC221_2 Q_CAP_C0805-22UF,4V,20%,X6S,CH622KMEA03
     1 PVDD11_S3_P0 @T6G_MB_LIB.T6G(SCH_1):PVDD11_S3_P0    I90 @T6G_MB_LIB.T6G(SCH_1):PAGE183
     2    GND @T6G_MB_LIB.T6G(SCH_1):GND    I90 @T6G_MB_LIB.T6G(SCH_1):PAGE183

PC222 Q_CAP_0402-0.1UF,25V,10%,X7R,CH4104K1B00
     1 PVDD11_S3_P0 @T6G_MB_LIB.T6G(SCH_1):PVDD11_S3_P0    I76 @T6G_MB_LIB.T6G(SCH_1):PAGE183
     2    GND @T6G_MB_LIB.T6G(SCH_1):GND    I76 @T6G_MB_LIB.T6G(SCH_1):PAGE183

PC223 Q_CAPP_SMLF-470UF,2.5V,20%,SPCAP,CH747LM8825
     1 PVDD11_S3_P0 @T6G_MB_LIB.T6G(SCH_1):PVDD11_S3_P0    I58 @T6G_MB_LIB.T6G(SCH_1):PAGE183
     2    GND @T6G_MB_LIB.T6G(SCH_1):GND    I58 @T6G_MB_LIB.T6G(SCH_1):PAGE183

PC224_1 Q_CAP_C0805-22UF,4V,20%,X6S,CH622KMEA03
     1 PVDD11_S3_P0 @T6G_MB_LIB.T6G(SCH_1):PVDD11_S3_P0    I81 @T6G_MB_LIB.T6G(SCH_1):PAGE183
     2    GND @T6G_MB_LIB.T6G(SCH_1):GND    I81 @T6G_MB_LIB.T6G(SCH_1):PAGE183

PC225_2 Q_CAP_C0805-22UF,4V,20%,X6S,CH622KMEA03
     1 PVDD11_S3_P0 @T6G_MB_LIB.T6G(SCH_1):PVDD11_S3_P0    I62 @T6G_MB_LIB.T6G(SCH_1):PAGE183
     2    GND @T6G_MB_LIB.T6G(SCH_1):GND    I62 @T6G_MB_LIB.T6G(SCH_1):PAGE183

PC226 Q_CAPP_SMLF-470UF,2.5V,20%,SPCAP,CH747LM8825
     1 PVDD11_S3_P0 @T6G_MB_LIB.T6G(SCH_1):PVDD11_S3_P0    I59 @T6G_MB_LIB.T6G(SCH_1):PAGE183
     2    GND @T6G_MB_LIB.T6G(SCH_1):GND    I59 @T6G_MB_LIB.T6G(SCH_1):PAGE183

PC227 Q_CAP_C0805-22UF,16V,20%,X6S,CH6223MEA01
     1 SW_P12V_AUX_PVDD18_S5_P0_FLT @T6G_MB_LIB.T6G(SCH_1):SW_P12V_AUX_PVDD18_S5_P0_FLT    I25 @T6G_MB_LIB.T6G(SCH_1):PAGE184
     2    GND @T6G_MB_LIB.T6G(SCH_1):GND    I25 @T6G_MB_LIB.T6G(SCH_1):PAGE184

PC227_1 Q_CAP_C0805-22UF,4V,20%,X6S,CH622KMEA03
     1 PVDD11_S3_P0 @T6G_MB_LIB.T6G(SCH_1):PVDD11_S3_P0    I82 @T6G_MB_LIB.T6G(SCH_1):PAGE183
     2    GND @T6G_MB_LIB.T6G(SCH_1):GND    I82 @T6G_MB_LIB.T6G(SCH_1):PAGE183

PC228 Q_CAPP_SMLF-390UF,2.5V,20%,ALUM,CC7390JMZ13
     1 PVDD11_S3_P0 @T6G_MB_LIB.T6G(SCH_1):PVDD11_S3_P0    I65 @T6G_MB_LIB.T6G(SCH_1):PAGE183
     2    GND @T6G_MB_LIB.T6G(SCH_1):GND    I65 @T6G_MB_LIB.T6G(SCH_1):PAGE183

PC229 Q_CAPP_SMLF-390UF,2.5V,20%,ALUM,CC7390JMZ13
     1 PVDD11_S3_P0 @T6G_MB_LIB.T6G(SCH_1):PVDD11_S3_P0    I66 @T6G_MB_LIB.T6G(SCH_1):PAGE183
     2    GND @T6G_MB_LIB.T6G(SCH_1):GND    I66 @T6G_MB_LIB.T6G(SCH_1):PAGE183

PC230 Q_CAPP_SMLF-390UF,2.5V,20%,ALUM,CC7390JMZ13
     1 PVDD11_S3_P0 @T6G_MB_LIB.T6G(SCH_1):PVDD11_S3_P0    I67 @T6G_MB_LIB.T6G(SCH_1):PAGE183
     2    GND @T6G_MB_LIB.T6G(SCH_1):GND    I67 @T6G_MB_LIB.T6G(SCH_1):PAGE183

PC237 Q_CAP_C0402-1UF,25V,10%,X6S,CH5104KEB02
     1 SW_P12V_AUX_PVDD18_S5_P0_FLT @T6G_MB_LIB.T6G(SCH_1):SW_P12V_AUX_PVDD18_S5_P0_FLT    I28 @T6G_MB_LIB.T6G(SCH_1):PAGE184
     2    GND @T6G_MB_LIB.T6G(SCH_1):GND    I28 @T6G_MB_LIB.T6G(SCH_1):PAGE184

PC243 Q_CAP_0402-0.1UF,25V,10%,X7R,CH4104K1B00
     1 PVDDCR_CPU0_P1_VMON @T6G_MB_LIB.T6G(SCH_1):PVDDCR_CPU0_P1_VMON    I22 @T6G_MB_LIB.T6G(SCH_1):PAGE185
     2    GND @T6G_MB_LIB.T6G(SCH_1):GND    I22 @T6G_MB_LIB.T6G(SCH_1):PAGE185

PC244 Q_CAP_0402-3300PF,50V,10%,X7R,TMP_QCH2336K1B12
     1 VSENSE_PVDDCR_CPU0_P1_VSEN0 @T6G_MB_LIB.T6G(SCH_1):VSENSE_PVDDCR_CPU0_P1_VSEN0    I60 @T6G_MB_LIB.T6G(SCH_1):PAGE185
     2 VSENSE_VSS_SENSE_A_P1 @T6G_MB_LIB.T6G(SCH_1):VSENSE_VSS_SENSE_A_P1    I60 @T6G_MB_LIB.T6G(SCH_1):PAGE185

PC245 Q_CAP_0402-3300PF,50V,10%,X7R,TMP_QCH2336K1B12
     1 VSENSE_PVDDCR_SOC_P1_VSEN1 @T6G_MB_LIB.T6G(SCH_1):VSENSE_PVDDCR_SOC_P1_VSEN1    I58 @T6G_MB_LIB.T6G(SCH_1):PAGE185
     2 VSENSE_VSS_SENSE_A_P1 @T6G_MB_LIB.T6G(SCH_1):VSENSE_VSS_SENSE_A_P1    I58 @T6G_MB_LIB.T6G(SCH_1):PAGE185

PC247 Q_CAP_0402-1UF,6.3V,10%,X7R,CH5101K1B01
     1 PVDD18_S5_P1 @T6G_MB_LIB.T6G(SCH_1):PVDD18_S5_P1   I132 @T6G_MB_LIB.T6G(SCH_1):PAGE185
     2    GND @T6G_MB_LIB.T6G(SCH_1):GND   I132 @T6G_MB_LIB.T6G(SCH_1):PAGE185

PC250 Q_CAP_0402-470PF,50V,10%,X7R,TMP_QCH14706KB18
     1 PVDDCR_CPU0_P1_TEMP0 @T6G_MB_LIB.T6G(SCH_1):PVDDCR_CPU0_P1_TEMP0    I91 @T6G_MB_LIB.T6G(SCH_1):PAGE185
     2    GND @T6G_MB_LIB.T6G(SCH_1):GND    I91 @T6G_MB_LIB.T6G(SCH_1):PAGE185

PC251 Q_CAP_C0402-10UF,6.3V,20%,X6S,CH6101MEB03
     1 PVDDCR_CPU0_P1_VCCS @T6G_MB_LIB.T6G(SCH_1):PVDDCR_CPU0_P1_VCCS   I125 @T6G_MB_LIB.T6G(SCH_1):PAGE185
     2    GND @T6G_MB_LIB.T6G(SCH_1):GND   I125 @T6G_MB_LIB.T6G(SCH_1):PAGE185

PC252 Q_CAP_C0402-1UF,16V,10%,X6S,CH5103KEB01
     1 PVDDCR_CPU0_P1_VCC @T6G_MB_LIB.T6G(SCH_1):PVDDCR_CPU0_P1_VCC   I127 @T6G_MB_LIB.T6G(SCH_1):PAGE185
     2    GND @T6G_MB_LIB.T6G(SCH_1):GND   I127 @T6G_MB_LIB.T6G(SCH_1):PAGE185

PC253 Q_CAP_0402-470PF,50V,10%,X7R,TMP_QCH14706KB18
     1 PVDDCR_SOC_P1_TEMP1 @T6G_MB_LIB.T6G(SCH_1):PVDDCR_SOC_P1_TEMP1    I94 @T6G_MB_LIB.T6G(SCH_1):PAGE185
     2    GND @T6G_MB_LIB.T6G(SCH_1):GND    I94 @T6G_MB_LIB.T6G(SCH_1):PAGE185

PC254 Q_CAP_C0805-22UF,16V,20%,X6S,CH6223MEA01
     1 SW_P12V_AUX_PVDD18_S5_P0_FLT @T6G_MB_LIB.T6G(SCH_1):SW_P12V_AUX_PVDD18_S5_P0_FLT    I26 @T6G_MB_LIB.T6G(SCH_1):PAGE184
     2    GND @T6G_MB_LIB.T6G(SCH_1):GND    I26 @T6G_MB_LIB.T6G(SCH_1):PAGE184

PC254_1 Q_CAP_0402-0.1UF,25V,10%,X7R,CH4104K1B00
     1 PVDDCR_CPU0_P1_VCCS @T6G_MB_LIB.T6G(SCH_1):PVDDCR_CPU0_P1_VCCS    I16 @T6G_MB_LIB.T6G(SCH_1):PAGE186
     2    GND @T6G_MB_LIB.T6G(SCH_1):GND    I16 @T6G_MB_LIB.T6G(SCH_1):PAGE186

PC255 Q_CAP_C0402-560PF,50V,10%,EMPTY,CH1566K1B09
     1 SW_PVDD11_S3_P1_SW2 @T6G_MB_LIB.T6G(SCH_1):SW_PVDD11_S3_P1_SW2    I27 @T6G_MB_LIB.T6G(SCH_1):PAGE200
     2 SW_PVDD11_S3_P1_SW2_RC @T6G_MB_LIB.T6G(SCH_1):SW_PVDD11_S3_P1_SW2_RC    I27 @T6G_MB_LIB.T6G(SCH_1):PAGE200

PC255_2 Q_CAP_0402-0.1UF,25V,10%,X7R,CH4104K1B00
     1 PVDDCR_CPU0_P1_VCCS @T6G_MB_LIB.T6G(SCH_1):PVDDCR_CPU0_P1_VCCS     I5 @T6G_MB_LIB.T6G(SCH_1):PAGE186
     2    GND @T6G_MB_LIB.T6G(SCH_1):GND     I5 @T6G_MB_LIB.T6G(SCH_1):PAGE186

PC256 Q_CAP_C0402-2.2UF,10V,10%,X6S,CH5222KEB01
     1 PVDDCR_CPU0_P1_VCC1 @T6G_MB_LIB.T6G(SCH_1):PVDDCR_CPU0_P1_VCC1    I36 @T6G_MB_LIB.T6G(SCH_1):PAGE186
     2    GND @T6G_MB_LIB.T6G(SCH_1):GND    I36 @T6G_MB_LIB.T6G(SCH_1):PAGE186

PC257 Q_CAP_C0402-2.2UF,10V,10%,X6S,CH5222KEB01
     1 PVDDCR_CPU0_P1_VCC2 @T6G_MB_LIB.T6G(SCH_1):PVDDCR_CPU0_P1_VCC2     I9 @T6G_MB_LIB.T6G(SCH_1):PAGE186
     2    GND @T6G_MB_LIB.T6G(SCH_1):GND     I9 @T6G_MB_LIB.T6G(SCH_1):PAGE186

PC258 Q_CAP_0402-0.022UF,25V,10%,X7R,CH3224K1B01
     1 PVDD18_S5_P0_REF @T6G_MB_LIB.T6G(SCH_1):PVDD18_S5_P0_REF    I21 @T6G_MB_LIB.T6G(SCH_1):PAGE184
     2    GND @T6G_MB_LIB.T6G(SCH_1):GND    I21 @T6G_MB_LIB.T6G(SCH_1):PAGE184

PC258_C0P1_1 Q_CAP_C0402-2.2UF,10V,10%,X6S,CH5222KEB01
     1 PVDDCR_CPU0_P1_PVCC @T6G_MB_LIB.T6G(SCH_1):PVDDCR_CPU0_P1_PVCC    I44 @T6G_MB_LIB.T6G(SCH_1):PAGE186
     2    GND @T6G_MB_LIB.T6G(SCH_1):GND    I44 @T6G_MB_LIB.T6G(SCH_1):PAGE186

PC259 Q_CAP_0402-220PF,50V,10%,X7R,TMP_QCH12206KB14
     1 PVDD18_S5_P0_FB @T6G_MB_LIB.T6G(SCH_1):PVDD18_S5_P0_FB    I33 @T6G_MB_LIB.T6G(SCH_1):PAGE184
     2 PVDD18_S5_P0_FB_RC @T6G_MB_LIB.T6G(SCH_1):PVDD18_S5_P0_FB_RC    I33 @T6G_MB_LIB.T6G(SCH_1):PAGE184

PC259_C0P1_2 Q_CAP_C0402-2.2UF,10V,10%,X6S,CH5222KEB01
     1 PVDDCR_CPU0_P1_PVCC @T6G_MB_LIB.T6G(SCH_1):PVDDCR_CPU0_P1_PVCC    I13 @T6G_MB_LIB.T6G(SCH_1):PAGE186
     2    GND @T6G_MB_LIB.T6G(SCH_1):GND    I13 @T6G_MB_LIB.T6G(SCH_1):PAGE186

PC260 Q_CAP_C0805-22UF,4V,20%,EMPTY,CH622KMEA03
     1 PVDD18_S5_P0 @T6G_MB_LIB.T6G(SCH_1):PVDD18_S5_P0    I41 @T6G_MB_LIB.T6G(SCH_1):PAGE184
     2    GND @T6G_MB_LIB.T6G(SCH_1):GND    I41 @T6G_MB_LIB.T6G(SCH_1):PAGE184

PC260_1 Q_CAP_0402-0.1UF,25V,10%,X7R,CH4104K1B00
     1 SW_P12V_AUX_PVDDCR_CPU0_P1_FLT @T6G_MB_LIB.T6G(SCH_1):SW_P12V_AUX_PVDDCR_CPU0_P1_FLT    I46 @T6G_MB_LIB.T6G(SCH_1):PAGE186
     2    GND @T6G_MB_LIB.T6G(SCH_1):GND    I46 @T6G_MB_LIB.T6G(SCH_1):PAGE186

PC261 Q_CAP_C0805-22UF,4V,20%,EMPTY,CH622KMEA03
     1 PVDD18_S5_P0 @T6G_MB_LIB.T6G(SCH_1):PVDD18_S5_P0    I46 @T6G_MB_LIB.T6G(SCH_1):PAGE184
     2    GND @T6G_MB_LIB.T6G(SCH_1):GND    I46 @T6G_MB_LIB.T6G(SCH_1):PAGE184

PC261_2 Q_CAP_0402-0.1UF,25V,10%,X7R,CH4104K1B00
     1 SW_P12V_AUX_PVDDCR_CPU0_P1_FLT @T6G_MB_LIB.T6G(SCH_1):SW_P12V_AUX_PVDDCR_CPU0_P1_FLT    I25 @T6G_MB_LIB.T6G(SCH_1):PAGE186
     2    GND @T6G_MB_LIB.T6G(SCH_1):GND    I25 @T6G_MB_LIB.T6G(SCH_1):PAGE186

PC262_1 Q_CAP_C0402-1UF,25V,10%,X6S,CH5104KEB02
     1 SW_P12V_AUX_PVDDCR_CPU0_P1_FLT @T6G_MB_LIB.T6G(SCH_1):SW_P12V_AUX_PVDDCR_CPU0_P1_FLT    I47 @T6G_MB_LIB.T6G(SCH_1):PAGE186
     2    GND @T6G_MB_LIB.T6G(SCH_1):GND    I47 @T6G_MB_LIB.T6G(SCH_1):PAGE186

PC263_2 Q_CAP_C0402-1UF,25V,10%,X6S,CH5104KEB02
     1 SW_P12V_AUX_PVDDCR_CPU0_P1_FLT @T6G_MB_LIB.T6G(SCH_1):SW_P12V_AUX_PVDDCR_CPU0_P1_FLT    I26 @T6G_MB_LIB.T6G(SCH_1):PAGE186
     2    GND @T6G_MB_LIB.T6G(SCH_1):GND    I26 @T6G_MB_LIB.T6G(SCH_1):PAGE186

PC264_1 Q_CAP_C0805-22UF,16V,20%,X6S,CH6223MEA01
     1 SW_P12V_AUX_PVDDCR_CPU0_P1_FLT @T6G_MB_LIB.T6G(SCH_1):SW_P12V_AUX_PVDDCR_CPU0_P1_FLT    I51 @T6G_MB_LIB.T6G(SCH_1):PAGE186
     2    GND @T6G_MB_LIB.T6G(SCH_1):GND    I51 @T6G_MB_LIB.T6G(SCH_1):PAGE186

PC265_2 Q_CAP_C0805-22UF,16V,20%,X6S,CH6223MEA01
     1 SW_P12V_AUX_PVDDCR_CPU0_P1_FLT @T6G_MB_LIB.T6G(SCH_1):SW_P12V_AUX_PVDDCR_CPU0_P1_FLT    I28 @T6G_MB_LIB.T6G(SCH_1):PAGE186
     2    GND @T6G_MB_LIB.T6G(SCH_1):GND    I28 @T6G_MB_LIB.T6G(SCH_1):PAGE186

PC266_1 Q_CAP_C0805-22UF,16V,20%,X6S,CH6223MEA01
     1 SW_P12V_AUX_PVDDCR_CPU0_P1_FLT @T6G_MB_LIB.T6G(SCH_1):SW_P12V_AUX_PVDDCR_CPU0_P1_FLT    I52 @T6G_MB_LIB.T6G(SCH_1):PAGE186
     2    GND @T6G_MB_LIB.T6G(SCH_1):GND    I52 @T6G_MB_LIB.T6G(SCH_1):PAGE186

PC267_2 Q_CAP_C0805-22UF,16V,20%,X6S,CH6223MEA01
     1 SW_P12V_AUX_PVDDCR_CPU0_P1_FLT @T6G_MB_LIB.T6G(SCH_1):SW_P12V_AUX_PVDDCR_CPU0_P1_FLT    I29 @T6G_MB_LIB.T6G(SCH_1):PAGE186
     2    GND @T6G_MB_LIB.T6G(SCH_1):GND    I29 @T6G_MB_LIB.T6G(SCH_1):PAGE186

PC268_1 Q_CAP_C0805-22UF,16V,20%,X6S,CH6223MEA01
     1 SW_P12V_AUX_PVDDCR_CPU0_P1_FLT @T6G_MB_LIB.T6G(SCH_1):SW_P12V_AUX_PVDDCR_CPU0_P1_FLT    I53 @T6G_MB_LIB.T6G(SCH_1):PAGE186
     2    GND @T6G_MB_LIB.T6G(SCH_1):GND    I53 @T6G_MB_LIB.T6G(SCH_1):PAGE186

PC269_2 Q_CAP_C0805-22UF,16V,20%,X6S,CH6223MEA01
     1 SW_P12V_AUX_PVDDCR_CPU0_P1_FLT @T6G_MB_LIB.T6G(SCH_1):SW_P12V_AUX_PVDDCR_CPU0_P1_FLT    I31 @T6G_MB_LIB.T6G(SCH_1):PAGE186
     2    GND @T6G_MB_LIB.T6G(SCH_1):GND    I31 @T6G_MB_LIB.T6G(SCH_1):PAGE186

PC270 Q_CAP_0402-0.22UF,16V,10%,X7R,CH4223K1B00
     1 SW_PVDDCR_CPU0_P1_BOOT1_RC @T6G_MB_LIB.T6G(SCH_1):SW_PVDDCR_CPU0_P1_BOOT1_RC    I89 @T6G_MB_LIB.T6G(SCH_1):PAGE186
     2 SW_PVDDCR_CPU0_P1_PH1 @T6G_MB_LIB.T6G(SCH_1):SW_PVDDCR_CPU0_P1_PH1    I89 @T6G_MB_LIB.T6G(SCH_1):PAGE186

PC271 Q_CAP_0402-0.22UF,16V,10%,X7R,CH4223K1B00
     1 SW_PVDDCR_CPU0_P1_BOOT2_RC @T6G_MB_LIB.T6G(SCH_1):SW_PVDDCR_CPU0_P1_BOOT2_RC    I55 @T6G_MB_LIB.T6G(SCH_1):PAGE186
     2 SW_PVDDCR_CPU0_P1_PH2 @T6G_MB_LIB.T6G(SCH_1):SW_PVDDCR_CPU0_P1_PH2    I55 @T6G_MB_LIB.T6G(SCH_1):PAGE186

PC272 Q_CAPP_THLF-270UF,16V,20%,OSCON,CC72703MD38
     1 SW_P12V_AUX_PVDDCR_CPU0_P1_FLT @T6G_MB_LIB.T6G(SCH_1):SW_P12V_AUX_PVDDCR_CPU0_P1_FLT    I70 @T6G_MB_LIB.T6G(SCH_1):PAGE186
     2    GND @T6G_MB_LIB.T6G(SCH_1):GND    I70 @T6G_MB_LIB.T6G(SCH_1):PAGE186

PC273 Q_CAPP_THLF-270UF,16V,20%,OSCON,CC72703MD38
     1 SW_P12V_AUX_PVDDCR_CPU0_P1_FLT @T6G_MB_LIB.T6G(SCH_1):SW_P12V_AUX_PVDDCR_CPU0_P1_FLT    I71 @T6G_MB_LIB.T6G(SCH_1):PAGE186
     2    GND @T6G_MB_LIB.T6G(SCH_1):GND    I71 @T6G_MB_LIB.T6G(SCH_1):PAGE186

PC275 Q_CAPP_SMLF-220UF,4V,20%,SPCAP,CH122KM8801
     1 PVDDCR_CPU0_P1 @T6G_MB_LIB.T6G(SCH_1):PVDDCR_CPU0_P1    I58 @T6G_MB_LIB.T6G(SCH_1):PAGE186
     2    GND @T6G_MB_LIB.T6G(SCH_1):GND    I58 @T6G_MB_LIB.T6G(SCH_1):PAGE186

PC276 Q_CAPP_SMLF-220UF,4V,20%,SPCAP,CH122KM8801
     1 PVDDCR_CPU0_P1 @T6G_MB_LIB.T6G(SCH_1):PVDDCR_CPU0_P1    I59 @T6G_MB_LIB.T6G(SCH_1):PAGE186
     2    GND @T6G_MB_LIB.T6G(SCH_1):GND    I59 @T6G_MB_LIB.T6G(SCH_1):PAGE186

PC277 Q_CAPP_SMLF-220UF,4V,20%,SPCAP,CH122KM8801
     1 PVDDCR_CPU0_P1 @T6G_MB_LIB.T6G(SCH_1):PVDDCR_CPU0_P1    I60 @T6G_MB_LIB.T6G(SCH_1):PAGE186
     2    GND @T6G_MB_LIB.T6G(SCH_1):GND    I60 @T6G_MB_LIB.T6G(SCH_1):PAGE186

PC278 Q_CAP_0402-0.1UF,25V,10%,X7R,CH4104K1B00
     1 PVDDCR_CPU0_P1 @T6G_MB_LIB.T6G(SCH_1):PVDDCR_CPU0_P1    I85 @T6G_MB_LIB.T6G(SCH_1):PAGE186
     2    GND @T6G_MB_LIB.T6G(SCH_1):GND    I85 @T6G_MB_LIB.T6G(SCH_1):PAGE186

PC279 Q_CAPP_SMLF-220UF,4V,20%,SPCAP,CH122KM8801
     1 PVDDCR_CPU0_P1 @T6G_MB_LIB.T6G(SCH_1):PVDDCR_CPU0_P1    I66 @T6G_MB_LIB.T6G(SCH_1):PAGE186
     2    GND @T6G_MB_LIB.T6G(SCH_1):GND    I66 @T6G_MB_LIB.T6G(SCH_1):PAGE186

PC280_2 Q_CAP_C0805-22UF,4V,20%,X6S,CH622KMEA03
     1 PVDDCR_CPU0_P1 @T6G_MB_LIB.T6G(SCH_1):PVDDCR_CPU0_P1    I61 @T6G_MB_LIB.T6G(SCH_1):PAGE186
     2    GND @T6G_MB_LIB.T6G(SCH_1):GND    I61 @T6G_MB_LIB.T6G(SCH_1):PAGE186

PC281_1 Q_CAP_C0805-22UF,4V,20%,X6S,CH622KMEA03
     1 PVDDCR_CPU0_P1 @T6G_MB_LIB.T6G(SCH_1):PVDDCR_CPU0_P1    I76 @T6G_MB_LIB.T6G(SCH_1):PAGE186
     2    GND @T6G_MB_LIB.T6G(SCH_1):GND    I76 @T6G_MB_LIB.T6G(SCH_1):PAGE186

PC282_2 Q_CAP_C0805-22UF,4V,20%,X6S,CH622KMEA03
     1 PVDDCR_CPU0_P1 @T6G_MB_LIB.T6G(SCH_1):PVDDCR_CPU0_P1    I63 @T6G_MB_LIB.T6G(SCH_1):PAGE186
     2    GND @T6G_MB_LIB.T6G(SCH_1):GND    I63 @T6G_MB_LIB.T6G(SCH_1):PAGE186

PC283_1 Q_CAP_C0805-22UF,4V,20%,X6S,CH622KMEA03
     1 PVDDCR_CPU0_P1 @T6G_MB_LIB.T6G(SCH_1):PVDDCR_CPU0_P1    I77 @T6G_MB_LIB.T6G(SCH_1):PAGE186
     2    GND @T6G_MB_LIB.T6G(SCH_1):GND    I77 @T6G_MB_LIB.T6G(SCH_1):PAGE186

PC284_3 Q_CAP_0402-0.1UF,25V,10%,X7R,CH4104K1B00
     1 PVDDCR_CPU0_P1_VCCS @T6G_MB_LIB.T6G(SCH_1):PVDDCR_CPU0_P1_VCCS    I28 @T6G_MB_LIB.T6G(SCH_1):PAGE187
     2    GND @T6G_MB_LIB.T6G(SCH_1):GND    I28 @T6G_MB_LIB.T6G(SCH_1):PAGE187

PC285 Q_CAP_C0805-22UF,4V,20%,X6S,CH622KMEA03
     1 PVDD18_S5_P0 @T6G_MB_LIB.T6G(SCH_1):PVDD18_S5_P0    I54 @T6G_MB_LIB.T6G(SCH_1):PAGE184
     2    GND @T6G_MB_LIB.T6G(SCH_1):GND    I54 @T6G_MB_LIB.T6G(SCH_1):PAGE184

PC285_4 Q_CAP_0402-0.1UF,25V,10%,X7R,CH4104K1B00
     1 PVDDCR_CPU0_P1_VCCS @T6G_MB_LIB.T6G(SCH_1):PVDDCR_CPU0_P1_VCCS     I2 @T6G_MB_LIB.T6G(SCH_1):PAGE187
     2    GND @T6G_MB_LIB.T6G(SCH_1):GND     I2 @T6G_MB_LIB.T6G(SCH_1):PAGE187

PC286 Q_CAP_C0402-2.2UF,10V,10%,X6S,CH5222KEB01
     1 PVDDCR_CPU0_P1_VCC3 @T6G_MB_LIB.T6G(SCH_1):PVDDCR_CPU0_P1_VCC3    I37 @T6G_MB_LIB.T6G(SCH_1):PAGE187
     2    GND @T6G_MB_LIB.T6G(SCH_1):GND    I37 @T6G_MB_LIB.T6G(SCH_1):PAGE187

PC287 Q_CAP_C0402-2.2UF,10V,10%,X6S,CH5222KEB01
     1 PVDDCR_CPU0_P1_VCC4 @T6G_MB_LIB.T6G(SCH_1):PVDDCR_CPU0_P1_VCC4     I6 @T6G_MB_LIB.T6G(SCH_1):PAGE187
     2    GND @T6G_MB_LIB.T6G(SCH_1):GND     I6 @T6G_MB_LIB.T6G(SCH_1):PAGE187

PC288 Q_CAP_C0805-22UF,4V,20%,X6S,CH622KMEA03
     1 PVDD18_S5_P0 @T6G_MB_LIB.T6G(SCH_1):PVDD18_S5_P0    I40 @T6G_MB_LIB.T6G(SCH_1):PAGE184
     2    GND @T6G_MB_LIB.T6G(SCH_1):GND    I40 @T6G_MB_LIB.T6G(SCH_1):PAGE184

PC288_C0P1_3 Q_CAP_C0402-2.2UF,10V,10%,X6S,CH5222KEB01
     1 PVDDCR_CPU0_P1_PVCC @T6G_MB_LIB.T6G(SCH_1):PVDDCR_CPU0_P1_PVCC    I41 @T6G_MB_LIB.T6G(SCH_1):PAGE187
     2    GND @T6G_MB_LIB.T6G(SCH_1):GND    I41 @T6G_MB_LIB.T6G(SCH_1):PAGE187

PC289_C0P1_4 Q_CAP_C0402-2.2UF,10V,10%,X6S,CH5222KEB01
     1 PVDDCR_CPU0_P1_PVCC @T6G_MB_LIB.T6G(SCH_1):PVDDCR_CPU0_P1_PVCC    I15 @T6G_MB_LIB.T6G(SCH_1):PAGE187
     2    GND @T6G_MB_LIB.T6G(SCH_1):GND    I15 @T6G_MB_LIB.T6G(SCH_1):PAGE187

PC290_3 Q_CAP_0402-0.1UF,25V,10%,X7R,CH4104K1B00
     1 SW_P12V_AUX_PVDDCR_CPU0_P1_FLT @T6G_MB_LIB.T6G(SCH_1):SW_P12V_AUX_PVDDCR_CPU0_P1_FLT    I44 @T6G_MB_LIB.T6G(SCH_1):PAGE187
     2    GND @T6G_MB_LIB.T6G(SCH_1):GND    I44 @T6G_MB_LIB.T6G(SCH_1):PAGE187

PC291_4 Q_CAP_C0402-1UF,25V,10%,X6S,CH5104KEB02
     1 SW_P12V_AUX_PVDDCR_CPU0_P1_FLT @T6G_MB_LIB.T6G(SCH_1):SW_P12V_AUX_PVDDCR_CPU0_P1_FLT    I23 @T6G_MB_LIB.T6G(SCH_1):PAGE187
     2    GND @T6G_MB_LIB.T6G(SCH_1):GND    I23 @T6G_MB_LIB.T6G(SCH_1):PAGE187

PC292_3 Q_CAP_C0402-1UF,25V,10%,X6S,CH5104KEB02
     1 SW_P12V_AUX_PVDDCR_CPU0_P1_FLT @T6G_MB_LIB.T6G(SCH_1):SW_P12V_AUX_PVDDCR_CPU0_P1_FLT    I48 @T6G_MB_LIB.T6G(SCH_1):PAGE187
     2    GND @T6G_MB_LIB.T6G(SCH_1):GND    I48 @T6G_MB_LIB.T6G(SCH_1):PAGE187

PC293_4 Q_CAP_0402-0.1UF,25V,10%,X7R,CH4104K1B00
     1 SW_P12V_AUX_PVDDCR_CPU0_P1_FLT @T6G_MB_LIB.T6G(SCH_1):SW_P12V_AUX_PVDDCR_CPU0_P1_FLT    I22 @T6G_MB_LIB.T6G(SCH_1):PAGE187
     2    GND @T6G_MB_LIB.T6G(SCH_1):GND    I22 @T6G_MB_LIB.T6G(SCH_1):PAGE187

PC294_3 Q_CAP_C0805-22UF,16V,20%,X6S,CH6223MEA01
     1 SW_P12V_AUX_PVDDCR_CPU0_P1_FLT @T6G_MB_LIB.T6G(SCH_1):SW_P12V_AUX_PVDDCR_CPU0_P1_FLT    I49 @T6G_MB_LIB.T6G(SCH_1):PAGE187
     2    GND @T6G_MB_LIB.T6G(SCH_1):GND    I49 @T6G_MB_LIB.T6G(SCH_1):PAGE187

PC295_4 Q_CAP_C0805-22UF,16V,20%,X6S,CH6223MEA01
     1 SW_P12V_AUX_PVDDCR_CPU0_P1_FLT @T6G_MB_LIB.T6G(SCH_1):SW_P12V_AUX_PVDDCR_CPU0_P1_FLT    I24 @T6G_MB_LIB.T6G(SCH_1):PAGE187
     2    GND @T6G_MB_LIB.T6G(SCH_1):GND    I24 @T6G_MB_LIB.T6G(SCH_1):PAGE187

PC296_3 Q_CAP_C0805-22UF,16V,20%,X6S,CH6223MEA01
     1 SW_P12V_AUX_PVDDCR_CPU0_P1_FLT @T6G_MB_LIB.T6G(SCH_1):SW_P12V_AUX_PVDDCR_CPU0_P1_FLT    I50 @T6G_MB_LIB.T6G(SCH_1):PAGE187
     2    GND @T6G_MB_LIB.T6G(SCH_1):GND    I50 @T6G_MB_LIB.T6G(SCH_1):PAGE187

PC297_4 Q_CAP_C0805-22UF,16V,20%,X6S,CH6223MEA01
     1 SW_P12V_AUX_PVDDCR_CPU0_P1_FLT @T6G_MB_LIB.T6G(SCH_1):SW_P12V_AUX_PVDDCR_CPU0_P1_FLT    I25 @T6G_MB_LIB.T6G(SCH_1):PAGE187
     2    GND @T6G_MB_LIB.T6G(SCH_1):GND    I25 @T6G_MB_LIB.T6G(SCH_1):PAGE187

PC298_3 Q_CAP_C0805-22UF,16V,20%,X6S,CH6223MEA01
     1 SW_P12V_AUX_PVDDCR_CPU0_P1_FLT @T6G_MB_LIB.T6G(SCH_1):SW_P12V_AUX_PVDDCR_CPU0_P1_FLT    I65 @T6G_MB_LIB.T6G(SCH_1):PAGE187
     2    GND @T6G_MB_LIB.T6G(SCH_1):GND    I65 @T6G_MB_LIB.T6G(SCH_1):PAGE187

PC299_4 Q_CAP_C0805-22UF,16V,20%,X6S,CH6223MEA01
     1 SW_P12V_AUX_PVDDCR_CPU0_P1_FLT @T6G_MB_LIB.T6G(SCH_1):SW_P12V_AUX_PVDDCR_CPU0_P1_FLT    I55 @T6G_MB_LIB.T6G(SCH_1):PAGE187
     2    GND @T6G_MB_LIB.T6G(SCH_1):GND    I55 @T6G_MB_LIB.T6G(SCH_1):PAGE187

PC300 Q_CAP_0402-0.22UF,16V,10%,X7R,CH4223K1B00
     1 SW_PVDDCR_CPU0_P1_BOOT3_RC @T6G_MB_LIB.T6G(SCH_1):SW_PVDDCR_CPU0_P1_BOOT3_RC    I63 @T6G_MB_LIB.T6G(SCH_1):PAGE187
     2 SW_PVDDCR_CPU0_P1_PH3 @T6G_MB_LIB.T6G(SCH_1):SW_PVDDCR_CPU0_P1_PH3    I63 @T6G_MB_LIB.T6G(SCH_1):PAGE187

PC301 Q_CAP_0402-0.22UF,16V,10%,X7R,CH4223K1B00
     1 SW_PVDDCR_CPU0_P1_BOOT4_RC @T6G_MB_LIB.T6G(SCH_1):SW_PVDDCR_CPU0_P1_BOOT4_RC    I52 @T6G_MB_LIB.T6G(SCH_1):PAGE187
     2 SW_PVDDCR_CPU0_P1_PH4 @T6G_MB_LIB.T6G(SCH_1):SW_PVDDCR_CPU0_P1_PH4    I52 @T6G_MB_LIB.T6G(SCH_1):PAGE187

PC302_3 Q_CAP_C0805-22UF,4V,20%,X6S,CH622KMEA03
     1 PVDDCR_CPU0_P1 @T6G_MB_LIB.T6G(SCH_1):PVDDCR_CPU0_P1    I69 @T6G_MB_LIB.T6G(SCH_1):PAGE187
     2    GND @T6G_MB_LIB.T6G(SCH_1):GND    I69 @T6G_MB_LIB.T6G(SCH_1):PAGE187

PC303_4 Q_CAP_C0805-22UF,4V,20%,X6S,CH622KMEA03
     1 PVDDCR_CPU0_P1 @T6G_MB_LIB.T6G(SCH_1):PVDDCR_CPU0_P1    I58 @T6G_MB_LIB.T6G(SCH_1):PAGE187
     2    GND @T6G_MB_LIB.T6G(SCH_1):GND    I58 @T6G_MB_LIB.T6G(SCH_1):PAGE187

PC304_3 Q_CAP_C0805-22UF,4V,20%,X6S,CH622KMEA03
     1 PVDDCR_CPU0_P1 @T6G_MB_LIB.T6G(SCH_1):PVDDCR_CPU0_P1    I71 @T6G_MB_LIB.T6G(SCH_1):PAGE187
     2    GND @T6G_MB_LIB.T6G(SCH_1):GND    I71 @T6G_MB_LIB.T6G(SCH_1):PAGE187

PC305_4 Q_CAP_C0805-22UF,4V,20%,X6S,CH622KMEA03
     1 PVDDCR_CPU0_P1 @T6G_MB_LIB.T6G(SCH_1):PVDDCR_CPU0_P1    I60 @T6G_MB_LIB.T6G(SCH_1):PAGE187
     2    GND @T6G_MB_LIB.T6G(SCH_1):GND    I60 @T6G_MB_LIB.T6G(SCH_1):PAGE187

PC306_5 Q_CAP_0402-0.1UF,25V,10%,X7R,CH4104K1B00
     1 PVDDCR_CPU0_P1_VCCS @T6G_MB_LIB.T6G(SCH_1):PVDDCR_CPU0_P1_VCCS    I34 @T6G_MB_LIB.T6G(SCH_1):PAGE188
     2    GND @T6G_MB_LIB.T6G(SCH_1):GND    I34 @T6G_MB_LIB.T6G(SCH_1):PAGE188

PC307 Q_CAP_C0402-2.2UF,10V,10%,X6S,CH5222KEB01
     1 PVDDCR_CPU0_P1_VCC5 @T6G_MB_LIB.T6G(SCH_1):PVDDCR_CPU0_P1_VCC5    I39 @T6G_MB_LIB.T6G(SCH_1):PAGE188
     2    GND @T6G_MB_LIB.T6G(SCH_1):GND    I39 @T6G_MB_LIB.T6G(SCH_1):PAGE188

PC308_C0P1_5 Q_CAP_C0402-2.2UF,10V,10%,X6S,CH5222KEB01
     1 PVDDCR_CPU0_P1_PVCC @T6G_MB_LIB.T6G(SCH_1):PVDDCR_CPU0_P1_PVCC    I43 @T6G_MB_LIB.T6G(SCH_1):PAGE188
     2    GND @T6G_MB_LIB.T6G(SCH_1):GND    I43 @T6G_MB_LIB.T6G(SCH_1):PAGE188

PC309_5 Q_CAP_0402-0.1UF,25V,10%,X7R,CH4104K1B00
     1 SW_P12V_AUX_PVDDCR_CPU0_P1_FLT @T6G_MB_LIB.T6G(SCH_1):SW_P12V_AUX_PVDDCR_CPU0_P1_FLT    I45 @T6G_MB_LIB.T6G(SCH_1):PAGE188
     2    GND @T6G_MB_LIB.T6G(SCH_1):GND    I45 @T6G_MB_LIB.T6G(SCH_1):PAGE188

PC310_5 Q_CAP_C0402-1UF,25V,10%,X6S,CH5104KEB02
     1 SW_P12V_AUX_PVDDCR_CPU0_P1_FLT @T6G_MB_LIB.T6G(SCH_1):SW_P12V_AUX_PVDDCR_CPU0_P1_FLT    I48 @T6G_MB_LIB.T6G(SCH_1):PAGE188
     2    GND @T6G_MB_LIB.T6G(SCH_1):GND    I48 @T6G_MB_LIB.T6G(SCH_1):PAGE188

PC311_5 Q_CAP_C0805-22UF,16V,20%,X6S,CH6223MEA01
     1 SW_P12V_AUX_PVDDCR_CPU0_P1_FLT @T6G_MB_LIB.T6G(SCH_1):SW_P12V_AUX_PVDDCR_CPU0_P1_FLT    I49 @T6G_MB_LIB.T6G(SCH_1):PAGE188
     2    GND @T6G_MB_LIB.T6G(SCH_1):GND    I49 @T6G_MB_LIB.T6G(SCH_1):PAGE188

PC312_5 Q_CAP_C0805-22UF,16V,20%,X6S,CH6223MEA01
     1 SW_P12V_AUX_PVDDCR_CPU0_P1_FLT @T6G_MB_LIB.T6G(SCH_1):SW_P12V_AUX_PVDDCR_CPU0_P1_FLT    I50 @T6G_MB_LIB.T6G(SCH_1):PAGE188
     2    GND @T6G_MB_LIB.T6G(SCH_1):GND    I50 @T6G_MB_LIB.T6G(SCH_1):PAGE188

PC313_5 Q_CAP_C0805-22UF,16V,20%,X6S,CH6223MEA01
     1 SW_P12V_AUX_PVDDCR_CPU0_P1_FLT @T6G_MB_LIB.T6G(SCH_1):SW_P12V_AUX_PVDDCR_CPU0_P1_FLT    I66 @T6G_MB_LIB.T6G(SCH_1):PAGE188
     2    GND @T6G_MB_LIB.T6G(SCH_1):GND    I66 @T6G_MB_LIB.T6G(SCH_1):PAGE188

PC314 Q_CAP_0402-0.22UF,16V,10%,X7R,CH4223K1B00
     1 SW_PVDDCR_CPU0_P1_BOOT5_RC @T6G_MB_LIB.T6G(SCH_1):SW_PVDDCR_CPU0_P1_BOOT5_RC    I63 @T6G_MB_LIB.T6G(SCH_1):PAGE188
     2 SW_PVDDCR_CPU0_P1_PH5 @T6G_MB_LIB.T6G(SCH_1):SW_PVDDCR_CPU0_P1_PH5    I63 @T6G_MB_LIB.T6G(SCH_1):PAGE188

PC315 Q_CAP_C0402-560PF,50V,10%,EMPTY,CH1566K1B09
     1 SW_PVDD11_S3_P1_SW1 @T6G_MB_LIB.T6G(SCH_1):SW_PVDD11_S3_P1_SW1    I46 @T6G_MB_LIB.T6G(SCH_1):PAGE200
     2 SW_PVDD11_S3_P1_SW1_RC @T6G_MB_LIB.T6G(SCH_1):SW_PVDD11_S3_P1_SW1_RC    I46 @T6G_MB_LIB.T6G(SCH_1):PAGE200

PC315_5 Q_CAP_C0805-22UF,4V,20%,X6S,CH622KMEA03
     1 PVDDCR_CPU0_P1 @T6G_MB_LIB.T6G(SCH_1):PVDDCR_CPU0_P1    I69 @T6G_MB_LIB.T6G(SCH_1):PAGE188
     2    GND @T6G_MB_LIB.T6G(SCH_1):GND    I69 @T6G_MB_LIB.T6G(SCH_1):PAGE188

PC316 Q_CAP_C0402-560PF,50V,10%,EMPTY,CH1566K1B09
     1 SW_PVDDCR_CPU0_P1_SW3 @T6G_MB_LIB.T6G(SCH_1):SW_PVDDCR_CPU0_P1_SW3    I46 @T6G_MB_LIB.T6G(SCH_1):PAGE187
     2 SW_PVDDCR_CPU0_P1_SW3_RC @T6G_MB_LIB.T6G(SCH_1):SW_PVDDCR_CPU0_P1_SW3_RC    I46 @T6G_MB_LIB.T6G(SCH_1):PAGE187

PC316_5 Q_CAP_C0805-22UF,4V,20%,X6S,CH622KMEA03
     1 PVDDCR_CPU0_P1 @T6G_MB_LIB.T6G(SCH_1):PVDDCR_CPU0_P1    I71 @T6G_MB_LIB.T6G(SCH_1):PAGE188
     2    GND @T6G_MB_LIB.T6G(SCH_1):GND    I71 @T6G_MB_LIB.T6G(SCH_1):PAGE188

PC317 Q_CAP_C0402-560PF,50V,10%,EMPTY,CH1566K1B09
     1 SW_PVDDCR_CPU0_P1_SW4 @T6G_MB_LIB.T6G(SCH_1):SW_PVDDCR_CPU0_P1_SW4    I20 @T6G_MB_LIB.T6G(SCH_1):PAGE187
     2 SW_PVDDCR_CPU0_P1_SW4_RC @T6G_MB_LIB.T6G(SCH_1):SW_PVDDCR_CPU0_P1_SW4_RC    I20 @T6G_MB_LIB.T6G(SCH_1):PAGE187

PC317_7 Q_CAP_0402-0.1UF,25V,10%,X7R,CH4104K1B00
     1 PVDDCR_CPU0_P1_VCCS @T6G_MB_LIB.T6G(SCH_1):PVDDCR_CPU0_P1_VCCS    I32 @T6G_MB_LIB.T6G(SCH_1):PAGE190
     2    GND @T6G_MB_LIB.T6G(SCH_1):GND    I32 @T6G_MB_LIB.T6G(SCH_1):PAGE190

PC318 Q_CAP_C0402-560PF,50V,10%,EMPTY,CH1566K1B09
     1 SW_PVDDCR_CPU0_P1_SW5 @T6G_MB_LIB.T6G(SCH_1):SW_PVDDCR_CPU0_P1_SW5    I46 @T6G_MB_LIB.T6G(SCH_1):PAGE188
     2 SW_PVDDCR_CPU0_P1_SW5_RC @T6G_MB_LIB.T6G(SCH_1):SW_PVDDCR_CPU0_P1_SW5_RC    I46 @T6G_MB_LIB.T6G(SCH_1):PAGE188

PC318_8 Q_CAP_0402-0.1UF,25V,10%,X7R,CH4104K1B00
     1 PVDDCR_CPU0_P1_VCCS @T6G_MB_LIB.T6G(SCH_1):PVDDCR_CPU0_P1_VCCS     I4 @T6G_MB_LIB.T6G(SCH_1):PAGE190
     2    GND @T6G_MB_LIB.T6G(SCH_1):GND     I4 @T6G_MB_LIB.T6G(SCH_1):PAGE190

PC319 Q_CAP_C0402-2.2UF,10V,10%,X6S,CH5222KEB01
     1 PVDDCR_SOC_P1_VCC1 @T6G_MB_LIB.T6G(SCH_1):PVDDCR_SOC_P1_VCC1    I36 @T6G_MB_LIB.T6G(SCH_1):PAGE190
     2    GND @T6G_MB_LIB.T6G(SCH_1):GND    I36 @T6G_MB_LIB.T6G(SCH_1):PAGE190

PC320 Q_CAP_C0402-2.2UF,10V,10%,X6S,CH5222KEB01
     1 PVDDCR_SOC_P1_VCC2 @T6G_MB_LIB.T6G(SCH_1):PVDDCR_SOC_P1_VCC2    I11 @T6G_MB_LIB.T6G(SCH_1):PAGE190
     2    GND @T6G_MB_LIB.T6G(SCH_1):GND    I11 @T6G_MB_LIB.T6G(SCH_1):PAGE190

PC321 Q_CAP_C0402-560PF,50V,10%,EMPTY,CH1566K1B09
     1 SW_PVDDCR_CPU0_P1_SW6 @T6G_MB_LIB.T6G(SCH_1):SW_PVDDCR_CPU0_P1_SW6    I23 @T6G_MB_LIB.T6G(SCH_1):PAGE188
     2 SW_PVDDCR_CPU0_P1_SW6_RC @T6G_MB_LIB.T6G(SCH_1):SW_PVDDCR_CPU0_P1_SW6_RC    I23 @T6G_MB_LIB.T6G(SCH_1):PAGE188

PC321_SOP1_1 Q_CAP_C0402-2.2UF,10V,10%,X6S,CH5222KEB01
     1 PVDDCR_CPU0_P1_PVCC @T6G_MB_LIB.T6G(SCH_1):PVDDCR_CPU0_P1_PVCC    I41 @T6G_MB_LIB.T6G(SCH_1):PAGE190
     2    GND @T6G_MB_LIB.T6G(SCH_1):GND    I41 @T6G_MB_LIB.T6G(SCH_1):PAGE190

PC322_SOP1_2 Q_CAP_C0402-2.2UF,10V,10%,X6S,CH5222KEB01
     1 PVDDCR_CPU0_P1_PVCC @T6G_MB_LIB.T6G(SCH_1):PVDDCR_CPU0_P1_PVCC    I14 @T6G_MB_LIB.T6G(SCH_1):PAGE190
     2    GND @T6G_MB_LIB.T6G(SCH_1):GND    I14 @T6G_MB_LIB.T6G(SCH_1):PAGE190

PC323_1 Q_CAP_C0402-1UF,25V,10%,X6S,CH5104KEB02
     1 SW_P12V_AUX_PVDDCR_SOC_P1_FLT @T6G_MB_LIB.T6G(SCH_1):SW_P12V_AUX_PVDDCR_SOC_P1_FLT    I44 @T6G_MB_LIB.T6G(SCH_1):PAGE190
     2    GND @T6G_MB_LIB.T6G(SCH_1):GND    I44 @T6G_MB_LIB.T6G(SCH_1):PAGE190

PC324_2 Q_CAP_C0402-1UF,25V,10%,X6S,CH5104KEB02
     1 SW_P12V_AUX_PVDDCR_SOC_P1_FLT @T6G_MB_LIB.T6G(SCH_1):SW_P12V_AUX_PVDDCR_SOC_P1_FLT    I25 @T6G_MB_LIB.T6G(SCH_1):PAGE190
     2    GND @T6G_MB_LIB.T6G(SCH_1):GND    I25 @T6G_MB_LIB.T6G(SCH_1):PAGE190

PC325_1 Q_CAP_0402-0.1UF,25V,10%,X7R,CH4104K1B00
     1 SW_P12V_AUX_PVDDCR_SOC_P1_FLT @T6G_MB_LIB.T6G(SCH_1):SW_P12V_AUX_PVDDCR_SOC_P1_FLT    I43 @T6G_MB_LIB.T6G(SCH_1):PAGE190
     2    GND @T6G_MB_LIB.T6G(SCH_1):GND    I43 @T6G_MB_LIB.T6G(SCH_1):PAGE190

PC326_2 Q_CAP_0402-0.1UF,25V,10%,X7R,CH4104K1B00
     1 SW_P12V_AUX_PVDDCR_SOC_P1_FLT @T6G_MB_LIB.T6G(SCH_1):SW_P12V_AUX_PVDDCR_SOC_P1_FLT    I22 @T6G_MB_LIB.T6G(SCH_1):PAGE190
     2    GND @T6G_MB_LIB.T6G(SCH_1):GND    I22 @T6G_MB_LIB.T6G(SCH_1):PAGE190

PC327_1 Q_CAP_C0805-22UF,16V,20%,X6S,CH6223MEA01
     1 SW_P12V_AUX_PVDDCR_SOC_P1_FLT @T6G_MB_LIB.T6G(SCH_1):SW_P12V_AUX_PVDDCR_SOC_P1_FLT    I48 @T6G_MB_LIB.T6G(SCH_1):PAGE190
     2    GND @T6G_MB_LIB.T6G(SCH_1):GND    I48 @T6G_MB_LIB.T6G(SCH_1):PAGE190

PC328_2 Q_CAP_C0805-22UF,16V,20%,X6S,CH6223MEA01
     1 SW_P12V_AUX_PVDDCR_SOC_P1_FLT @T6G_MB_LIB.T6G(SCH_1):SW_P12V_AUX_PVDDCR_SOC_P1_FLT    I26 @T6G_MB_LIB.T6G(SCH_1):PAGE190
     2    GND @T6G_MB_LIB.T6G(SCH_1):GND    I26 @T6G_MB_LIB.T6G(SCH_1):PAGE190

PC329_1 Q_CAP_C0805-22UF,16V,20%,X6S,CH6223MEA01
     1 SW_P12V_AUX_PVDDCR_SOC_P1_FLT @T6G_MB_LIB.T6G(SCH_1):SW_P12V_AUX_PVDDCR_SOC_P1_FLT    I49 @T6G_MB_LIB.T6G(SCH_1):PAGE190
     2    GND @T6G_MB_LIB.T6G(SCH_1):GND    I49 @T6G_MB_LIB.T6G(SCH_1):PAGE190

PC330_2 Q_CAP_C0805-22UF,16V,20%,X6S,CH6223MEA01
     1 SW_P12V_AUX_PVDDCR_SOC_P1_FLT @T6G_MB_LIB.T6G(SCH_1):SW_P12V_AUX_PVDDCR_SOC_P1_FLT    I27 @T6G_MB_LIB.T6G(SCH_1):PAGE190
     2    GND @T6G_MB_LIB.T6G(SCH_1):GND    I27 @T6G_MB_LIB.T6G(SCH_1):PAGE190

PC331_1 Q_CAP_C0805-22UF,16V,20%,X6S,CH6223MEA01
     1 SW_P12V_AUX_PVDDCR_SOC_P1_FLT @T6G_MB_LIB.T6G(SCH_1):SW_P12V_AUX_PVDDCR_SOC_P1_FLT    I50 @T6G_MB_LIB.T6G(SCH_1):PAGE190
     2    GND @T6G_MB_LIB.T6G(SCH_1):GND    I50 @T6G_MB_LIB.T6G(SCH_1):PAGE190

PC332_2 Q_CAP_C0805-22UF,16V,20%,X6S,CH6223MEA01
     1 SW_P12V_AUX_PVDDCR_SOC_P1_FLT @T6G_MB_LIB.T6G(SCH_1):SW_P12V_AUX_PVDDCR_SOC_P1_FLT    I56 @T6G_MB_LIB.T6G(SCH_1):PAGE190
     2    GND @T6G_MB_LIB.T6G(SCH_1):GND    I56 @T6G_MB_LIB.T6G(SCH_1):PAGE190

PC333 Q_CAP_0402-0.22UF,16V,10%,X7R,CH4223K1B00
     1 SW_PVDDCR_SOC_P1_BOOT1_RC @T6G_MB_LIB.T6G(SCH_1):SW_PVDDCR_SOC_P1_BOOT1_RC    I68 @T6G_MB_LIB.T6G(SCH_1):PAGE190
     2 SW_PVDDCR_SOC_P1_PH1 @T6G_MB_LIB.T6G(SCH_1):SW_PVDDCR_SOC_P1_PH1    I68 @T6G_MB_LIB.T6G(SCH_1):PAGE190

PC334 Q_CAP_0402-0.22UF,16V,10%,X7R,CH4223K1B00
     1 SW_PVDDCR_SOC_P1_BOOT2_RC @T6G_MB_LIB.T6G(SCH_1):SW_PVDDCR_SOC_P1_BOOT2_RC    I54 @T6G_MB_LIB.T6G(SCH_1):PAGE190
     2 SW_PVDDCR_SOC_P1_PH2 @T6G_MB_LIB.T6G(SCH_1):SW_PVDDCR_SOC_P1_PH2    I54 @T6G_MB_LIB.T6G(SCH_1):PAGE190

PC334_1 Q_CAP_C0805-22UF,16V,20%,X6S,CH6223MEA01
     1 SW_P12V_AUX_PVDDCR_SOC_P1_FLT @T6G_MB_LIB.T6G(SCH_1):SW_P12V_AUX_PVDDCR_SOC_P1_FLT    I71 @T6G_MB_LIB.T6G(SCH_1):PAGE190
     2    GND @T6G_MB_LIB.T6G(SCH_1):GND    I71 @T6G_MB_LIB.T6G(SCH_1):PAGE190

PC335_2 Q_CAP_C0805-22UF,16V,20%,X6S,CH6223MEA01
     1 SW_P12V_AUX_PVDDCR_SOC_P1_FLT @T6G_MB_LIB.T6G(SCH_1):SW_P12V_AUX_PVDDCR_SOC_P1_FLT    I57 @T6G_MB_LIB.T6G(SCH_1):PAGE190
     2    GND @T6G_MB_LIB.T6G(SCH_1):GND    I57 @T6G_MB_LIB.T6G(SCH_1):PAGE190

PC336 Q_CAPP_THLF-270UF,16V,20%,OSCON,CC72703MD38
     1 SW_P12V_AUX_PVDDCR_SOC_P1_FLT @T6G_MB_LIB.T6G(SCH_1):SW_P12V_AUX_PVDDCR_SOC_P1_FLT    I73 @T6G_MB_LIB.T6G(SCH_1):PAGE190
     2    GND @T6G_MB_LIB.T6G(SCH_1):GND    I73 @T6G_MB_LIB.T6G(SCH_1):PAGE190

PC337 Q_CAPP_SMLF-470UF,2.5V,20%,SPCAP,CH747LM8825
     1 PVDDCR_SOC_P1 @T6G_MB_LIB.T6G(SCH_1):PVDDCR_SOC_P1    I59 @T6G_MB_LIB.T6G(SCH_1):PAGE190
     2    GND @T6G_MB_LIB.T6G(SCH_1):GND    I59 @T6G_MB_LIB.T6G(SCH_1):PAGE190

PC338 Q_CAP_0402-0.1UF,25V,10%,X7R,CH4104K1B00
     1 PVDDCR_SOC_P1 @T6G_MB_LIB.T6G(SCH_1):PVDDCR_SOC_P1    I79 @T6G_MB_LIB.T6G(SCH_1):PAGE190
     2    GND @T6G_MB_LIB.T6G(SCH_1):GND    I79 @T6G_MB_LIB.T6G(SCH_1):PAGE190

PC339_2 Q_CAP_C0805-22UF,4V,20%,X6S,CH622KMEA03
     1 PVDDCR_SOC_P1 @T6G_MB_LIB.T6G(SCH_1):PVDDCR_SOC_P1    I60 @T6G_MB_LIB.T6G(SCH_1):PAGE190
     2    GND @T6G_MB_LIB.T6G(SCH_1):GND    I60 @T6G_MB_LIB.T6G(SCH_1):PAGE190

PC340 Q_CAPP_SMLF-470UF,2.5V,20%,EMPTY,CH747LM8825
     1 PVDDCR_SOC_P1 @T6G_MB_LIB.T6G(SCH_1):PVDDCR_SOC_P1    I63 @T6G_MB_LIB.T6G(SCH_1):PAGE190
     2    GND @T6G_MB_LIB.T6G(SCH_1):GND    I63 @T6G_MB_LIB.T6G(SCH_1):PAGE190

PC341_1 Q_CAP_C0805-22UF,4V,20%,X6S,CH622KMEA03
     1 PVDDCR_SOC_P1 @T6G_MB_LIB.T6G(SCH_1):PVDDCR_SOC_P1    I80 @T6G_MB_LIB.T6G(SCH_1):PAGE190
     2    GND @T6G_MB_LIB.T6G(SCH_1):GND    I80 @T6G_MB_LIB.T6G(SCH_1):PAGE190

PC342_2 Q_CAP_C0805-22UF,4V,20%,X6S,CH622KMEA03
     1 PVDDCR_SOC_P1 @T6G_MB_LIB.T6G(SCH_1):PVDDCR_SOC_P1    I62 @T6G_MB_LIB.T6G(SCH_1):PAGE190
     2    GND @T6G_MB_LIB.T6G(SCH_1):GND    I62 @T6G_MB_LIB.T6G(SCH_1):PAGE190

PC343 Q_CAPP_SMLF-470UF,2.5V,20%,SPCAP,CH747LM8825
     1 PVDDCR_SOC_P1 @T6G_MB_LIB.T6G(SCH_1):PVDDCR_SOC_P1    I66 @T6G_MB_LIB.T6G(SCH_1):PAGE190
     2    GND @T6G_MB_LIB.T6G(SCH_1):GND    I66 @T6G_MB_LIB.T6G(SCH_1):PAGE190

PC344_1 Q_CAP_C0805-22UF,4V,20%,X6S,CH622KMEA03
     1 PVDDCR_SOC_P1 @T6G_MB_LIB.T6G(SCH_1):PVDDCR_SOC_P1    I81 @T6G_MB_LIB.T6G(SCH_1):PAGE190
     2    GND @T6G_MB_LIB.T6G(SCH_1):GND    I81 @T6G_MB_LIB.T6G(SCH_1):PAGE190

PC345_9 Q_CAP_0402-0.1UF,25V,10%,X7R,CH4104K1B00
     1 PVDDCR_CPU0_P1_VCCS @T6G_MB_LIB.T6G(SCH_1):PVDDCR_CPU0_P1_VCCS     I2 @T6G_MB_LIB.T6G(SCH_1):PAGE191
     2    GND @T6G_MB_LIB.T6G(SCH_1):GND     I2 @T6G_MB_LIB.T6G(SCH_1):PAGE191

PC346 Q_CAP_C0402-2.2UF,10V,10%,X6S,CH5222KEB01
     1 PVDDCR_SOC_P1_VCC3 @T6G_MB_LIB.T6G(SCH_1):PVDDCR_SOC_P1_VCC3    I13 @T6G_MB_LIB.T6G(SCH_1):PAGE191
     2    GND @T6G_MB_LIB.T6G(SCH_1):GND    I13 @T6G_MB_LIB.T6G(SCH_1):PAGE191

PC347_SOP1_3 Q_CAP_C0402-2.2UF,10V,10%,X6S,CH5222KEB01
     1 PVDDCR_CPU0_P1_PVCC @T6G_MB_LIB.T6G(SCH_1):PVDDCR_CPU0_P1_PVCC    I18 @T6G_MB_LIB.T6G(SCH_1):PAGE191
     2    GND @T6G_MB_LIB.T6G(SCH_1):GND    I18 @T6G_MB_LIB.T6G(SCH_1):PAGE191

PC348_3 Q_CAP_0402-0.1UF,25V,10%,X7R,CH4104K1B00
     1 SW_P12V_AUX_PVDDCR_SOC_P1_FLT @T6G_MB_LIB.T6G(SCH_1):SW_P12V_AUX_PVDDCR_SOC_P1_FLT    I19 @T6G_MB_LIB.T6G(SCH_1):PAGE191
     2    GND @T6G_MB_LIB.T6G(SCH_1):GND    I19 @T6G_MB_LIB.T6G(SCH_1):PAGE191

PC349_3 Q_CAP_C0402-1UF,25V,10%,X6S,CH5104KEB02
     1 SW_P12V_AUX_PVDDCR_SOC_P1_FLT @T6G_MB_LIB.T6G(SCH_1):SW_P12V_AUX_PVDDCR_SOC_P1_FLT    I20 @T6G_MB_LIB.T6G(SCH_1):PAGE191
     2    GND @T6G_MB_LIB.T6G(SCH_1):GND    I20 @T6G_MB_LIB.T6G(SCH_1):PAGE191

PC350_3 Q_CAP_C0805-22UF,16V,20%,X6S,CH6223MEA01
     1 SW_P12V_AUX_PVDDCR_SOC_P1_FLT @T6G_MB_LIB.T6G(SCH_1):SW_P12V_AUX_PVDDCR_SOC_P1_FLT    I22 @T6G_MB_LIB.T6G(SCH_1):PAGE191
     2    GND @T6G_MB_LIB.T6G(SCH_1):GND    I22 @T6G_MB_LIB.T6G(SCH_1):PAGE191

PC351_3 Q_CAP_C0805-22UF,16V,20%,X6S,CH6223MEA01
     1 SW_P12V_AUX_PVDDCR_SOC_P1_FLT @T6G_MB_LIB.T6G(SCH_1):SW_P12V_AUX_PVDDCR_SOC_P1_FLT    I31 @T6G_MB_LIB.T6G(SCH_1):PAGE191
     2    GND @T6G_MB_LIB.T6G(SCH_1):GND    I31 @T6G_MB_LIB.T6G(SCH_1):PAGE191

PC352_3 Q_CAP_C0805-22UF,16V,20%,X6S,CH6223MEA01
     1 SW_P12V_AUX_PVDDCR_SOC_P1_FLT @T6G_MB_LIB.T6G(SCH_1):SW_P12V_AUX_PVDDCR_SOC_P1_FLT    I32 @T6G_MB_LIB.T6G(SCH_1):PAGE191
     2    GND @T6G_MB_LIB.T6G(SCH_1):GND    I32 @T6G_MB_LIB.T6G(SCH_1):PAGE191

PC353 Q_CAP_0402-0.22UF,16V,10%,X7R,CH4223K1B00
     1 SW_PVDDCR_SOC_P1_BOOT3_RC @T6G_MB_LIB.T6G(SCH_1):SW_PVDDCR_SOC_P1_BOOT3_RC    I33 @T6G_MB_LIB.T6G(SCH_1):PAGE191
     2 SW_PVDDCR_SOC_P1_PH3 @T6G_MB_LIB.T6G(SCH_1):SW_PVDDCR_SOC_P1_PH3    I33 @T6G_MB_LIB.T6G(SCH_1):PAGE191

PC353_3 Q_CAP_C0805-22UF,16V,20%,X6S,CH6223MEA01
     1 SW_P12V_AUX_PVDDCR_SOC_P1_FLT @T6G_MB_LIB.T6G(SCH_1):SW_P12V_AUX_PVDDCR_SOC_P1_FLT    I34 @T6G_MB_LIB.T6G(SCH_1):PAGE191
     2    GND @T6G_MB_LIB.T6G(SCH_1):GND    I34 @T6G_MB_LIB.T6G(SCH_1):PAGE191

PC354_3 Q_CAP_C0805-22UF,4V,20%,X6S,CH622KMEA03
     1 PVDDCR_SOC_P1 @T6G_MB_LIB.T6G(SCH_1):PVDDCR_SOC_P1    I28 @T6G_MB_LIB.T6G(SCH_1):PAGE191
     2    GND @T6G_MB_LIB.T6G(SCH_1):GND    I28 @T6G_MB_LIB.T6G(SCH_1):PAGE191

PC355_3 Q_CAP_C0805-22UF,4V,20%,X6S,CH622KMEA03
     1 PVDDCR_SOC_P1 @T6G_MB_LIB.T6G(SCH_1):PVDDCR_SOC_P1    I30 @T6G_MB_LIB.T6G(SCH_1):PAGE191
     2    GND @T6G_MB_LIB.T6G(SCH_1):GND    I30 @T6G_MB_LIB.T6G(SCH_1):PAGE191

PC357 Q_CAP_0402-0.1UF,25V,10%,X7R,CH4104K1B00
     1 PVDDCR_CPU1_P1_VMON @T6G_MB_LIB.T6G(SCH_1):PVDDCR_CPU1_P1_VMON    I47 @T6G_MB_LIB.T6G(SCH_1):PAGE192
     2    GND @T6G_MB_LIB.T6G(SCH_1):GND    I47 @T6G_MB_LIB.T6G(SCH_1):PAGE192

PC358 Q_CAP_0402-3300PF,50V,10%,X7R,TMP_QCH2336K1B12
     1 VSENSE_PVDDCR_CPU1_P1_VSEN0 @T6G_MB_LIB.T6G(SCH_1):VSENSE_PVDDCR_CPU1_P1_VSEN0    I79 @T6G_MB_LIB.T6G(SCH_1):PAGE192
     2 VSENSE_VSS_SENSE_C_P1 @T6G_MB_LIB.T6G(SCH_1):VSENSE_VSS_SENSE_C_P1    I79 @T6G_MB_LIB.T6G(SCH_1):PAGE192

PC361 Q_CAP_0402-3300PF,50V,10%,X7R,TMP_QCH2336K1B12
     1 VSENSE_PVDDIO_P1_VSEN1 @T6G_MB_LIB.T6G(SCH_1):VSENSE_PVDDIO_P1_VSEN1    I67 @T6G_MB_LIB.T6G(SCH_1):PAGE192
     2 VSENSE_VSS_SENSE_B_P1 @T6G_MB_LIB.T6G(SCH_1):VSENSE_VSS_SENSE_B_P1    I67 @T6G_MB_LIB.T6G(SCH_1):PAGE192

PC363 Q_CAP_0402-1UF,6.3V,10%,X7R,CH5101K1B01
     1 PVDD18_S5_P1 @T6G_MB_LIB.T6G(SCH_1):PVDD18_S5_P1    I60 @T6G_MB_LIB.T6G(SCH_1):PAGE192
     2    GND @T6G_MB_LIB.T6G(SCH_1):GND    I60 @T6G_MB_LIB.T6G(SCH_1):PAGE192

PC364 Q_CAP_0402-0.1UF,25V,10%,X7R,CH4104K1B00
     1 PVDDCR_CPU1_P1_VINSEN @T6G_MB_LIB.T6G(SCH_1):PVDDCR_CPU1_P1_VINSEN    I56 @T6G_MB_LIB.T6G(SCH_1):PAGE192
     2    GND @T6G_MB_LIB.T6G(SCH_1):GND    I56 @T6G_MB_LIB.T6G(SCH_1):PAGE192

PC365 Q_CAP_C0402-1UF,16V,10%,X6S,CH5103KEB01
     1 PVDDCR_CPU1_P1_VCC @T6G_MB_LIB.T6G(SCH_1):PVDDCR_CPU1_P1_VCC    I99 @T6G_MB_LIB.T6G(SCH_1):PAGE192
     2    GND @T6G_MB_LIB.T6G(SCH_1):GND    I99 @T6G_MB_LIB.T6G(SCH_1):PAGE192

PC366 Q_CAP_C0402-10UF,6.3V,20%,X6S,CH6101MEB03
     1 PVDDCR_CPU1_P1_VCCS @T6G_MB_LIB.T6G(SCH_1):PVDDCR_CPU1_P1_VCCS    I97 @T6G_MB_LIB.T6G(SCH_1):PAGE192
     2    GND @T6G_MB_LIB.T6G(SCH_1):GND    I97 @T6G_MB_LIB.T6G(SCH_1):PAGE192

PC367 Q_CAP_0402-470PF,50V,10%,X7R,TMP_QCH14706KB18
     1 PVDDIO_P1_TEMP1 @T6G_MB_LIB.T6G(SCH_1):PVDDIO_P1_TEMP1    I75 @T6G_MB_LIB.T6G(SCH_1):PAGE192
     2    GND @T6G_MB_LIB.T6G(SCH_1):GND    I75 @T6G_MB_LIB.T6G(SCH_1):PAGE192

PC368 Q_CAP_0402-470PF,50V,10%,X7R,TMP_QCH14706KB18
     1 PVDDCR_CPU1_P1_TEMP0 @T6G_MB_LIB.T6G(SCH_1):PVDDCR_CPU1_P1_TEMP0    I73 @T6G_MB_LIB.T6G(SCH_1):PAGE192
     2    GND @T6G_MB_LIB.T6G(SCH_1):GND    I73 @T6G_MB_LIB.T6G(SCH_1):PAGE192

PC369 Q_CAP_C0402-2.2UF,10V,10%,X6S,CH5222KEB01
     1 PVDDCR_CPU1_P1_VCC1 @T6G_MB_LIB.T6G(SCH_1):PVDDCR_CPU1_P1_VCC1    I23 @T6G_MB_LIB.T6G(SCH_1):PAGE193
     2    GND @T6G_MB_LIB.T6G(SCH_1):GND    I23 @T6G_MB_LIB.T6G(SCH_1):PAGE193

PC370 Q_CAP_C0402-2.2UF,10V,10%,X6S,CH5222KEB01
     1 PVDDCR_CPU1_P1_VCC2 @T6G_MB_LIB.T6G(SCH_1):PVDDCR_CPU1_P1_VCC2    I12 @T6G_MB_LIB.T6G(SCH_1):PAGE193
     2    GND @T6G_MB_LIB.T6G(SCH_1):GND    I12 @T6G_MB_LIB.T6G(SCH_1):PAGE193

PC371_C1P1_1 Q_CAP_C0402-2.2UF,10V,10%,X6S,CH5222KEB01
     1 PVDDCR_CPU1_P1_PVCC @T6G_MB_LIB.T6G(SCH_1):PVDDCR_CPU1_P1_PVCC    I29 @T6G_MB_LIB.T6G(SCH_1):PAGE193
     2    GND @T6G_MB_LIB.T6G(SCH_1):GND    I29 @T6G_MB_LIB.T6G(SCH_1):PAGE193

PC372_C1P1_2 Q_CAP_C0402-2.2UF,10V,10%,X6S,CH5222KEB01
     1 PVDDCR_CPU1_P1_PVCC @T6G_MB_LIB.T6G(SCH_1):PVDDCR_CPU1_P1_PVCC    I15 @T6G_MB_LIB.T6G(SCH_1):PAGE193
     2    GND @T6G_MB_LIB.T6G(SCH_1):GND    I15 @T6G_MB_LIB.T6G(SCH_1):PAGE193

PC373_2 Q_CAP_0402-0.1UF,25V,10%,X7R,CH4104K1B00
     1 PVDDCR_CPU1_P1_VCCS @T6G_MB_LIB.T6G(SCH_1):PVDDCR_CPU1_P1_VCCS     I2 @T6G_MB_LIB.T6G(SCH_1):PAGE193
     2    GND @T6G_MB_LIB.T6G(SCH_1):GND     I2 @T6G_MB_LIB.T6G(SCH_1):PAGE193

PC374_1 Q_CAP_0402-0.1UF,25V,10%,X7R,CH4104K1B00
     1 PVDDCR_CPU1_P1_VCCS @T6G_MB_LIB.T6G(SCH_1):PVDDCR_CPU1_P1_VCCS    I11 @T6G_MB_LIB.T6G(SCH_1):PAGE193
     2    GND @T6G_MB_LIB.T6G(SCH_1):GND    I11 @T6G_MB_LIB.T6G(SCH_1):PAGE193

PC375 Q_CAP_0402-0.1UF,25V,10%,X7R,CH4104K1B00
     1 P12V_AUX @T6G_MB_LIB.T6G(SCH_1):P12V_AUX    I83 @T6G_MB_LIB.T6G(SCH_1):PAGE193
     2    GND @T6G_MB_LIB.T6G(SCH_1):GND    I83 @T6G_MB_LIB.T6G(SCH_1):PAGE193

PC375_1 Q_CAP_0402-0.1UF,25V,10%,X7R,CH4104K1B00
     1 SW_P12V_AUX_PVDDCR_CPU1_P1_FLT @T6G_MB_LIB.T6G(SCH_1):SW_P12V_AUX_PVDDCR_CPU1_P1_FLT    I50 @T6G_MB_LIB.T6G(SCH_1):PAGE193
     2    GND @T6G_MB_LIB.T6G(SCH_1):GND    I50 @T6G_MB_LIB.T6G(SCH_1):PAGE193

PC376_2 Q_CAP_0402-0.1UF,25V,10%,X7R,CH4104K1B00
     1 SW_P12V_AUX_PVDDCR_CPU1_P1_FLT @T6G_MB_LIB.T6G(SCH_1):SW_P12V_AUX_PVDDCR_CPU1_P1_FLT    I34 @T6G_MB_LIB.T6G(SCH_1):PAGE193
     2    GND @T6G_MB_LIB.T6G(SCH_1):GND    I34 @T6G_MB_LIB.T6G(SCH_1):PAGE193

PC377_1 Q_CAP_C0402-1UF,25V,10%,X6S,CH5104KEB02
     1 SW_P12V_AUX_PVDDCR_CPU1_P1_FLT @T6G_MB_LIB.T6G(SCH_1):SW_P12V_AUX_PVDDCR_CPU1_P1_FLT    I53 @T6G_MB_LIB.T6G(SCH_1):PAGE193
     2    GND @T6G_MB_LIB.T6G(SCH_1):GND    I53 @T6G_MB_LIB.T6G(SCH_1):PAGE193

PC378_2 Q_CAP_C0402-1UF,25V,10%,X6S,CH5104KEB02
     1 SW_P12V_AUX_PVDDCR_CPU1_P1_FLT @T6G_MB_LIB.T6G(SCH_1):SW_P12V_AUX_PVDDCR_CPU1_P1_FLT    I42 @T6G_MB_LIB.T6G(SCH_1):PAGE193
     2    GND @T6G_MB_LIB.T6G(SCH_1):GND    I42 @T6G_MB_LIB.T6G(SCH_1):PAGE193

PC379_1 Q_CAP_C0805-22UF,16V,20%,X6S,CH6223MEA01
     1 SW_P12V_AUX_PVDDCR_CPU1_P1_FLT @T6G_MB_LIB.T6G(SCH_1):SW_P12V_AUX_PVDDCR_CPU1_P1_FLT    I54 @T6G_MB_LIB.T6G(SCH_1):PAGE193
     2    GND @T6G_MB_LIB.T6G(SCH_1):GND    I54 @T6G_MB_LIB.T6G(SCH_1):PAGE193

PC380_2 Q_CAP_C0805-22UF,16V,20%,X6S,CH6223MEA01
     1 SW_P12V_AUX_PVDDCR_CPU1_P1_FLT @T6G_MB_LIB.T6G(SCH_1):SW_P12V_AUX_PVDDCR_CPU1_P1_FLT    I43 @T6G_MB_LIB.T6G(SCH_1):PAGE193
     2    GND @T6G_MB_LIB.T6G(SCH_1):GND    I43 @T6G_MB_LIB.T6G(SCH_1):PAGE193

PC381_1 Q_CAP_C0805-22UF,16V,20%,X6S,CH6223MEA01
     1 SW_P12V_AUX_PVDDCR_CPU1_P1_FLT @T6G_MB_LIB.T6G(SCH_1):SW_P12V_AUX_PVDDCR_CPU1_P1_FLT    I58 @T6G_MB_LIB.T6G(SCH_1):PAGE193
     2    GND @T6G_MB_LIB.T6G(SCH_1):GND    I58 @T6G_MB_LIB.T6G(SCH_1):PAGE193

PC382_2 Q_CAP_C0805-22UF,16V,20%,X6S,CH6223MEA01
     1 SW_P12V_AUX_PVDDCR_CPU1_P1_FLT @T6G_MB_LIB.T6G(SCH_1):SW_P12V_AUX_PVDDCR_CPU1_P1_FLT    I46 @T6G_MB_LIB.T6G(SCH_1):PAGE193
     2    GND @T6G_MB_LIB.T6G(SCH_1):GND    I46 @T6G_MB_LIB.T6G(SCH_1):PAGE193

PC383 Q_CAP_0402-0.22UF,16V,10%,X7R,CH4223K1B00
     1 SW_PVDDCR_CPU1_P1_BOOT1_R @T6G_MB_LIB.T6G(SCH_1):SW_PVDDCR_CPU1_P1_BOOT1_R    I57 @T6G_MB_LIB.T6G(SCH_1):PAGE193
     2 SW_PVDDCR_CPU1_P1_BOOTR1 @T6G_MB_LIB.T6G(SCH_1):SW_PVDDCR_CPU1_P1_BOOTR1    I57 @T6G_MB_LIB.T6G(SCH_1):PAGE193

PC384 Q_CAP_0402-3300PF,50V,10%,X7R,TMP_QCH2336K1B12
     1 P1V8_AUX_REF @T6G_MB_LIB.T6G(SCH_1):P1V8_AUX_REF    I21 @T6G_MB_LIB.T6G(SCH_1):PAGE315
     2    GND @T6G_MB_LIB.T6G(SCH_1):GND    I21 @T6G_MB_LIB.T6G(SCH_1):PAGE315

PC384_1 Q_CAP_C0805-22UF,16V,20%,X6S,CH6223MEA01
     1 SW_P12V_AUX_PVDDCR_CPU1_P1_FLT @T6G_MB_LIB.T6G(SCH_1):SW_P12V_AUX_PVDDCR_CPU1_P1_FLT    I60 @T6G_MB_LIB.T6G(SCH_1):PAGE193
     2    GND @T6G_MB_LIB.T6G(SCH_1):GND    I60 @T6G_MB_LIB.T6G(SCH_1):PAGE193

PC385_2 Q_CAP_C0805-22UF,16V,20%,X6S,CH6223MEA01
     1 SW_P12V_AUX_PVDDCR_CPU1_P1_FLT @T6G_MB_LIB.T6G(SCH_1):SW_P12V_AUX_PVDDCR_CPU1_P1_FLT    I48 @T6G_MB_LIB.T6G(SCH_1):PAGE193
     2    GND @T6G_MB_LIB.T6G(SCH_1):GND    I48 @T6G_MB_LIB.T6G(SCH_1):PAGE193

PC386 Q_CAP_0402-0.22UF,16V,10%,X7R,CH4223K1B00
     1 SW_PVDDCR_CPU1_P1_BOOT2_R @T6G_MB_LIB.T6G(SCH_1):SW_PVDDCR_CPU1_P1_BOOT2_R    I40 @T6G_MB_LIB.T6G(SCH_1):PAGE193
     2 SW_PVDDCR_CPU1_P1_BOOTR2 @T6G_MB_LIB.T6G(SCH_1):SW_PVDDCR_CPU1_P1_BOOTR2    I40 @T6G_MB_LIB.T6G(SCH_1):PAGE193

PC387 Q_CAPP_SMLF-220UF,4V,20%,SPCAP,CH122KM8801
     1 PVDDCR_CPU1_P1 @T6G_MB_LIB.T6G(SCH_1):PVDDCR_CPU1_P1    I66 @T6G_MB_LIB.T6G(SCH_1):PAGE193
     2    GND @T6G_MB_LIB.T6G(SCH_1):GND    I66 @T6G_MB_LIB.T6G(SCH_1):PAGE193

PC388 Q_CAPP_SMLF-220UF,4V,20%,SPCAP,CH122KM8801
     1 PVDDCR_CPU1_P1 @T6G_MB_LIB.T6G(SCH_1):PVDDCR_CPU1_P1    I67 @T6G_MB_LIB.T6G(SCH_1):PAGE193
     2    GND @T6G_MB_LIB.T6G(SCH_1):GND    I67 @T6G_MB_LIB.T6G(SCH_1):PAGE193

PC389 Q_CAPP_SMLF-220UF,4V,20%,SPCAP,CH122KM8801
     1 PVDDCR_CPU1_P1 @T6G_MB_LIB.T6G(SCH_1):PVDDCR_CPU1_P1    I73 @T6G_MB_LIB.T6G(SCH_1):PAGE193
     2    GND @T6G_MB_LIB.T6G(SCH_1):GND    I73 @T6G_MB_LIB.T6G(SCH_1):PAGE193

PC390 Q_CAPP_SMLF-270UF,16V,20%,OSCON,CC72703MZ11
     1 SW_P12V_AUX_PVDDCR_CPU1_P1_FLT @T6G_MB_LIB.T6G(SCH_1):SW_P12V_AUX_PVDDCR_CPU1_P1_FLT    I93 @T6G_MB_LIB.T6G(SCH_1):PAGE193
     2    GND @T6G_MB_LIB.T6G(SCH_1):GND    I93 @T6G_MB_LIB.T6G(SCH_1):PAGE193

PC391 Q_CAPP_SMLF-220UF,4V,20%,SPCAP,CH122KM8801
     1 PVDDCR_CPU1_P1 @T6G_MB_LIB.T6G(SCH_1):PVDDCR_CPU1_P1    I74 @T6G_MB_LIB.T6G(SCH_1):PAGE193
     2    GND @T6G_MB_LIB.T6G(SCH_1):GND    I74 @T6G_MB_LIB.T6G(SCH_1):PAGE193

PC392 Q_CAP_0402-0.1UF,25V,10%,X7R,CH4104K1B00
     1 PVDDCR_CPU1_P1 @T6G_MB_LIB.T6G(SCH_1):PVDDCR_CPU1_P1    I82 @T6G_MB_LIB.T6G(SCH_1):PAGE193
     2    GND @T6G_MB_LIB.T6G(SCH_1):GND    I82 @T6G_MB_LIB.T6G(SCH_1):PAGE193

PC393 Q_CAPP_SMLF-270UF,16V,20%,OSCON,CC72703MZ11
     1 SW_P12V_AUX_PVDDCR_CPU1_P1_FLT @T6G_MB_LIB.T6G(SCH_1):SW_P12V_AUX_PVDDCR_CPU1_P1_FLT    I92 @T6G_MB_LIB.T6G(SCH_1):PAGE193
     2    GND @T6G_MB_LIB.T6G(SCH_1):GND    I92 @T6G_MB_LIB.T6G(SCH_1):PAGE193

PC394_2 Q_CAP_C0805-22UF,4V,20%,X6S,CH622KMEA03
     1 PVDDCR_CPU1_P1 @T6G_MB_LIB.T6G(SCH_1):PVDDCR_CPU1_P1    I68 @T6G_MB_LIB.T6G(SCH_1):PAGE193
     2    GND @T6G_MB_LIB.T6G(SCH_1):GND    I68 @T6G_MB_LIB.T6G(SCH_1):PAGE193

PC395_1 Q_CAP_C0805-22UF,4V,20%,X6S,CH622KMEA03
     1 PVDDCR_CPU1_P1 @T6G_MB_LIB.T6G(SCH_1):PVDDCR_CPU1_P1    I85 @T6G_MB_LIB.T6G(SCH_1):PAGE193
     2    GND @T6G_MB_LIB.T6G(SCH_1):GND    I85 @T6G_MB_LIB.T6G(SCH_1):PAGE193

PC397_2 Q_CAP_C0805-22UF,4V,20%,X6S,CH622KMEA03
     1 PVDDCR_CPU1_P1 @T6G_MB_LIB.T6G(SCH_1):PVDDCR_CPU1_P1    I70 @T6G_MB_LIB.T6G(SCH_1):PAGE193
     2    GND @T6G_MB_LIB.T6G(SCH_1):GND    I70 @T6G_MB_LIB.T6G(SCH_1):PAGE193

PC398_1 Q_CAP_C0805-22UF,4V,20%,X6S,CH622KMEA03
     1 PVDDCR_CPU1_P1 @T6G_MB_LIB.T6G(SCH_1):PVDDCR_CPU1_P1    I86 @T6G_MB_LIB.T6G(SCH_1):PAGE193
     2    GND @T6G_MB_LIB.T6G(SCH_1):GND    I86 @T6G_MB_LIB.T6G(SCH_1):PAGE193

PC399 Q_CAP_C0402-2.2UF,10V,10%,X6S,CH5222KEB01
     1 PVDDCR_CPU1_P1_VCC4 @T6G_MB_LIB.T6G(SCH_1):PVDDCR_CPU1_P1_VCC4     I7 @T6G_MB_LIB.T6G(SCH_1):PAGE194
     2    GND @T6G_MB_LIB.T6G(SCH_1):GND     I7 @T6G_MB_LIB.T6G(SCH_1):PAGE194

PC400 Q_CAP_C0402-2.2UF,10V,10%,X6S,CH5222KEB01
     1 PVDDCR_CPU1_P1_VCC3 @T6G_MB_LIB.T6G(SCH_1):PVDDCR_CPU1_P1_VCC3    I27 @T6G_MB_LIB.T6G(SCH_1):PAGE194
     2    GND @T6G_MB_LIB.T6G(SCH_1):GND    I27 @T6G_MB_LIB.T6G(SCH_1):PAGE194

PC401_C1P1_4 Q_CAP_C0402-2.2UF,10V,10%,X6S,CH5222KEB01
     1 PVDDCR_CPU1_P1_PVCC @T6G_MB_LIB.T6G(SCH_1):PVDDCR_CPU1_P1_PVCC    I16 @T6G_MB_LIB.T6G(SCH_1):PAGE194
     2    GND @T6G_MB_LIB.T6G(SCH_1):GND    I16 @T6G_MB_LIB.T6G(SCH_1):PAGE194

PC402_C1P1_3 Q_CAP_C0402-2.2UF,10V,10%,X6S,CH5222KEB01
     1 PVDDCR_CPU1_P1_PVCC @T6G_MB_LIB.T6G(SCH_1):PVDDCR_CPU1_P1_PVCC    I31 @T6G_MB_LIB.T6G(SCH_1):PAGE194
     2    GND @T6G_MB_LIB.T6G(SCH_1):GND    I31 @T6G_MB_LIB.T6G(SCH_1):PAGE194

PC403_4 Q_CAP_0402-0.1UF,25V,10%,X7R,CH4104K1B00
     1 PVDDCR_CPU1_P1_VCCS @T6G_MB_LIB.T6G(SCH_1):PVDDCR_CPU1_P1_VCCS     I2 @T6G_MB_LIB.T6G(SCH_1):PAGE194
     2    GND @T6G_MB_LIB.T6G(SCH_1):GND     I2 @T6G_MB_LIB.T6G(SCH_1):PAGE194

PC404_3 Q_CAP_0402-0.1UF,25V,10%,X7R,CH4104K1B00
     1 PVDDCR_CPU1_P1_VCCS @T6G_MB_LIB.T6G(SCH_1):PVDDCR_CPU1_P1_VCCS    I12 @T6G_MB_LIB.T6G(SCH_1):PAGE194
     2    GND @T6G_MB_LIB.T6G(SCH_1):GND    I12 @T6G_MB_LIB.T6G(SCH_1):PAGE194

PC405_4 Q_CAP_0402-0.1UF,25V,10%,X7R,CH4104K1B00
     1 SW_P12V_AUX_PVDDCR_CPU1_P1_FLT @T6G_MB_LIB.T6G(SCH_1):SW_P12V_AUX_PVDDCR_CPU1_P1_FLT    I23 @T6G_MB_LIB.T6G(SCH_1):PAGE194
     2    GND @T6G_MB_LIB.T6G(SCH_1):GND    I23 @T6G_MB_LIB.T6G(SCH_1):PAGE194

PC406_3 Q_CAP_C0402-1UF,25V,10%,X6S,CH5104KEB02
     1 SW_P12V_AUX_PVDDCR_CPU1_P1_FLT @T6G_MB_LIB.T6G(SCH_1):SW_P12V_AUX_PVDDCR_CPU1_P1_FLT    I54 @T6G_MB_LIB.T6G(SCH_1):PAGE194
     2    GND @T6G_MB_LIB.T6G(SCH_1):GND    I54 @T6G_MB_LIB.T6G(SCH_1):PAGE194

PC407_4 Q_CAP_C0402-1UF,25V,10%,X6S,CH5104KEB02
     1 SW_P12V_AUX_PVDDCR_CPU1_P1_FLT @T6G_MB_LIB.T6G(SCH_1):SW_P12V_AUX_PVDDCR_CPU1_P1_FLT    I41 @T6G_MB_LIB.T6G(SCH_1):PAGE194
     2    GND @T6G_MB_LIB.T6G(SCH_1):GND    I41 @T6G_MB_LIB.T6G(SCH_1):PAGE194

PC408_3 Q_CAP_0402-0.1UF,25V,10%,X7R,CH4104K1B00
     1 SW_P12V_AUX_PVDDCR_CPU1_P1_FLT @T6G_MB_LIB.T6G(SCH_1):SW_P12V_AUX_PVDDCR_CPU1_P1_FLT    I33 @T6G_MB_LIB.T6G(SCH_1):PAGE194
     2    GND @T6G_MB_LIB.T6G(SCH_1):GND    I33 @T6G_MB_LIB.T6G(SCH_1):PAGE194

PC409_4 Q_CAP_C0805-22UF,16V,20%,X6S,CH6223MEA01
     1 SW_P12V_AUX_PVDDCR_CPU1_P1_FLT @T6G_MB_LIB.T6G(SCH_1):SW_P12V_AUX_PVDDCR_CPU1_P1_FLT    I42 @T6G_MB_LIB.T6G(SCH_1):PAGE194
     2    GND @T6G_MB_LIB.T6G(SCH_1):GND    I42 @T6G_MB_LIB.T6G(SCH_1):PAGE194

PC410_3 Q_CAP_C0805-22UF,16V,20%,X6S,CH6223MEA01
     1 SW_P12V_AUX_PVDDCR_CPU1_P1_FLT @T6G_MB_LIB.T6G(SCH_1):SW_P12V_AUX_PVDDCR_CPU1_P1_FLT    I55 @T6G_MB_LIB.T6G(SCH_1):PAGE194
     2    GND @T6G_MB_LIB.T6G(SCH_1):GND    I55 @T6G_MB_LIB.T6G(SCH_1):PAGE194

PC411_4 Q_CAP_C0805-22UF,16V,20%,X6S,CH6223MEA01
     1 SW_P12V_AUX_PVDDCR_CPU1_P1_FLT @T6G_MB_LIB.T6G(SCH_1):SW_P12V_AUX_PVDDCR_CPU1_P1_FLT    I45 @T6G_MB_LIB.T6G(SCH_1):PAGE194
     2    GND @T6G_MB_LIB.T6G(SCH_1):GND    I45 @T6G_MB_LIB.T6G(SCH_1):PAGE194

PC412_3 Q_CAP_C0805-22UF,16V,20%,X6S,CH6223MEA01
     1 SW_P12V_AUX_PVDDCR_CPU1_P1_FLT @T6G_MB_LIB.T6G(SCH_1):SW_P12V_AUX_PVDDCR_CPU1_P1_FLT    I59 @T6G_MB_LIB.T6G(SCH_1):PAGE194
     2    GND @T6G_MB_LIB.T6G(SCH_1):GND    I59 @T6G_MB_LIB.T6G(SCH_1):PAGE194

PC413 Q_CAP_0402-0.22UF,16V,10%,X7R,CH4223K1B00
     1 SW_PVDDCR_CPU1_P1_BOOT4_R @T6G_MB_LIB.T6G(SCH_1):SW_PVDDCR_CPU1_P1_BOOT4_R    I40 @T6G_MB_LIB.T6G(SCH_1):PAGE194
     2 SW_PVDDCR_CPU1_P1_BOOTR4 @T6G_MB_LIB.T6G(SCH_1):SW_PVDDCR_CPU1_P1_BOOTR4    I40 @T6G_MB_LIB.T6G(SCH_1):PAGE194

PC414 Q_CAP_0402-0.22UF,16V,10%,X7R,CH4223K1B00
     1 SW_PVDDCR_CPU1_P1_BOOT3_R @T6G_MB_LIB.T6G(SCH_1):SW_PVDDCR_CPU1_P1_BOOT3_R    I57 @T6G_MB_LIB.T6G(SCH_1):PAGE194
     2 SW_PVDDCR_CPU1_P1_BOOTR3 @T6G_MB_LIB.T6G(SCH_1):SW_PVDDCR_CPU1_P1_BOOTR3    I57 @T6G_MB_LIB.T6G(SCH_1):PAGE194

PC415_4 Q_CAP_C0805-22UF,16V,20%,X6S,CH6223MEA01
     1 SW_P12V_AUX_PVDDCR_CPU1_P1_FLT @T6G_MB_LIB.T6G(SCH_1):SW_P12V_AUX_PVDDCR_CPU1_P1_FLT    I47 @T6G_MB_LIB.T6G(SCH_1):PAGE194
     2    GND @T6G_MB_LIB.T6G(SCH_1):GND    I47 @T6G_MB_LIB.T6G(SCH_1):PAGE194

PC416_3 Q_CAP_C0805-22UF,16V,20%,X6S,CH6223MEA01
     1 SW_P12V_AUX_PVDDCR_CPU1_P1_FLT @T6G_MB_LIB.T6G(SCH_1):SW_P12V_AUX_PVDDCR_CPU1_P1_FLT    I60 @T6G_MB_LIB.T6G(SCH_1):PAGE194
     2    GND @T6G_MB_LIB.T6G(SCH_1):GND    I60 @T6G_MB_LIB.T6G(SCH_1):PAGE194

PC417_3 Q_CAP_C0805-22UF,4V,20%,X6S,CH622KMEA03
     1 PVDDCR_CPU1_P1 @T6G_MB_LIB.T6G(SCH_1):PVDDCR_CPU1_P1    I64 @T6G_MB_LIB.T6G(SCH_1):PAGE194
     2    GND @T6G_MB_LIB.T6G(SCH_1):GND    I64 @T6G_MB_LIB.T6G(SCH_1):PAGE194

PC418_4 Q_CAP_C0805-22UF,4V,20%,X6S,CH622KMEA03
     1 PVDDCR_CPU1_P1 @T6G_MB_LIB.T6G(SCH_1):PVDDCR_CPU1_P1    I65 @T6G_MB_LIB.T6G(SCH_1):PAGE194
     2    GND @T6G_MB_LIB.T6G(SCH_1):GND    I65 @T6G_MB_LIB.T6G(SCH_1):PAGE194

PC419_3 Q_CAP_C0805-22UF,4V,20%,X6S,CH622KMEA03
     1 PVDDCR_CPU1_P1 @T6G_MB_LIB.T6G(SCH_1):PVDDCR_CPU1_P1    I70 @T6G_MB_LIB.T6G(SCH_1):PAGE194
     2    GND @T6G_MB_LIB.T6G(SCH_1):GND    I70 @T6G_MB_LIB.T6G(SCH_1):PAGE194

PC420_4 Q_CAP_C0805-22UF,4V,20%,X6S,CH622KMEA03
     1 PVDDCR_CPU1_P1 @T6G_MB_LIB.T6G(SCH_1):PVDDCR_CPU1_P1    I67 @T6G_MB_LIB.T6G(SCH_1):PAGE194
     2    GND @T6G_MB_LIB.T6G(SCH_1):GND    I67 @T6G_MB_LIB.T6G(SCH_1):PAGE194

PC421 Q_CAP_C0402-2.2UF,10V,10%,X6S,CH5222KEB01
     1 PVDDCR_CPU1_P1_VCC5 @T6G_MB_LIB.T6G(SCH_1):PVDDCR_CPU1_P1_VCC5    I27 @T6G_MB_LIB.T6G(SCH_1):PAGE195
     2    GND @T6G_MB_LIB.T6G(SCH_1):GND    I27 @T6G_MB_LIB.T6G(SCH_1):PAGE195

PC422_5 Q_CAP_0402-0.1UF,25V,10%,X7R,CH4104K1B00
     1 PVDDCR_CPU1_P1_VCCS @T6G_MB_LIB.T6G(SCH_1):PVDDCR_CPU1_P1_VCCS    I10 @T6G_MB_LIB.T6G(SCH_1):PAGE195
     2    GND @T6G_MB_LIB.T6G(SCH_1):GND    I10 @T6G_MB_LIB.T6G(SCH_1):PAGE195

PC423_C1P1_5 Q_CAP_C0402-2.2UF,10V,10%,X6S,CH5222KEB01
     1 PVDDCR_CPU1_P1_PVCC @T6G_MB_LIB.T6G(SCH_1):PVDDCR_CPU1_P1_PVCC    I31 @T6G_MB_LIB.T6G(SCH_1):PAGE195
     2    GND @T6G_MB_LIB.T6G(SCH_1):GND    I31 @T6G_MB_LIB.T6G(SCH_1):PAGE195

PC424_5 Q_CAP_C0402-1UF,25V,10%,X6S,CH5104KEB02
     1 SW_P12V_AUX_PVDDCR_CPU1_P1_FLT @T6G_MB_LIB.T6G(SCH_1):SW_P12V_AUX_PVDDCR_CPU1_P1_FLT    I55 @T6G_MB_LIB.T6G(SCH_1):PAGE195
     2    GND @T6G_MB_LIB.T6G(SCH_1):GND    I55 @T6G_MB_LIB.T6G(SCH_1):PAGE195

PC425_5 Q_CAP_0402-0.1UF,25V,10%,X7R,CH4104K1B00
     1 SW_P12V_AUX_PVDDCR_CPU1_P1_FLT @T6G_MB_LIB.T6G(SCH_1):SW_P12V_AUX_PVDDCR_CPU1_P1_FLT    I54 @T6G_MB_LIB.T6G(SCH_1):PAGE195
     2    GND @T6G_MB_LIB.T6G(SCH_1):GND    I54 @T6G_MB_LIB.T6G(SCH_1):PAGE195

PC426_5 Q_CAP_C0805-22UF,16V,20%,X6S,CH6223MEA01
     1 SW_P12V_AUX_PVDDCR_CPU1_P1_FLT @T6G_MB_LIB.T6G(SCH_1):SW_P12V_AUX_PVDDCR_CPU1_P1_FLT    I56 @T6G_MB_LIB.T6G(SCH_1):PAGE195
     2    GND @T6G_MB_LIB.T6G(SCH_1):GND    I56 @T6G_MB_LIB.T6G(SCH_1):PAGE195

PC427_5 Q_CAP_C0805-22UF,16V,20%,X6S,CH6223MEA01
     1 SW_P12V_AUX_PVDDCR_CPU1_P1_FLT @T6G_MB_LIB.T6G(SCH_1):SW_P12V_AUX_PVDDCR_CPU1_P1_FLT    I60 @T6G_MB_LIB.T6G(SCH_1):PAGE195
     2    GND @T6G_MB_LIB.T6G(SCH_1):GND    I60 @T6G_MB_LIB.T6G(SCH_1):PAGE195

PC428 Q_CAP_0402-0.22UF,16V,10%,X7R,CH4223K1B00
     1 SW_PVDDCR_CPU1_P1_BOOT5_R @T6G_MB_LIB.T6G(SCH_1):SW_PVDDCR_CPU1_P1_BOOT5_R    I57 @T6G_MB_LIB.T6G(SCH_1):PAGE195
     2 SW_PVDDCR_CPU1_P1_BOOTR5 @T6G_MB_LIB.T6G(SCH_1):SW_PVDDCR_CPU1_P1_BOOTR5    I57 @T6G_MB_LIB.T6G(SCH_1):PAGE195

PC429_5 Q_CAP_C0805-22UF,16V,20%,X6S,CH6223MEA01
     1 SW_P12V_AUX_PVDDCR_CPU1_P1_FLT @T6G_MB_LIB.T6G(SCH_1):SW_P12V_AUX_PVDDCR_CPU1_P1_FLT    I61 @T6G_MB_LIB.T6G(SCH_1):PAGE195
     2    GND @T6G_MB_LIB.T6G(SCH_1):GND    I61 @T6G_MB_LIB.T6G(SCH_1):PAGE195

PC430_5 Q_CAP_C0805-22UF,4V,20%,X6S,CH622KMEA03
     1 PVDDCR_CPU1_P1 @T6G_MB_LIB.T6G(SCH_1):PVDDCR_CPU1_P1    I70 @T6G_MB_LIB.T6G(SCH_1):PAGE195
     2    GND @T6G_MB_LIB.T6G(SCH_1):GND    I70 @T6G_MB_LIB.T6G(SCH_1):PAGE195

PC431_5 Q_CAP_C0805-22UF,4V,20%,X6S,CH622KMEA03
     1 PVDDCR_CPU1_P1 @T6G_MB_LIB.T6G(SCH_1):PVDDCR_CPU1_P1    I71 @T6G_MB_LIB.T6G(SCH_1):PAGE195
     2    GND @T6G_MB_LIB.T6G(SCH_1):GND    I71 @T6G_MB_LIB.T6G(SCH_1):PAGE195

PC432 Q_CAP_C0402-2.2UF,10V,10%,X6S,CH5222KEB01
     1 PVDDIO_P1_VCC2 @T6G_MB_LIB.T6G(SCH_1):PVDDIO_P1_VCC2    I12 @T6G_MB_LIB.T6G(SCH_1):PAGE197
     2    GND @T6G_MB_LIB.T6G(SCH_1):GND    I12 @T6G_MB_LIB.T6G(SCH_1):PAGE197

PC433 Q_CAP_C0402-2.2UF,10V,10%,X6S,CH5222KEB01
     1 PVDDIO_P1_VCC1 @T6G_MB_LIB.T6G(SCH_1):PVDDIO_P1_VCC1    I34 @T6G_MB_LIB.T6G(SCH_1):PAGE197
     2    GND @T6G_MB_LIB.T6G(SCH_1):GND    I34 @T6G_MB_LIB.T6G(SCH_1):PAGE197

PC434_IOP1_2 Q_CAP_C0402-2.2UF,10V,10%,X6S,CH5222KEB01
     1 PVDDCR_CPU1_P1_PVCC @T6G_MB_LIB.T6G(SCH_1):PVDDCR_CPU1_P1_PVCC    I16 @T6G_MB_LIB.T6G(SCH_1):PAGE197
     2    GND @T6G_MB_LIB.T6G(SCH_1):GND    I16 @T6G_MB_LIB.T6G(SCH_1):PAGE197

PC435_7 Q_CAP_0402-0.1UF,25V,10%,X7R,CH4104K1B00
     1 PVDDCR_CPU1_P1_VCCS @T6G_MB_LIB.T6G(SCH_1):PVDDCR_CPU1_P1_VCCS     I4 @T6G_MB_LIB.T6G(SCH_1):PAGE197
     2    GND @T6G_MB_LIB.T6G(SCH_1):GND     I4 @T6G_MB_LIB.T6G(SCH_1):PAGE197

PC436_8 Q_CAP_0402-0.1UF,25V,10%,X7R,CH4104K1B00
     1 PVDDCR_CPU1_P1_VCCS @T6G_MB_LIB.T6G(SCH_1):PVDDCR_CPU1_P1_VCCS     I3 @T6G_MB_LIB.T6G(SCH_1):PAGE197
     2    GND @T6G_MB_LIB.T6G(SCH_1):GND     I3 @T6G_MB_LIB.T6G(SCH_1):PAGE197

PC437_IOP1_1 Q_CAP_C0402-2.2UF,10V,10%,X6S,CH5222KEB01
     1 PVDDCR_CPU1_P1_PVCC @T6G_MB_LIB.T6G(SCH_1):PVDDCR_CPU1_P1_PVCC    I38 @T6G_MB_LIB.T6G(SCH_1):PAGE197
     2    GND @T6G_MB_LIB.T6G(SCH_1):GND    I38 @T6G_MB_LIB.T6G(SCH_1):PAGE197

PC438 Q_CAP_0402-0.1UF,25V,10%,X7R,CH4104K1B00
     1 P12V_AUX @T6G_MB_LIB.T6G(SCH_1):P12V_AUX    I74 @T6G_MB_LIB.T6G(SCH_1):PAGE197
     2    GND @T6G_MB_LIB.T6G(SCH_1):GND    I74 @T6G_MB_LIB.T6G(SCH_1):PAGE197

PC438_1 Q_CAP_0402-0.1UF,25V,10%,X7R,CH4104K1B00
     1 SW_P12V_AUX_PVDDIO_P1_FLT @T6G_MB_LIB.T6G(SCH_1):SW_P12V_AUX_PVDDIO_P1_FLT    I41 @T6G_MB_LIB.T6G(SCH_1):PAGE197
     2    GND @T6G_MB_LIB.T6G(SCH_1):GND    I41 @T6G_MB_LIB.T6G(SCH_1):PAGE197

PC439_2 Q_CAP_0402-0.1UF,25V,10%,X7R,CH4104K1B00
     1 SW_P12V_AUX_PVDDIO_P1_FLT @T6G_MB_LIB.T6G(SCH_1):SW_P12V_AUX_PVDDIO_P1_FLT    I21 @T6G_MB_LIB.T6G(SCH_1):PAGE197
     2    GND @T6G_MB_LIB.T6G(SCH_1):GND    I21 @T6G_MB_LIB.T6G(SCH_1):PAGE197

PC440_1 Q_CAP_C0402-1UF,25V,10%,X6S,CH5104KEB02
     1 SW_P12V_AUX_PVDDIO_P1_FLT @T6G_MB_LIB.T6G(SCH_1):SW_P12V_AUX_PVDDIO_P1_FLT    I42 @T6G_MB_LIB.T6G(SCH_1):PAGE197
     2    GND @T6G_MB_LIB.T6G(SCH_1):GND    I42 @T6G_MB_LIB.T6G(SCH_1):PAGE197

PC441_2 Q_CAP_C0402-1UF,25V,10%,X6S,CH5104KEB02
     1 SW_P12V_AUX_PVDDIO_P1_FLT @T6G_MB_LIB.T6G(SCH_1):SW_P12V_AUX_PVDDIO_P1_FLT    I23 @T6G_MB_LIB.T6G(SCH_1):PAGE197
     2    GND @T6G_MB_LIB.T6G(SCH_1):GND    I23 @T6G_MB_LIB.T6G(SCH_1):PAGE197

PC442_1 Q_CAP_C0805-22UF,16V,20%,X6S,CH6223MEA01
     1 SW_P12V_AUX_PVDDIO_P1_FLT @T6G_MB_LIB.T6G(SCH_1):SW_P12V_AUX_PVDDIO_P1_FLT    I44 @T6G_MB_LIB.T6G(SCH_1):PAGE197
     2    GND @T6G_MB_LIB.T6G(SCH_1):GND    I44 @T6G_MB_LIB.T6G(SCH_1):PAGE197

PC443_2 Q_CAP_C0805-22UF,16V,20%,X6S,CH6223MEA01
     1 SW_P12V_AUX_PVDDIO_P1_FLT @T6G_MB_LIB.T6G(SCH_1):SW_P12V_AUX_PVDDIO_P1_FLT    I48 @T6G_MB_LIB.T6G(SCH_1):PAGE197
     2    GND @T6G_MB_LIB.T6G(SCH_1):GND    I48 @T6G_MB_LIB.T6G(SCH_1):PAGE197

PC444_1 Q_CAP_C0805-22UF,16V,20%,X6S,CH6223MEA01
     1 SW_P12V_AUX_PVDDIO_P1_FLT @T6G_MB_LIB.T6G(SCH_1):SW_P12V_AUX_PVDDIO_P1_FLT    I66 @T6G_MB_LIB.T6G(SCH_1):PAGE197
     2    GND @T6G_MB_LIB.T6G(SCH_1):GND    I66 @T6G_MB_LIB.T6G(SCH_1):PAGE197

PC445 Q_CAP_0402-0.22UF,16V,10%,X7R,CH4223K1B00
     1 SW_PVDDIO_P1_BOOT2_R @T6G_MB_LIB.T6G(SCH_1):SW_PVDDIO_P1_BOOT2_R    I47 @T6G_MB_LIB.T6G(SCH_1):PAGE197
     2 SW_PVDDIO_P1_BOOTR2 @T6G_MB_LIB.T6G(SCH_1):SW_PVDDIO_P1_BOOTR2    I47 @T6G_MB_LIB.T6G(SCH_1):PAGE197

PC446_2 Q_CAP_C0805-22UF,16V,20%,X6S,CH6223MEA01
     1 SW_P12V_AUX_PVDDIO_P1_FLT @T6G_MB_LIB.T6G(SCH_1):SW_P12V_AUX_PVDDIO_P1_FLT    I49 @T6G_MB_LIB.T6G(SCH_1):PAGE197
     2    GND @T6G_MB_LIB.T6G(SCH_1):GND    I49 @T6G_MB_LIB.T6G(SCH_1):PAGE197

PC447 Q_CAP_0402-0.22UF,16V,10%,X7R,CH4223K1B00
     1 SW_PVDDIO_P1_BOOT1_R @T6G_MB_LIB.T6G(SCH_1):SW_PVDDIO_P1_BOOT1_R    I65 @T6G_MB_LIB.T6G(SCH_1):PAGE197
     2 SW_PVDDIO_P1_BOOTR1 @T6G_MB_LIB.T6G(SCH_1):SW_PVDDIO_P1_BOOTR1    I65 @T6G_MB_LIB.T6G(SCH_1):PAGE197

PC448_1 Q_CAP_C0805-22UF,16V,20%,X6S,CH6223MEA01
     1 SW_P12V_AUX_PVDDIO_P1_FLT @T6G_MB_LIB.T6G(SCH_1):SW_P12V_AUX_PVDDIO_P1_FLT    I69 @T6G_MB_LIB.T6G(SCH_1):PAGE197
     2    GND @T6G_MB_LIB.T6G(SCH_1):GND    I69 @T6G_MB_LIB.T6G(SCH_1):PAGE197

PC449_2 Q_CAP_C0805-22UF,16V,20%,X6S,CH6223MEA01
     1 SW_P12V_AUX_PVDDIO_P1_FLT @T6G_MB_LIB.T6G(SCH_1):SW_P12V_AUX_PVDDIO_P1_FLT    I52 @T6G_MB_LIB.T6G(SCH_1):PAGE197
     2    GND @T6G_MB_LIB.T6G(SCH_1):GND    I52 @T6G_MB_LIB.T6G(SCH_1):PAGE197

PC450 Q_CAPP_SMLF-470UF,2.5V,20%,SPCAP,CH747LM8825
     1 PVDDIO_P1 @T6G_MB_LIB.T6G(SCH_1):PVDDIO_P1    I58 @T6G_MB_LIB.T6G(SCH_1):PAGE197
     2    GND @T6G_MB_LIB.T6G(SCH_1):GND    I58 @T6G_MB_LIB.T6G(SCH_1):PAGE197

PC451 Q_CAP_C0402-100NF,50V,10%,X7R,CH4106K1B01
     1 PVDDIO_P1 @T6G_MB_LIB.T6G(SCH_1):PVDDIO_P1    I77 @T6G_MB_LIB.T6G(SCH_1):PAGE197
     2    GND @T6G_MB_LIB.T6G(SCH_1):GND    I77 @T6G_MB_LIB.T6G(SCH_1):PAGE197

PC452 Q_CAPP_SMLF-470UF,2.5V,20%,SPCAP,CH747LM8825
     1 PVDDIO_P1 @T6G_MB_LIB.T6G(SCH_1):PVDDIO_P1    I59 @T6G_MB_LIB.T6G(SCH_1):PAGE197
     2    GND @T6G_MB_LIB.T6G(SCH_1):GND    I59 @T6G_MB_LIB.T6G(SCH_1):PAGE197

PC454 Q_CAPP_SMLF-270UF,16V,20%,OSCON,CC72703MZ11
     1 SW_P12V_AUX_PVDDIO_P1_FLT @T6G_MB_LIB.T6G(SCH_1):SW_P12V_AUX_PVDDIO_P1_FLT    I85 @T6G_MB_LIB.T6G(SCH_1):PAGE197
     2    GND @T6G_MB_LIB.T6G(SCH_1):GND    I85 @T6G_MB_LIB.T6G(SCH_1):PAGE197

PC455 Q_CAPP_SMLF-470UF,2.5V,20%,EMPTY,CH747LM8825
     1 PVDDIO_P1 @T6G_MB_LIB.T6G(SCH_1):PVDDIO_P1    I62 @T6G_MB_LIB.T6G(SCH_1):PAGE197
     2    GND @T6G_MB_LIB.T6G(SCH_1):GND    I62 @T6G_MB_LIB.T6G(SCH_1):PAGE197

PC456_1 Q_CAP_C0805-22UF,4V,20%,X6S,CH622KMEA03
     1 PVDDIO_P1 @T6G_MB_LIB.T6G(SCH_1):PVDDIO_P1    I78 @T6G_MB_LIB.T6G(SCH_1):PAGE197
     2    GND @T6G_MB_LIB.T6G(SCH_1):GND    I78 @T6G_MB_LIB.T6G(SCH_1):PAGE197

PC458_2 Q_CAP_C0805-22UF,4V,20%,X6S,CH622KMEA03
     1 PVDDIO_P1 @T6G_MB_LIB.T6G(SCH_1):PVDDIO_P1    I55 @T6G_MB_LIB.T6G(SCH_1):PAGE197
     2    GND @T6G_MB_LIB.T6G(SCH_1):GND    I55 @T6G_MB_LIB.T6G(SCH_1):PAGE197

PC459_1 Q_CAP_C0805-22UF,4V,20%,X6S,CH622KMEA03
     1 PVDDIO_P1 @T6G_MB_LIB.T6G(SCH_1):PVDDIO_P1    I79 @T6G_MB_LIB.T6G(SCH_1):PAGE197
     2    GND @T6G_MB_LIB.T6G(SCH_1):GND    I79 @T6G_MB_LIB.T6G(SCH_1):PAGE197

PC460_2 Q_CAP_C0805-22UF,4V,20%,X6S,CH622KMEA03
     1 PVDDIO_P1 @T6G_MB_LIB.T6G(SCH_1):PVDDIO_P1    I57 @T6G_MB_LIB.T6G(SCH_1):PAGE197
     2    GND @T6G_MB_LIB.T6G(SCH_1):GND    I57 @T6G_MB_LIB.T6G(SCH_1):PAGE197

PC462 Q_CAP_0402-0.1UF,25V,10%,X7R,CH4104K1B00
     1 PVDDCR_CPU0_P0_VMON @T6G_MB_LIB.T6G(SCH_1):PVDDCR_CPU0_P0_VMON    I23 @T6G_MB_LIB.T6G(SCH_1):PAGE168
     2    GND @T6G_MB_LIB.T6G(SCH_1):GND    I23 @T6G_MB_LIB.T6G(SCH_1):PAGE168

PC463 Q_CAP_0402-3300PF,50V,10%,X7R,TMP_QCH2336K1B12
     1 VSENSE_PVDDCR_CPU0_P0_VSEN0 @T6G_MB_LIB.T6G(SCH_1):VSENSE_PVDDCR_CPU0_P0_VSEN0    I62 @T6G_MB_LIB.T6G(SCH_1):PAGE168
     2 VSENSE_VSS_SENSE_A_P0 @T6G_MB_LIB.T6G(SCH_1):VSENSE_VSS_SENSE_A_P0    I62 @T6G_MB_LIB.T6G(SCH_1):PAGE168

PC464 Q_CAP_0402-3300PF,50V,10%,X7R,TMP_QCH2336K1B12
     1 VSENSE_PVDDCR_SOC_P0_VSEN1 @T6G_MB_LIB.T6G(SCH_1):VSENSE_PVDDCR_SOC_P0_VSEN1    I60 @T6G_MB_LIB.T6G(SCH_1):PAGE168
     2 VSENSE_VSS_SENSE_A_P0 @T6G_MB_LIB.T6G(SCH_1):VSENSE_VSS_SENSE_A_P0    I60 @T6G_MB_LIB.T6G(SCH_1):PAGE168

PC466 Q_CAP_0402-1UF,6.3V,10%,X7R,CH5101K1B01
     1 PVDD18_S5_P0 @T6G_MB_LIB.T6G(SCH_1):PVDD18_S5_P0    I52 @T6G_MB_LIB.T6G(SCH_1):PAGE168
     2    GND @T6G_MB_LIB.T6G(SCH_1):GND    I52 @T6G_MB_LIB.T6G(SCH_1):PAGE168

PC469 Q_CAP_0402-470PF,50V,10%,X7R,TMP_QCH14706KB18
     1 PVDDCR_CPU0_P0_TEMP0 @T6G_MB_LIB.T6G(SCH_1):PVDDCR_CPU0_P0_TEMP0    I95 @T6G_MB_LIB.T6G(SCH_1):PAGE168
     2    GND @T6G_MB_LIB.T6G(SCH_1):GND    I95 @T6G_MB_LIB.T6G(SCH_1):PAGE168

PC470 Q_CAP_C0402-10UF,6.3V,20%,X6S,CH6101MEB03
     1 PVDDCR_CPU0_P0_VCCS @T6G_MB_LIB.T6G(SCH_1):PVDDCR_CPU0_P0_VCCS   I129 @T6G_MB_LIB.T6G(SCH_1):PAGE168
     2    GND @T6G_MB_LIB.T6G(SCH_1):GND   I129 @T6G_MB_LIB.T6G(SCH_1):PAGE168

PC471 Q_CAP_C0402-1UF,16V,10%,X6S,CH5103KEB01
     1 PVDDCR_CPU0_P0_VCC @T6G_MB_LIB.T6G(SCH_1):PVDDCR_CPU0_P0_VCC   I131 @T6G_MB_LIB.T6G(SCH_1):PAGE168
     2    GND @T6G_MB_LIB.T6G(SCH_1):GND   I131 @T6G_MB_LIB.T6G(SCH_1):PAGE168

PC472 Q_CAP_0402-470PF,50V,10%,X7R,TMP_QCH14706KB18
     1 PVDDCR_SOC_P0_TEMP1 @T6G_MB_LIB.T6G(SCH_1):PVDDCR_SOC_P0_TEMP1    I98 @T6G_MB_LIB.T6G(SCH_1):PAGE168
     2    GND @T6G_MB_LIB.T6G(SCH_1):GND    I98 @T6G_MB_LIB.T6G(SCH_1):PAGE168

PC473 Q_CAPP_SMLF-100UF,16V,20%,OSCON,CC71003MZ30
     1 SW_P12V_AUX_P0V9_RETIMER_CPU1_FLT @T6G_MB_LIB.T6G(SCH_1):SW_P12V_AUX_P0V9_RETIMER_CPU1_FLT    I88 @T6G_MB_LIB.T6G(SCH_1):PAGE478
     2    GND @T6G_MB_LIB.T6G(SCH_1):GND    I88 @T6G_MB_LIB.T6G(SCH_1):PAGE478

PC473_1 Q_CAP_0402-0.1UF,25V,10%,X7R,CH4104K1B00
     1 PVDDCR_CPU0_P0_VCCS @T6G_MB_LIB.T6G(SCH_1):PVDDCR_CPU0_P0_VCCS    I22 @T6G_MB_LIB.T6G(SCH_1):PAGE169
     2    GND @T6G_MB_LIB.T6G(SCH_1):GND    I22 @T6G_MB_LIB.T6G(SCH_1):PAGE169

PC474_2 Q_CAP_0402-0.1UF,25V,10%,X7R,CH4104K1B00
     1 PVDDCR_CPU0_P0_VCCS @T6G_MB_LIB.T6G(SCH_1):PVDDCR_CPU0_P0_VCCS     I8 @T6G_MB_LIB.T6G(SCH_1):PAGE169
     2    GND @T6G_MB_LIB.T6G(SCH_1):GND     I8 @T6G_MB_LIB.T6G(SCH_1):PAGE169

PC475 Q_CAP_C0402-2.2UF,10V,10%,X6S,CH5222KEB01
     1 PVDDCR_CPU0_P0_VCC1 @T6G_MB_LIB.T6G(SCH_1):PVDDCR_CPU0_P0_VCC1    I45 @T6G_MB_LIB.T6G(SCH_1):PAGE169
     2    GND @T6G_MB_LIB.T6G(SCH_1):GND    I45 @T6G_MB_LIB.T6G(SCH_1):PAGE169

PC476 Q_CAP_C0402-2.2UF,10V,10%,X6S,CH5222KEB01
     1 PVDDCR_CPU0_P0_VCC2 @T6G_MB_LIB.T6G(SCH_1):PVDDCR_CPU0_P0_VCC2    I14 @T6G_MB_LIB.T6G(SCH_1):PAGE169
     2    GND @T6G_MB_LIB.T6G(SCH_1):GND    I14 @T6G_MB_LIB.T6G(SCH_1):PAGE169

PC477_C0P0_1 Q_CAP_C0402-2.2UF,10V,10%,X6S,CH5222KEB01
     1 PVDDCR_CPU0_P0_PVCC @T6G_MB_LIB.T6G(SCH_1):PVDDCR_CPU0_P0_PVCC    I51 @T6G_MB_LIB.T6G(SCH_1):PAGE169
     2    GND @T6G_MB_LIB.T6G(SCH_1):GND    I51 @T6G_MB_LIB.T6G(SCH_1):PAGE169

PC478_C0P0_2 Q_CAP_C0402-2.2UF,10V,10%,X6S,CH5222KEB01
     1 PVDDCR_CPU0_P0_PVCC @T6G_MB_LIB.T6G(SCH_1):PVDDCR_CPU0_P0_PVCC    I19 @T6G_MB_LIB.T6G(SCH_1):PAGE169
     2    GND @T6G_MB_LIB.T6G(SCH_1):GND    I19 @T6G_MB_LIB.T6G(SCH_1):PAGE169

PC479 Q_CAP_0402-0.1UF,25V,10%,X7R,CH4104K1B00
     1 P12V_AUX @T6G_MB_LIB.T6G(SCH_1):P12V_AUX    I85 @T6G_MB_LIB.T6G(SCH_1):PAGE169
     2    GND @T6G_MB_LIB.T6G(SCH_1):GND    I85 @T6G_MB_LIB.T6G(SCH_1):PAGE169

PC479_1 Q_CAP_0402-0.1UF,25V,10%,X7R,CH4104K1B00
     1 SW_P12V_AUX_PVDDCR_CPU0_P0_FLT @T6G_MB_LIB.T6G(SCH_1):SW_P12V_AUX_PVDDCR_CPU0_P0_FLT    I52 @T6G_MB_LIB.T6G(SCH_1):PAGE169
     2    GND @T6G_MB_LIB.T6G(SCH_1):GND    I52 @T6G_MB_LIB.T6G(SCH_1):PAGE169

PC480_2 Q_CAP_C0402-1UF,25V,10%,X6S,CH5104KEB02
     1 SW_P12V_AUX_PVDDCR_CPU0_P0_FLT @T6G_MB_LIB.T6G(SCH_1):SW_P12V_AUX_PVDDCR_CPU0_P0_FLT    I34 @T6G_MB_LIB.T6G(SCH_1):PAGE169
     2    GND @T6G_MB_LIB.T6G(SCH_1):GND    I34 @T6G_MB_LIB.T6G(SCH_1):PAGE169

PC481_1 Q_CAP_C0402-1UF,25V,10%,X6S,CH5104KEB02
     1 SW_P12V_AUX_PVDDCR_CPU0_P0_FLT @T6G_MB_LIB.T6G(SCH_1):SW_P12V_AUX_PVDDCR_CPU0_P0_FLT    I53 @T6G_MB_LIB.T6G(SCH_1):PAGE169
     2    GND @T6G_MB_LIB.T6G(SCH_1):GND    I53 @T6G_MB_LIB.T6G(SCH_1):PAGE169

PC482_2 Q_CAP_0402-0.1UF,25V,10%,X7R,CH4104K1B00
     1 SW_P12V_AUX_PVDDCR_CPU0_P0_FLT @T6G_MB_LIB.T6G(SCH_1):SW_P12V_AUX_PVDDCR_CPU0_P0_FLT    I33 @T6G_MB_LIB.T6G(SCH_1):PAGE169
     2    GND @T6G_MB_LIB.T6G(SCH_1):GND    I33 @T6G_MB_LIB.T6G(SCH_1):PAGE169

PC483_1 Q_CAP_C0805-22UF,16V,20%,X6S,CH6223MEA01
     1 SW_P12V_AUX_PVDDCR_CPU0_P0_FLT @T6G_MB_LIB.T6G(SCH_1):SW_P12V_AUX_PVDDCR_CPU0_P0_FLT    I57 @T6G_MB_LIB.T6G(SCH_1):PAGE169
     2    GND @T6G_MB_LIB.T6G(SCH_1):GND    I57 @T6G_MB_LIB.T6G(SCH_1):PAGE169

PC484_2 Q_CAP_C0805-22UF,16V,20%,X6S,CH6223MEA01
     1 SW_P12V_AUX_PVDDCR_CPU0_P0_FLT @T6G_MB_LIB.T6G(SCH_1):SW_P12V_AUX_PVDDCR_CPU0_P0_FLT    I36 @T6G_MB_LIB.T6G(SCH_1):PAGE169
     2    GND @T6G_MB_LIB.T6G(SCH_1):GND    I36 @T6G_MB_LIB.T6G(SCH_1):PAGE169

PC485_1 Q_CAP_C0805-22UF,16V,20%,X6S,CH6223MEA01
     1 SW_P12V_AUX_PVDDCR_CPU0_P0_FLT @T6G_MB_LIB.T6G(SCH_1):SW_P12V_AUX_PVDDCR_CPU0_P0_FLT    I58 @T6G_MB_LIB.T6G(SCH_1):PAGE169
     2    GND @T6G_MB_LIB.T6G(SCH_1):GND    I58 @T6G_MB_LIB.T6G(SCH_1):PAGE169

PC486_2 Q_CAP_C0805-22UF,16V,20%,X6S,CH6223MEA01
     1 SW_P12V_AUX_PVDDCR_CPU0_P0_FLT @T6G_MB_LIB.T6G(SCH_1):SW_P12V_AUX_PVDDCR_CPU0_P0_FLT    I37 @T6G_MB_LIB.T6G(SCH_1):PAGE169
     2    GND @T6G_MB_LIB.T6G(SCH_1):GND    I37 @T6G_MB_LIB.T6G(SCH_1):PAGE169

PC487_1 Q_CAP_C0805-22UF,16V,20%,X6S,CH6223MEA01
     1 SW_P12V_AUX_PVDDCR_CPU0_P0_FLT @T6G_MB_LIB.T6G(SCH_1):SW_P12V_AUX_PVDDCR_CPU0_P0_FLT    I59 @T6G_MB_LIB.T6G(SCH_1):PAGE169
     2    GND @T6G_MB_LIB.T6G(SCH_1):GND    I59 @T6G_MB_LIB.T6G(SCH_1):PAGE169

PC488_2 Q_CAP_C0805-22UF,16V,20%,X6S,CH6223MEA01
     1 SW_P12V_AUX_PVDDCR_CPU0_P0_FLT @T6G_MB_LIB.T6G(SCH_1):SW_P12V_AUX_PVDDCR_CPU0_P0_FLT    I39 @T6G_MB_LIB.T6G(SCH_1):PAGE169
     2    GND @T6G_MB_LIB.T6G(SCH_1):GND    I39 @T6G_MB_LIB.T6G(SCH_1):PAGE169

PC489 Q_CAP_0402-0.22UF,16V,10%,X7R,CH4223K1B00
     1 SW_PVDDCR_CPU0_P0_BOOT1_RC @T6G_MB_LIB.T6G(SCH_1):SW_PVDDCR_CPU0_P0_BOOT1_RC    I76 @T6G_MB_LIB.T6G(SCH_1):PAGE169
     2 SW_PVDDCR_CPU0_P0_PH1 @T6G_MB_LIB.T6G(SCH_1):SW_PVDDCR_CPU0_P0_PH1    I76 @T6G_MB_LIB.T6G(SCH_1):PAGE169

PC490 Q_CAP_0402-0.22UF,16V,10%,X7R,CH4223K1B00
     1 SW_PVDDCR_CPU0_P0_BOOT2_RC @T6G_MB_LIB.T6G(SCH_1):SW_PVDDCR_CPU0_P0_BOOT2_RC    I61 @T6G_MB_LIB.T6G(SCH_1):PAGE169
     2 SW_PVDDCR_CPU0_P0_PH2 @T6G_MB_LIB.T6G(SCH_1):SW_PVDDCR_CPU0_P0_PH2    I61 @T6G_MB_LIB.T6G(SCH_1):PAGE169

PC491 Q_CAPP_THLF-270UF,16V,20%,OSCON,CC72703MD38
     1 SW_P12V_AUX_PVDDCR_CPU0_P0_FLT @T6G_MB_LIB.T6G(SCH_1):SW_P12V_AUX_PVDDCR_CPU0_P0_FLT    I79 @T6G_MB_LIB.T6G(SCH_1):PAGE169
     2    GND @T6G_MB_LIB.T6G(SCH_1):GND    I79 @T6G_MB_LIB.T6G(SCH_1):PAGE169

PC492 Q_CAPP_THLF-270UF,16V,20%,OSCON,CC72703MD38
     1 SW_P12V_AUX_PVDDCR_CPU0_P0_FLT @T6G_MB_LIB.T6G(SCH_1):SW_P12V_AUX_PVDDCR_CPU0_P0_FLT    I81 @T6G_MB_LIB.T6G(SCH_1):PAGE169
     2    GND @T6G_MB_LIB.T6G(SCH_1):GND    I81 @T6G_MB_LIB.T6G(SCH_1):PAGE169

PC494 Q_CAPP_SMLF-220UF,4V,20%,SPCAP,CH122KM8801
     1 PVDDCR_CPU0_P0 @T6G_MB_LIB.T6G(SCH_1):PVDDCR_CPU0_P0    I65 @T6G_MB_LIB.T6G(SCH_1):PAGE169
     2    GND @T6G_MB_LIB.T6G(SCH_1):GND    I65 @T6G_MB_LIB.T6G(SCH_1):PAGE169

PC495 Q_CAPP_SMLF-220UF,4V,20%,SPCAP,CH122KM8801
     1 PVDDCR_CPU0_P0 @T6G_MB_LIB.T6G(SCH_1):PVDDCR_CPU0_P0    I66 @T6G_MB_LIB.T6G(SCH_1):PAGE169
     2    GND @T6G_MB_LIB.T6G(SCH_1):GND    I66 @T6G_MB_LIB.T6G(SCH_1):PAGE169

PC496 Q_CAPP_SMLF-220UF,4V,20%,SPCAP,CH122KM8801
     1 PVDDCR_CPU0_P0 @T6G_MB_LIB.T6G(SCH_1):PVDDCR_CPU0_P0    I67 @T6G_MB_LIB.T6G(SCH_1):PAGE169
     2    GND @T6G_MB_LIB.T6G(SCH_1):GND    I67 @T6G_MB_LIB.T6G(SCH_1):PAGE169

PC497 Q_CAP_0402-0.1UF,25V,10%,X7R,CH4104K1B00
     1 PVDDCR_CPU0_P0 @T6G_MB_LIB.T6G(SCH_1):PVDDCR_CPU0_P0    I87 @T6G_MB_LIB.T6G(SCH_1):PAGE169
     2    GND @T6G_MB_LIB.T6G(SCH_1):GND    I87 @T6G_MB_LIB.T6G(SCH_1):PAGE169

PC498 Q_CAPP_SMLF-220UF,4V,20%,SPCAP,CH122KM8801
     1 PVDDCR_CPU0_P0 @T6G_MB_LIB.T6G(SCH_1):PVDDCR_CPU0_P0    I73 @T6G_MB_LIB.T6G(SCH_1):PAGE169
     2    GND @T6G_MB_LIB.T6G(SCH_1):GND    I73 @T6G_MB_LIB.T6G(SCH_1):PAGE169

PC499_2 Q_CAP_C0805-22UF,4V,20%,X6S,CH622KMEA03
     1 PVDDCR_CPU0_P0 @T6G_MB_LIB.T6G(SCH_1):PVDDCR_CPU0_P0    I68 @T6G_MB_LIB.T6G(SCH_1):PAGE169
     2    GND @T6G_MB_LIB.T6G(SCH_1):GND    I68 @T6G_MB_LIB.T6G(SCH_1):PAGE169

PC500_1 Q_CAP_C0805-22UF,4V,20%,X6S,CH622KMEA03
     1 PVDDCR_CPU0_P0 @T6G_MB_LIB.T6G(SCH_1):PVDDCR_CPU0_P0    I88 @T6G_MB_LIB.T6G(SCH_1):PAGE169
     2    GND @T6G_MB_LIB.T6G(SCH_1):GND    I88 @T6G_MB_LIB.T6G(SCH_1):PAGE169

PC501_2 Q_CAP_C0805-22UF,4V,20%,X6S,CH622KMEA03
     1 PVDDCR_CPU0_P0 @T6G_MB_LIB.T6G(SCH_1):PVDDCR_CPU0_P0    I70 @T6G_MB_LIB.T6G(SCH_1):PAGE169
     2    GND @T6G_MB_LIB.T6G(SCH_1):GND    I70 @T6G_MB_LIB.T6G(SCH_1):PAGE169

PC502_1 Q_CAP_C0805-22UF,4V,20%,X6S,CH622KMEA03
     1 PVDDCR_CPU0_P0 @T6G_MB_LIB.T6G(SCH_1):PVDDCR_CPU0_P0    I89 @T6G_MB_LIB.T6G(SCH_1):PAGE169
     2    GND @T6G_MB_LIB.T6G(SCH_1):GND    I89 @T6G_MB_LIB.T6G(SCH_1):PAGE169

PC503_1 Q_CAP_0402-0.1UF,25V,10%,X7R,CH4104K1B00
     1 PVDD11_S3_P1_VCCS @T6G_MB_LIB.T6G(SCH_1):PVDD11_S3_P1_VCCS    I34 @T6G_MB_LIB.T6G(SCH_1):PAGE200
     2    GND @T6G_MB_LIB.T6G(SCH_1):GND    I34 @T6G_MB_LIB.T6G(SCH_1):PAGE200

PC504_2 Q_CAP_0402-0.1UF,25V,10%,X7R,CH4104K1B00
     1 PVDD11_S3_P1_VCCS @T6G_MB_LIB.T6G(SCH_1):PVDD11_S3_P1_VCCS     I8 @T6G_MB_LIB.T6G(SCH_1):PAGE200
     2    GND @T6G_MB_LIB.T6G(SCH_1):GND     I8 @T6G_MB_LIB.T6G(SCH_1):PAGE200

PC505 Q_CAP_C0402-2.2UF,10V,10%,X6S,CH5222KEB01
     1 PVDD11_S3_P1_VCC1 @T6G_MB_LIB.T6G(SCH_1):PVDD11_S3_P1_VCC1    I36 @T6G_MB_LIB.T6G(SCH_1):PAGE200
     2    GND @T6G_MB_LIB.T6G(SCH_1):GND    I36 @T6G_MB_LIB.T6G(SCH_1):PAGE200

PC506 Q_CAP_C0402-2.2UF,10V,10%,X6S,CH5222KEB01
     1 PVDD11_S3_P1_VCC2 @T6G_MB_LIB.T6G(SCH_1):PVDD11_S3_P1_VCC2    I10 @T6G_MB_LIB.T6G(SCH_1):PAGE200
     2    GND @T6G_MB_LIB.T6G(SCH_1):GND    I10 @T6G_MB_LIB.T6G(SCH_1):PAGE200

PC507_11P1_1 Q_CAP_C0402-2.2UF,10V,10%,X6S,CH5222KEB01
     1 PVDD11_S3_P1_PVCC @T6G_MB_LIB.T6G(SCH_1):PVDD11_S3_P1_PVCC    I43 @T6G_MB_LIB.T6G(SCH_1):PAGE200
     2    GND @T6G_MB_LIB.T6G(SCH_1):GND    I43 @T6G_MB_LIB.T6G(SCH_1):PAGE200

PC508_11P1_2 Q_CAP_C0402-2.2UF,10V,10%,X6S,CH5222KEB01
     1 PVDD11_S3_P1_PVCC @T6G_MB_LIB.T6G(SCH_1):PVDD11_S3_P1_PVCC    I17 @T6G_MB_LIB.T6G(SCH_1):PAGE200
     2    GND @T6G_MB_LIB.T6G(SCH_1):GND    I17 @T6G_MB_LIB.T6G(SCH_1):PAGE200

PC509_1 Q_CAP_0402-0.1UF,25V,10%,X7R,CH4104K1B00
     1 SW_P12V_AUX_PVDD11_S3_P1_FLT @T6G_MB_LIB.T6G(SCH_1):SW_P12V_AUX_PVDD11_S3_P1_FLT    I48 @T6G_MB_LIB.T6G(SCH_1):PAGE200
     2    GND @T6G_MB_LIB.T6G(SCH_1):GND    I48 @T6G_MB_LIB.T6G(SCH_1):PAGE200

PC510_2 Q_CAP_0402-0.1UF,25V,10%,X7R,CH4104K1B00
     1 SW_P12V_AUX_PVDD11_S3_P1_FLT @T6G_MB_LIB.T6G(SCH_1):SW_P12V_AUX_PVDD11_S3_P1_FLT    I29 @T6G_MB_LIB.T6G(SCH_1):PAGE200
     2    GND @T6G_MB_LIB.T6G(SCH_1):GND    I29 @T6G_MB_LIB.T6G(SCH_1):PAGE200

PC511 Q_CAP_0402-0.1UF,25V,10%,X7R,CH4104K1B00
     1 P12V_AUX @T6G_MB_LIB.T6G(SCH_1):P12V_AUX    I85 @T6G_MB_LIB.T6G(SCH_1):PAGE200
     2    GND @T6G_MB_LIB.T6G(SCH_1):GND    I85 @T6G_MB_LIB.T6G(SCH_1):PAGE200

PC511_1 Q_CAP_C0402-1UF,25V,10%,X6S,CH5104KEB02
     1 SW_P12V_AUX_PVDD11_S3_P1_FLT @T6G_MB_LIB.T6G(SCH_1):SW_P12V_AUX_PVDD11_S3_P1_FLT    I45 @T6G_MB_LIB.T6G(SCH_1):PAGE200
     2    GND @T6G_MB_LIB.T6G(SCH_1):GND    I45 @T6G_MB_LIB.T6G(SCH_1):PAGE200

PC512_2 Q_CAP_C0402-1UF,25V,10%,X6S,CH5104KEB02
     1 SW_P12V_AUX_PVDD11_S3_P1_FLT @T6G_MB_LIB.T6G(SCH_1):SW_P12V_AUX_PVDD11_S3_P1_FLT    I91 @T6G_MB_LIB.T6G(SCH_1):PAGE200
     2    GND @T6G_MB_LIB.T6G(SCH_1):GND    I91 @T6G_MB_LIB.T6G(SCH_1):PAGE200

PC513_1 Q_CAP_C0805-22UF,16V,20%,X6S,CH6223MEA01
     1 SW_P12V_AUX_PVDD11_S3_P1_FLT @T6G_MB_LIB.T6G(SCH_1):SW_P12V_AUX_PVDD11_S3_P1_FLT    I49 @T6G_MB_LIB.T6G(SCH_1):PAGE200
     2    GND @T6G_MB_LIB.T6G(SCH_1):GND    I49 @T6G_MB_LIB.T6G(SCH_1):PAGE200

PC514 Q_CAP_0402-0.1UF,25V,10%,EMPTY,CH4104K1B00
     1 P0V9_RETIMER_CPU1_VMON @T6G_MB_LIB.T6G(SCH_1):P0V9_RETIMER_CPU1_VMON     I5 @T6G_MB_LIB.T6G(SCH_1):PAGE477
     2    GND @T6G_MB_LIB.T6G(SCH_1):GND     I5 @T6G_MB_LIB.T6G(SCH_1):PAGE477

PC514_2 Q_CAP_C0805-22UF,16V,20%,X6S,CH6223MEA01
     1 SW_P12V_AUX_PVDD11_S3_P1_FLT @T6G_MB_LIB.T6G(SCH_1):SW_P12V_AUX_PVDD11_S3_P1_FLT    I30 @T6G_MB_LIB.T6G(SCH_1):PAGE200
     2    GND @T6G_MB_LIB.T6G(SCH_1):GND    I30 @T6G_MB_LIB.T6G(SCH_1):PAGE200

PC515_1 Q_CAP_C0805-22UF,16V,20%,X6S,CH6223MEA01
     1 SW_P12V_AUX_PVDD11_S3_P1_FLT @T6G_MB_LIB.T6G(SCH_1):SW_P12V_AUX_PVDD11_S3_P1_FLT    I50 @T6G_MB_LIB.T6G(SCH_1):PAGE200
     2    GND @T6G_MB_LIB.T6G(SCH_1):GND    I50 @T6G_MB_LIB.T6G(SCH_1):PAGE200

PC516_2 Q_CAP_C0805-22UF,16V,20%,X6S,CH6223MEA01
     1 SW_P12V_AUX_PVDD11_S3_P1_FLT @T6G_MB_LIB.T6G(SCH_1):SW_P12V_AUX_PVDD11_S3_P1_FLT    I31 @T6G_MB_LIB.T6G(SCH_1):PAGE200
     2    GND @T6G_MB_LIB.T6G(SCH_1):GND    I31 @T6G_MB_LIB.T6G(SCH_1):PAGE200

PC517_1 Q_CAP_C0805-22UF,16V,20%,X6S,CH6223MEA01
     1 SW_P12V_AUX_PVDD11_S3_P1_FLT @T6G_MB_LIB.T6G(SCH_1):SW_P12V_AUX_PVDD11_S3_P1_FLT    I51 @T6G_MB_LIB.T6G(SCH_1):PAGE200
     2    GND @T6G_MB_LIB.T6G(SCH_1):GND    I51 @T6G_MB_LIB.T6G(SCH_1):PAGE200

PC518_2 Q_CAP_C0805-22UF,16V,20%,X6S,CH6223MEA01
     1 SW_P12V_AUX_PVDD11_S3_P1_FLT @T6G_MB_LIB.T6G(SCH_1):SW_P12V_AUX_PVDD11_S3_P1_FLT    I52 @T6G_MB_LIB.T6G(SCH_1):PAGE200
     2    GND @T6G_MB_LIB.T6G(SCH_1):GND    I52 @T6G_MB_LIB.T6G(SCH_1):PAGE200

PC519 Q_CAP_0402-0.22UF,16V,10%,X7R,CH4223K1B00
     1 SW_PVDD11_S3_P1_BOOT1_RC @T6G_MB_LIB.T6G(SCH_1):SW_PVDD11_S3_P1_BOOT1_RC    I76 @T6G_MB_LIB.T6G(SCH_1):PAGE200
     2 SW_PVDD11_S3_P1_PH1 @T6G_MB_LIB.T6G(SCH_1):SW_PVDD11_S3_P1_PH1    I76 @T6G_MB_LIB.T6G(SCH_1):PAGE200

PC520 Q_CAP_0402-0.22UF,16V,10%,X7R,CH4223K1B00
     1 SW_PVDD11_S3_P1_BOOT2_RC @T6G_MB_LIB.T6G(SCH_1):SW_PVDD11_S3_P1_BOOT2_RC    I54 @T6G_MB_LIB.T6G(SCH_1):PAGE200
     2 SW_PVDD11_S3_P1_PH2 @T6G_MB_LIB.T6G(SCH_1):SW_PVDD11_S3_P1_PH2    I54 @T6G_MB_LIB.T6G(SCH_1):PAGE200

PC521_1 Q_CAP_C0805-22UF,16V,20%,X6S,CH6223MEA01
     1 SW_P12V_AUX_PVDD11_S3_P1_FLT @T6G_MB_LIB.T6G(SCH_1):SW_P12V_AUX_PVDD11_S3_P1_FLT    I80 @T6G_MB_LIB.T6G(SCH_1):PAGE200
     2    GND @T6G_MB_LIB.T6G(SCH_1):GND    I80 @T6G_MB_LIB.T6G(SCH_1):PAGE200

PC522 Q_CAPP_THLF-270UF,16V,20%,OSCON,CC72703MD38
     1 SW_P12V_AUX_PVDD11_S3_P1_FLT @T6G_MB_LIB.T6G(SCH_1):SW_P12V_AUX_PVDD11_S3_P1_FLT    I81 @T6G_MB_LIB.T6G(SCH_1):PAGE200
     2    GND @T6G_MB_LIB.T6G(SCH_1):GND    I81 @T6G_MB_LIB.T6G(SCH_1):PAGE200

PC523 Q_CAP_0402-470PF,50V,10%,X7R,TMP_QCH14706KB18
     1 P0V9_RETIMER_CPU1_TEMP0 @T6G_MB_LIB.T6G(SCH_1):P0V9_RETIMER_CPU1_TEMP0    I51 @T6G_MB_LIB.T6G(SCH_1):PAGE477
     2    GND @T6G_MB_LIB.T6G(SCH_1):GND    I51 @T6G_MB_LIB.T6G(SCH_1):PAGE477

PC523_2 Q_CAP_C0805-22UF,4V,20%,X6S,CH622KMEA03
     1 PVDD11_S3_P1 @T6G_MB_LIB.T6G(SCH_1):PVDD11_S3_P1    I56 @T6G_MB_LIB.T6G(SCH_1):PAGE200
     2    GND @T6G_MB_LIB.T6G(SCH_1):GND    I56 @T6G_MB_LIB.T6G(SCH_1):PAGE200

PC524 Q_CAP_C0402-100NF,50V,10%,X7R,CH4106K1B01
     1 PVDD11_S3_P1 @T6G_MB_LIB.T6G(SCH_1):PVDD11_S3_P1    I82 @T6G_MB_LIB.T6G(SCH_1):PAGE200
     2    GND @T6G_MB_LIB.T6G(SCH_1):GND    I82 @T6G_MB_LIB.T6G(SCH_1):PAGE200

PC525 Q_CAPP_SMLF-470UF,2.5V,20%,SPCAP,CH747LM8825
     1 PVDD11_S3_P1 @T6G_MB_LIB.T6G(SCH_1):PVDD11_S3_P1    I62 @T6G_MB_LIB.T6G(SCH_1):PAGE200
     2    GND @T6G_MB_LIB.T6G(SCH_1):GND    I62 @T6G_MB_LIB.T6G(SCH_1):PAGE200

PC526_1 Q_CAP_C0805-22UF,4V,20%,X6S,CH622KMEA03
     1 PVDD11_S3_P1 @T6G_MB_LIB.T6G(SCH_1):PVDD11_S3_P1    I87 @T6G_MB_LIB.T6G(SCH_1):PAGE200
     2    GND @T6G_MB_LIB.T6G(SCH_1):GND    I87 @T6G_MB_LIB.T6G(SCH_1):PAGE200

PC527_2 Q_CAP_C0805-22UF,4V,20%,X6S,CH622KMEA03
     1 PVDD11_S3_P1 @T6G_MB_LIB.T6G(SCH_1):PVDD11_S3_P1    I67 @T6G_MB_LIB.T6G(SCH_1):PAGE200
     2    GND @T6G_MB_LIB.T6G(SCH_1):GND    I67 @T6G_MB_LIB.T6G(SCH_1):PAGE200

PC528 Q_CAPP_SMLF-470UF,2.5V,20%,SPCAP,CH747LM8825
     1 PVDD11_S3_P1 @T6G_MB_LIB.T6G(SCH_1):PVDD11_S3_P1    I63 @T6G_MB_LIB.T6G(SCH_1):PAGE200
     2    GND @T6G_MB_LIB.T6G(SCH_1):GND    I63 @T6G_MB_LIB.T6G(SCH_1):PAGE200

PC529_1 Q_CAP_C0805-22UF,4V,20%,X6S,CH622KMEA03
     1 PVDD11_S3_P1 @T6G_MB_LIB.T6G(SCH_1):PVDD11_S3_P1    I88 @T6G_MB_LIB.T6G(SCH_1):PAGE200
     2    GND @T6G_MB_LIB.T6G(SCH_1):GND    I88 @T6G_MB_LIB.T6G(SCH_1):PAGE200

PC530 Q_CAPP_SMLF-390UF,2.5V,20%,ALUM,CC7390JMZ13
     1 PVDD11_S3_P1 @T6G_MB_LIB.T6G(SCH_1):PVDD11_S3_P1    I69 @T6G_MB_LIB.T6G(SCH_1):PAGE200
     2    GND @T6G_MB_LIB.T6G(SCH_1):GND    I69 @T6G_MB_LIB.T6G(SCH_1):PAGE200

PC531 Q_CAPP_SMLF-390UF,2.5V,20%,ALUM,CC7390JMZ13
     1 PVDD11_S3_P1 @T6G_MB_LIB.T6G(SCH_1):PVDD11_S3_P1    I72 @T6G_MB_LIB.T6G(SCH_1):PAGE200
     2    GND @T6G_MB_LIB.T6G(SCH_1):GND    I72 @T6G_MB_LIB.T6G(SCH_1):PAGE200

PC532 Q_CAPP_SMLF-390UF,2.5V,20%,ALUM,CC7390JMZ13
     1 PVDD11_S3_P1 @T6G_MB_LIB.T6G(SCH_1):PVDD11_S3_P1    I73 @T6G_MB_LIB.T6G(SCH_1):PAGE200
     2    GND @T6G_MB_LIB.T6G(SCH_1):GND    I73 @T6G_MB_LIB.T6G(SCH_1):PAGE200

PC534 Q_CAPP_SMLF-470UF,2.5V,20%,SPCAP,CH747LM8818
     1 P0V9_CPU0_RT_2D @T6G_MB_LIB.T6G(SCH_1):P0V9_CPU0_RT_2D   I239 @T6G_MB_LIB.T6G(SCH_1):PAGE476
     2    GND @T6G_MB_LIB.T6G(SCH_1):GND   I239 @T6G_MB_LIB.T6G(SCH_1):PAGE476

PC544_3 Q_CAP_0402-0.1UF,25V,10%,X7R,CH4104K1B00
     1 PVDDCR_CPU0_P0_VCCS @T6G_MB_LIB.T6G(SCH_1):PVDDCR_CPU0_P0_VCCS    I27 @T6G_MB_LIB.T6G(SCH_1):PAGE170
     2    GND @T6G_MB_LIB.T6G(SCH_1):GND    I27 @T6G_MB_LIB.T6G(SCH_1):PAGE170

PC545_4 Q_CAP_0402-0.1UF,25V,10%,X7R,CH4104K1B00
     1 PVDDCR_CPU0_P0_VCCS @T6G_MB_LIB.T6G(SCH_1):PVDDCR_CPU0_P0_VCCS     I2 @T6G_MB_LIB.T6G(SCH_1):PAGE170
     2    GND @T6G_MB_LIB.T6G(SCH_1):GND     I2 @T6G_MB_LIB.T6G(SCH_1):PAGE170

PC546 Q_CAP_C0402-2.2UF,10V,10%,X6S,CH5222KEB01
     1 PVDDCR_CPU0_P0_VCC3 @T6G_MB_LIB.T6G(SCH_1):PVDDCR_CPU0_P0_VCC3    I36 @T6G_MB_LIB.T6G(SCH_1):PAGE170
     2    GND @T6G_MB_LIB.T6G(SCH_1):GND    I36 @T6G_MB_LIB.T6G(SCH_1):PAGE170

PC547 Q_CAP_C0402-2.2UF,10V,10%,X6S,CH5222KEB01
     1 PVDDCR_CPU0_P0_VCC4 @T6G_MB_LIB.T6G(SCH_1):PVDDCR_CPU0_P0_VCC4     I6 @T6G_MB_LIB.T6G(SCH_1):PAGE170
     2    GND @T6G_MB_LIB.T6G(SCH_1):GND     I6 @T6G_MB_LIB.T6G(SCH_1):PAGE170

PC548_C0P0_3 Q_CAP_C0402-2.2UF,10V,10%,X6S,CH5222KEB01
     1 PVDDCR_CPU0_P0_PVCC @T6G_MB_LIB.T6G(SCH_1):PVDDCR_CPU0_P0_PVCC    I40 @T6G_MB_LIB.T6G(SCH_1):PAGE170
     2    GND @T6G_MB_LIB.T6G(SCH_1):GND    I40 @T6G_MB_LIB.T6G(SCH_1):PAGE170

PC549_C0P0_4 Q_CAP_C0402-2.2UF,10V,10%,X6S,CH5222KEB01
     1 PVDDCR_CPU0_P0_PVCC @T6G_MB_LIB.T6G(SCH_1):PVDDCR_CPU0_P0_PVCC    I15 @T6G_MB_LIB.T6G(SCH_1):PAGE170
     2    GND @T6G_MB_LIB.T6G(SCH_1):GND    I15 @T6G_MB_LIB.T6G(SCH_1):PAGE170

PC550_3 Q_CAP_C0402-1UF,25V,10%,X6S,CH5104KEB02
     1 SW_P12V_AUX_PVDDCR_CPU0_P0_FLT @T6G_MB_LIB.T6G(SCH_1):SW_P12V_AUX_PVDDCR_CPU0_P0_FLT    I47 @T6G_MB_LIB.T6G(SCH_1):PAGE170
     2    GND @T6G_MB_LIB.T6G(SCH_1):GND    I47 @T6G_MB_LIB.T6G(SCH_1):PAGE170

PC551_4 Q_CAP_0402-0.1UF,25V,10%,X7R,CH4104K1B00
     1 SW_P12V_AUX_PVDDCR_CPU0_P0_FLT @T6G_MB_LIB.T6G(SCH_1):SW_P12V_AUX_PVDDCR_CPU0_P0_FLT    I21 @T6G_MB_LIB.T6G(SCH_1):PAGE170
     2    GND @T6G_MB_LIB.T6G(SCH_1):GND    I21 @T6G_MB_LIB.T6G(SCH_1):PAGE170

PC552_3 Q_CAP_0402-0.1UF,25V,10%,X7R,CH4104K1B00
     1 SW_P12V_AUX_PVDDCR_CPU0_P0_FLT @T6G_MB_LIB.T6G(SCH_1):SW_P12V_AUX_PVDDCR_CPU0_P0_FLT    I43 @T6G_MB_LIB.T6G(SCH_1):PAGE170
     2    GND @T6G_MB_LIB.T6G(SCH_1):GND    I43 @T6G_MB_LIB.T6G(SCH_1):PAGE170

PC553_4 Q_CAP_C0402-1UF,25V,10%,X6S,CH5104KEB02
     1 SW_P12V_AUX_PVDDCR_CPU0_P0_FLT @T6G_MB_LIB.T6G(SCH_1):SW_P12V_AUX_PVDDCR_CPU0_P0_FLT    I22 @T6G_MB_LIB.T6G(SCH_1):PAGE170
     2    GND @T6G_MB_LIB.T6G(SCH_1):GND    I22 @T6G_MB_LIB.T6G(SCH_1):PAGE170

PC554_3 Q_CAP_C0805-22UF,16V,20%,X6S,CH6223MEA01
     1 SW_P12V_AUX_PVDDCR_CPU0_P0_FLT @T6G_MB_LIB.T6G(SCH_1):SW_P12V_AUX_PVDDCR_CPU0_P0_FLT    I48 @T6G_MB_LIB.T6G(SCH_1):PAGE170
     2    GND @T6G_MB_LIB.T6G(SCH_1):GND    I48 @T6G_MB_LIB.T6G(SCH_1):PAGE170

PC555_4 Q_CAP_C0805-22UF,16V,20%,X6S,CH6223MEA01
     1 SW_P12V_AUX_PVDDCR_CPU0_P0_FLT @T6G_MB_LIB.T6G(SCH_1):SW_P12V_AUX_PVDDCR_CPU0_P0_FLT    I23 @T6G_MB_LIB.T6G(SCH_1):PAGE170
     2    GND @T6G_MB_LIB.T6G(SCH_1):GND    I23 @T6G_MB_LIB.T6G(SCH_1):PAGE170

PC556_3 Q_CAP_C0805-22UF,16V,20%,X6S,CH6223MEA01
     1 SW_P12V_AUX_PVDDCR_CPU0_P0_FLT @T6G_MB_LIB.T6G(SCH_1):SW_P12V_AUX_PVDDCR_CPU0_P0_FLT    I49 @T6G_MB_LIB.T6G(SCH_1):PAGE170
     2    GND @T6G_MB_LIB.T6G(SCH_1):GND    I49 @T6G_MB_LIB.T6G(SCH_1):PAGE170

PC557_4 Q_CAP_C0805-22UF,16V,20%,X6S,CH6223MEA01
     1 SW_P12V_AUX_PVDDCR_CPU0_P0_FLT @T6G_MB_LIB.T6G(SCH_1):SW_P12V_AUX_PVDDCR_CPU0_P0_FLT    I24 @T6G_MB_LIB.T6G(SCH_1):PAGE170
     2    GND @T6G_MB_LIB.T6G(SCH_1):GND    I24 @T6G_MB_LIB.T6G(SCH_1):PAGE170

PC558_3 Q_CAP_C0805-22UF,16V,20%,X6S,CH6223MEA01
     1 SW_P12V_AUX_PVDDCR_CPU0_P0_FLT @T6G_MB_LIB.T6G(SCH_1):SW_P12V_AUX_PVDDCR_CPU0_P0_FLT    I66 @T6G_MB_LIB.T6G(SCH_1):PAGE170
     2    GND @T6G_MB_LIB.T6G(SCH_1):GND    I66 @T6G_MB_LIB.T6G(SCH_1):PAGE170

PC559_4 Q_CAP_C0805-22UF,16V,20%,X6S,CH6223MEA01
     1 SW_P12V_AUX_PVDDCR_CPU0_P0_FLT @T6G_MB_LIB.T6G(SCH_1):SW_P12V_AUX_PVDDCR_CPU0_P0_FLT    I55 @T6G_MB_LIB.T6G(SCH_1):PAGE170
     2    GND @T6G_MB_LIB.T6G(SCH_1):GND    I55 @T6G_MB_LIB.T6G(SCH_1):PAGE170

PC560 Q_CAP_0402-0.22UF,16V,10%,X7R,CH4223K1B00
     1 SW_PVDDCR_CPU0_P0_BOOT3_RC @T6G_MB_LIB.T6G(SCH_1):SW_PVDDCR_CPU0_P0_BOOT3_RC    I63 @T6G_MB_LIB.T6G(SCH_1):PAGE170
     2 SW_PVDDCR_CPU0_P0_PH3 @T6G_MB_LIB.T6G(SCH_1):SW_PVDDCR_CPU0_P0_PH3    I63 @T6G_MB_LIB.T6G(SCH_1):PAGE170

PC561 Q_CAP_0402-0.22UF,16V,10%,X7R,CH4223K1B00
     1 SW_PVDDCR_CPU0_P0_BOOT4_RC @T6G_MB_LIB.T6G(SCH_1):SW_PVDDCR_CPU0_P0_BOOT4_RC    I53 @T6G_MB_LIB.T6G(SCH_1):PAGE170
     2 SW_PVDDCR_CPU0_P0_PH4 @T6G_MB_LIB.T6G(SCH_1):SW_PVDDCR_CPU0_P0_PH4    I53 @T6G_MB_LIB.T6G(SCH_1):PAGE170

PC562_3 Q_CAP_C0805-22UF,4V,20%,X6S,CH622KMEA03
     1 PVDDCR_CPU0_P0 @T6G_MB_LIB.T6G(SCH_1):PVDDCR_CPU0_P0    I70 @T6G_MB_LIB.T6G(SCH_1):PAGE170
     2    GND @T6G_MB_LIB.T6G(SCH_1):GND    I70 @T6G_MB_LIB.T6G(SCH_1):PAGE170

PC563_4 Q_CAP_C0805-22UF,4V,20%,X6S,CH622KMEA03
     1 PVDDCR_CPU0_P0 @T6G_MB_LIB.T6G(SCH_1):PVDDCR_CPU0_P0    I58 @T6G_MB_LIB.T6G(SCH_1):PAGE170
     2    GND @T6G_MB_LIB.T6G(SCH_1):GND    I58 @T6G_MB_LIB.T6G(SCH_1):PAGE170

PC564_3 Q_CAP_C0805-22UF,4V,20%,X6S,CH622KMEA03
     1 PVDDCR_CPU0_P0 @T6G_MB_LIB.T6G(SCH_1):PVDDCR_CPU0_P0    I71 @T6G_MB_LIB.T6G(SCH_1):PAGE170
     2    GND @T6G_MB_LIB.T6G(SCH_1):GND    I71 @T6G_MB_LIB.T6G(SCH_1):PAGE170

PC565_4 Q_CAP_C0805-22UF,4V,20%,X6S,CH622KMEA03
     1 PVDDCR_CPU0_P0 @T6G_MB_LIB.T6G(SCH_1):PVDDCR_CPU0_P0    I60 @T6G_MB_LIB.T6G(SCH_1):PAGE170
     2    GND @T6G_MB_LIB.T6G(SCH_1):GND    I60 @T6G_MB_LIB.T6G(SCH_1):PAGE170

PC566 Q_CAPP_THLF-270UF,16V,20%,OSCON,CC72703MD38
     1 SW_P3V3_AUX_FLT @T6G_MB_LIB.T6G(SCH_1):SW_P3V3_AUX_FLT    I30 @T6G_MB_LIB.T6G(SCH_1):PAGE245
     2    GND @T6G_MB_LIB.T6G(SCH_1):GND    I30 @T6G_MB_LIB.T6G(SCH_1):PAGE245

PC566_5 Q_CAP_0402-0.1UF,25V,10%,X7R,CH4104K1B00
     1 PVDDCR_CPU0_P0_VCCS @T6G_MB_LIB.T6G(SCH_1):PVDDCR_CPU0_P0_VCCS    I33 @T6G_MB_LIB.T6G(SCH_1):PAGE171
     2    GND @T6G_MB_LIB.T6G(SCH_1):GND    I33 @T6G_MB_LIB.T6G(SCH_1):PAGE171

PC567 Q_CAP_C0402-2.2UF,10V,10%,X6S,CH5222KEB01
     1 PVDDCR_CPU0_P0_VCC5 @T6G_MB_LIB.T6G(SCH_1):PVDDCR_CPU0_P0_VCC5    I38 @T6G_MB_LIB.T6G(SCH_1):PAGE171
     2    GND @T6G_MB_LIB.T6G(SCH_1):GND    I38 @T6G_MB_LIB.T6G(SCH_1):PAGE171

PC568 Q_CAP_C0402-0.22UF,25V,10%,X7R,CH4224K1B01
     1 SW_P3V3_AUX_BOOTR @T6G_MB_LIB.T6G(SCH_1):SW_P3V3_AUX_BOOTR    I48 @T6G_MB_LIB.T6G(SCH_1):PAGE245
     2 SW_P3V3_AUX_BOOT_R @T6G_MB_LIB.T6G(SCH_1):SW_P3V3_AUX_BOOT_R    I48 @T6G_MB_LIB.T6G(SCH_1):PAGE245

PC568_C0P0_5 Q_CAP_C0402-2.2UF,10V,10%,X6S,CH5222KEB01
     1 PVDDCR_CPU0_P0_PVCC @T6G_MB_LIB.T6G(SCH_1):PVDDCR_CPU0_P0_PVCC    I42 @T6G_MB_LIB.T6G(SCH_1):PAGE171
     2    GND @T6G_MB_LIB.T6G(SCH_1):GND    I42 @T6G_MB_LIB.T6G(SCH_1):PAGE171

PC569 Q_CAP_0402-10PF,50V,1%,NPO,TMP_QCH0106F0B00
     1 P3V3_AUX_FB @T6G_MB_LIB.T6G(SCH_1):P3V3_AUX_FB    I53 @T6G_MB_LIB.T6G(SCH_1):PAGE245
     2 P3V3_AUX @T6G_MB_LIB.T6G(SCH_1):P3V3_AUX    I53 @T6G_MB_LIB.T6G(SCH_1):PAGE245

PC569_5 Q_CAP_C0402-1UF,25V,10%,X6S,CH5104KEB02
     1 SW_P12V_AUX_PVDDCR_CPU0_P0_FLT @T6G_MB_LIB.T6G(SCH_1):SW_P12V_AUX_PVDDCR_CPU0_P0_FLT    I47 @T6G_MB_LIB.T6G(SCH_1):PAGE171
     2    GND @T6G_MB_LIB.T6G(SCH_1):GND    I47 @T6G_MB_LIB.T6G(SCH_1):PAGE171

PC570 Q_CAP_C0805-22UF,16V,20%,X6S,CH6223MEA01
     1 SW_P3V3_AUX_FLT @T6G_MB_LIB.T6G(SCH_1):SW_P3V3_AUX_FLT    I35 @T6G_MB_LIB.T6G(SCH_1):PAGE245
     2    GND @T6G_MB_LIB.T6G(SCH_1):GND    I35 @T6G_MB_LIB.T6G(SCH_1):PAGE245

PC570_5 Q_CAP_0402-0.1UF,25V,10%,X7R,CH4104K1B00
     1 SW_P12V_AUX_PVDDCR_CPU0_P0_FLT @T6G_MB_LIB.T6G(SCH_1):SW_P12V_AUX_PVDDCR_CPU0_P0_FLT    I44 @T6G_MB_LIB.T6G(SCH_1):PAGE171
     2    GND @T6G_MB_LIB.T6G(SCH_1):GND    I44 @T6G_MB_LIB.T6G(SCH_1):PAGE171

PC571 Q_CAP_C0805-22UF,16V,20%,X6S,CH6223MEA01
     1 SW_P3V3_AUX_FLT @T6G_MB_LIB.T6G(SCH_1):SW_P3V3_AUX_FLT    I36 @T6G_MB_LIB.T6G(SCH_1):PAGE245
     2    GND @T6G_MB_LIB.T6G(SCH_1):GND    I36 @T6G_MB_LIB.T6G(SCH_1):PAGE245

PC571_5 Q_CAP_C0805-22UF,16V,20%,X6S,CH6223MEA01
     1 SW_P12V_AUX_PVDDCR_CPU0_P0_FLT @T6G_MB_LIB.T6G(SCH_1):SW_P12V_AUX_PVDDCR_CPU0_P0_FLT    I48 @T6G_MB_LIB.T6G(SCH_1):PAGE171
     2    GND @T6G_MB_LIB.T6G(SCH_1):GND    I48 @T6G_MB_LIB.T6G(SCH_1):PAGE171

PC572_5 Q_CAP_C0805-22UF,16V,20%,X6S,CH6223MEA01
     1 SW_P12V_AUX_PVDDCR_CPU0_P0_FLT @T6G_MB_LIB.T6G(SCH_1):SW_P12V_AUX_PVDDCR_CPU0_P0_FLT    I49 @T6G_MB_LIB.T6G(SCH_1):PAGE171
     2    GND @T6G_MB_LIB.T6G(SCH_1):GND    I49 @T6G_MB_LIB.T6G(SCH_1):PAGE171

PC573_5 Q_CAP_C0805-22UF,16V,20%,X6S,CH6223MEA01
     1 SW_P12V_AUX_PVDDCR_CPU0_P0_FLT @T6G_MB_LIB.T6G(SCH_1):SW_P12V_AUX_PVDDCR_CPU0_P0_FLT    I66 @T6G_MB_LIB.T6G(SCH_1):PAGE171
     2    GND @T6G_MB_LIB.T6G(SCH_1):GND    I66 @T6G_MB_LIB.T6G(SCH_1):PAGE171

PC574 Q_CAP_0402-0.22UF,16V,10%,X7R,CH4223K1B00
     1 SW_PVDDCR_CPU0_P0_BOOT5_RC @T6G_MB_LIB.T6G(SCH_1):SW_PVDDCR_CPU0_P0_BOOT5_RC    I63 @T6G_MB_LIB.T6G(SCH_1):PAGE171
     2 SW_PVDDCR_CPU0_P0_PH5 @T6G_MB_LIB.T6G(SCH_1):SW_PVDDCR_CPU0_P0_PH5    I63 @T6G_MB_LIB.T6G(SCH_1):PAGE171

PC575_5 Q_CAP_C0805-22UF,4V,20%,X6S,CH622KMEA03
     1 PVDDCR_CPU0_P0 @T6G_MB_LIB.T6G(SCH_1):PVDDCR_CPU0_P0    I69 @T6G_MB_LIB.T6G(SCH_1):PAGE171
     2    GND @T6G_MB_LIB.T6G(SCH_1):GND    I69 @T6G_MB_LIB.T6G(SCH_1):PAGE171

PC576 Q_CAP_C0805-22UF,16V,20%,X6S,CH6223MEA01
     1 SW_P3V3_AUX_FLT @T6G_MB_LIB.T6G(SCH_1):SW_P3V3_AUX_FLT    I39 @T6G_MB_LIB.T6G(SCH_1):PAGE245
     2    GND @T6G_MB_LIB.T6G(SCH_1):GND    I39 @T6G_MB_LIB.T6G(SCH_1):PAGE245

PC576_5 Q_CAP_C0805-22UF,4V,20%,X6S,CH622KMEA03
     1 PVDDCR_CPU0_P0 @T6G_MB_LIB.T6G(SCH_1):PVDDCR_CPU0_P0    I71 @T6G_MB_LIB.T6G(SCH_1):PAGE171
     2    GND @T6G_MB_LIB.T6G(SCH_1):GND    I71 @T6G_MB_LIB.T6G(SCH_1):PAGE171

PC577 Q_CAP_0402-0.1UF,25V,10%,X7R,CH4104K1B00
     1 SW_P3V3_AUX_FLT @T6G_MB_LIB.T6G(SCH_1):SW_P3V3_AUX_FLT    I41 @T6G_MB_LIB.T6G(SCH_1):PAGE245
     2    GND @T6G_MB_LIB.T6G(SCH_1):GND    I41 @T6G_MB_LIB.T6G(SCH_1):PAGE245

PC577_7 Q_CAP_0402-0.1UF,25V,10%,X7R,CH4104K1B00
     1 PVDDCR_CPU0_P0_VCCS @T6G_MB_LIB.T6G(SCH_1):PVDDCR_CPU0_P0_VCCS    I29 @T6G_MB_LIB.T6G(SCH_1):PAGE173
     2    GND @T6G_MB_LIB.T6G(SCH_1):GND    I29 @T6G_MB_LIB.T6G(SCH_1):PAGE173

PC578_8 Q_CAP_0402-0.1UF,25V,10%,X7R,CH4104K1B00
     1 PVDDCR_CPU0_P0_VCCS @T6G_MB_LIB.T6G(SCH_1):PVDDCR_CPU0_P0_VCCS     I4 @T6G_MB_LIB.T6G(SCH_1):PAGE173
     2    GND @T6G_MB_LIB.T6G(SCH_1):GND     I4 @T6G_MB_LIB.T6G(SCH_1):PAGE173

PC579 Q_CAP_C0402-2.2UF,10V,10%,X6S,CH5222KEB01
     1 PVDDCR_SOC_P0_VCC1 @T6G_MB_LIB.T6G(SCH_1):PVDDCR_SOC_P0_VCC1    I36 @T6G_MB_LIB.T6G(SCH_1):PAGE173
     2    GND @T6G_MB_LIB.T6G(SCH_1):GND    I36 @T6G_MB_LIB.T6G(SCH_1):PAGE173

PC580 Q_CAP_C0402-2.2UF,10V,10%,X6S,CH5222KEB01
     1 PVDDCR_SOC_P0_VCC2 @T6G_MB_LIB.T6G(SCH_1):PVDDCR_SOC_P0_VCC2    I11 @T6G_MB_LIB.T6G(SCH_1):PAGE173
     2    GND @T6G_MB_LIB.T6G(SCH_1):GND    I11 @T6G_MB_LIB.T6G(SCH_1):PAGE173

PC581 Q_CAP_C0603-4.7UF,16V,10%,X6S,CH5473KE902
     1 P3V3_AUX_VDRV @T6G_MB_LIB.T6G(SCH_1):P3V3_AUX_VDRV    I12 @T6G_MB_LIB.T6G(SCH_1):PAGE245
     2    GND @T6G_MB_LIB.T6G(SCH_1):GND    I12 @T6G_MB_LIB.T6G(SCH_1):PAGE245

PC581_SOP0_1 Q_CAP_C0402-2.2UF,10V,10%,X6S,CH5222KEB01
     1 PVDDCR_CPU0_P0_PVCC @T6G_MB_LIB.T6G(SCH_1):PVDDCR_CPU0_P0_PVCC    I40 @T6G_MB_LIB.T6G(SCH_1):PAGE173
     2    GND @T6G_MB_LIB.T6G(SCH_1):GND    I40 @T6G_MB_LIB.T6G(SCH_1):PAGE173

PC582_SOP0_2 Q_CAP_C0402-2.2UF,10V,10%,X6S,CH5222KEB01
     1 PVDDCR_CPU0_P0_PVCC @T6G_MB_LIB.T6G(SCH_1):PVDDCR_CPU0_P0_PVCC    I14 @T6G_MB_LIB.T6G(SCH_1):PAGE173
     2    GND @T6G_MB_LIB.T6G(SCH_1):GND    I14 @T6G_MB_LIB.T6G(SCH_1):PAGE173

PC583 Q_CAP_0402-0.1UF,25V,10%,X7R,CH4104K1B00
     1 P12V_AUX @T6G_MB_LIB.T6G(SCH_1):P12V_AUX    I77 @T6G_MB_LIB.T6G(SCH_1):PAGE173
     2    GND @T6G_MB_LIB.T6G(SCH_1):GND    I77 @T6G_MB_LIB.T6G(SCH_1):PAGE173

PC583_1 Q_CAP_0402-0.1UF,25V,10%,X7R,CH4104K1B00
     1 SW_P12V_AUX_PVDDCR_SOC_P0_FLT @T6G_MB_LIB.T6G(SCH_1):SW_P12V_AUX_PVDDCR_SOC_P0_FLT    I43 @T6G_MB_LIB.T6G(SCH_1):PAGE173
     2    GND @T6G_MB_LIB.T6G(SCH_1):GND    I43 @T6G_MB_LIB.T6G(SCH_1):PAGE173

PC584_2 Q_CAP_C0402-1UF,25V,10%,X6S,CH5104KEB02
     1 SW_P12V_AUX_PVDDCR_SOC_P0_FLT @T6G_MB_LIB.T6G(SCH_1):SW_P12V_AUX_PVDDCR_SOC_P0_FLT    I23 @T6G_MB_LIB.T6G(SCH_1):PAGE173
     2    GND @T6G_MB_LIB.T6G(SCH_1):GND    I23 @T6G_MB_LIB.T6G(SCH_1):PAGE173

PC585_1 Q_CAP_C0402-1UF,25V,10%,X6S,CH5104KEB02
     1 SW_P12V_AUX_PVDDCR_SOC_P0_FLT @T6G_MB_LIB.T6G(SCH_1):SW_P12V_AUX_PVDDCR_SOC_P0_FLT    I44 @T6G_MB_LIB.T6G(SCH_1):PAGE173
     2    GND @T6G_MB_LIB.T6G(SCH_1):GND    I44 @T6G_MB_LIB.T6G(SCH_1):PAGE173

PC586_2 Q_CAP_0402-0.1UF,25V,10%,X7R,CH4104K1B00
     1 SW_P12V_AUX_PVDDCR_SOC_P0_FLT @T6G_MB_LIB.T6G(SCH_1):SW_P12V_AUX_PVDDCR_SOC_P0_FLT    I21 @T6G_MB_LIB.T6G(SCH_1):PAGE173
     2    GND @T6G_MB_LIB.T6G(SCH_1):GND    I21 @T6G_MB_LIB.T6G(SCH_1):PAGE173

PC587_1 Q_CAP_C0805-22UF,16V,20%,X6S,CH6223MEA01
     1 SW_P12V_AUX_PVDDCR_SOC_P0_FLT @T6G_MB_LIB.T6G(SCH_1):SW_P12V_AUX_PVDDCR_SOC_P0_FLT    I49 @T6G_MB_LIB.T6G(SCH_1):PAGE173
     2    GND @T6G_MB_LIB.T6G(SCH_1):GND    I49 @T6G_MB_LIB.T6G(SCH_1):PAGE173

PC588_2 Q_CAP_C0805-22UF,16V,20%,X6S,CH6223MEA01
     1 SW_P12V_AUX_PVDDCR_SOC_P0_FLT @T6G_MB_LIB.T6G(SCH_1):SW_P12V_AUX_PVDDCR_SOC_P0_FLT    I24 @T6G_MB_LIB.T6G(SCH_1):PAGE173
     2    GND @T6G_MB_LIB.T6G(SCH_1):GND    I24 @T6G_MB_LIB.T6G(SCH_1):PAGE173

PC589_1 Q_CAP_C0805-22UF,16V,20%,X6S,CH6223MEA01
     1 SW_P12V_AUX_PVDDCR_SOC_P0_FLT @T6G_MB_LIB.T6G(SCH_1):SW_P12V_AUX_PVDDCR_SOC_P0_FLT    I50 @T6G_MB_LIB.T6G(SCH_1):PAGE173
     2    GND @T6G_MB_LIB.T6G(SCH_1):GND    I50 @T6G_MB_LIB.T6G(SCH_1):PAGE173

PC590_2 Q_CAP_C0805-22UF,16V,20%,X6S,CH6223MEA01
     1 SW_P12V_AUX_PVDDCR_SOC_P0_FLT @T6G_MB_LIB.T6G(SCH_1):SW_P12V_AUX_PVDDCR_SOC_P0_FLT    I25 @T6G_MB_LIB.T6G(SCH_1):PAGE173
     2    GND @T6G_MB_LIB.T6G(SCH_1):GND    I25 @T6G_MB_LIB.T6G(SCH_1):PAGE173

PC591 Q_CAP_C0603-2.2UF,16V,10%,X6S,CH5223KE901
     1 P3V3_AUX_VCC @T6G_MB_LIB.T6G(SCH_1):P3V3_AUX_VCC    I19 @T6G_MB_LIB.T6G(SCH_1):PAGE245
     2    GND @T6G_MB_LIB.T6G(SCH_1):GND    I19 @T6G_MB_LIB.T6G(SCH_1):PAGE245

PC591_1 Q_CAP_C0805-22UF,16V,20%,X6S,CH6223MEA01
     1 SW_P12V_AUX_PVDDCR_SOC_P0_FLT @T6G_MB_LIB.T6G(SCH_1):SW_P12V_AUX_PVDDCR_SOC_P0_FLT    I51 @T6G_MB_LIB.T6G(SCH_1):PAGE173
     2    GND @T6G_MB_LIB.T6G(SCH_1):GND    I51 @T6G_MB_LIB.T6G(SCH_1):PAGE173

PC592_2 Q_CAP_C0805-22UF,16V,20%,X6S,CH6223MEA01
     1 SW_P12V_AUX_PVDDCR_SOC_P0_FLT @T6G_MB_LIB.T6G(SCH_1):SW_P12V_AUX_PVDDCR_SOC_P0_FLT    I56 @T6G_MB_LIB.T6G(SCH_1):PAGE173
     2    GND @T6G_MB_LIB.T6G(SCH_1):GND    I56 @T6G_MB_LIB.T6G(SCH_1):PAGE173

PC593 Q_CAP_0402-0.22UF,16V,10%,X7R,CH4223K1B00
     1 SW_PVDDCR_SOC_P0_BOOT1_RC @T6G_MB_LIB.T6G(SCH_1):SW_PVDDCR_SOC_P0_BOOT1_RC    I68 @T6G_MB_LIB.T6G(SCH_1):PAGE173
     2 SW_PVDDCR_SOC_P0_PH1 @T6G_MB_LIB.T6G(SCH_1):SW_PVDDCR_SOC_P0_PH1    I68 @T6G_MB_LIB.T6G(SCH_1):PAGE173

PC593_1 Q_CAP_C0805-22UF,16V,20%,X6S,CH6223MEA01
     1 SW_P12V_AUX_PVDDCR_SOC_P0_FLT @T6G_MB_LIB.T6G(SCH_1):SW_P12V_AUX_PVDDCR_SOC_P0_FLT    I72 @T6G_MB_LIB.T6G(SCH_1):PAGE173
     2    GND @T6G_MB_LIB.T6G(SCH_1):GND    I72 @T6G_MB_LIB.T6G(SCH_1):PAGE173

PC594 Q_CAP_0402-0.22UF,16V,10%,X7R,CH4223K1B00
     1 SW_PVDDCR_SOC_P0_BOOT2_RC @T6G_MB_LIB.T6G(SCH_1):SW_PVDDCR_SOC_P0_BOOT2_RC    I52 @T6G_MB_LIB.T6G(SCH_1):PAGE173
     2 SW_PVDDCR_SOC_P0_PH2 @T6G_MB_LIB.T6G(SCH_1):SW_PVDDCR_SOC_P0_PH2    I52 @T6G_MB_LIB.T6G(SCH_1):PAGE173

PC595_2 Q_CAP_C0805-22UF,16V,20%,X6S,CH6223MEA01
     1 SW_P12V_AUX_PVDDCR_SOC_P0_FLT @T6G_MB_LIB.T6G(SCH_1):SW_P12V_AUX_PVDDCR_SOC_P0_FLT    I57 @T6G_MB_LIB.T6G(SCH_1):PAGE173
     2    GND @T6G_MB_LIB.T6G(SCH_1):GND    I57 @T6G_MB_LIB.T6G(SCH_1):PAGE173

PC596 Q_CAPP_THLF-270UF,16V,20%,OSCON,CC72703MD38
     1 SW_P12V_AUX_PVDDCR_SOC_P0_FLT @T6G_MB_LIB.T6G(SCH_1):SW_P12V_AUX_PVDDCR_SOC_P0_FLT    I73 @T6G_MB_LIB.T6G(SCH_1):PAGE173
     2    GND @T6G_MB_LIB.T6G(SCH_1):GND    I73 @T6G_MB_LIB.T6G(SCH_1):PAGE173

PC597 Q_CAPP_SMLF-470UF,2.5V,20%,EMPTY,CH747LM8825
     1 PVDDCR_SOC_P0 @T6G_MB_LIB.T6G(SCH_1):PVDDCR_SOC_P0    I63 @T6G_MB_LIB.T6G(SCH_1):PAGE173
     2    GND @T6G_MB_LIB.T6G(SCH_1):GND    I63 @T6G_MB_LIB.T6G(SCH_1):PAGE173

PC598 Q_CAPP_SMLF-470UF,2.5V,20%,SPCAP,CH747LM8825
     1 PVDDCR_SOC_P0 @T6G_MB_LIB.T6G(SCH_1):PVDDCR_SOC_P0    I64 @T6G_MB_LIB.T6G(SCH_1):PAGE173
     2    GND @T6G_MB_LIB.T6G(SCH_1):GND    I64 @T6G_MB_LIB.T6G(SCH_1):PAGE173

PC599 Q_CAP_0402-0.1UF,25V,10%,X7R,CH4104K1B00
     1 PVDDCR_SOC_P0 @T6G_MB_LIB.T6G(SCH_1):PVDDCR_SOC_P0    I79 @T6G_MB_LIB.T6G(SCH_1):PAGE173
     2    GND @T6G_MB_LIB.T6G(SCH_1):GND    I79 @T6G_MB_LIB.T6G(SCH_1):PAGE173

PC600_2 Q_CAP_C0805-22UF,4V,20%,X6S,CH622KMEA03
     1 PVDDCR_SOC_P0 @T6G_MB_LIB.T6G(SCH_1):PVDDCR_SOC_P0    I59 @T6G_MB_LIB.T6G(SCH_1):PAGE173
     2    GND @T6G_MB_LIB.T6G(SCH_1):GND    I59 @T6G_MB_LIB.T6G(SCH_1):PAGE173

PC601 Q_CAPP_SMLF-470UF,2.5V,20%,SPCAP,CH747LM8825
     1 PVDDCR_SOC_P0 @T6G_MB_LIB.T6G(SCH_1):PVDDCR_SOC_P0    I66 @T6G_MB_LIB.T6G(SCH_1):PAGE173
     2    GND @T6G_MB_LIB.T6G(SCH_1):GND    I66 @T6G_MB_LIB.T6G(SCH_1):PAGE173

PC602_1 Q_CAP_C0805-22UF,4V,20%,X6S,CH622KMEA03
     1 PVDDCR_SOC_P0 @T6G_MB_LIB.T6G(SCH_1):PVDDCR_SOC_P0    I80 @T6G_MB_LIB.T6G(SCH_1):PAGE173
     2    GND @T6G_MB_LIB.T6G(SCH_1):GND    I80 @T6G_MB_LIB.T6G(SCH_1):PAGE173

PC603_2 Q_CAP_C0805-22UF,4V,20%,X6S,CH622KMEA03
     1 PVDDCR_SOC_P0 @T6G_MB_LIB.T6G(SCH_1):PVDDCR_SOC_P0    I61 @T6G_MB_LIB.T6G(SCH_1):PAGE173
     2    GND @T6G_MB_LIB.T6G(SCH_1):GND    I61 @T6G_MB_LIB.T6G(SCH_1):PAGE173

PC604_1 Q_CAP_C0805-22UF,4V,20%,X6S,CH622KMEA03
     1 PVDDCR_SOC_P0 @T6G_MB_LIB.T6G(SCH_1):PVDDCR_SOC_P0    I83 @T6G_MB_LIB.T6G(SCH_1):PAGE173
     2    GND @T6G_MB_LIB.T6G(SCH_1):GND    I83 @T6G_MB_LIB.T6G(SCH_1):PAGE173

PC605_9 Q_CAP_0402-0.1UF,25V,10%,X7R,CH4104K1B00
     1 PVDDCR_CPU0_P0_VCCS @T6G_MB_LIB.T6G(SCH_1):PVDDCR_CPU0_P0_VCCS     I2 @T6G_MB_LIB.T6G(SCH_1):PAGE174
     2    GND @T6G_MB_LIB.T6G(SCH_1):GND     I2 @T6G_MB_LIB.T6G(SCH_1):PAGE174

PC606 Q_CAP_C0402-2.2UF,10V,10%,X6S,CH5222KEB01
     1 PVDDCR_SOC_P0_VCC3 @T6G_MB_LIB.T6G(SCH_1):PVDDCR_SOC_P0_VCC3    I14 @T6G_MB_LIB.T6G(SCH_1):PAGE174
     2    GND @T6G_MB_LIB.T6G(SCH_1):GND    I14 @T6G_MB_LIB.T6G(SCH_1):PAGE174

PC607_SOP0_3 Q_CAP_C0402-2.2UF,10V,10%,X6S,CH5222KEB01
     1 PVDDCR_CPU0_P0_PVCC @T6G_MB_LIB.T6G(SCH_1):PVDDCR_CPU0_P0_PVCC    I19 @T6G_MB_LIB.T6G(SCH_1):PAGE174
     2    GND @T6G_MB_LIB.T6G(SCH_1):GND    I19 @T6G_MB_LIB.T6G(SCH_1):PAGE174

PC608_3 Q_CAP_C0402-1UF,25V,10%,X6S,CH5104KEB02
     1 SW_P12V_AUX_PVDDCR_SOC_P0_FLT @T6G_MB_LIB.T6G(SCH_1):SW_P12V_AUX_PVDDCR_SOC_P0_FLT    I21 @T6G_MB_LIB.T6G(SCH_1):PAGE174
     2    GND @T6G_MB_LIB.T6G(SCH_1):GND    I21 @T6G_MB_LIB.T6G(SCH_1):PAGE174

PC609_3 Q_CAP_0402-0.1UF,25V,10%,X7R,CH4104K1B00
     1 SW_P12V_AUX_PVDDCR_SOC_P0_FLT @T6G_MB_LIB.T6G(SCH_1):SW_P12V_AUX_PVDDCR_SOC_P0_FLT    I37 @T6G_MB_LIB.T6G(SCH_1):PAGE174
     2    GND @T6G_MB_LIB.T6G(SCH_1):GND    I37 @T6G_MB_LIB.T6G(SCH_1):PAGE174

PC610_3 Q_CAP_C0805-22UF,16V,20%,X6S,CH6223MEA01
     1 SW_P12V_AUX_PVDDCR_SOC_P0_FLT @T6G_MB_LIB.T6G(SCH_1):SW_P12V_AUX_PVDDCR_SOC_P0_FLT    I22 @T6G_MB_LIB.T6G(SCH_1):PAGE174
     2    GND @T6G_MB_LIB.T6G(SCH_1):GND    I22 @T6G_MB_LIB.T6G(SCH_1):PAGE174

PC611_3 Q_CAP_C0805-22UF,16V,20%,X6S,CH6223MEA01
     1 SW_P12V_AUX_PVDDCR_SOC_P0_FLT @T6G_MB_LIB.T6G(SCH_1):SW_P12V_AUX_PVDDCR_SOC_P0_FLT    I31 @T6G_MB_LIB.T6G(SCH_1):PAGE174
     2    GND @T6G_MB_LIB.T6G(SCH_1):GND    I31 @T6G_MB_LIB.T6G(SCH_1):PAGE174

PC612 Q_CAP_0402-0.22UF,16V,10%,X7R,CH4223K1B00
     1 SW_PVDDCR_SOC_P0_BOOT3_RC @T6G_MB_LIB.T6G(SCH_1):SW_PVDDCR_SOC_P0_BOOT3_RC    I30 @T6G_MB_LIB.T6G(SCH_1):PAGE174
     2 SW_PVDDCR_SOC_P0_PH3 @T6G_MB_LIB.T6G(SCH_1):SW_PVDDCR_SOC_P0_PH3    I30 @T6G_MB_LIB.T6G(SCH_1):PAGE174

PC612_3 Q_CAP_C0805-22UF,16V,20%,X6S,CH6223MEA01
     1 SW_P12V_AUX_PVDDCR_SOC_P0_FLT @T6G_MB_LIB.T6G(SCH_1):SW_P12V_AUX_PVDDCR_SOC_P0_FLT    I34 @T6G_MB_LIB.T6G(SCH_1):PAGE174
     2    GND @T6G_MB_LIB.T6G(SCH_1):GND    I34 @T6G_MB_LIB.T6G(SCH_1):PAGE174

PC613_3 Q_CAP_C0805-22UF,16V,20%,X6S,CH6223MEA01
     1 SW_P12V_AUX_PVDDCR_SOC_P0_FLT @T6G_MB_LIB.T6G(SCH_1):SW_P12V_AUX_PVDDCR_SOC_P0_FLT    I32 @T6G_MB_LIB.T6G(SCH_1):PAGE174
     2    GND @T6G_MB_LIB.T6G(SCH_1):GND    I32 @T6G_MB_LIB.T6G(SCH_1):PAGE174

PC614_3 Q_CAP_C0805-22UF,4V,20%,X6S,CH622KMEA03
     1 PVDDCR_SOC_P0 @T6G_MB_LIB.T6G(SCH_1):PVDDCR_SOC_P0    I27 @T6G_MB_LIB.T6G(SCH_1):PAGE174
     2    GND @T6G_MB_LIB.T6G(SCH_1):GND    I27 @T6G_MB_LIB.T6G(SCH_1):PAGE174

PC615_3 Q_CAP_C0805-22UF,4V,20%,X6S,CH622KMEA03
     1 PVDDCR_SOC_P0 @T6G_MB_LIB.T6G(SCH_1):PVDDCR_SOC_P0    I29 @T6G_MB_LIB.T6G(SCH_1):PAGE174
     2    GND @T6G_MB_LIB.T6G(SCH_1):GND    I29 @T6G_MB_LIB.T6G(SCH_1):PAGE174

PC616 Q_CAP_C0402-2.2UF,10V,10%,X6S,CH5222KEB01
     1 PVDDIO_P1_VCC4 @T6G_MB_LIB.T6G(SCH_1):PVDDIO_P1_VCC4    I10 @T6G_MB_LIB.T6G(SCH_1):PAGE198
     2    GND @T6G_MB_LIB.T6G(SCH_1):GND    I10 @T6G_MB_LIB.T6G(SCH_1):PAGE198

PC617 Q_CAP_C0402-2.2UF,10V,10%,X6S,CH5222KEB01
     1 PVDDIO_P1_VCC3 @T6G_MB_LIB.T6G(SCH_1):PVDDIO_P1_VCC3    I28 @T6G_MB_LIB.T6G(SCH_1):PAGE198
     2    GND @T6G_MB_LIB.T6G(SCH_1):GND    I28 @T6G_MB_LIB.T6G(SCH_1):PAGE198

PC618_IOP1_4 Q_CAP_C0402-2.2UF,10V,10%,X6S,CH5222KEB01
     1 PVDDCR_CPU1_P1_PVCC @T6G_MB_LIB.T6G(SCH_1):PVDDCR_CPU1_P1_PVCC    I13 @T6G_MB_LIB.T6G(SCH_1):PAGE198
     2    GND @T6G_MB_LIB.T6G(SCH_1):GND    I13 @T6G_MB_LIB.T6G(SCH_1):PAGE198

PC619_IOP1_3 Q_CAP_C0402-2.2UF,10V,10%,X6S,CH5222KEB01
     1 PVDDCR_CPU1_P1_PVCC @T6G_MB_LIB.T6G(SCH_1):PVDDCR_CPU1_P1_PVCC    I31 @T6G_MB_LIB.T6G(SCH_1):PAGE198
     2    GND @T6G_MB_LIB.T6G(SCH_1):GND    I31 @T6G_MB_LIB.T6G(SCH_1):PAGE198

PC620_9 Q_CAP_0402-0.1UF,25V,10%,X7R,CH4104K1B00
     1 PVDDCR_CPU1_P1_VCCS @T6G_MB_LIB.T6G(SCH_1):PVDDCR_CPU1_P1_VCCS    I20 @T6G_MB_LIB.T6G(SCH_1):PAGE198
     2    GND @T6G_MB_LIB.T6G(SCH_1):GND    I20 @T6G_MB_LIB.T6G(SCH_1):PAGE198

PC621_10 Q_CAP_0402-0.1UF,25V,10%,X7R,CH4104K1B00
     1 PVDDCR_CPU1_P1_VCCS @T6G_MB_LIB.T6G(SCH_1):PVDDCR_CPU1_P1_VCCS     I2 @T6G_MB_LIB.T6G(SCH_1):PAGE198
     2    GND @T6G_MB_LIB.T6G(SCH_1):GND     I2 @T6G_MB_LIB.T6G(SCH_1):PAGE198

PC622_3 Q_CAP_0402-0.1UF,25V,10%,X7R,CH4104K1B00
     1 SW_P12V_AUX_PVDDIO_P1_FLT @T6G_MB_LIB.T6G(SCH_1):SW_P12V_AUX_PVDDIO_P1_FLT    I35 @T6G_MB_LIB.T6G(SCH_1):PAGE198
     2    GND @T6G_MB_LIB.T6G(SCH_1):GND    I35 @T6G_MB_LIB.T6G(SCH_1):PAGE198

PC623_4 Q_CAP_0402-0.1UF,25V,10%,X7R,CH4104K1B00
     1 SW_P12V_AUX_PVDDIO_P1_FLT @T6G_MB_LIB.T6G(SCH_1):SW_P12V_AUX_PVDDIO_P1_FLT    I18 @T6G_MB_LIB.T6G(SCH_1):PAGE198
     2    GND @T6G_MB_LIB.T6G(SCH_1):GND    I18 @T6G_MB_LIB.T6G(SCH_1):PAGE198

PC624_3 Q_CAP_C0402-1UF,25V,10%,X6S,CH5104KEB02
     1 SW_P12V_AUX_PVDDIO_P1_FLT @T6G_MB_LIB.T6G(SCH_1):SW_P12V_AUX_PVDDIO_P1_FLT    I36 @T6G_MB_LIB.T6G(SCH_1):PAGE198
     2    GND @T6G_MB_LIB.T6G(SCH_1):GND    I36 @T6G_MB_LIB.T6G(SCH_1):PAGE198

PC625_4 Q_CAP_C0402-1UF,25V,10%,X6S,CH5104KEB02
     1 SW_P12V_AUX_PVDDIO_P1_FLT @T6G_MB_LIB.T6G(SCH_1):SW_P12V_AUX_PVDDIO_P1_FLT    I45 @T6G_MB_LIB.T6G(SCH_1):PAGE198
     2    GND @T6G_MB_LIB.T6G(SCH_1):GND    I45 @T6G_MB_LIB.T6G(SCH_1):PAGE198

PC626_3 Q_CAP_C0805-22UF,16V,20%,X6S,CH6223MEA01
     1 SW_P12V_AUX_PVDDIO_P1_FLT @T6G_MB_LIB.T6G(SCH_1):SW_P12V_AUX_PVDDIO_P1_FLT    I60 @T6G_MB_LIB.T6G(SCH_1):PAGE198
     2    GND @T6G_MB_LIB.T6G(SCH_1):GND    I60 @T6G_MB_LIB.T6G(SCH_1):PAGE198

PC627_4 Q_CAP_C0805-22UF,16V,20%,X6S,CH6223MEA01
     1 SW_P12V_AUX_PVDDIO_P1_FLT @T6G_MB_LIB.T6G(SCH_1):SW_P12V_AUX_PVDDIO_P1_FLT    I72 @T6G_MB_LIB.T6G(SCH_1):PAGE198
     2    GND @T6G_MB_LIB.T6G(SCH_1):GND    I72 @T6G_MB_LIB.T6G(SCH_1):PAGE198

PC628_3 Q_CAP_C0805-22UF,16V,20%,X6S,CH6223MEA01
     1 SW_P12V_AUX_PVDDIO_P1_FLT @T6G_MB_LIB.T6G(SCH_1):SW_P12V_AUX_PVDDIO_P1_FLT    I61 @T6G_MB_LIB.T6G(SCH_1):PAGE198
     2    GND @T6G_MB_LIB.T6G(SCH_1):GND    I61 @T6G_MB_LIB.T6G(SCH_1):PAGE198

PC629_4 Q_CAP_C0805-22UF,16V,20%,X6S,CH6223MEA01
     1 SW_P12V_AUX_PVDDIO_P1_FLT @T6G_MB_LIB.T6G(SCH_1):SW_P12V_AUX_PVDDIO_P1_FLT    I46 @T6G_MB_LIB.T6G(SCH_1):PAGE198
     2    GND @T6G_MB_LIB.T6G(SCH_1):GND    I46 @T6G_MB_LIB.T6G(SCH_1):PAGE198

PC630 Q_CAP_0402-0.22UF,16V,10%,X7R,CH4223K1B00
     1 SW_PVDDIO_P1_BOOT4_R @T6G_MB_LIB.T6G(SCH_1):SW_PVDDIO_P1_BOOT4_R    I44 @T6G_MB_LIB.T6G(SCH_1):PAGE198
     2 SW_PVDDIO_P1_BOOTR4 @T6G_MB_LIB.T6G(SCH_1):SW_PVDDIO_P1_BOOTR4    I44 @T6G_MB_LIB.T6G(SCH_1):PAGE198

PC631 Q_CAP_0402-0.22UF,16V,10%,X7R,CH4223K1B00
     1 SW_PVDDIO_P1_BOOT3_R @T6G_MB_LIB.T6G(SCH_1):SW_PVDDIO_P1_BOOT3_R    I63 @T6G_MB_LIB.T6G(SCH_1):PAGE198
     2 SW_PVDDIO_P1_BOOTR3 @T6G_MB_LIB.T6G(SCH_1):SW_PVDDIO_P1_BOOTR3    I63 @T6G_MB_LIB.T6G(SCH_1):PAGE198

PC632_3 Q_CAP_C0805-22UF,16V,20%,X6S,CH6223MEA01
     1 SW_P12V_AUX_PVDDIO_P1_FLT @T6G_MB_LIB.T6G(SCH_1):SW_P12V_AUX_PVDDIO_P1_FLT    I65 @T6G_MB_LIB.T6G(SCH_1):PAGE198
     2    GND @T6G_MB_LIB.T6G(SCH_1):GND    I65 @T6G_MB_LIB.T6G(SCH_1):PAGE198

PC633_4 Q_CAP_C0805-22UF,16V,20%,X6S,CH6223MEA01
     1 SW_P12V_AUX_PVDDIO_P1_FLT @T6G_MB_LIB.T6G(SCH_1):SW_P12V_AUX_PVDDIO_P1_FLT    I48 @T6G_MB_LIB.T6G(SCH_1):PAGE198
     2    GND @T6G_MB_LIB.T6G(SCH_1):GND    I48 @T6G_MB_LIB.T6G(SCH_1):PAGE198

PC634_4 Q_CAP_C0805-22UF,4V,20%,X6S,CH622KMEA03
     1 PVDDIO_P1 @T6G_MB_LIB.T6G(SCH_1):PVDDIO_P1    I51 @T6G_MB_LIB.T6G(SCH_1):PAGE198
     2    GND @T6G_MB_LIB.T6G(SCH_1):GND    I51 @T6G_MB_LIB.T6G(SCH_1):PAGE198

PC635_3 Q_CAP_C0805-22UF,4V,20%,X6S,CH622KMEA03
     1 PVDDIO_P1 @T6G_MB_LIB.T6G(SCH_1):PVDDIO_P1    I68 @T6G_MB_LIB.T6G(SCH_1):PAGE198
     2    GND @T6G_MB_LIB.T6G(SCH_1):GND    I68 @T6G_MB_LIB.T6G(SCH_1):PAGE198

PC636_4 Q_CAP_C0805-22UF,4V,20%,X6S,CH622KMEA03
     1 PVDDIO_P1 @T6G_MB_LIB.T6G(SCH_1):PVDDIO_P1    I53 @T6G_MB_LIB.T6G(SCH_1):PAGE198
     2    GND @T6G_MB_LIB.T6G(SCH_1):GND    I53 @T6G_MB_LIB.T6G(SCH_1):PAGE198

PC637_3 Q_CAP_C0805-22UF,4V,20%,X6S,CH622KMEA03
     1 PVDDIO_P1 @T6G_MB_LIB.T6G(SCH_1):PVDDIO_P1    I70 @T6G_MB_LIB.T6G(SCH_1):PAGE198
     2    GND @T6G_MB_LIB.T6G(SCH_1):GND    I70 @T6G_MB_LIB.T6G(SCH_1):PAGE198

PC638 Q_CAP_0402-0.1UF,25V,10%,X7R,CH4104K1B00
     1 PVDD11_S3_P1_VMON @T6G_MB_LIB.T6G(SCH_1):PVDD11_S3_P1_VMON     I4 @T6G_MB_LIB.T6G(SCH_1):PAGE199
     2    GND @T6G_MB_LIB.T6G(SCH_1):GND     I4 @T6G_MB_LIB.T6G(SCH_1):PAGE199

PC639 Q_CAP_0402-3300PF,50V,10%,X7R,TMP_QCH2336K1B12
     1 VSENSE_PVDD11_S3_P1_R @T6G_MB_LIB.T6G(SCH_1):VSENSE_PVDD11_S3_P1_R    I28 @T6G_MB_LIB.T6G(SCH_1):PAGE199
     2 VSENSE_VSS_SENSE_C_P1 @T6G_MB_LIB.T6G(SCH_1):VSENSE_VSS_SENSE_C_P1    I28 @T6G_MB_LIB.T6G(SCH_1):PAGE199

PC641 Q_CAP_C0402-0.22UF,25V,10%,X7R,CH4224K1B01
     1 SW_P1V8_AUX_BT_R @T6G_MB_LIB.T6G(SCH_1):SW_P1V8_AUX_BT_R    I30 @T6G_MB_LIB.T6G(SCH_1):PAGE315
     2 SW_P1V8_AUX_PH @T6G_MB_LIB.T6G(SCH_1):SW_P1V8_AUX_PH    I30 @T6G_MB_LIB.T6G(SCH_1):PAGE315

PC643 Q_CAP_0402-470PF,50V,10%,X7R,TMP_QCH14706KB18
     1 PVDD11_S3_P1_TEMP0 @T6G_MB_LIB.T6G(SCH_1):PVDD11_S3_P1_TEMP0    I49 @T6G_MB_LIB.T6G(SCH_1):PAGE199
     2    GND @T6G_MB_LIB.T6G(SCH_1):GND    I49 @T6G_MB_LIB.T6G(SCH_1):PAGE199

PC644 Q_CAP_C0402-10UF,6.3V,20%,X6S,CH6101MEB03
     1 PVDD11_S3_P1_VCCS @T6G_MB_LIB.T6G(SCH_1):PVDD11_S3_P1_VCCS    I80 @T6G_MB_LIB.T6G(SCH_1):PAGE199
     2    GND @T6G_MB_LIB.T6G(SCH_1):GND    I80 @T6G_MB_LIB.T6G(SCH_1):PAGE199

PC645 Q_CAP_C0402-1UF,16V,10%,X6S,CH5103KEB01
     1 PVDD11_S3_P1_VCC @T6G_MB_LIB.T6G(SCH_1):PVDD11_S3_P1_VCC    I81 @T6G_MB_LIB.T6G(SCH_1):PAGE199
     2    GND @T6G_MB_LIB.T6G(SCH_1):GND    I81 @T6G_MB_LIB.T6G(SCH_1):PAGE199

PC800 Q_CAPP_SMLF-470UF,2.5V,20%,SPCAP,CH747LM8825
     1 PVDD11_S3_P0 @T6G_MB_LIB.T6G(SCH_1):PVDD11_S3_P0    I89 @T6G_MB_LIB.T6G(SCH_1):PAGE183
     2    GND @T6G_MB_LIB.T6G(SCH_1):GND    I89 @T6G_MB_LIB.T6G(SCH_1):PAGE183

PC801 Q_CAPP_SMLF-390UF,2.5V,20%,ALUM,CC7390JMZ13
     1 PVDD11_S3_P0 @T6G_MB_LIB.T6G(SCH_1):PVDD11_S3_P0    I70 @T6G_MB_LIB.T6G(SCH_1):PAGE183
     2    GND @T6G_MB_LIB.T6G(SCH_1):GND    I70 @T6G_MB_LIB.T6G(SCH_1):PAGE183

PC802 Q_CAPP_SMLF-470UF,2.5V,20%,SPCAP,CH747LM8825
     1 PVDD11_S3_P1 @T6G_MB_LIB.T6G(SCH_1):PVDD11_S3_P1    I65 @T6G_MB_LIB.T6G(SCH_1):PAGE200
     2    GND @T6G_MB_LIB.T6G(SCH_1):GND    I65 @T6G_MB_LIB.T6G(SCH_1):PAGE200

PC803 Q_CAPP_SMLF-390UF,2.5V,20%,ALUM,CC7390JMZ13
     1 PVDD11_S3_P1 @T6G_MB_LIB.T6G(SCH_1):PVDD11_S3_P1    I75 @T6G_MB_LIB.T6G(SCH_1):PAGE200
     2    GND @T6G_MB_LIB.T6G(SCH_1):GND    I75 @T6G_MB_LIB.T6G(SCH_1):PAGE200

PC819 Q_CAP_0402-0.1UF,25V,10%,X7R,CH4104K1B00
     1 P0V9_RETIMER_CPU1_VINSEN @T6G_MB_LIB.T6G(SCH_1):P0V9_RETIMER_CPU1_VINSEN    I48 @T6G_MB_LIB.T6G(SCH_1):PAGE477
     2    GND @T6G_MB_LIB.T6G(SCH_1):GND    I48 @T6G_MB_LIB.T6G(SCH_1):PAGE477

PC850 Q_CAP_C0805-22UF,4V,20%,X6S,CH622KMEA03
     1 P1V8_AUX @T6G_MB_LIB.T6G(SCH_1):P1V8_AUX    I37 @T6G_MB_LIB.T6G(SCH_1):PAGE315
     2    GND @T6G_MB_LIB.T6G(SCH_1):GND    I37 @T6G_MB_LIB.T6G(SCH_1):PAGE315

PC852 Q_CAP_0402-330PF,50V,10%,X7R,CH1336K1B02
     1 P1V2_AUX_FB @T6G_MB_LIB.T6G(SCH_1):P1V2_AUX_FB    I26 @T6G_MB_LIB.T6G(SCH_1):PAGE380
     2 P1V2_AUX @T6G_MB_LIB.T6G(SCH_1):P1V2_AUX    I26 @T6G_MB_LIB.T6G(SCH_1):PAGE380

PC865 Q_CAP_C0805-22UF,4V,20%,X6S,CH622KMEA03
     1 P1V8_AUX @T6G_MB_LIB.T6G(SCH_1):P1V8_AUX    I29 @T6G_MB_LIB.T6G(SCH_1):PAGE315
     2    GND @T6G_MB_LIB.T6G(SCH_1):GND    I29 @T6G_MB_LIB.T6G(SCH_1):PAGE315

PC866 Q_CAP_C0805-22UF,4V,20%,X6S,CH622KMEA03
     1 P1V8_AUX @T6G_MB_LIB.T6G(SCH_1):P1V8_AUX    I34 @T6G_MB_LIB.T6G(SCH_1):PAGE315
     2    GND @T6G_MB_LIB.T6G(SCH_1):GND    I34 @T6G_MB_LIB.T6G(SCH_1):PAGE315

PC867 Q_CAP_C0805-22UF,4V,20%,X6S,CH622KMEA03
     1 P1V8_AUX @T6G_MB_LIB.T6G(SCH_1):P1V8_AUX    I36 @T6G_MB_LIB.T6G(SCH_1):PAGE315
     2    GND @T6G_MB_LIB.T6G(SCH_1):GND    I36 @T6G_MB_LIB.T6G(SCH_1):PAGE315

PC1320 Q_CAP_C0603-2.2UF,16V,20%,X7R,CH5223M1900
     1 P12V_OCP_AVIN_PD_2 @T6G_MB_LIB.T6G(SCH_1):P12V_OCP_AVIN_PD_2    I24 @T6G_MB_LIB.T6G(SCH_1):PAGE344
     2    GND @T6G_MB_LIB.T6G(SCH_1):GND    I24 @T6G_MB_LIB.T6G(SCH_1):PAGE344

PC1321 Q_CAP_0402-0.068UF,16V,10%,X7R,CH3683K1B09
     1 P3V3_OCP_DVDT_2 @T6G_MB_LIB.T6G(SCH_1):P3V3_OCP_DVDT_2    I50 @T6G_MB_LIB.T6G(SCH_1):PAGE344
     2    GND @T6G_MB_LIB.T6G(SCH_1):GND    I50 @T6G_MB_LIB.T6G(SCH_1):PAGE344

PC1322 Q_CAP_0402-100PF,50V,5%,X7R,CH11006JB18
     1 P3V3_OCP_GATE_PU207_2 @T6G_MB_LIB.T6G(SCH_1):P3V3_OCP_GATE_PU207_2    I54 @T6G_MB_LIB.T6G(SCH_1):PAGE344
     2    GND @T6G_MB_LIB.T6G(SCH_1):GND    I54 @T6G_MB_LIB.T6G(SCH_1):PAGE344

PC1525 Q_CAP_C0402-1UF,25V,10%,X6S,CH5104KEB02
     1 HSC_VDD_R_1 @T6G_MB_LIB.T6G(SCH_1):HSC_VDD_R_1    I20 @T6G_MB_LIB.T6G(SCH_1):PAGE301
     2 AGND_HSC @T6G_MB_LIB.T6G(SCH_1):AGND_HSC    I20 @T6G_MB_LIB.T6G(SCH_1):PAGE301

PC1599 Q_CAP_C0805-22UF,10V,20%,X6S,CH6222MEA01
     1 P3V3_AUX @T6G_MB_LIB.T6G(SCH_1):P3V3_AUX    I60 @T6G_MB_LIB.T6G(SCH_1):PAGE245
     2    GND @T6G_MB_LIB.T6G(SCH_1):GND    I60 @T6G_MB_LIB.T6G(SCH_1):PAGE245

PC1600 Q_CAP_C0805-22UF,10V,20%,X6S,CH6222MEA01
     1 P3V3_AUX @T6G_MB_LIB.T6G(SCH_1):P3V3_AUX    I62 @T6G_MB_LIB.T6G(SCH_1):PAGE245
     2    GND @T6G_MB_LIB.T6G(SCH_1):GND    I62 @T6G_MB_LIB.T6G(SCH_1):PAGE245

PC1648 Q_CAP_C0402-0.1UF,25V,10%,X6S,CH4104KEB00
     1 P12V_AUX @T6G_MB_LIB.T6G(SCH_1):P12V_AUX     I2 @T6G_MB_LIB.T6G(SCH_1):PAGE244
     2    GND @T6G_MB_LIB.T6G(SCH_1):GND     I2 @T6G_MB_LIB.T6G(SCH_1):PAGE244

PC1649 Q_CAP_C0402-0.1UF,25V,10%,X6S,CH4104KEB00
     1 P12V_AUX @T6G_MB_LIB.T6G(SCH_1):P12V_AUX    I23 @T6G_MB_LIB.T6G(SCH_1):PAGE245
     2    GND @T6G_MB_LIB.T6G(SCH_1):GND    I23 @T6G_MB_LIB.T6G(SCH_1):PAGE245

PC1750 Q_CAP_C0402-33NF,25V,10%,EMPTY,CH3334K1B00
     1 P12V_AUX @T6G_MB_LIB.T6G(SCH_1):P12V_AUX    I63 @T6G_MB_LIB.T6G(SCH_1):PAGE302
     2 P12V_HSC_GATE2 @T6G_MB_LIB.T6G(SCH_1):P12V_HSC_GATE2    I63 @T6G_MB_LIB.T6G(SCH_1):PAGE302

PC1751 Q_CAP_0402-1NF,50V,10%,EMPTY,CH21006KB16
     1 P12V_HSC_GATE_RC @T6G_MB_LIB.T6G(SCH_1):P12V_HSC_GATE_RC    I70 @T6G_MB_LIB.T6G(SCH_1):PAGE302
     2 P12V_HSC_GATE2 @T6G_MB_LIB.T6G(SCH_1):P12V_HSC_GATE2    I70 @T6G_MB_LIB.T6G(SCH_1):PAGE302

PC1789 Q_CAP_0402-0.1UF,25V,10%,X7R,CH4104K1B00
     1 P12V_AUX @T6G_MB_LIB.T6G(SCH_1):P12V_AUX    I28 @T6G_MB_LIB.T6G(SCH_1):PAGE371
     2    GND @T6G_MB_LIB.T6G(SCH_1):GND    I28 @T6G_MB_LIB.T6G(SCH_1):PAGE371

PC1845 Q_CAPP_SMLF-220UF,6.3V,20%,ALUM,CC72201MZ28
     1 P5V_AUX @T6G_MB_LIB.T6G(SCH_1):P5V_AUX    I30 @T6G_MB_LIB.T6G(SCH_1):PAGE244
     2    GND @T6G_MB_LIB.T6G(SCH_1):GND    I30 @T6G_MB_LIB.T6G(SCH_1):PAGE244

PC1846 Q_CAP_C0402-1UF,16V,10%,X6S,CH5103KEB01
     1 SW_P5V_AUX_FLT @T6G_MB_LIB.T6G(SCH_1):SW_P5V_AUX_FLT    I13 @T6G_MB_LIB.T6G(SCH_1):PAGE244
     2    GND @T6G_MB_LIB.T6G(SCH_1):GND    I13 @T6G_MB_LIB.T6G(SCH_1):PAGE244

PC1847 Q_CAP_C0402-0.22UF,25V,10%,X7R,CH4224K1B01
     1 SW_P5V_AUX_BST @T6G_MB_LIB.T6G(SCH_1):SW_P5V_AUX_BST    I24 @T6G_MB_LIB.T6G(SCH_1):PAGE244
     2 SW_P5V_AUX_SW @T6G_MB_LIB.T6G(SCH_1):SW_P5V_AUX_SW    I24 @T6G_MB_LIB.T6G(SCH_1):PAGE244

PC1848 Q_CAP_C0402-1UF,25V,10%,X6S,CH5104KEB02
     1 P5V_AUX_VCC @T6G_MB_LIB.T6G(SCH_1):P5V_AUX_VCC     I8 @T6G_MB_LIB.T6G(SCH_1):PAGE244
     2    GND @T6G_MB_LIB.T6G(SCH_1):GND     I8 @T6G_MB_LIB.T6G(SCH_1):PAGE244

PC1849 Q_CAP_C0805-22UF,16V,20%,X6S,CH6223MEA01
     1 SW_P5V_AUX_FLT @T6G_MB_LIB.T6G(SCH_1):SW_P5V_AUX_FLT     I7 @T6G_MB_LIB.T6G(SCH_1):PAGE244
     2    GND @T6G_MB_LIB.T6G(SCH_1):GND     I7 @T6G_MB_LIB.T6G(SCH_1):PAGE244

PC1850 Q_CAP_C0805-22UF,16V,20%,X6S,CH6223MEA01
     1 SW_P5V_AUX_FLT @T6G_MB_LIB.T6G(SCH_1):SW_P5V_AUX_FLT    I10 @T6G_MB_LIB.T6G(SCH_1):PAGE244
     2    GND @T6G_MB_LIB.T6G(SCH_1):GND    I10 @T6G_MB_LIB.T6G(SCH_1):PAGE244

PC1852 Q_CAP_0402-0.1UF,25V,10%,X7R,CH4104K1B00
     1 P5V_AUX @T6G_MB_LIB.T6G(SCH_1):P5V_AUX    I34 @T6G_MB_LIB.T6G(SCH_1):PAGE244
     2    GND @T6G_MB_LIB.T6G(SCH_1):GND    I34 @T6G_MB_LIB.T6G(SCH_1):PAGE244

PC1853 Q_CAP_0402-0.1UF,25V,10%,X7R,CH4104K1B00
     1 P5V_AUX_REF @T6G_MB_LIB.T6G(SCH_1):P5V_AUX_REF    I19 @T6G_MB_LIB.T6G(SCH_1):PAGE244
     2    GND @T6G_MB_LIB.T6G(SCH_1):GND    I19 @T6G_MB_LIB.T6G(SCH_1):PAGE244

PC1855 Q_CAP_C0805-22UF,10V,20%,X6S,CH6222MEA01
     1 P5V_AUX @T6G_MB_LIB.T6G(SCH_1):P5V_AUX    I31 @T6G_MB_LIB.T6G(SCH_1):PAGE244
     2    GND @T6G_MB_LIB.T6G(SCH_1):GND    I31 @T6G_MB_LIB.T6G(SCH_1):PAGE244

PC1856 Q_CAP_C0805-22UF,10V,20%,X6S,CH6222MEA01
     1 P5V_AUX @T6G_MB_LIB.T6G(SCH_1):P5V_AUX    I32 @T6G_MB_LIB.T6G(SCH_1):PAGE244
     2    GND @T6G_MB_LIB.T6G(SCH_1):GND    I32 @T6G_MB_LIB.T6G(SCH_1):PAGE244

PC1866 Q_CAPP_THLF-560UF,6.3V,20%,OSCON,CC75601MD16
     1 P3V3_AUX @T6G_MB_LIB.T6G(SCH_1):P3V3_AUX    I57 @T6G_MB_LIB.T6G(SCH_1):PAGE245
     2    GND @T6G_MB_LIB.T6G(SCH_1):GND    I57 @T6G_MB_LIB.T6G(SCH_1):PAGE245

PC1867 Q_CAPP_THLF-560UF,6.3V,20%,OSCON,CC75601MD16
     1 P3V3_AUX @T6G_MB_LIB.T6G(SCH_1):P3V3_AUX    I58 @T6G_MB_LIB.T6G(SCH_1):PAGE245
     2    GND @T6G_MB_LIB.T6G(SCH_1):GND    I58 @T6G_MB_LIB.T6G(SCH_1):PAGE245

PC1868 Q_CAP_C0805-22UF,10V,20%,X6S,CH6222MEA01
     1 P3V3_AUX @T6G_MB_LIB.T6G(SCH_1):P3V3_AUX    I59 @T6G_MB_LIB.T6G(SCH_1):PAGE245
     2    GND @T6G_MB_LIB.T6G(SCH_1):GND    I59 @T6G_MB_LIB.T6G(SCH_1):PAGE245

PC1869 Q_CAP_0402-0.1UF,25V,10%,X7R,CH4104K1B00
     1 P3V3_AUX @T6G_MB_LIB.T6G(SCH_1):P3V3_AUX    I63 @T6G_MB_LIB.T6G(SCH_1):PAGE245
     2    GND @T6G_MB_LIB.T6G(SCH_1):GND    I63 @T6G_MB_LIB.T6G(SCH_1):PAGE245

PC1870 Q_CAP_0402-0.1UF,25V,10%,EMPTY,CH4104K1B00
     1 P3V3_AUX_EN @T6G_MB_LIB.T6G(SCH_1):P3V3_AUX_EN     I8 @T6G_MB_LIB.T6G(SCH_1):PAGE245
     2    GND @T6G_MB_LIB.T6G(SCH_1):GND     I8 @T6G_MB_LIB.T6G(SCH_1):PAGE245

PC1877 Q_CAP_0402-47PF,50V,5%,NPO,TMP_QCH04706JB01
     1 P5V_AUX_FB @T6G_MB_LIB.T6G(SCH_1):P5V_AUX_FB    I20 @T6G_MB_LIB.T6G(SCH_1):PAGE244
     2 P5V_AUX @T6G_MB_LIB.T6G(SCH_1):P5V_AUX    I20 @T6G_MB_LIB.T6G(SCH_1):PAGE244

PC1898 Q_CAP_C0805-22UF,16V,20%,X6S,CH6223MEA01
     1 SW_P5V_AUX_FLT @T6G_MB_LIB.T6G(SCH_1):SW_P5V_AUX_FLT    I11 @T6G_MB_LIB.T6G(SCH_1):PAGE244
     2    GND @T6G_MB_LIB.T6G(SCH_1):GND    I11 @T6G_MB_LIB.T6G(SCH_1):PAGE244

PC2079 Q_CAP_C0402-1UF,25V,10%,X6S,CH5104KEB02
     1 P12V_AUX @T6G_MB_LIB.T6G(SCH_1):P12V_AUX    I45 @T6G_MB_LIB.T6G(SCH_1):PAGE338
     2    GND @T6G_MB_LIB.T6G(SCH_1):GND    I45 @T6G_MB_LIB.T6G(SCH_1):PAGE338

PC2080 Q_CAP_C0805-22UF,16V,20%,X6S,CH6223MEA01
     1 P12V_OCP_SFF @T6G_MB_LIB.T6G(SCH_1):P12V_OCP_SFF    I87 @T6G_MB_LIB.T6G(SCH_1):PAGE338
     2    GND @T6G_MB_LIB.T6G(SCH_1):GND    I87 @T6G_MB_LIB.T6G(SCH_1):PAGE338

PC2081 Q_CAP_C0805-10UF,16V,10%,X6S,CH6103KEA01
     1 P3V3_OCP_SFF_R @T6G_MB_LIB.T6G(SCH_1):P3V3_OCP_SFF_R   I106 @T6G_MB_LIB.T6G(SCH_1):PAGE338
     2    GND @T6G_MB_LIB.T6G(SCH_1):GND   I106 @T6G_MB_LIB.T6G(SCH_1):PAGE338

PC2082 Q_CAP_C0805-10UF,16V,10%,X6S,CH6103KEA01
     1 P12V_OCP_SFF @T6G_MB_LIB.T6G(SCH_1):P12V_OCP_SFF    I89 @T6G_MB_LIB.T6G(SCH_1):PAGE338
     2    GND @T6G_MB_LIB.T6G(SCH_1):GND    I89 @T6G_MB_LIB.T6G(SCH_1):PAGE338

PC2085 Q_CAP_C0402-1UF,25V,10%,X6S,CH5104KEB02
     1 P12V_OCP_VCC_1 @T6G_MB_LIB.T6G(SCH_1):P12V_OCP_VCC_1    I55 @T6G_MB_LIB.T6G(SCH_1):PAGE338
     2    GND @T6G_MB_LIB.T6G(SCH_1):GND    I55 @T6G_MB_LIB.T6G(SCH_1):PAGE338

PC2086 Q_CAP_C0402-1UF,25V,10%,X6S,CH5104KEB02
     1 P3V3_OCP_VCC_1 @T6G_MB_LIB.T6G(SCH_1):P3V3_OCP_VCC_1   I110 @T6G_MB_LIB.T6G(SCH_1):PAGE338
     2    GND @T6G_MB_LIB.T6G(SCH_1):GND   I110 @T6G_MB_LIB.T6G(SCH_1):PAGE338

PC2087 Q_CAP_C0402-1UF,25V,10%,X6S,CH5104KEB02
     1    GND @T6G_MB_LIB.T6G(SCH_1):GND    I54 @T6G_MB_LIB.T6G(SCH_1):PAGE338
     2 P12V_OCP_REG_1 @T6G_MB_LIB.T6G(SCH_1):P12V_OCP_REG_1    I54 @T6G_MB_LIB.T6G(SCH_1):PAGE338

PC2088 Q_CAP_C0402-0.01UF,50V,10%,EMPTY,CH31006KB18
     1 P12V_OCP_SFF @T6G_MB_LIB.T6G(SCH_1):P12V_OCP_SFF    I74 @T6G_MB_LIB.T6G(SCH_1):PAGE338
     2 P12V_OCP_GATE_1 @T6G_MB_LIB.T6G(SCH_1):P12V_OCP_GATE_1    I74 @T6G_MB_LIB.T6G(SCH_1):PAGE338

PC2089 Q_CAP_C0402-6800PF,50V,10%,X7R,CH2686K1B01
     1 P3V3_OCP_GATE_PU202_1 @T6G_MB_LIB.T6G(SCH_1):P3V3_OCP_GATE_PU202_1   I100 @T6G_MB_LIB.T6G(SCH_1):PAGE338
     2    GND @T6G_MB_LIB.T6G(SCH_1):GND   I100 @T6G_MB_LIB.T6G(SCH_1):PAGE338

PC2091 Q_CAP_0402-0.1UF,25V,10%,X7R,CH4104K1B00
     1 P3V3_OCP_SFF_R @T6G_MB_LIB.T6G(SCH_1):P3V3_OCP_SFF_R   I104 @T6G_MB_LIB.T6G(SCH_1):PAGE338
     2    GND @T6G_MB_LIB.T6G(SCH_1):GND   I104 @T6G_MB_LIB.T6G(SCH_1):PAGE338

PC2092 Q_CAP_0402-0.1UF,25V,10%,X7R,CH4104K1B00
     1 P12V_OCP_SFF @T6G_MB_LIB.T6G(SCH_1):P12V_OCP_SFF    I86 @T6G_MB_LIB.T6G(SCH_1):PAGE338
     2    GND @T6G_MB_LIB.T6G(SCH_1):GND    I86 @T6G_MB_LIB.T6G(SCH_1):PAGE338

PC2093 Q_CAP_C0402-1UF,25V,10%,X6S,CH5104KEB02
     1    GND @T6G_MB_LIB.T6G(SCH_1):GND    I67 @T6G_MB_LIB.T6G(SCH_1):PAGE338
     2 P3V3_OCP_REG_1 @T6G_MB_LIB.T6G(SCH_1):P3V3_OCP_REG_1    I67 @T6G_MB_LIB.T6G(SCH_1):PAGE338

PC2098 Q_CAP_C0402-1UF,25V,10%,X6S,CH5104KEB02
     1 P12V_OCP_VCC_2 @T6G_MB_LIB.T6G(SCH_1):P12V_OCP_VCC_2    I65 @T6G_MB_LIB.T6G(SCH_1):PAGE343
     2    GND @T6G_MB_LIB.T6G(SCH_1):GND    I65 @T6G_MB_LIB.T6G(SCH_1):PAGE343

PC2103 Q_CAP_C0402-1UF,25V,10%,X6S,CH5104KEB02
     1 HSC_VDD18 @T6G_MB_LIB.T6G(SCH_1):HSC_VDD18    I50 @T6G_MB_LIB.T6G(SCH_1):PAGE267
     2 AGND_HSC @T6G_MB_LIB.T6G(SCH_1):AGND_HSC    I50 @T6G_MB_LIB.T6G(SCH_1):PAGE267

PC2137 Q_CAP_0402-0.1UF,25V,10%,X7R,CH4104K1B00
     1 P3V3_OCP_V3_2_R @T6G_MB_LIB.T6G(SCH_1):P3V3_OCP_V3_2_R   I108 @T6G_MB_LIB.T6G(SCH_1):PAGE343
     2    GND @T6G_MB_LIB.T6G(SCH_1):GND   I108 @T6G_MB_LIB.T6G(SCH_1):PAGE343

PC2139 Q_CAP_C0402-1UF,25V,10%,X6S,CH5104KEB02
     1 P12V_AUX @T6G_MB_LIB.T6G(SCH_1):P12V_AUX    I49 @T6G_MB_LIB.T6G(SCH_1):PAGE343
     2    GND @T6G_MB_LIB.T6G(SCH_1):GND    I49 @T6G_MB_LIB.T6G(SCH_1):PAGE343

PC2140 Q_CAP_C0402-1UF,25V,10%,X6S,CH5104KEB02
     1 P3V3_AUX @T6G_MB_LIB.T6G(SCH_1):P3V3_AUX    I55 @T6G_MB_LIB.T6G(SCH_1):PAGE343
     2    GND @T6G_MB_LIB.T6G(SCH_1):GND    I55 @T6G_MB_LIB.T6G(SCH_1):PAGE343

PC2141 Q_CAP_C0805-22UF,16V,20%,X6S,CH6223MEA01
     1 P12V_OCP_V3_2 @T6G_MB_LIB.T6G(SCH_1):P12V_OCP_V3_2    I99 @T6G_MB_LIB.T6G(SCH_1):PAGE343
     2    GND @T6G_MB_LIB.T6G(SCH_1):GND    I99 @T6G_MB_LIB.T6G(SCH_1):PAGE343

PC2142 Q_CAP_C0805-10UF,16V,10%,X6S,CH6103KEA01
     1 P3V3_OCP_V3_2_R @T6G_MB_LIB.T6G(SCH_1):P3V3_OCP_V3_2_R   I112 @T6G_MB_LIB.T6G(SCH_1):PAGE343
     2    GND @T6G_MB_LIB.T6G(SCH_1):GND   I112 @T6G_MB_LIB.T6G(SCH_1):PAGE343

PC2143 Q_CAP_C0805-10UF,16V,10%,X6S,CH6103KEA01
     1 P12V_OCP_V3_2 @T6G_MB_LIB.T6G(SCH_1):P12V_OCP_V3_2   I101 @T6G_MB_LIB.T6G(SCH_1):PAGE343
     2    GND @T6G_MB_LIB.T6G(SCH_1):GND   I101 @T6G_MB_LIB.T6G(SCH_1):PAGE343

PC2144 Q_CAP_C0402-0.01UF,50V,10%,EMPTY,CH31006KB18
     1 P3V3_OCP_SFF_R @T6G_MB_LIB.T6G(SCH_1):P3V3_OCP_SFF_R    I94 @T6G_MB_LIB.T6G(SCH_1):PAGE338
     2 P3V3_OCP_GATE_PU202_1 @T6G_MB_LIB.T6G(SCH_1):P3V3_OCP_GATE_PU202_1    I94 @T6G_MB_LIB.T6G(SCH_1):PAGE338

PC2146 Q_CAP_C0402-1UF,25V,10%,X6S,CH5104KEB02
     1    GND @T6G_MB_LIB.T6G(SCH_1):GND    I66 @T6G_MB_LIB.T6G(SCH_1):PAGE343
     2 P12V_OCP_REG_2 @T6G_MB_LIB.T6G(SCH_1):P12V_OCP_REG_2    I66 @T6G_MB_LIB.T6G(SCH_1):PAGE343

PC2147 Q_CAP_C0402-1UF,25V,10%,X6S,CH5104KEB02
     1    GND @T6G_MB_LIB.T6G(SCH_1):GND    I86 @T6G_MB_LIB.T6G(SCH_1):PAGE343
     2 P3V3_OCP_REG_2 @T6G_MB_LIB.T6G(SCH_1):P3V3_OCP_REG_2    I86 @T6G_MB_LIB.T6G(SCH_1):PAGE343

PC2149 Q_CAP_C0402-0.01UF,50V,10%,EMPTY,CH31006KB18
     1 P3V3_OCP_V3_2_R @T6G_MB_LIB.T6G(SCH_1):P3V3_OCP_V3_2_R   I104 @T6G_MB_LIB.T6G(SCH_1):PAGE343
     2 P3V3_OCP_GATE_2 @T6G_MB_LIB.T6G(SCH_1):P3V3_OCP_GATE_2   I104 @T6G_MB_LIB.T6G(SCH_1):PAGE343

PC2150 Q_CAP_C0402-3900PF,50V,10%,X7R,CH23906KB14
     1 P12V_OCP_GATE_2 @T6G_MB_LIB.T6G(SCH_1):P12V_OCP_GATE_2    I75 @T6G_MB_LIB.T6G(SCH_1):PAGE343
     2    GND @T6G_MB_LIB.T6G(SCH_1):GND    I75 @T6G_MB_LIB.T6G(SCH_1):PAGE343

PC2151 Q_CAP_C0402-6800PF,50V,10%,X7R,CH2686K1B01
     1 P3V3_OCP_GATE_2 @T6G_MB_LIB.T6G(SCH_1):P3V3_OCP_GATE_2    I95 @T6G_MB_LIB.T6G(SCH_1):PAGE343
     2    GND @T6G_MB_LIB.T6G(SCH_1):GND    I95 @T6G_MB_LIB.T6G(SCH_1):PAGE343

PC2152 Q_CAP_0402-0.1UF,25V,10%,X7R,CH4104K1B00
     1 P12V_OCP_V3_2 @T6G_MB_LIB.T6G(SCH_1):P12V_OCP_V3_2    I97 @T6G_MB_LIB.T6G(SCH_1):PAGE343
     2    GND @T6G_MB_LIB.T6G(SCH_1):GND    I97 @T6G_MB_LIB.T6G(SCH_1):PAGE343

PC2153 Q_CAP_0402-0.22UF,16V,10%,X7R,CH4223K1B00
     1 P12V_OCP_TIMER_1 @T6G_MB_LIB.T6G(SCH_1):P12V_OCP_TIMER_1    I60 @T6G_MB_LIB.T6G(SCH_1):PAGE339
     2    GND @T6G_MB_LIB.T6G(SCH_1):GND    I60 @T6G_MB_LIB.T6G(SCH_1):PAGE339

PC2154 Q_CAP_C0402-1UF,25V,10%,X6S,CH5104KEB02
     1 P12V_AUX @T6G_MB_LIB.T6G(SCH_1):P12V_AUX    I68 @T6G_MB_LIB.T6G(SCH_1):PAGE339
     2    GND @T6G_MB_LIB.T6G(SCH_1):GND    I68 @T6G_MB_LIB.T6G(SCH_1):PAGE339

PC2155 Q_CAP_C0402-0.047UF,25V,10%,X7R,CH3474K1B04
     1 P12V_OCP_SS_1 @T6G_MB_LIB.T6G(SCH_1):P12V_OCP_SS_1    I64 @T6G_MB_LIB.T6G(SCH_1):PAGE339
     2    GND @T6G_MB_LIB.T6G(SCH_1):GND    I64 @T6G_MB_LIB.T6G(SCH_1):PAGE339

PC2156 Q_CAP_C0402-100NF,50V,10%,X7R,CH4106K1B01
     1 P12V_OCP_IMON_1 @T6G_MB_LIB.T6G(SCH_1):P12V_OCP_IMON_1    I73 @T6G_MB_LIB.T6G(SCH_1):PAGE339
     2    GND @T6G_MB_LIB.T6G(SCH_1):GND    I73 @T6G_MB_LIB.T6G(SCH_1):PAGE339

PC2157 Q_CAP_0402-39PF,50V,5%,NPO,CH03906JB06
     1 P3V3_OCP_MODE_1 @T6G_MB_LIB.T6G(SCH_1):P3V3_OCP_MODE_1    I98 @T6G_MB_LIB.T6G(SCH_1):PAGE339
     2    GND @T6G_MB_LIB.T6G(SCH_1):GND    I98 @T6G_MB_LIB.T6G(SCH_1):PAGE339

PC2158 Q_CAP_C0603-2.2UF,16V,20%,X7R,CH5223M1900
     1 P12V_OCP_AVIN_PD_1 @T6G_MB_LIB.T6G(SCH_1):P12V_OCP_AVIN_PD_1    I86 @T6G_MB_LIB.T6G(SCH_1):PAGE339
     2    GND @T6G_MB_LIB.T6G(SCH_1):GND    I86 @T6G_MB_LIB.T6G(SCH_1):PAGE339

PC2159 Q_CAP_C0402-1UF,25V,10%,X6S,CH5104KEB02
     1 P3V3_AUX @T6G_MB_LIB.T6G(SCH_1):P3V3_AUX   I111 @T6G_MB_LIB.T6G(SCH_1):PAGE339
     2    GND @T6G_MB_LIB.T6G(SCH_1):GND   I111 @T6G_MB_LIB.T6G(SCH_1):PAGE339

PC2160 Q_CAP_0402-0.1UF,25V,10%,X7R,CH4104K1B00
     1 P12V_OCP_SFF @T6G_MB_LIB.T6G(SCH_1):P12V_OCP_SFF    I91 @T6G_MB_LIB.T6G(SCH_1):PAGE339
     2    GND @T6G_MB_LIB.T6G(SCH_1):GND    I91 @T6G_MB_LIB.T6G(SCH_1):PAGE339

PC2161 Q_CAP_0402-0.068UF,16V,10%,X7R,CH3683K1B09
     1 P3V3_OCP_DVDT_1 @T6G_MB_LIB.T6G(SCH_1):P3V3_OCP_DVDT_1   I104 @T6G_MB_LIB.T6G(SCH_1):PAGE339
     2    GND @T6G_MB_LIB.T6G(SCH_1):GND   I104 @T6G_MB_LIB.T6G(SCH_1):PAGE339

PC2162 Q_CAP_0402-100PF,50V,5%,X7R,CH11006JB18
     1 P3V3_OCP_GATE_1 @T6G_MB_LIB.T6G(SCH_1):P3V3_OCP_GATE_1   I106 @T6G_MB_LIB.T6G(SCH_1):PAGE339
     2    GND @T6G_MB_LIB.T6G(SCH_1):GND   I106 @T6G_MB_LIB.T6G(SCH_1):PAGE339

PC2163 Q_CAP_C0805-10UF,16V,10%,X6S,CH6103KEA01
     1 P3V3_OCP_SFF_R @T6G_MB_LIB.T6G(SCH_1):P3V3_OCP_SFF_R   I108 @T6G_MB_LIB.T6G(SCH_1):PAGE339
     2    GND @T6G_MB_LIB.T6G(SCH_1):GND   I108 @T6G_MB_LIB.T6G(SCH_1):PAGE339

PC2164 Q_CAP_0402-0.22UF,16V,10%,X7R,CH4223K1B00
     1 P12V_OCP_TIMER_2 @T6G_MB_LIB.T6G(SCH_1):P12V_OCP_TIMER_2     I2 @T6G_MB_LIB.T6G(SCH_1):PAGE344
     2    GND @T6G_MB_LIB.T6G(SCH_1):GND     I2 @T6G_MB_LIB.T6G(SCH_1):PAGE344

PC2165 Q_CAP_C0402-1UF,25V,10%,X6S,CH5104KEB02
     1 P12V_AUX @T6G_MB_LIB.T6G(SCH_1):P12V_AUX    I13 @T6G_MB_LIB.T6G(SCH_1):PAGE344
     2    GND @T6G_MB_LIB.T6G(SCH_1):GND    I13 @T6G_MB_LIB.T6G(SCH_1):PAGE344

PC2166 Q_CAP_C0402-0.047UF,25V,10%,X7R,CH3474K1B04
     1 P12V_OCP_SS_2 @T6G_MB_LIB.T6G(SCH_1):P12V_OCP_SS_2     I6 @T6G_MB_LIB.T6G(SCH_1):PAGE344
     2    GND @T6G_MB_LIB.T6G(SCH_1):GND     I6 @T6G_MB_LIB.T6G(SCH_1):PAGE344

PC2167 Q_CAP_0402-100PF,50V,5%,NPO,CH11006JB00
     1 P12V_OCP_IMON_2 @T6G_MB_LIB.T6G(SCH_1):P12V_OCP_IMON_2    I58 @T6G_MB_LIB.T6G(SCH_1):PAGE344
     2    GND @T6G_MB_LIB.T6G(SCH_1):GND    I58 @T6G_MB_LIB.T6G(SCH_1):PAGE344

PC2168 Q_CAP_0402-39PF,50V,5%,NPO,CH03906JB06
     1 P3V3_OCP_MODE_2 @T6G_MB_LIB.T6G(SCH_1):P3V3_OCP_MODE_2    I35 @T6G_MB_LIB.T6G(SCH_1):PAGE344
     2    GND @T6G_MB_LIB.T6G(SCH_1):GND    I35 @T6G_MB_LIB.T6G(SCH_1):PAGE344

PC2169 Q_CAP_C0402-1UF,25V,10%,X6S,CH5104KEB02
     1 P3V3_AUX @T6G_MB_LIB.T6G(SCH_1):P3V3_AUX    I48 @T6G_MB_LIB.T6G(SCH_1):PAGE344
     2    GND @T6G_MB_LIB.T6G(SCH_1):GND    I48 @T6G_MB_LIB.T6G(SCH_1):PAGE344

PC2173 Q_CAP_C0805-10UF,16V,10%,X6S,CH6103KEA01
     1 P3V3_OCP_V3_2_R @T6G_MB_LIB.T6G(SCH_1):P3V3_OCP_V3_2_R    I56 @T6G_MB_LIB.T6G(SCH_1):PAGE344
     2    GND @T6G_MB_LIB.T6G(SCH_1):GND    I56 @T6G_MB_LIB.T6G(SCH_1):PAGE344

PC2174 Q_CAP_0402-0.1UF,25V,10%,X7R,CH4104K1B00
     1 P12V_OCP_V3_2 @T6G_MB_LIB.T6G(SCH_1):P12V_OCP_V3_2    I40 @T6G_MB_LIB.T6G(SCH_1):PAGE344
     2    GND @T6G_MB_LIB.T6G(SCH_1):GND    I40 @T6G_MB_LIB.T6G(SCH_1):PAGE344

PC2181 Q_CAP_C0402-1UF,25V,10%,X6S,CH5104KEB02
     1 HSC_VDD_R_2 @T6G_MB_LIB.T6G(SCH_1):HSC_VDD_R_2     I4 @T6G_MB_LIB.T6G(SCH_1):PAGE301
     2 AGND_HSC @T6G_MB_LIB.T6G(SCH_1):AGND_HSC     I4 @T6G_MB_LIB.T6G(SCH_1):PAGE301

PC2182 Q_CAP_0402-220PF,50V,10%,X7R,TMP_QCH12206KB14
     1 HSC_ON @T6G_MB_LIB.T6G(SCH_1):HSC_ON    I24 @T6G_MB_LIB.T6G(SCH_1):PAGE301
     2 AGND_HSC @T6G_MB_LIB.T6G(SCH_1):AGND_HSC    I24 @T6G_MB_LIB.T6G(SCH_1):PAGE301

PC2183 Q_CAP_0402-220PF,50V,10%,EMPTY,TMP_QCH12206KB14
     1 HSC_ON @T6G_MB_LIB.T6G(SCH_1):HSC_ON     I2 @T6G_MB_LIB.T6G(SCH_1):PAGE301
     2 AGND_HSC @T6G_MB_LIB.T6G(SCH_1):AGND_HSC     I2 @T6G_MB_LIB.T6G(SCH_1):PAGE301

PC2184 Q_CAP_0402-0.068UF,16V,10%,X7R,CH3683K1B09
     1 HSC_SS @T6G_MB_LIB.T6G(SCH_1):HSC_SS    I47 @T6G_MB_LIB.T6G(SCH_1):PAGE301
     2 AGND_HSC @T6G_MB_LIB.T6G(SCH_1):AGND_HSC    I47 @T6G_MB_LIB.T6G(SCH_1):PAGE301

PC2185 Q_CAP_0402-0.068UF,16V,10%,X7R,CH3683K1B09
     1 HSC_SS @T6G_MB_LIB.T6G(SCH_1):HSC_SS    I38 @T6G_MB_LIB.T6G(SCH_1):PAGE301
     2 AGND_HSC @T6G_MB_LIB.T6G(SCH_1):AGND_HSC    I38 @T6G_MB_LIB.T6G(SCH_1):PAGE301

PC2186 Q_CAP_C0402-1UF,25V,10%,X6S,CH5104KEB02
     1 HSC_VDD_R @T6G_MB_LIB.T6G(SCH_1):HSC_VDD_R    I27 @T6G_MB_LIB.T6G(SCH_1):PAGE267
     2 AGND_HSC @T6G_MB_LIB.T6G(SCH_1):AGND_HSC    I27 @T6G_MB_LIB.T6G(SCH_1):PAGE267

PC2187 Q_CAP_C0402-1UF,25V,10%,X6S,CH5104KEB02
     1 HSC_VDD_R @T6G_MB_LIB.T6G(SCH_1):HSC_VDD_R    I30 @T6G_MB_LIB.T6G(SCH_1):PAGE267
     2 AGND_HSC @T6G_MB_LIB.T6G(SCH_1):AGND_HSC    I30 @T6G_MB_LIB.T6G(SCH_1):PAGE267

PC2188 Q_CAP_C0402-1UF,25V,10%,X6S,CH5104KEB02
     1 P12V_PSU @T6G_MB_LIB.T6G(SCH_1):P12V_PSU    I46 @T6G_MB_LIB.T6G(SCH_1):PAGE267
     2    GND @T6G_MB_LIB.T6G(SCH_1):GND    I46 @T6G_MB_LIB.T6G(SCH_1):PAGE267

PC2189 Q_CAP_C0402-0.01UF,50V,10%,X7R,CH31006KB18
     1 HSC_VSENSE @T6G_MB_LIB.T6G(SCH_1):HSC_VSENSE    I59 @T6G_MB_LIB.T6G(SCH_1):PAGE267
     2 AGND_HSC @T6G_MB_LIB.T6G(SCH_1):AGND_HSC    I59 @T6G_MB_LIB.T6G(SCH_1):PAGE267

PC2190 Q_CAP_C0402-0.01UF,50V,10%,X7R,CH31006KB18
     1 HSC_VOSEN @T6G_MB_LIB.T6G(SCH_1):HSC_VOSEN    I72 @T6G_MB_LIB.T6G(SCH_1):PAGE267
     2 AGND_HSC @T6G_MB_LIB.T6G(SCH_1):AGND_HSC    I72 @T6G_MB_LIB.T6G(SCH_1):PAGE267

PC2191 Q_CAP_0402-0.068UF,16V,10%,X7R,CH3683K1B09
     1 HSC_SS @T6G_MB_LIB.T6G(SCH_1):HSC_SS    I75 @T6G_MB_LIB.T6G(SCH_1):PAGE267
     2 AGND_HSC @T6G_MB_LIB.T6G(SCH_1):AGND_HSC    I75 @T6G_MB_LIB.T6G(SCH_1):PAGE267

PC2192 Q_CAP_C0402-0.001UF,50V,10%,X7R,CH30106KB19
     1 HSC_VTEMP @T6G_MB_LIB.T6G(SCH_1):HSC_VTEMP    I78 @T6G_MB_LIB.T6G(SCH_1):PAGE267
     2 AGND_HSC @T6G_MB_LIB.T6G(SCH_1):AGND_HSC    I78 @T6G_MB_LIB.T6G(SCH_1):PAGE267

PC2193 Q_CAP_C0402-0.047UF,25V,10%,X7R,CH3474K1B04
     1 HSC_IMON @T6G_MB_LIB.T6G(SCH_1):HSC_IMON    I84 @T6G_MB_LIB.T6G(SCH_1):PAGE267
     2 AGND_HSC @T6G_MB_LIB.T6G(SCH_1):AGND_HSC    I84 @T6G_MB_LIB.T6G(SCH_1):PAGE267

PC2196 Q_CAP_0402-0.22UF,16V,10%,X7R,CH4223K1B00
     1 P12V_E1S_TIMER_0 @T6G_MB_LIB.T6G(SCH_1):P12V_E1S_TIMER_0    I13 @T6G_MB_LIB.T6G(SCH_1):PAGE323
     2    GND @T6G_MB_LIB.T6G(SCH_1):GND    I13 @T6G_MB_LIB.T6G(SCH_1):PAGE323

PC2197 Q_CAP_0402-39PF,50V,5%,NPO,CH03906JB06
     1 P3V3_E1S_MODE_0 @T6G_MB_LIB.T6G(SCH_1):P3V3_E1S_MODE_0     I3 @T6G_MB_LIB.T6G(SCH_1):PAGE323
     2    GND @T6G_MB_LIB.T6G(SCH_1):GND     I3 @T6G_MB_LIB.T6G(SCH_1):PAGE323

PC2198 Q_CAP_C0402-1UF,25V,10%,X6S,CH5104KEB02
     1 P12V_AUX @T6G_MB_LIB.T6G(SCH_1):P12V_AUX    I25 @T6G_MB_LIB.T6G(SCH_1):PAGE323
     2    GND @T6G_MB_LIB.T6G(SCH_1):GND    I25 @T6G_MB_LIB.T6G(SCH_1):PAGE323

PC2200 Q_CAP_C0402-1UF,25V,10%,X6S,CH5104KEB02
     1 P3V3_AUX @T6G_MB_LIB.T6G(SCH_1):P3V3_AUX     I9 @T6G_MB_LIB.T6G(SCH_1):PAGE323
     2    GND @T6G_MB_LIB.T6G(SCH_1):GND     I9 @T6G_MB_LIB.T6G(SCH_1):PAGE323

PC2201 Q_CAP_0402-0.068UF,16V,10%,X7R,CH3683K1B09
     1 P3V3_E1S_DVDT_0 @T6G_MB_LIB.T6G(SCH_1):P3V3_E1S_DVDT_0    I30 @T6G_MB_LIB.T6G(SCH_1):PAGE323
     2    GND @T6G_MB_LIB.T6G(SCH_1):GND    I30 @T6G_MB_LIB.T6G(SCH_1):PAGE323

PC2202 Q_CAP_C0402-100NF,50V,10%,X7R,CH4106K1B01
     1 P12V_E1S_IMON_0 @T6G_MB_LIB.T6G(SCH_1):P12V_E1S_IMON_0    I39 @T6G_MB_LIB.T6G(SCH_1):PAGE323
     2    GND @T6G_MB_LIB.T6G(SCH_1):GND    I39 @T6G_MB_LIB.T6G(SCH_1):PAGE323

PC2203 Q_CAP_0402-100PF,50V,5%,X7R,CH11006JB18
     1 P3V3_E1S_GATE_0_PU293 @T6G_MB_LIB.T6G(SCH_1):P3V3_E1S_GATE_0_PU293    I32 @T6G_MB_LIB.T6G(SCH_1):PAGE323
     2    GND @T6G_MB_LIB.T6G(SCH_1):GND    I32 @T6G_MB_LIB.T6G(SCH_1):PAGE323

PC2204 Q_CAP_C0805-10UF,16V,10%,X6S,CH6103KEA01
     1 P3V3_E1S_0_R @T6G_MB_LIB.T6G(SCH_1):P3V3_E1S_0_R    I34 @T6G_MB_LIB.T6G(SCH_1):PAGE323
     2    GND @T6G_MB_LIB.T6G(SCH_1):GND    I34 @T6G_MB_LIB.T6G(SCH_1):PAGE323

PC2205 Q_CAP_C0603-2.2UF,16V,20%,X7R,CH5223M1900
     1 P12V_E1S_AVIN_PD_0 @T6G_MB_LIB.T6G(SCH_1):P12V_E1S_AVIN_PD_0    I51 @T6G_MB_LIB.T6G(SCH_1):PAGE323
     2    GND @T6G_MB_LIB.T6G(SCH_1):GND    I51 @T6G_MB_LIB.T6G(SCH_1):PAGE323

PC2206 Q_CAP_0402-0.1UF,25V,10%,X7R,CH4104K1B00
     1 P12V_E1S_0 @T6G_MB_LIB.T6G(SCH_1):P12V_E1S_0    I56 @T6G_MB_LIB.T6G(SCH_1):PAGE323
     2    GND @T6G_MB_LIB.T6G(SCH_1):GND    I56 @T6G_MB_LIB.T6G(SCH_1):PAGE323

PC2207 Q_CAP_C0402-1UF,25V,10%,X6S,CH5104KEB02
     1 P12V_AUX @T6G_MB_LIB.T6G(SCH_1):P12V_AUX    I36 @T6G_MB_LIB.T6G(SCH_1):PAGE324
     2    GND @T6G_MB_LIB.T6G(SCH_1):GND    I36 @T6G_MB_LIB.T6G(SCH_1):PAGE324

PC2208 Q_CAP_C0402-1UF,25V,10%,X6S,CH5104KEB02
     1 P3V3_AUX @T6G_MB_LIB.T6G(SCH_1):P3V3_AUX    I20 @T6G_MB_LIB.T6G(SCH_1):PAGE324
     2    GND @T6G_MB_LIB.T6G(SCH_1):GND    I20 @T6G_MB_LIB.T6G(SCH_1):PAGE324

PC2209 Q_CAP_C0402-1UF,25V,10%,X6S,CH5104KEB02
     1 P12V_E1S_VCC_0 @T6G_MB_LIB.T6G(SCH_1):P12V_E1S_VCC_0    I64 @T6G_MB_LIB.T6G(SCH_1):PAGE324
     2    GND @T6G_MB_LIB.T6G(SCH_1):GND    I64 @T6G_MB_LIB.T6G(SCH_1):PAGE324

PC2210 Q_CAP_C0402-1UF,25V,10%,X6S,CH5104KEB02
     1 P3V3_E1S_VCC_0 @T6G_MB_LIB.T6G(SCH_1):P3V3_E1S_VCC_0    I41 @T6G_MB_LIB.T6G(SCH_1):PAGE324
     2    GND @T6G_MB_LIB.T6G(SCH_1):GND    I41 @T6G_MB_LIB.T6G(SCH_1):PAGE324

PC2211 Q_CAP_C0402-1UF,25V,10%,X6S,CH5104KEB02
     1    GND @T6G_MB_LIB.T6G(SCH_1):GND    I61 @T6G_MB_LIB.T6G(SCH_1):PAGE324
     2 P12V_E1S_REG_0 @T6G_MB_LIB.T6G(SCH_1):P12V_E1S_REG_0    I61 @T6G_MB_LIB.T6G(SCH_1):PAGE324

PC2212 Q_CAP_C0402-1UF,25V,10%,X6S,CH5104KEB02
     1    GND @T6G_MB_LIB.T6G(SCH_1):GND    I42 @T6G_MB_LIB.T6G(SCH_1):PAGE324
     2 P3V3_E1S_REG_0 @T6G_MB_LIB.T6G(SCH_1):P3V3_E1S_REG_0    I42 @T6G_MB_LIB.T6G(SCH_1):PAGE324

PC2213 Q_CAP_C0402-0.01UF,50V,10%,EMPTY,CH31006KB18
     1 P3V3_E1S_0_R @T6G_MB_LIB.T6G(SCH_1):P3V3_E1S_0_R    I46 @T6G_MB_LIB.T6G(SCH_1):PAGE324
     2 P3V3_E1S_GATE_0 @T6G_MB_LIB.T6G(SCH_1):P3V3_E1S_GATE_0    I46 @T6G_MB_LIB.T6G(SCH_1):PAGE324

PC2214 Q_CAP_C0402-0.01UF,50V,10%,EMPTY,CH31006KB18
     1 P12V_E1S_0 @T6G_MB_LIB.T6G(SCH_1):P12V_E1S_0    I72 @T6G_MB_LIB.T6G(SCH_1):PAGE324
     2 P12V_E1S_GATE_0 @T6G_MB_LIB.T6G(SCH_1):P12V_E1S_GATE_0    I72 @T6G_MB_LIB.T6G(SCH_1):PAGE324

PC2215 Q_CAP_C0402-3900PF,50V,10%,X7R,CH23906KB14
     1 P12V_E1S_GATE_0 @T6G_MB_LIB.T6G(SCH_1):P12V_E1S_GATE_0    I69 @T6G_MB_LIB.T6G(SCH_1):PAGE324
     2    GND @T6G_MB_LIB.T6G(SCH_1):GND    I69 @T6G_MB_LIB.T6G(SCH_1):PAGE324

PC2216 Q_CAP_C0402-6800PF,50V,10%,X7R,CH2686K1B01
     1 P3V3_E1S_GATE_0 @T6G_MB_LIB.T6G(SCH_1):P3V3_E1S_GATE_0    I49 @T6G_MB_LIB.T6G(SCH_1):PAGE324
     2    GND @T6G_MB_LIB.T6G(SCH_1):GND    I49 @T6G_MB_LIB.T6G(SCH_1):PAGE324

PC2217 Q_CAP_0402-0.1UF,25V,10%,X7R,CH4104K1B00
     1 P12V_E1S_0 @T6G_MB_LIB.T6G(SCH_1):P12V_E1S_0    I78 @T6G_MB_LIB.T6G(SCH_1):PAGE324
     2    GND @T6G_MB_LIB.T6G(SCH_1):GND    I78 @T6G_MB_LIB.T6G(SCH_1):PAGE324

PC2218 Q_CAP_0402-0.1UF,25V,10%,X7R,CH4104K1B00
     1 P3V3_E1S_0_R @T6G_MB_LIB.T6G(SCH_1):P3V3_E1S_0_R    I57 @T6G_MB_LIB.T6G(SCH_1):PAGE324
     2    GND @T6G_MB_LIB.T6G(SCH_1):GND    I57 @T6G_MB_LIB.T6G(SCH_1):PAGE324

PC2219 Q_CAP_C0805-10UF,16V,10%,X6S,CH6103KEA01
     1 P12V_E1S_0 @T6G_MB_LIB.T6G(SCH_1):P12V_E1S_0    I79 @T6G_MB_LIB.T6G(SCH_1):PAGE324
     2    GND @T6G_MB_LIB.T6G(SCH_1):GND    I79 @T6G_MB_LIB.T6G(SCH_1):PAGE324

PC2220 Q_CAP_C0805-10UF,16V,10%,X6S,CH6103KEA01
     1 P3V3_E1S_0_R @T6G_MB_LIB.T6G(SCH_1):P3V3_E1S_0_R    I58 @T6G_MB_LIB.T6G(SCH_1):PAGE324
     2    GND @T6G_MB_LIB.T6G(SCH_1):GND    I58 @T6G_MB_LIB.T6G(SCH_1):PAGE324

PC2223 Q_CAP_C0402-1UF,25V,10%,X6S,CH5104KEB02
     1 HSC_VDD_R_4 @T6G_MB_LIB.T6G(SCH_1):HSC_VDD_R_4     I4 @T6G_MB_LIB.T6G(SCH_1):PAGE325
     2 AGND_HSC @T6G_MB_LIB.T6G(SCH_1):AGND_HSC     I4 @T6G_MB_LIB.T6G(SCH_1):PAGE325

PC2224 Q_CAP_0402-220PF,50V,10%,EMPTY,TMP_QCH12206KB14
     1 HSC_ON @T6G_MB_LIB.T6G(SCH_1):HSC_ON    I24 @T6G_MB_LIB.T6G(SCH_1):PAGE325
     2 AGND_HSC @T6G_MB_LIB.T6G(SCH_1):AGND_HSC    I24 @T6G_MB_LIB.T6G(SCH_1):PAGE325

PC2225 Q_CAP_0402-220PF,50V,10%,EMPTY,TMP_QCH12206KB14
     1 HSC_ON @T6G_MB_LIB.T6G(SCH_1):HSC_ON     I2 @T6G_MB_LIB.T6G(SCH_1):PAGE325
     2 AGND_HSC @T6G_MB_LIB.T6G(SCH_1):AGND_HSC     I2 @T6G_MB_LIB.T6G(SCH_1):PAGE325

PC2226 Q_CAP_0402-0.068UF,16V,10%,X7R,CH3683K1B09
     1 HSC_SS @T6G_MB_LIB.T6G(SCH_1):HSC_SS    I47 @T6G_MB_LIB.T6G(SCH_1):PAGE325
     2 AGND_HSC @T6G_MB_LIB.T6G(SCH_1):AGND_HSC    I47 @T6G_MB_LIB.T6G(SCH_1):PAGE325

PC2227 Q_CAP_0402-0.068UF,16V,10%,X7R,CH3683K1B09
     1 HSC_SS @T6G_MB_LIB.T6G(SCH_1):HSC_SS    I38 @T6G_MB_LIB.T6G(SCH_1):PAGE325
     2 AGND_HSC @T6G_MB_LIB.T6G(SCH_1):AGND_HSC    I38 @T6G_MB_LIB.T6G(SCH_1):PAGE325

PC2229 Q_CAP_0402-0.22UF,16V,10%,X7R,CH4223K1B00
     1 P12V_SCM_TIMER @T6G_MB_LIB.T6G(SCH_1):P12V_SCM_TIMER     I8 @T6G_MB_LIB.T6G(SCH_1):PAGE350
     2    GND @T6G_MB_LIB.T6G(SCH_1):GND     I8 @T6G_MB_LIB.T6G(SCH_1):PAGE350

PC2230 Q_CAP_C0402-1UF,25V,10%,X6S,CH5104KEB02
     1 P12V_AUX @T6G_MB_LIB.T6G(SCH_1):P12V_AUX    I31 @T6G_MB_LIB.T6G(SCH_1):PAGE350
     2    GND @T6G_MB_LIB.T6G(SCH_1):GND    I31 @T6G_MB_LIB.T6G(SCH_1):PAGE350

PC2231 Q_CAP_C0402-1UF,25V,10%,X6S,CH5104KEB02
     1 P12V_AUX @T6G_MB_LIB.T6G(SCH_1):P12V_AUX    I37 @T6G_MB_LIB.T6G(SCH_1):PAGE350
     2    GND @T6G_MB_LIB.T6G(SCH_1):GND    I37 @T6G_MB_LIB.T6G(SCH_1):PAGE350

PC2232 Q_CAP_C0402-0.047UF,25V,10%,X7R,CH3474K1B04
     1 P12V_SCM_SS @T6G_MB_LIB.T6G(SCH_1):P12V_SCM_SS    I33 @T6G_MB_LIB.T6G(SCH_1):PAGE350
     2    GND @T6G_MB_LIB.T6G(SCH_1):GND    I33 @T6G_MB_LIB.T6G(SCH_1):PAGE350

PC2233 Q_CAP_C0402-1UF,25V,10%,X6S,CH5104KEB02
     1 P12V_SCM_VCC @T6G_MB_LIB.T6G(SCH_1):P12V_SCM_VCC    I66 @T6G_MB_LIB.T6G(SCH_1):PAGE350
     2    GND @T6G_MB_LIB.T6G(SCH_1):GND    I66 @T6G_MB_LIB.T6G(SCH_1):PAGE350

PC2234 Q_CAP_C0402-1UF,25V,10%,X6S,CH5104KEB02
     1    GND @T6G_MB_LIB.T6G(SCH_1):GND    I67 @T6G_MB_LIB.T6G(SCH_1):PAGE350
     2 P12V_SCM_REG @T6G_MB_LIB.T6G(SCH_1):P12V_SCM_REG    I67 @T6G_MB_LIB.T6G(SCH_1):PAGE350

PC2235 Q_CAP_C0402-100NF,50V,10%,X7R,CH4106K1B01
     1 P12V_SCM_IMON @T6G_MB_LIB.T6G(SCH_1):P12V_SCM_IMON    I45 @T6G_MB_LIB.T6G(SCH_1):PAGE350
     2    GND @T6G_MB_LIB.T6G(SCH_1):GND    I45 @T6G_MB_LIB.T6G(SCH_1):PAGE350

PC2236 Q_CAP_C0402-0.01UF,50V,10%,EMPTY,CH31006KB18
     1 P12V_SCM_R @T6G_MB_LIB.T6G(SCH_1):P12V_SCM_R    I71 @T6G_MB_LIB.T6G(SCH_1):PAGE350
     2 P12V_SCM_GATE @T6G_MB_LIB.T6G(SCH_1):P12V_SCM_GATE    I71 @T6G_MB_LIB.T6G(SCH_1):PAGE350

PC2237 Q_CAP_C0402-3900PF,50V,10%,X7R,CH23906KB14
     1 P12V_SCM_GATE @T6G_MB_LIB.T6G(SCH_1):P12V_SCM_GATE    I72 @T6G_MB_LIB.T6G(SCH_1):PAGE350
     2    GND @T6G_MB_LIB.T6G(SCH_1):GND    I72 @T6G_MB_LIB.T6G(SCH_1):PAGE350

PC2238 Q_CAP_0402-0.1UF,25V,10%,X7R,CH4104K1B00
     1 P12V_SCM_R @T6G_MB_LIB.T6G(SCH_1):P12V_SCM_R    I80 @T6G_MB_LIB.T6G(SCH_1):PAGE350
     2    GND @T6G_MB_LIB.T6G(SCH_1):GND    I80 @T6G_MB_LIB.T6G(SCH_1):PAGE350

PC2239 Q_CAP_C0603-2.2UF,16V,20%,X7R,CH5223M1900
     1 P12V_SCM_AVIN_PD @T6G_MB_LIB.T6G(SCH_1):P12V_SCM_AVIN_PD    I52 @T6G_MB_LIB.T6G(SCH_1):PAGE350
     2    GND @T6G_MB_LIB.T6G(SCH_1):GND    I52 @T6G_MB_LIB.T6G(SCH_1):PAGE350

PC2240 Q_CAP_C0805-10UF,16V,10%,X6S,CH6103KEA01
     1 P12V_SCM_R @T6G_MB_LIB.T6G(SCH_1):P12V_SCM_R    I81 @T6G_MB_LIB.T6G(SCH_1):PAGE350
     2    GND @T6G_MB_LIB.T6G(SCH_1):GND    I81 @T6G_MB_LIB.T6G(SCH_1):PAGE350

PC2241 Q_CAP_0402-0.1UF,25V,10%,X7R,CH4104K1B00
     1 P12V_SCM_R @T6G_MB_LIB.T6G(SCH_1):P12V_SCM_R    I56 @T6G_MB_LIB.T6G(SCH_1):PAGE350
     2    GND @T6G_MB_LIB.T6G(SCH_1):GND    I56 @T6G_MB_LIB.T6G(SCH_1):PAGE350

PC2242 Q_CAP_C0805-22UF,16V,20%,X6S,CH6223MEA01
     1 P12V_SCM_R @T6G_MB_LIB.T6G(SCH_1):P12V_SCM_R    I84 @T6G_MB_LIB.T6G(SCH_1):PAGE350
     2    GND @T6G_MB_LIB.T6G(SCH_1):GND    I84 @T6G_MB_LIB.T6G(SCH_1):PAGE350

PC2260 Q_CAP_C0805-22UF,16V,20%,X6S,CH6223MEA01
     1 SW_P3V3_AUX_FLT @T6G_MB_LIB.T6G(SCH_1):SW_P3V3_AUX_FLT    I26 @T6G_MB_LIB.T6G(SCH_1):PAGE245
     2    GND @T6G_MB_LIB.T6G(SCH_1):GND    I26 @T6G_MB_LIB.T6G(SCH_1):PAGE245

PC2261 Q_CAP_C0805-22UF,16V,20%,X6S,CH6223MEA01
     1 SW_P3V3_AUX_FLT @T6G_MB_LIB.T6G(SCH_1):SW_P3V3_AUX_FLT    I27 @T6G_MB_LIB.T6G(SCH_1):PAGE245
     2    GND @T6G_MB_LIB.T6G(SCH_1):GND    I27 @T6G_MB_LIB.T6G(SCH_1):PAGE245

PC2262 Q_CAP_C0805-22UF,16V,20%,X6S,CH6223MEA01
     1 SW_P3V3_AUX_FLT @T6G_MB_LIB.T6G(SCH_1):SW_P3V3_AUX_FLT    I31 @T6G_MB_LIB.T6G(SCH_1):PAGE245
     2    GND @T6G_MB_LIB.T6G(SCH_1):GND    I31 @T6G_MB_LIB.T6G(SCH_1):PAGE245

PC2263 Q_CAP_C0805-22UF,16V,20%,X6S,CH6223MEA01
     1 SW_P3V3_AUX_FLT @T6G_MB_LIB.T6G(SCH_1):SW_P3V3_AUX_FLT    I33 @T6G_MB_LIB.T6G(SCH_1):PAGE245
     2    GND @T6G_MB_LIB.T6G(SCH_1):GND    I33 @T6G_MB_LIB.T6G(SCH_1):PAGE245

PC2280 Q_CAP_C0805-10UF,16V,10%,X6S,CH6103KEA01
     1 P12V_E1S_0 @T6G_MB_LIB.T6G(SCH_1):P12V_E1S_0    I80 @T6G_MB_LIB.T6G(SCH_1):PAGE324
     2    GND @T6G_MB_LIB.T6G(SCH_1):GND    I80 @T6G_MB_LIB.T6G(SCH_1):PAGE324

PC2281 Q_CAP_C0402-0.047UF,25V,10%,X7R,CH3474K1B04
     1 P12V_E1S_SS_0 @T6G_MB_LIB.T6G(SCH_1):P12V_E1S_SS_0    I22 @T6G_MB_LIB.T6G(SCH_1):PAGE323
     2    GND @T6G_MB_LIB.T6G(SCH_1):GND    I22 @T6G_MB_LIB.T6G(SCH_1):PAGE323

PC2340 Q_CAP_C0402-560PF,50V,10%,X7R,CH1566K1B09
     1 P12V_SCM_ISET_R @T6G_MB_LIB.T6G(SCH_1):P12V_SCM_ISET_R     I6 @T6G_MB_LIB.T6G(SCH_1):PAGE350
     2    GND @T6G_MB_LIB.T6G(SCH_1):GND     I6 @T6G_MB_LIB.T6G(SCH_1):PAGE350

PC2341 Q_CAP_C0402-560PF,50V,10%,X7R,CH1566K1B09
     1 P12V_E1S_ISET_0_R @T6G_MB_LIB.T6G(SCH_1):P12V_E1S_ISET_0_R    I17 @T6G_MB_LIB.T6G(SCH_1):PAGE323
     2    GND @T6G_MB_LIB.T6G(SCH_1):GND    I17 @T6G_MB_LIB.T6G(SCH_1):PAGE323

PC2342 Q_CAP_C0805-22UF,16V,20%,X6S,CH6223MEA01
     1 SW_P3V3_AUX_FLT @T6G_MB_LIB.T6G(SCH_1):SW_P3V3_AUX_FLT    I34 @T6G_MB_LIB.T6G(SCH_1):PAGE245
     2    GND @T6G_MB_LIB.T6G(SCH_1):GND    I34 @T6G_MB_LIB.T6G(SCH_1):PAGE245

PC2343 Q_CAP_C0805-22UF,16V,20%,X6S,CH6223MEA01
     1 SW_P3V3_AUX_FLT @T6G_MB_LIB.T6G(SCH_1):SW_P3V3_AUX_FLT    I37 @T6G_MB_LIB.T6G(SCH_1):PAGE245
     2    GND @T6G_MB_LIB.T6G(SCH_1):GND    I37 @T6G_MB_LIB.T6G(SCH_1):PAGE245

PC2344 Q_CAP_C0805-22UF,16V,20%,X6S,CH6223MEA01
     1 SW_P3V3_AUX_FLT @T6G_MB_LIB.T6G(SCH_1):SW_P3V3_AUX_FLT    I38 @T6G_MB_LIB.T6G(SCH_1):PAGE245
     2    GND @T6G_MB_LIB.T6G(SCH_1):GND    I38 @T6G_MB_LIB.T6G(SCH_1):PAGE245

PC2347 Q_CAP_0402-1NF,50V,10%,EMPTY,CH21006KB16
     1 HSC_OCREF @T6G_MB_LIB.T6G(SCH_1):HSC_OCREF    I30 @T6G_MB_LIB.T6G(SCH_1):PAGE301
     2 AGND_HSC @T6G_MB_LIB.T6G(SCH_1):AGND_HSC    I30 @T6G_MB_LIB.T6G(SCH_1):PAGE301

PC2348 Q_CAP_0402-1NF,50V,10%,EMPTY,CH21006KB16
     1 HSC_OCREF @T6G_MB_LIB.T6G(SCH_1):HSC_OCREF    I12 @T6G_MB_LIB.T6G(SCH_1):PAGE301
     2 AGND_HSC @T6G_MB_LIB.T6G(SCH_1):AGND_HSC    I12 @T6G_MB_LIB.T6G(SCH_1):PAGE301

PC2349 Q_CAP_0402-1NF,50V,10%,EMPTY,CH21006KB16
     1 HSC_OCREF @T6G_MB_LIB.T6G(SCH_1):HSC_OCREF    I12 @T6G_MB_LIB.T6G(SCH_1):PAGE325
     2 AGND_HSC @T6G_MB_LIB.T6G(SCH_1):AGND_HSC    I12 @T6G_MB_LIB.T6G(SCH_1):PAGE325

PC2350 Q_CAP_0402-1NF,50V,10%,EMPTY,CH21006KB16
     1 HSC_OCREF @T6G_MB_LIB.T6G(SCH_1):HSC_OCREF    I30 @T6G_MB_LIB.T6G(SCH_1):PAGE325
     2 AGND_HSC @T6G_MB_LIB.T6G(SCH_1):AGND_HSC    I30 @T6G_MB_LIB.T6G(SCH_1):PAGE325

PC3272 Q_CAP_C0402-1UF,25V,10%,X6S,CH5104KEB02
     1 HSC_VDD_R_3 @T6G_MB_LIB.T6G(SCH_1):HSC_VDD_R_3    I20 @T6G_MB_LIB.T6G(SCH_1):PAGE325
     2 AGND_HSC @T6G_MB_LIB.T6G(SCH_1):AGND_HSC    I20 @T6G_MB_LIB.T6G(SCH_1):PAGE325

PC4056 Q_CAP_C0402-3900PF,50V,10%,X7R,CH23906KB14
     1 P12V_OCP_GATE_1 @T6G_MB_LIB.T6G(SCH_1):P12V_OCP_GATE_1    I77 @T6G_MB_LIB.T6G(SCH_1):PAGE338
     2    GND @T6G_MB_LIB.T6G(SCH_1):GND    I77 @T6G_MB_LIB.T6G(SCH_1):PAGE338

PC5328 Q_CAP_C0402-1UF,25V,10%,X6S,CH5104KEB02
     1 P3V3_AUX @T6G_MB_LIB.T6G(SCH_1):P3V3_AUX    I62 @T6G_MB_LIB.T6G(SCH_1):PAGE338
     2    GND @T6G_MB_LIB.T6G(SCH_1):GND    I62 @T6G_MB_LIB.T6G(SCH_1):PAGE338

PC6000 Q_CAP_C0402-0.1UF,25V,10%,X6S,CH4104KEB00
     1 P12V_AUX @T6G_MB_LIB.T6G(SCH_1):P12V_AUX     I8 @T6G_MB_LIB.T6G(SCH_1):PAGE167
     2    GND @T6G_MB_LIB.T6G(SCH_1):GND     I8 @T6G_MB_LIB.T6G(SCH_1):PAGE167

PC6001 Q_CAP_C0402-0.1UF,25V,10%,X6S,CH4104KEB00
     1 P12V_AUX @T6G_MB_LIB.T6G(SCH_1):P12V_AUX     I5 @T6G_MB_LIB.T6G(SCH_1):PAGE184
     2    GND @T6G_MB_LIB.T6G(SCH_1):GND     I5 @T6G_MB_LIB.T6G(SCH_1):PAGE184

PC6002 Q_CAP_0402-0.1UF,25V,10%,X7R,CH4104K1B00
     1 P12V_AUX @T6G_MB_LIB.T6G(SCH_1):P12V_AUX     I3 @T6G_MB_LIB.T6G(SCH_1):PAGE201
     2    GND @T6G_MB_LIB.T6G(SCH_1):GND     I3 @T6G_MB_LIB.T6G(SCH_1):PAGE201

PC6003 Q_CAP_0402-0.1UF,25V,10%,X7R,CH4104K1B00
     1 P12V_AUX @T6G_MB_LIB.T6G(SCH_1):P12V_AUX    I79 @T6G_MB_LIB.T6G(SCH_1):PAGE183
     2    GND @T6G_MB_LIB.T6G(SCH_1):GND    I79 @T6G_MB_LIB.T6G(SCH_1):PAGE183

PC6004 Q_CAP_0402-0.1UF,25V,10%,X7R,CH4104K1B00
     1 P12V_AUX @T6G_MB_LIB.T6G(SCH_1):P12V_AUX    I74 @T6G_MB_LIB.T6G(SCH_1):PAGE186
     2    GND @T6G_MB_LIB.T6G(SCH_1):GND    I74 @T6G_MB_LIB.T6G(SCH_1):PAGE186

PC6005 Q_CAP_C0402-0.01UF,25V,10%,EMPTY,CH3104K1B11
     1 PVDD18_S5_P0_FB_RC @T6G_MB_LIB.T6G(SCH_1):PVDD18_S5_P0_FB_RC    I34 @T6G_MB_LIB.T6G(SCH_1):PAGE184
     2 PVDD18_S5_P0_RGND @T6G_MB_LIB.T6G(SCH_1):PVDD18_S5_P0_RGND    I34 @T6G_MB_LIB.T6G(SCH_1):PAGE184

PC6006 Q_CAP_C0402-0.01UF,25V,10%,EMPTY,CH3104K1B11
     1 PVDD18_S5_P1_FB_RC @T6G_MB_LIB.T6G(SCH_1):PVDD18_S5_P1_FB_RC    I34 @T6G_MB_LIB.T6G(SCH_1):PAGE201
     2 PVDD18_SS_P1_RGND @T6G_MB_LIB.T6G(SCH_1):PVDD18_SS_P1_RGND    I34 @T6G_MB_LIB.T6G(SCH_1):PAGE201

PC6007 Q_CAP_0402-0.1UF,25V,10%,X7R,CH4104K1B00
     1 P12V_AUX @T6G_MB_LIB.T6G(SCH_1):P12V_AUX    I77 @T6G_MB_LIB.T6G(SCH_1):PAGE190
     2    GND @T6G_MB_LIB.T6G(SCH_1):GND    I77 @T6G_MB_LIB.T6G(SCH_1):PAGE190

PC6008 Q_CAP_C0402-1UF,25V,10%,X6S,CH5104KEB02
     1 P1V8_AUX_VCC @T6G_MB_LIB.T6G(SCH_1):P1V8_AUX_VCC    I13 @T6G_MB_LIB.T6G(SCH_1):PAGE315
     2    GND @T6G_MB_LIB.T6G(SCH_1):GND    I13 @T6G_MB_LIB.T6G(SCH_1):PAGE315

PC6009 Q_CAP_C0402-1UF,25V,10%,X6S,CH5104KEB02
     1 P1V2_AUX_VCC @T6G_MB_LIB.T6G(SCH_1):P1V2_AUX_VCC     I7 @T6G_MB_LIB.T6G(SCH_1):PAGE380
     2    GND @T6G_MB_LIB.T6G(SCH_1):GND     I7 @T6G_MB_LIB.T6G(SCH_1):PAGE380

PC6010 Q_CAP_C0402-1UF,25V,10%,X6S,CH5104KEB02
     1 SW_P12V_AUX_P1V8_AUX_FLT @T6G_MB_LIB.T6G(SCH_1):SW_P12V_AUX_P1V8_AUX_FLT    I19 @T6G_MB_LIB.T6G(SCH_1):PAGE315
     2    GND @T6G_MB_LIB.T6G(SCH_1):GND    I19 @T6G_MB_LIB.T6G(SCH_1):PAGE315

PC6011 Q_CAP_C0402-1UF,25V,10%,X6S,CH5104KEB02
     1 SW_P12V_AUX_P1V2_AUX_FLT @T6G_MB_LIB.T6G(SCH_1):SW_P12V_AUX_P1V2_AUX_FLT    I12 @T6G_MB_LIB.T6G(SCH_1):PAGE380
     2    GND @T6G_MB_LIB.T6G(SCH_1):GND    I12 @T6G_MB_LIB.T6G(SCH_1):PAGE380

PC6012 Q_CAP_C0805-22UF,16V,20%,X6S,CH6223MEA01
     1 SW_P12V_AUX_P1V8_AUX_FLT @T6G_MB_LIB.T6G(SCH_1):SW_P12V_AUX_P1V8_AUX_FLT     I8 @T6G_MB_LIB.T6G(SCH_1):PAGE315
     2    GND @T6G_MB_LIB.T6G(SCH_1):GND     I8 @T6G_MB_LIB.T6G(SCH_1):PAGE315

PC6013 Q_CAP_C0805-22UF,16V,20%,X6S,CH6223MEA01
     1 SW_P12V_AUX_P1V2_AUX_FLT @T6G_MB_LIB.T6G(SCH_1):SW_P12V_AUX_P1V2_AUX_FLT     I3 @T6G_MB_LIB.T6G(SCH_1):PAGE380
     2    GND @T6G_MB_LIB.T6G(SCH_1):GND     I3 @T6G_MB_LIB.T6G(SCH_1):PAGE380

PC6014 Q_CAP_C0805-22UF,16V,20%,X6S,CH6223MEA01
     1 SW_P12V_AUX_P1V8_AUX_FLT @T6G_MB_LIB.T6G(SCH_1):SW_P12V_AUX_P1V8_AUX_FLT    I10 @T6G_MB_LIB.T6G(SCH_1):PAGE315
     2    GND @T6G_MB_LIB.T6G(SCH_1):GND    I10 @T6G_MB_LIB.T6G(SCH_1):PAGE315

PC6015 Q_CAP_C0805-22UF,16V,20%,X6S,CH6223MEA01
     1 SW_P12V_AUX_P1V2_AUX_FLT @T6G_MB_LIB.T6G(SCH_1):SW_P12V_AUX_P1V2_AUX_FLT    I10 @T6G_MB_LIB.T6G(SCH_1):PAGE380
     2    GND @T6G_MB_LIB.T6G(SCH_1):GND    I10 @T6G_MB_LIB.T6G(SCH_1):PAGE380

PC6016 Q_CAP_0402-3300PF,50V,10%,X7R,TMP_QCH2336K1B12
     1 P1V2_AUX_REF @T6G_MB_LIB.T6G(SCH_1):P1V2_AUX_REF    I17 @T6G_MB_LIB.T6G(SCH_1):PAGE380
     2    GND @T6G_MB_LIB.T6G(SCH_1):GND    I17 @T6G_MB_LIB.T6G(SCH_1):PAGE380

PC6017 Q_CAP_C0402-0.22UF,25V,10%,X7R,CH4224K1B01
     1 SW_P1V2_AUX_BT_R @T6G_MB_LIB.T6G(SCH_1):SW_P1V2_AUX_BT_R    I18 @T6G_MB_LIB.T6G(SCH_1):PAGE380
     2 SW_P1V2_AUX_PH @T6G_MB_LIB.T6G(SCH_1):SW_P1V2_AUX_PH    I18 @T6G_MB_LIB.T6G(SCH_1):PAGE380

PC6018 Q_CAP_C0805-22UF,4V,20%,X6S,CH622KMEA03
     1 P1V2_AUX @T6G_MB_LIB.T6G(SCH_1):P1V2_AUX    I33 @T6G_MB_LIB.T6G(SCH_1):PAGE380
     2    GND @T6G_MB_LIB.T6G(SCH_1):GND    I33 @T6G_MB_LIB.T6G(SCH_1):PAGE380

PC6019 Q_CAP_0402-330PF,50V,10%,X7R,CH1336K1B02
     1 P1V8_AUX_FB @T6G_MB_LIB.T6G(SCH_1):P1V8_AUX_FB    I26 @T6G_MB_LIB.T6G(SCH_1):PAGE315
     2 P1V8_AUX @T6G_MB_LIB.T6G(SCH_1):P1V8_AUX    I26 @T6G_MB_LIB.T6G(SCH_1):PAGE315

PC6020 Q_CAP_C0402-100NF,50V,10%,X7R,CH4106K1B01
     1 P12V_AUX @T6G_MB_LIB.T6G(SCH_1):P12V_AUX     I5 @T6G_MB_LIB.T6G(SCH_1):PAGE315
     2    GND @T6G_MB_LIB.T6G(SCH_1):GND     I5 @T6G_MB_LIB.T6G(SCH_1):PAGE315

PC6021 Q_CAP_C0402-100NF,50V,10%,X7R,CH4106K1B01
     1 P1V8_AUX @T6G_MB_LIB.T6G(SCH_1):P1V8_AUX    I27 @T6G_MB_LIB.T6G(SCH_1):PAGE315
     2    GND @T6G_MB_LIB.T6G(SCH_1):GND    I27 @T6G_MB_LIB.T6G(SCH_1):PAGE315

PC6022 Q_CAP_C0402-100NF,50V,10%,X7R,CH4106K1B01
     1 P1V2_AUX @T6G_MB_LIB.T6G(SCH_1):P1V2_AUX    I23 @T6G_MB_LIB.T6G(SCH_1):PAGE380
     2    GND @T6G_MB_LIB.T6G(SCH_1):GND    I23 @T6G_MB_LIB.T6G(SCH_1):PAGE380

PC6023 Q_CAP_C0402-100NF,50V,10%,X7R,CH4106K1B01
     1 P12V_AUX @T6G_MB_LIB.T6G(SCH_1):P12V_AUX    I35 @T6G_MB_LIB.T6G(SCH_1):PAGE380
     2    GND @T6G_MB_LIB.T6G(SCH_1):GND    I35 @T6G_MB_LIB.T6G(SCH_1):PAGE380

PC6024 Q_CAP_C0805-22UF,4V,20%,X6S,CH622KMEA03
     1 P1V2_AUX @T6G_MB_LIB.T6G(SCH_1):P1V2_AUX    I28 @T6G_MB_LIB.T6G(SCH_1):PAGE380
     2    GND @T6G_MB_LIB.T6G(SCH_1):GND    I28 @T6G_MB_LIB.T6G(SCH_1):PAGE380

PC6025 Q_CAP_C0805-22UF,4V,20%,X6S,CH622KMEA03
     1 P1V2_AUX @T6G_MB_LIB.T6G(SCH_1):P1V2_AUX    I29 @T6G_MB_LIB.T6G(SCH_1):PAGE380
     2    GND @T6G_MB_LIB.T6G(SCH_1):GND    I29 @T6G_MB_LIB.T6G(SCH_1):PAGE380

PC6026 Q_CAP_C0805-22UF,4V,20%,X6S,CH622KMEA03
     1 P1V2_AUX @T6G_MB_LIB.T6G(SCH_1):P1V2_AUX    I32 @T6G_MB_LIB.T6G(SCH_1):PAGE380
     2    GND @T6G_MB_LIB.T6G(SCH_1):GND    I32 @T6G_MB_LIB.T6G(SCH_1):PAGE380

PC6500 Q_CAP_C0402-0.1UF,25V,10%,X6S,CH4104KEB00
     1 P12V_AUX @T6G_MB_LIB.T6G(SCH_1):P12V_AUX     I4 @T6G_MB_LIB.T6G(SCH_1):PAGE469
     2    GND @T6G_MB_LIB.T6G(SCH_1):GND     I4 @T6G_MB_LIB.T6G(SCH_1):PAGE469

PC6501 Q_CAP_C0805-22UF,16V,20%,X6S,CH6223MEA01
     1 SW_P12V_AUX_P1V8_RETIMER_CPU0_FLT @T6G_MB_LIB.T6G(SCH_1):SW_P12V_AUX_P1V8_RETIMER_CPU0_FLT    I16 @T6G_MB_LIB.T6G(SCH_1):PAGE469
     2    GND @T6G_MB_LIB.T6G(SCH_1):GND    I16 @T6G_MB_LIB.T6G(SCH_1):PAGE469

PC6502 Q_CAP_C0805-22UF,16V,20%,X6S,CH6223MEA01
     1 SW_P12V_AUX_P1V8_RETIMER_CPU0_FLT @T6G_MB_LIB.T6G(SCH_1):SW_P12V_AUX_P1V8_RETIMER_CPU0_FLT    I17 @T6G_MB_LIB.T6G(SCH_1):PAGE469
     2    GND @T6G_MB_LIB.T6G(SCH_1):GND    I17 @T6G_MB_LIB.T6G(SCH_1):PAGE469

PC6503 Q_CAP_C0805-22UF,16V,20%,X6S,CH6223MEA01
     1 SW_P12V_AUX_P1V8_RETIMER_CPU0_FLT @T6G_MB_LIB.T6G(SCH_1):SW_P12V_AUX_P1V8_RETIMER_CPU0_FLT    I18 @T6G_MB_LIB.T6G(SCH_1):PAGE469
     2    GND @T6G_MB_LIB.T6G(SCH_1):GND    I18 @T6G_MB_LIB.T6G(SCH_1):PAGE469

PC6504 Q_CAP_C0805-22UF,16V,20%,X6S,CH6223MEA01
     1 SW_P12V_AUX_P1V8_RETIMER_CPU0_FLT @T6G_MB_LIB.T6G(SCH_1):SW_P12V_AUX_P1V8_RETIMER_CPU0_FLT    I22 @T6G_MB_LIB.T6G(SCH_1):PAGE469
     2    GND @T6G_MB_LIB.T6G(SCH_1):GND    I22 @T6G_MB_LIB.T6G(SCH_1):PAGE469

PC6505 Q_CAP_C0402-1UF,25V,10%,X6S,CH5104KEB02
     1 SW_P12V_AUX_P1V8_RETIMER_CPU0_FLT @T6G_MB_LIB.T6G(SCH_1):SW_P12V_AUX_P1V8_RETIMER_CPU0_FLT    I23 @T6G_MB_LIB.T6G(SCH_1):PAGE469
     2    GND @T6G_MB_LIB.T6G(SCH_1):GND    I23 @T6G_MB_LIB.T6G(SCH_1):PAGE469

PC6506 Q_CAP_C0402-1UF,25V,10%,X6S,CH5104KEB02
     1 P1V8_RETIMER_CPU0_VCC @T6G_MB_LIB.T6G(SCH_1):P1V8_RETIMER_CPU0_VCC    I12 @T6G_MB_LIB.T6G(SCH_1):PAGE469
     2    GND @T6G_MB_LIB.T6G(SCH_1):GND    I12 @T6G_MB_LIB.T6G(SCH_1):PAGE469

PC6507 Q_CAP_0402-0.22UF,16V,10%,X7R,CH4223K1B00
     1 SW_P1V8_RETIMER_CPU0_BST_R @T6G_MB_LIB.T6G(SCH_1):SW_P1V8_RETIMER_CPU0_BST_R    I32 @T6G_MB_LIB.T6G(SCH_1):PAGE469
     2 SW_P1V8_RETIMER_CPU0_SW @T6G_MB_LIB.T6G(SCH_1):SW_P1V8_RETIMER_CPU0_SW    I32 @T6G_MB_LIB.T6G(SCH_1):PAGE469

PC6508 Q_CAP_C0805-22UF,4V,20%,X6S,CH622KMEA03
     1 P1V8_CPU0_RT_1D @T6G_MB_LIB.T6G(SCH_1):P1V8_CPU0_RT_1D    I38 @T6G_MB_LIB.T6G(SCH_1):PAGE469
     2    GND @T6G_MB_LIB.T6G(SCH_1):GND    I38 @T6G_MB_LIB.T6G(SCH_1):PAGE469

PC6509 Q_CAP_C0805-22UF,4V,20%,X6S,CH622KMEA03
     1 P1V8_CPU0_RT_1D @T6G_MB_LIB.T6G(SCH_1):P1V8_CPU0_RT_1D    I39 @T6G_MB_LIB.T6G(SCH_1):PAGE469
     2    GND @T6G_MB_LIB.T6G(SCH_1):GND    I39 @T6G_MB_LIB.T6G(SCH_1):PAGE469

PC6510 Q_CAP_C0805-22UF,4V,20%,X6S,CH622KMEA03
     1 P1V8_CPU0_RT_1D @T6G_MB_LIB.T6G(SCH_1):P1V8_CPU0_RT_1D    I40 @T6G_MB_LIB.T6G(SCH_1):PAGE469
     2    GND @T6G_MB_LIB.T6G(SCH_1):GND    I40 @T6G_MB_LIB.T6G(SCH_1):PAGE469

PC6511 Q_CAP_C0805-22UF,4V,20%,X6S,CH622KMEA03
     1 P1V8_CPU0_RT_1D @T6G_MB_LIB.T6G(SCH_1):P1V8_CPU0_RT_1D    I44 @T6G_MB_LIB.T6G(SCH_1):PAGE469
     2    GND @T6G_MB_LIB.T6G(SCH_1):GND    I44 @T6G_MB_LIB.T6G(SCH_1):PAGE469

PC6512 Q_CAP_C0805-22UF,4V,20%,X6S,CH622KMEA03
     1 P1V8_CPU0_RT_1D @T6G_MB_LIB.T6G(SCH_1):P1V8_CPU0_RT_1D    I52 @T6G_MB_LIB.T6G(SCH_1):PAGE469
     2    GND @T6G_MB_LIB.T6G(SCH_1):GND    I52 @T6G_MB_LIB.T6G(SCH_1):PAGE469

PC6513 Q_CAPP_SMLF-390UF,2.5V,20%,ALUM,CC7390JMZ13
     1 P1V8_CPU0_RT_1D @T6G_MB_LIB.T6G(SCH_1):P1V8_CPU0_RT_1D    I46 @T6G_MB_LIB.T6G(SCH_1):PAGE469
     2    GND @T6G_MB_LIB.T6G(SCH_1):GND    I46 @T6G_MB_LIB.T6G(SCH_1):PAGE469

PC6514 Q_CAP_0402-0.1UF,25V,10%,X7R,CH4104K1B00
     1 P1V8_CPU0_RT_1D @T6G_MB_LIB.T6G(SCH_1):P1V8_CPU0_RT_1D    I49 @T6G_MB_LIB.T6G(SCH_1):PAGE469
     2    GND @T6G_MB_LIB.T6G(SCH_1):GND    I49 @T6G_MB_LIB.T6G(SCH_1):PAGE469

PC6515 Q_CAP_0402-150PF,50V,5%,NPO,TMP_QCH11506JB08
     1 P1V8_RETIMER_CPU0_FB @T6G_MB_LIB.T6G(SCH_1):P1V8_RETIMER_CPU0_FB    I34 @T6G_MB_LIB.T6G(SCH_1):PAGE469
     2 P1V8_CPU0_RT_1D @T6G_MB_LIB.T6G(SCH_1):P1V8_CPU0_RT_1D    I34 @T6G_MB_LIB.T6G(SCH_1):PAGE469

PC6518 Q_CAP_0402-0.1UF,25V,10%,X7R,CH4104K1B00
     1 P1V8_RETIMER_CPU0_REF @T6G_MB_LIB.T6G(SCH_1):P1V8_RETIMER_CPU0_REF    I26 @T6G_MB_LIB.T6G(SCH_1):PAGE469
     2    GND @T6G_MB_LIB.T6G(SCH_1):GND    I26 @T6G_MB_LIB.T6G(SCH_1):PAGE469

PC6519 Q_CAP_C0402-0.1UF,25V,10%,X6S,CH4104KEB00
     1 P12V_AUX @T6G_MB_LIB.T6G(SCH_1):P12V_AUX     I3 @T6G_MB_LIB.T6G(SCH_1):PAGE470
     2    GND @T6G_MB_LIB.T6G(SCH_1):GND     I3 @T6G_MB_LIB.T6G(SCH_1):PAGE470

PC6520 Q_CAP_C0805-22UF,16V,20%,X6S,CH6223MEA01
     1 SW_P12V_AUX_P1V8_RETIMER_CPU1_FLT @T6G_MB_LIB.T6G(SCH_1):SW_P12V_AUX_P1V8_RETIMER_CPU1_FLT    I16 @T6G_MB_LIB.T6G(SCH_1):PAGE470
     2    GND @T6G_MB_LIB.T6G(SCH_1):GND    I16 @T6G_MB_LIB.T6G(SCH_1):PAGE470

PC6521 Q_CAP_C0805-22UF,16V,20%,X6S,CH6223MEA01
     1 SW_P12V_AUX_P1V8_RETIMER_CPU1_FLT @T6G_MB_LIB.T6G(SCH_1):SW_P12V_AUX_P1V8_RETIMER_CPU1_FLT    I17 @T6G_MB_LIB.T6G(SCH_1):PAGE470
     2    GND @T6G_MB_LIB.T6G(SCH_1):GND    I17 @T6G_MB_LIB.T6G(SCH_1):PAGE470

PC6522 Q_CAP_C0805-22UF,16V,20%,X6S,CH6223MEA01
     1 SW_P12V_AUX_P1V8_RETIMER_CPU1_FLT @T6G_MB_LIB.T6G(SCH_1):SW_P12V_AUX_P1V8_RETIMER_CPU1_FLT    I18 @T6G_MB_LIB.T6G(SCH_1):PAGE470
     2    GND @T6G_MB_LIB.T6G(SCH_1):GND    I18 @T6G_MB_LIB.T6G(SCH_1):PAGE470

PC6523 Q_CAP_C0805-22UF,16V,20%,X6S,CH6223MEA01
     1 SW_P12V_AUX_P1V8_RETIMER_CPU1_FLT @T6G_MB_LIB.T6G(SCH_1):SW_P12V_AUX_P1V8_RETIMER_CPU1_FLT    I22 @T6G_MB_LIB.T6G(SCH_1):PAGE470
     2    GND @T6G_MB_LIB.T6G(SCH_1):GND    I22 @T6G_MB_LIB.T6G(SCH_1):PAGE470

PC6524 Q_CAP_C0402-1UF,25V,10%,X6S,CH5104KEB02
     1 SW_P12V_AUX_P1V8_RETIMER_CPU1_FLT @T6G_MB_LIB.T6G(SCH_1):SW_P12V_AUX_P1V8_RETIMER_CPU1_FLT    I23 @T6G_MB_LIB.T6G(SCH_1):PAGE470
     2    GND @T6G_MB_LIB.T6G(SCH_1):GND    I23 @T6G_MB_LIB.T6G(SCH_1):PAGE470

PC6525 Q_CAP_C0402-1UF,25V,10%,X6S,CH5104KEB02
     1 P1V8_RETIMER_CPU1_VCC @T6G_MB_LIB.T6G(SCH_1):P1V8_RETIMER_CPU1_VCC    I12 @T6G_MB_LIB.T6G(SCH_1):PAGE470
     2    GND @T6G_MB_LIB.T6G(SCH_1):GND    I12 @T6G_MB_LIB.T6G(SCH_1):PAGE470

PC6526 Q_CAP_0402-0.22UF,16V,10%,X7R,CH4223K1B00
     1 SW_P1V8_RETIMER_CPU1_BST_R @T6G_MB_LIB.T6G(SCH_1):SW_P1V8_RETIMER_CPU1_BST_R    I35 @T6G_MB_LIB.T6G(SCH_1):PAGE470
     2 SW_P1V8_RETIMER_CPU1_SW @T6G_MB_LIB.T6G(SCH_1):SW_P1V8_RETIMER_CPU1_SW    I35 @T6G_MB_LIB.T6G(SCH_1):PAGE470

PC6527 Q_CAP_C0805-22UF,4V,20%,X6S,CH622KMEA03
     1 P1V8_CPU1_RT_1D @T6G_MB_LIB.T6G(SCH_1):P1V8_CPU1_RT_1D    I38 @T6G_MB_LIB.T6G(SCH_1):PAGE470
     2    GND @T6G_MB_LIB.T6G(SCH_1):GND    I38 @T6G_MB_LIB.T6G(SCH_1):PAGE470

PC6528 Q_CAP_C0805-22UF,4V,20%,X6S,CH622KMEA03
     1 P1V8_CPU1_RT_1D @T6G_MB_LIB.T6G(SCH_1):P1V8_CPU1_RT_1D    I41 @T6G_MB_LIB.T6G(SCH_1):PAGE470
     2    GND @T6G_MB_LIB.T6G(SCH_1):GND    I41 @T6G_MB_LIB.T6G(SCH_1):PAGE470

PC6529 Q_CAP_C0805-22UF,4V,20%,X6S,CH622KMEA03
     1 P1V8_CPU1_RT_1D @T6G_MB_LIB.T6G(SCH_1):P1V8_CPU1_RT_1D    I42 @T6G_MB_LIB.T6G(SCH_1):PAGE470
     2    GND @T6G_MB_LIB.T6G(SCH_1):GND    I42 @T6G_MB_LIB.T6G(SCH_1):PAGE470

PC6530 Q_CAP_C0805-22UF,4V,20%,X6S,CH622KMEA03
     1 P1V8_CPU1_RT_1D @T6G_MB_LIB.T6G(SCH_1):P1V8_CPU1_RT_1D    I44 @T6G_MB_LIB.T6G(SCH_1):PAGE470
     2    GND @T6G_MB_LIB.T6G(SCH_1):GND    I44 @T6G_MB_LIB.T6G(SCH_1):PAGE470

PC6531 Q_CAP_C0805-22UF,4V,20%,X6S,CH622KMEA03
     1 P1V8_CPU1_RT_1D @T6G_MB_LIB.T6G(SCH_1):P1V8_CPU1_RT_1D    I45 @T6G_MB_LIB.T6G(SCH_1):PAGE470
     2    GND @T6G_MB_LIB.T6G(SCH_1):GND    I45 @T6G_MB_LIB.T6G(SCH_1):PAGE470

PC6532 Q_CAPP_SMLF-390UF,2.5V,20%,ALUM,CC7390JMZ13
     1 P1V8_CPU1_RT_1D @T6G_MB_LIB.T6G(SCH_1):P1V8_CPU1_RT_1D    I46 @T6G_MB_LIB.T6G(SCH_1):PAGE470
     2    GND @T6G_MB_LIB.T6G(SCH_1):GND    I46 @T6G_MB_LIB.T6G(SCH_1):PAGE470

PC6533 Q_CAP_0402-0.1UF,25V,10%,X7R,CH4104K1B00
     1 P1V8_CPU1_RT_1D @T6G_MB_LIB.T6G(SCH_1):P1V8_CPU1_RT_1D    I49 @T6G_MB_LIB.T6G(SCH_1):PAGE470
     2    GND @T6G_MB_LIB.T6G(SCH_1):GND    I49 @T6G_MB_LIB.T6G(SCH_1):PAGE470

PC6534 Q_CAP_0402-150PF,50V,5%,NPO,TMP_QCH11506JB08
     1 P1V8_RETIMER_CPU1_FB @T6G_MB_LIB.T6G(SCH_1):P1V8_RETIMER_CPU1_FB    I33 @T6G_MB_LIB.T6G(SCH_1):PAGE470
     2 P1V8_CPU1_RT_1D @T6G_MB_LIB.T6G(SCH_1):P1V8_CPU1_RT_1D    I33 @T6G_MB_LIB.T6G(SCH_1):PAGE470

PC6537 Q_CAP_0402-0.1UF,25V,10%,X7R,CH4104K1B00
     1 P1V8_RETIMER_CPU1_REF @T6G_MB_LIB.T6G(SCH_1):P1V8_RETIMER_CPU1_REF    I25 @T6G_MB_LIB.T6G(SCH_1):PAGE470
     2    GND @T6G_MB_LIB.T6G(SCH_1):GND    I25 @T6G_MB_LIB.T6G(SCH_1):PAGE470

PC6540 Q_CAP_0402-3300PF,50V,10%,X7R,TMP_QCH2336K1B12
     1 P0V9_RETIMER_CPU0_SENSE_R_P @T6G_MB_LIB.T6G(SCH_1):P0V9_RETIMER_CPU0_SENSE_R_P   I121 @T6G_MB_LIB.T6G(SCH_1):PAGE475
     2 P0V9_RETIMER_CPU0_SENSE_SH_N @T6G_MB_LIB.T6G(SCH_1):P0V9_RETIMER_CPU0_SENSE_SH_N   I121 @T6G_MB_LIB.T6G(SCH_1):PAGE475

PC6543 Q_CAP_C0402-100NF,50V,10%,X7R,CH4106K1B01
     1 P0V9_RETIMER_CPU1_VCC @T6G_MB_LIB.T6G(SCH_1):P0V9_RETIMER_CPU1_VCC    I74 @T6G_MB_LIB.T6G(SCH_1):PAGE477
     2    GND @T6G_MB_LIB.T6G(SCH_1):GND    I74 @T6G_MB_LIB.T6G(SCH_1):PAGE477

PC6544 Q_CAP_C0402-1UF,16V,10%,X6S,CH5103KEB01
     1 P0V9_RETIMER_CPU1_VCC @T6G_MB_LIB.T6G(SCH_1):P0V9_RETIMER_CPU1_VCC    I75 @T6G_MB_LIB.T6G(SCH_1):PAGE477
     2    GND @T6G_MB_LIB.T6G(SCH_1):GND    I75 @T6G_MB_LIB.T6G(SCH_1):PAGE477

PC6545 Q_CAP_C0402-1UF,16V,10%,X6S,CH5103KEB01
     1 PV09_RETIMER_CPU1_VCCS @T6G_MB_LIB.T6G(SCH_1):PV09_RETIMER_CPU1_VCCS    I73 @T6G_MB_LIB.T6G(SCH_1):PAGE477
     2    GND @T6G_MB_LIB.T6G(SCH_1):GND    I73 @T6G_MB_LIB.T6G(SCH_1):PAGE477

PC6546 Q_CAP_C0402-10UF,6.3V,20%,X6S,CH6101MEB03
     1 PV09_RETIMER_CPU1_VCCS @T6G_MB_LIB.T6G(SCH_1):PV09_RETIMER_CPU1_VCCS    I72 @T6G_MB_LIB.T6G(SCH_1):PAGE477
     2    GND @T6G_MB_LIB.T6G(SCH_1):GND    I72 @T6G_MB_LIB.T6G(SCH_1):PAGE477

PC6550_09P0_1 Q_CAP_C0402-2.2UF,10V,10%,X6S,CH5222KEB01
     1 P0V9_RETIMER_CPU0_PVCC @T6G_MB_LIB.T6G(SCH_1):P0V9_RETIMER_CPU0_PVCC    I47 @T6G_MB_LIB.T6G(SCH_1):PAGE476
     2    GND @T6G_MB_LIB.T6G(SCH_1):GND    I47 @T6G_MB_LIB.T6G(SCH_1):PAGE476

PC6551_09P0_2 Q_CAP_C0402-2.2UF,10V,10%,X6S,CH5222KEB01
     1 P0V9_RETIMER_CPU0_PVCC @T6G_MB_LIB.T6G(SCH_1):P0V9_RETIMER_CPU0_PVCC   I267 @T6G_MB_LIB.T6G(SCH_1):PAGE476
     2    GND @T6G_MB_LIB.T6G(SCH_1):GND   I267 @T6G_MB_LIB.T6G(SCH_1):PAGE476

PC6552 Q_CAP_C0402-2.2UF,10V,10%,X6S,CH5222KEB01
     1 P0V9_RETIMER_CPU0_VCC1 @T6G_MB_LIB.T6G(SCH_1):P0V9_RETIMER_CPU0_VCC1    I48 @T6G_MB_LIB.T6G(SCH_1):PAGE476
     2    GND @T6G_MB_LIB.T6G(SCH_1):GND    I48 @T6G_MB_LIB.T6G(SCH_1):PAGE476

PC6553_1 Q_CAP_C0402-100NF,50V,10%,X7R,CH4106K1B01
     1 PV09_RETIMER_CPU0_VCCS @T6G_MB_LIB.T6G(SCH_1):PV09_RETIMER_CPU0_VCCS    I68 @T6G_MB_LIB.T6G(SCH_1):PAGE476
     2    GND @T6G_MB_LIB.T6G(SCH_1):GND    I68 @T6G_MB_LIB.T6G(SCH_1):PAGE476

PC6554_1 Q_CAP_C0402-1UF,25V,10%,X6S,CH5104KEB02
     1 SW_P12V_AUX_P0V9_RETIMER_CPU0_FLT @T6G_MB_LIB.T6G(SCH_1):SW_P12V_AUX_P0V9_RETIMER_CPU0_FLT    I29 @T6G_MB_LIB.T6G(SCH_1):PAGE476
     2    GND @T6G_MB_LIB.T6G(SCH_1):GND    I29 @T6G_MB_LIB.T6G(SCH_1):PAGE476

PC6555_1 Q_CAP_0402-3300PF,50V,10%,X7R,TMP_QCH2336K1B12
     1 SW_P12V_AUX_P0V9_RETIMER_CPU0_FLT @T6G_MB_LIB.T6G(SCH_1):SW_P12V_AUX_P0V9_RETIMER_CPU0_FLT     I6 @T6G_MB_LIB.T6G(SCH_1):PAGE476
     2    GND @T6G_MB_LIB.T6G(SCH_1):GND     I6 @T6G_MB_LIB.T6G(SCH_1):PAGE476

PC6556_1 Q_CAP_C0805-22UF,16V,20%,X6S,CH6223MEA01
     1 SW_P12V_AUX_P0V9_RETIMER_CPU0_FLT @T6G_MB_LIB.T6G(SCH_1):SW_P12V_AUX_P0V9_RETIMER_CPU0_FLT    I27 @T6G_MB_LIB.T6G(SCH_1):PAGE476
     2    GND @T6G_MB_LIB.T6G(SCH_1):GND    I27 @T6G_MB_LIB.T6G(SCH_1):PAGE476

PC6557_1 Q_CAP_C0805-22UF,16V,20%,X6S,CH6223MEA01
     1 SW_P12V_AUX_P0V9_RETIMER_CPU0_FLT @T6G_MB_LIB.T6G(SCH_1):SW_P12V_AUX_P0V9_RETIMER_CPU0_FLT    I24 @T6G_MB_LIB.T6G(SCH_1):PAGE476
     2    GND @T6G_MB_LIB.T6G(SCH_1):GND    I24 @T6G_MB_LIB.T6G(SCH_1):PAGE476

PC6558_1 Q_CAP_C0805-22UF,16V,20%,X6S,CH6223MEA01
     1 SW_P12V_AUX_P0V9_RETIMER_CPU0_FLT @T6G_MB_LIB.T6G(SCH_1):SW_P12V_AUX_P0V9_RETIMER_CPU0_FLT    I21 @T6G_MB_LIB.T6G(SCH_1):PAGE476
     2    GND @T6G_MB_LIB.T6G(SCH_1):GND    I21 @T6G_MB_LIB.T6G(SCH_1):PAGE476

PC6559_1 Q_CAP_C0805-22UF,16V,20%,X6S,CH6223MEA01
     1 SW_P12V_AUX_P0V9_RETIMER_CPU0_FLT @T6G_MB_LIB.T6G(SCH_1):SW_P12V_AUX_P0V9_RETIMER_CPU0_FLT   I210 @T6G_MB_LIB.T6G(SCH_1):PAGE476
     2    GND @T6G_MB_LIB.T6G(SCH_1):GND   I210 @T6G_MB_LIB.T6G(SCH_1):PAGE476

PC6560 Q_CAP_C0805-22UF,16V,20%,X6S,CH6223MEA01
     1 SW_P12V_AUX_P0V9_RETIMER_CPU0_FLT @T6G_MB_LIB.T6G(SCH_1):SW_P12V_AUX_P0V9_RETIMER_CPU0_FLT   I217 @T6G_MB_LIB.T6G(SCH_1):PAGE476
     2    GND @T6G_MB_LIB.T6G(SCH_1):GND   I217 @T6G_MB_LIB.T6G(SCH_1):PAGE476

PC6561 Q_CAPP_SMLF-100UF,16V,20%,OSCON,CC71003MZ30
     1 SW_P12V_AUX_P0V9_RETIMER_CPU0_FLT @T6G_MB_LIB.T6G(SCH_1):SW_P12V_AUX_P0V9_RETIMER_CPU0_FLT   I209 @T6G_MB_LIB.T6G(SCH_1):PAGE476
     2    GND @T6G_MB_LIB.T6G(SCH_1):GND   I209 @T6G_MB_LIB.T6G(SCH_1):PAGE476

PC6562 Q_CAP_0402-0.1UF,25V,10%,X7R,CH4104K1B00
     1 P12V_AUX @T6G_MB_LIB.T6G(SCH_1):P12V_AUX   I291 @T6G_MB_LIB.T6G(SCH_1):PAGE476
     2    GND @T6G_MB_LIB.T6G(SCH_1):GND   I291 @T6G_MB_LIB.T6G(SCH_1):PAGE476

PC6563 Q_CAP_C0402-100NF,50V,10%,X7R,CH4106K1B01
     1 SW_P0V9_RETIMER_CPU0_BOOT1_RC @T6G_MB_LIB.T6G(SCH_1):SW_P0V9_RETIMER_CPU0_BOOT1_RC    I30 @T6G_MB_LIB.T6G(SCH_1):PAGE476
     2 SW_P0V9_RETIMER_CPU0_PH1 @T6G_MB_LIB.T6G(SCH_1):SW_P0V9_RETIMER_CPU0_PH1    I30 @T6G_MB_LIB.T6G(SCH_1):PAGE476

PC6564 Q_CAP_C0402-560PF,50V,10%,EMPTY,CH1566K1B09
     1 SW_P0V9_RETIMER_CPU0_SW1 @T6G_MB_LIB.T6G(SCH_1):SW_P0V9_RETIMER_CPU0_SW1   I285 @T6G_MB_LIB.T6G(SCH_1):PAGE476
     2 SW_P0V9_RETIMER_CPU0_SW1_RC @T6G_MB_LIB.T6G(SCH_1):SW_P0V9_RETIMER_CPU0_SW1_RC   I285 @T6G_MB_LIB.T6G(SCH_1):PAGE476

PC6565 Q_CAP_C0402-100NF,50V,10%,X7R,CH4106K1B01
     1 P0V9_CPU0_RT_2D @T6G_MB_LIB.T6G(SCH_1):P0V9_CPU0_RT_2D    I33 @T6G_MB_LIB.T6G(SCH_1):PAGE476
     2    GND @T6G_MB_LIB.T6G(SCH_1):GND    I33 @T6G_MB_LIB.T6G(SCH_1):PAGE476

PC6566_1 Q_CAP_C0805-22UF,4V,20%,X6S,CH622KMEA03
     1 P0V9_CPU0_RT_2D @T6G_MB_LIB.T6G(SCH_1):P0V9_CPU0_RT_2D   I202 @T6G_MB_LIB.T6G(SCH_1):PAGE476
     2    GND @T6G_MB_LIB.T6G(SCH_1):GND   I202 @T6G_MB_LIB.T6G(SCH_1):PAGE476

PC6567_1 Q_CAP_C0805-22UF,4V,20%,X6S,CH622KMEA03
     1 P0V9_CPU0_RT_2D @T6G_MB_LIB.T6G(SCH_1):P0V9_CPU0_RT_2D   I223 @T6G_MB_LIB.T6G(SCH_1):PAGE476
     2    GND @T6G_MB_LIB.T6G(SCH_1):GND   I223 @T6G_MB_LIB.T6G(SCH_1):PAGE476

PC6568 Q_CAPP_SMLF-470UF,2.5V,20%,SPCAP,CH747LM8818
     1 P0V9_CPU0_RT_2D @T6G_MB_LIB.T6G(SCH_1):P0V9_CPU0_RT_2D   I224 @T6G_MB_LIB.T6G(SCH_1):PAGE476
     2    GND @T6G_MB_LIB.T6G(SCH_1):GND   I224 @T6G_MB_LIB.T6G(SCH_1):PAGE476

PC6569 Q_CAPP_SMLF-470UF,2.5V,20%,SPCAP,CH747LM8818
     1 P0V9_CPU0_RT_2D @T6G_MB_LIB.T6G(SCH_1):P0V9_CPU0_RT_2D   I225 @T6G_MB_LIB.T6G(SCH_1):PAGE476
     2    GND @T6G_MB_LIB.T6G(SCH_1):GND   I225 @T6G_MB_LIB.T6G(SCH_1):PAGE476

PC6570 Q_CAPP_SMLF-470UF,2.5V,20%,SPCAP,CH747LM8818
     1 P0V9_CPU0_RT_2D @T6G_MB_LIB.T6G(SCH_1):P0V9_CPU0_RT_2D   I226 @T6G_MB_LIB.T6G(SCH_1):PAGE476
     2    GND @T6G_MB_LIB.T6G(SCH_1):GND   I226 @T6G_MB_LIB.T6G(SCH_1):PAGE476

PC6571 Q_CAPP_SMLF-390UF,2.5V,20%,ALUM,CC7390JMZ13
     1 P0V9_CPU0_RT_2D @T6G_MB_LIB.T6G(SCH_1):P0V9_CPU0_RT_2D   I227 @T6G_MB_LIB.T6G(SCH_1):PAGE476
     2    GND @T6G_MB_LIB.T6G(SCH_1):GND   I227 @T6G_MB_LIB.T6G(SCH_1):PAGE476

PC6572 Q_CAPP_SMLF-390UF,2.5V,20%,ALUM,CC7390JMZ13
     1 P0V9_CPU0_RT_2D @T6G_MB_LIB.T6G(SCH_1):P0V9_CPU0_RT_2D   I222 @T6G_MB_LIB.T6G(SCH_1):PAGE476
     2    GND @T6G_MB_LIB.T6G(SCH_1):GND   I222 @T6G_MB_LIB.T6G(SCH_1):PAGE476

PC6573 Q_CAPP_SMLF-390UF,2.5V,20%,ALUM,CC7390JMZ13
     1 P0V9_CPU0_RT_2D @T6G_MB_LIB.T6G(SCH_1):P0V9_CPU0_RT_2D   I238 @T6G_MB_LIB.T6G(SCH_1):PAGE476
     2    GND @T6G_MB_LIB.T6G(SCH_1):GND   I238 @T6G_MB_LIB.T6G(SCH_1):PAGE476

PC6574 Q_CAPP_SMLF-390UF,2.5V,20%,ALUM,CC7390JMZ13
     1 P0V9_CPU0_RT_2D @T6G_MB_LIB.T6G(SCH_1):P0V9_CPU0_RT_2D   I236 @T6G_MB_LIB.T6G(SCH_1):PAGE476
     2    GND @T6G_MB_LIB.T6G(SCH_1):GND   I236 @T6G_MB_LIB.T6G(SCH_1):PAGE476

PC6575 Q_CAP_C0402-2.2UF,10V,10%,X6S,CH5222KEB01
     1 P0V9_RETIMER_CPU0_VCC2 @T6G_MB_LIB.T6G(SCH_1):P0V9_RETIMER_CPU0_VCC2   I271 @T6G_MB_LIB.T6G(SCH_1):PAGE476
     2    GND @T6G_MB_LIB.T6G(SCH_1):GND   I271 @T6G_MB_LIB.T6G(SCH_1):PAGE476

PC6576 Q_CAP_C0402-100NF,50V,10%,X7R,CH4106K1B01
     1 PV09_RETIMER_CPU0_VCCS @T6G_MB_LIB.T6G(SCH_1):PV09_RETIMER_CPU0_VCCS   I281 @T6G_MB_LIB.T6G(SCH_1):PAGE476
     2    GND @T6G_MB_LIB.T6G(SCH_1):GND   I281 @T6G_MB_LIB.T6G(SCH_1):PAGE476

PC6577_2 Q_CAP_C0402-1UF,25V,10%,X6S,CH5104KEB02
     1 SW_P12V_AUX_P0V9_RETIMER_CPU0_FLT @T6G_MB_LIB.T6G(SCH_1):SW_P12V_AUX_P0V9_RETIMER_CPU0_FLT   I258 @T6G_MB_LIB.T6G(SCH_1):PAGE476
     2    GND @T6G_MB_LIB.T6G(SCH_1):GND   I258 @T6G_MB_LIB.T6G(SCH_1):PAGE476

PC6578_2 Q_CAP_0402-3300PF,50V,10%,X7R,TMP_QCH2336K1B12
     1 SW_P12V_AUX_P0V9_RETIMER_CPU0_FLT @T6G_MB_LIB.T6G(SCH_1):SW_P12V_AUX_P0V9_RETIMER_CPU0_FLT   I259 @T6G_MB_LIB.T6G(SCH_1):PAGE476
     2    GND @T6G_MB_LIB.T6G(SCH_1):GND   I259 @T6G_MB_LIB.T6G(SCH_1):PAGE476

PC6579_2 Q_CAP_C0805-22UF,16V,20%,X6S,CH6223MEA01
     1 SW_P12V_AUX_P0V9_RETIMER_CPU0_FLT @T6G_MB_LIB.T6G(SCH_1):SW_P12V_AUX_P0V9_RETIMER_CPU0_FLT   I245 @T6G_MB_LIB.T6G(SCH_1):PAGE476
     2    GND @T6G_MB_LIB.T6G(SCH_1):GND   I245 @T6G_MB_LIB.T6G(SCH_1):PAGE476

PC6580_2 Q_CAP_C0805-22UF,16V,20%,X6S,CH6223MEA01
     1 SW_P12V_AUX_P0V9_RETIMER_CPU0_FLT @T6G_MB_LIB.T6G(SCH_1):SW_P12V_AUX_P0V9_RETIMER_CPU0_FLT   I244 @T6G_MB_LIB.T6G(SCH_1):PAGE476
     2    GND @T6G_MB_LIB.T6G(SCH_1):GND   I244 @T6G_MB_LIB.T6G(SCH_1):PAGE476

PC6581_2 Q_CAP_C0805-22UF,16V,20%,X6S,CH6223MEA01
     1 SW_P12V_AUX_P0V9_RETIMER_CPU0_FLT @T6G_MB_LIB.T6G(SCH_1):SW_P12V_AUX_P0V9_RETIMER_CPU0_FLT   I243 @T6G_MB_LIB.T6G(SCH_1):PAGE476
     2    GND @T6G_MB_LIB.T6G(SCH_1):GND   I243 @T6G_MB_LIB.T6G(SCH_1):PAGE476

PC6582_2 Q_CAP_C0805-22UF,16V,20%,X6S,CH6223MEA01
     1 SW_P12V_AUX_P0V9_RETIMER_CPU0_FLT @T6G_MB_LIB.T6G(SCH_1):SW_P12V_AUX_P0V9_RETIMER_CPU0_FLT   I242 @T6G_MB_LIB.T6G(SCH_1):PAGE476
     2    GND @T6G_MB_LIB.T6G(SCH_1):GND   I242 @T6G_MB_LIB.T6G(SCH_1):PAGE476

PC6583 Q_CAP_C0805-22UF,16V,20%,X6S,CH6223MEA01
     1 SW_P12V_AUX_P0V9_RETIMER_CPU0_FLT @T6G_MB_LIB.T6G(SCH_1):SW_P12V_AUX_P0V9_RETIMER_CPU0_FLT   I241 @T6G_MB_LIB.T6G(SCH_1):PAGE476
     2    GND @T6G_MB_LIB.T6G(SCH_1):GND   I241 @T6G_MB_LIB.T6G(SCH_1):PAGE476

PC6584 Q_CAP_C0402-100NF,50V,10%,X7R,CH4106K1B01
     1 SW_P0V9_RETIMER_CPU0_BOOT2_RC @T6G_MB_LIB.T6G(SCH_1):SW_P0V9_RETIMER_CPU0_BOOT2_RC   I253 @T6G_MB_LIB.T6G(SCH_1):PAGE476
     2 SW_P0V9_RETIMER_CPU0_PH2 @T6G_MB_LIB.T6G(SCH_1):SW_P0V9_RETIMER_CPU0_PH2   I253 @T6G_MB_LIB.T6G(SCH_1):PAGE476

PC6585 Q_CAP_C0402-560PF,50V,10%,EMPTY,CH1566K1B09
     1 SW_P0V9_RETIMER_CPU0_SW2 @T6G_MB_LIB.T6G(SCH_1):SW_P0V9_RETIMER_CPU0_SW2   I288 @T6G_MB_LIB.T6G(SCH_1):PAGE476
     2 SW_P0V9_RETIMER_CPU0_SW2_RC @T6G_MB_LIB.T6G(SCH_1):SW_P0V9_RETIMER_CPU0_SW2_RC   I288 @T6G_MB_LIB.T6G(SCH_1):PAGE476

PC6586_2 Q_CAP_C0805-22UF,4V,20%,X6S,CH622KMEA03
     1 P0V9_CPU0_RT_2D @T6G_MB_LIB.T6G(SCH_1):P0V9_CPU0_RT_2D   I251 @T6G_MB_LIB.T6G(SCH_1):PAGE476
     2    GND @T6G_MB_LIB.T6G(SCH_1):GND   I251 @T6G_MB_LIB.T6G(SCH_1):PAGE476

PC6587_2 Q_CAP_C0805-22UF,4V,20%,X6S,CH622KMEA03
     1 P0V9_CPU0_RT_2D @T6G_MB_LIB.T6G(SCH_1):P0V9_CPU0_RT_2D   I250 @T6G_MB_LIB.T6G(SCH_1):PAGE476
     2    GND @T6G_MB_LIB.T6G(SCH_1):GND   I250 @T6G_MB_LIB.T6G(SCH_1):PAGE476

PC6600 Q_CAP_0402-3300PF,50V,10%,X7R,TMP_QCH2336K1B12
     1 P0V9_RETIMER_CPU1_SENSE_R_P @T6G_MB_LIB.T6G(SCH_1):P0V9_RETIMER_CPU1_SENSE_R_P    I28 @T6G_MB_LIB.T6G(SCH_1):PAGE477
     2 P0V9_RETIMER_CPU1_SENSE_SH_N @T6G_MB_LIB.T6G(SCH_1):P0V9_RETIMER_CPU1_SENSE_SH_N    I28 @T6G_MB_LIB.T6G(SCH_1):PAGE477

PC6601 Q_CAP_0402-0.1UF,25V,10%,EMPTY,CH4104K1B00
     1 P0V9_RETIMER_CPU0_VMON @T6G_MB_LIB.T6G(SCH_1):P0V9_RETIMER_CPU0_VMON   I151 @T6G_MB_LIB.T6G(SCH_1):PAGE475
     2    GND @T6G_MB_LIB.T6G(SCH_1):GND   I151 @T6G_MB_LIB.T6G(SCH_1):PAGE475

PC6602 Q_CAP_0402-0.1UF,25V,10%,X7R,CH4104K1B00
     1 P0V9_RETIMER_CPU0_VINSEN @T6G_MB_LIB.T6G(SCH_1):P0V9_RETIMER_CPU0_VINSEN   I123 @T6G_MB_LIB.T6G(SCH_1):PAGE475
     2    GND @T6G_MB_LIB.T6G(SCH_1):GND   I123 @T6G_MB_LIB.T6G(SCH_1):PAGE475

PC6603 Q_CAP_C0402-100NF,50V,10%,X7R,CH4106K1B01
     1 P0V9_RETIMER_CPU0_VCC @T6G_MB_LIB.T6G(SCH_1):P0V9_RETIMER_CPU0_VCC   I144 @T6G_MB_LIB.T6G(SCH_1):PAGE475
     2    GND @T6G_MB_LIB.T6G(SCH_1):GND   I144 @T6G_MB_LIB.T6G(SCH_1):PAGE475

PC6604 Q_CAP_C0402-1UF,16V,10%,X6S,CH5103KEB01
     1 P0V9_RETIMER_CPU0_VCC @T6G_MB_LIB.T6G(SCH_1):P0V9_RETIMER_CPU0_VCC   I132 @T6G_MB_LIB.T6G(SCH_1):PAGE475
     2    GND @T6G_MB_LIB.T6G(SCH_1):GND   I132 @T6G_MB_LIB.T6G(SCH_1):PAGE475

PC6605 Q_CAP_C0402-1UF,16V,10%,X6S,CH5103KEB01
     1 PV09_RETIMER_CPU0_VCCS @T6G_MB_LIB.T6G(SCH_1):PV09_RETIMER_CPU0_VCCS   I146 @T6G_MB_LIB.T6G(SCH_1):PAGE475
     2    GND @T6G_MB_LIB.T6G(SCH_1):GND   I146 @T6G_MB_LIB.T6G(SCH_1):PAGE475

PC6606 Q_CAP_C0402-10UF,6.3V,20%,X6S,CH6101MEB03
     1 PV09_RETIMER_CPU0_VCCS @T6G_MB_LIB.T6G(SCH_1):PV09_RETIMER_CPU0_VCCS   I145 @T6G_MB_LIB.T6G(SCH_1):PAGE475
     2    GND @T6G_MB_LIB.T6G(SCH_1):GND   I145 @T6G_MB_LIB.T6G(SCH_1):PAGE475

PC6607 Q_CAP_0402-470PF,50V,10%,X7R,TMP_QCH14706KB18
     1 P0V9_RETIMER_CPU0_TEMP0 @T6G_MB_LIB.T6G(SCH_1):P0V9_RETIMER_CPU0_TEMP0   I148 @T6G_MB_LIB.T6G(SCH_1):PAGE475
     2    GND @T6G_MB_LIB.T6G(SCH_1):GND   I148 @T6G_MB_LIB.T6G(SCH_1):PAGE475

PC6609_09P1_1 Q_CAP_C0402-2.2UF,10V,10%,X6S,CH5222KEB01
     1 P0V9_RETIMER_CPU1_PVCC @T6G_MB_LIB.T6G(SCH_1):P0V9_RETIMER_CPU1_PVCC    I55 @T6G_MB_LIB.T6G(SCH_1):PAGE478
     2    GND @T6G_MB_LIB.T6G(SCH_1):GND    I55 @T6G_MB_LIB.T6G(SCH_1):PAGE478

PC6610 Q_CAP_C0402-2.2UF,10V,10%,X6S,CH5222KEB01
     1 P0V9_RETIMER_CPU1_VCC1 @T6G_MB_LIB.T6G(SCH_1):P0V9_RETIMER_CPU1_VCC1    I52 @T6G_MB_LIB.T6G(SCH_1):PAGE478
     2    GND @T6G_MB_LIB.T6G(SCH_1):GND    I52 @T6G_MB_LIB.T6G(SCH_1):PAGE478

PC6611_1 Q_CAP_C0402-100NF,50V,10%,X7R,CH4106K1B01
     1 PV09_RETIMER_CPU1_VCCS @T6G_MB_LIB.T6G(SCH_1):PV09_RETIMER_CPU1_VCCS    I39 @T6G_MB_LIB.T6G(SCH_1):PAGE478
     2    GND @T6G_MB_LIB.T6G(SCH_1):GND    I39 @T6G_MB_LIB.T6G(SCH_1):PAGE478

PC6612_1 Q_CAP_C0402-1UF,25V,10%,X6S,CH5104KEB02
     1 SW_P12V_AUX_P0V9_RETIMER_CPU1_FLT @T6G_MB_LIB.T6G(SCH_1):SW_P12V_AUX_P0V9_RETIMER_CPU1_FLT    I64 @T6G_MB_LIB.T6G(SCH_1):PAGE478
     2    GND @T6G_MB_LIB.T6G(SCH_1):GND    I64 @T6G_MB_LIB.T6G(SCH_1):PAGE478

PC6613_1 Q_CAP_0402-3300PF,50V,10%,X7R,TMP_QCH2336K1B12
     1 SW_P12V_AUX_P0V9_RETIMER_CPU1_FLT @T6G_MB_LIB.T6G(SCH_1):SW_P12V_AUX_P0V9_RETIMER_CPU1_FLT    I61 @T6G_MB_LIB.T6G(SCH_1):PAGE478
     2    GND @T6G_MB_LIB.T6G(SCH_1):GND    I61 @T6G_MB_LIB.T6G(SCH_1):PAGE478

PC6614_1 Q_CAP_C0805-22UF,16V,20%,X6S,CH6223MEA01
     1 SW_P12V_AUX_P0V9_RETIMER_CPU1_FLT @T6G_MB_LIB.T6G(SCH_1):SW_P12V_AUX_P0V9_RETIMER_CPU1_FLT    I72 @T6G_MB_LIB.T6G(SCH_1):PAGE478
     2    GND @T6G_MB_LIB.T6G(SCH_1):GND    I72 @T6G_MB_LIB.T6G(SCH_1):PAGE478

PC6615_1 Q_CAP_C0805-22UF,16V,20%,X6S,CH6223MEA01
     1 SW_P12V_AUX_P0V9_RETIMER_CPU1_FLT @T6G_MB_LIB.T6G(SCH_1):SW_P12V_AUX_P0V9_RETIMER_CPU1_FLT    I74 @T6G_MB_LIB.T6G(SCH_1):PAGE478
     2    GND @T6G_MB_LIB.T6G(SCH_1):GND    I74 @T6G_MB_LIB.T6G(SCH_1):PAGE478

PC6616_1 Q_CAP_C0805-22UF,16V,20%,X6S,CH6223MEA01
     1 SW_P12V_AUX_P0V9_RETIMER_CPU1_FLT @T6G_MB_LIB.T6G(SCH_1):SW_P12V_AUX_P0V9_RETIMER_CPU1_FLT    I77 @T6G_MB_LIB.T6G(SCH_1):PAGE478
     2    GND @T6G_MB_LIB.T6G(SCH_1):GND    I77 @T6G_MB_LIB.T6G(SCH_1):PAGE478

PC6617_1 Q_CAP_C0805-22UF,16V,20%,X6S,CH6223MEA01
     1 SW_P12V_AUX_P0V9_RETIMER_CPU1_FLT @T6G_MB_LIB.T6G(SCH_1):SW_P12V_AUX_P0V9_RETIMER_CPU1_FLT    I79 @T6G_MB_LIB.T6G(SCH_1):PAGE478
     2    GND @T6G_MB_LIB.T6G(SCH_1):GND    I79 @T6G_MB_LIB.T6G(SCH_1):PAGE478

PC6618 Q_CAP_C0805-22UF,16V,20%,X6S,CH6223MEA01
     1 SW_P12V_AUX_P0V9_RETIMER_CPU1_FLT @T6G_MB_LIB.T6G(SCH_1):SW_P12V_AUX_P0V9_RETIMER_CPU1_FLT    I80 @T6G_MB_LIB.T6G(SCH_1):PAGE478
     2    GND @T6G_MB_LIB.T6G(SCH_1):GND    I80 @T6G_MB_LIB.T6G(SCH_1):PAGE478

PC6619 Q_CAPP_SMLF-100UF,16V,20%,OSCON,CC71003MZ30
     1 SW_P12V_AUX_P0V9_RETIMER_CPU1_FLT @T6G_MB_LIB.T6G(SCH_1):SW_P12V_AUX_P0V9_RETIMER_CPU1_FLT   I102 @T6G_MB_LIB.T6G(SCH_1):PAGE478
     2    GND @T6G_MB_LIB.T6G(SCH_1):GND   I102 @T6G_MB_LIB.T6G(SCH_1):PAGE478

PC6620 Q_CAP_0402-0.1UF,25V,10%,X7R,CH4104K1B00
     1 P12V_AUX @T6G_MB_LIB.T6G(SCH_1):P12V_AUX   I114 @T6G_MB_LIB.T6G(SCH_1):PAGE478
     2    GND @T6G_MB_LIB.T6G(SCH_1):GND   I114 @T6G_MB_LIB.T6G(SCH_1):PAGE478

PC6621 Q_CAP_C0402-100NF,50V,10%,X7R,CH4106K1B01
     1 SW_P0V9_RETIMER_CPU1_BOOT1_RC @T6G_MB_LIB.T6G(SCH_1):SW_P0V9_RETIMER_CPU1_BOOT1_RC    I76 @T6G_MB_LIB.T6G(SCH_1):PAGE478
     2 SW_P0V9_RETIMER_CPU1_PH1 @T6G_MB_LIB.T6G(SCH_1):SW_P0V9_RETIMER_CPU1_PH1    I76 @T6G_MB_LIB.T6G(SCH_1):PAGE478

PC6622 Q_CAP_C0402-560PF,50V,10%,EMPTY,CH1566K1B09
     1 SW_P0V9_RETIMER_CPU1_SW1 @T6G_MB_LIB.T6G(SCH_1):SW_P0V9_RETIMER_CPU1_SW1   I108 @T6G_MB_LIB.T6G(SCH_1):PAGE478
     2 SW_P0V9_RETIMER_CPU1_SW1_RC @T6G_MB_LIB.T6G(SCH_1):SW_P0V9_RETIMER_CPU1_SW1_RC   I108 @T6G_MB_LIB.T6G(SCH_1):PAGE478

PC6623 Q_CAP_C0402-100NF,50V,10%,X7R,CH4106K1B01
     1 P0V9_CPU1_RT_2D @T6G_MB_LIB.T6G(SCH_1):P0V9_CPU1_RT_2D    I66 @T6G_MB_LIB.T6G(SCH_1):PAGE478
     2    GND @T6G_MB_LIB.T6G(SCH_1):GND    I66 @T6G_MB_LIB.T6G(SCH_1):PAGE478

PC6624_1 Q_CAP_C0805-22UF,4V,20%,X6S,CH622KMEA03
     1 P0V9_CPU1_RT_2D @T6G_MB_LIB.T6G(SCH_1):P0V9_CPU1_RT_2D    I67 @T6G_MB_LIB.T6G(SCH_1):PAGE478
     2    GND @T6G_MB_LIB.T6G(SCH_1):GND    I67 @T6G_MB_LIB.T6G(SCH_1):PAGE478

PC6625_1 Q_CAP_C0805-22UF,4V,20%,X6S,CH622KMEA03
     1 P0V9_CPU1_RT_2D @T6G_MB_LIB.T6G(SCH_1):P0V9_CPU1_RT_2D    I68 @T6G_MB_LIB.T6G(SCH_1):PAGE478
     2    GND @T6G_MB_LIB.T6G(SCH_1):GND    I68 @T6G_MB_LIB.T6G(SCH_1):PAGE478

PC6626 Q_CAPP_SMLF-470UF,2.5V,20%,SPCAP,CH747LM8818
     1 P0V9_CPU1_RT_2D @T6G_MB_LIB.T6G(SCH_1):P0V9_CPU1_RT_2D    I69 @T6G_MB_LIB.T6G(SCH_1):PAGE478
     2    GND @T6G_MB_LIB.T6G(SCH_1):GND    I69 @T6G_MB_LIB.T6G(SCH_1):PAGE478

PC6627 Q_CAPP_SMLF-470UF,2.5V,20%,SPCAP,CH747LM8818
     1 P0V9_CPU1_RT_2D @T6G_MB_LIB.T6G(SCH_1):P0V9_CPU1_RT_2D    I70 @T6G_MB_LIB.T6G(SCH_1):PAGE478
     2    GND @T6G_MB_LIB.T6G(SCH_1):GND    I70 @T6G_MB_LIB.T6G(SCH_1):PAGE478

PC6628 Q_CAPP_SMLF-470UF,2.5V,20%,SPCAP,CH747LM8818
     1 P0V9_CPU1_RT_2D @T6G_MB_LIB.T6G(SCH_1):P0V9_CPU1_RT_2D    I93 @T6G_MB_LIB.T6G(SCH_1):PAGE478
     2    GND @T6G_MB_LIB.T6G(SCH_1):GND    I93 @T6G_MB_LIB.T6G(SCH_1):PAGE478

PC6629 Q_CAPP_SMLF-390UF,2.5V,20%,ALUM,CC7390JMZ13
     1 P0V9_CPU1_RT_2D @T6G_MB_LIB.T6G(SCH_1):P0V9_CPU1_RT_2D    I94 @T6G_MB_LIB.T6G(SCH_1):PAGE478
     2    GND @T6G_MB_LIB.T6G(SCH_1):GND    I94 @T6G_MB_LIB.T6G(SCH_1):PAGE478

PC6630 Q_CAPP_SMLF-390UF,2.5V,20%,ALUM,CC7390JMZ13
     1 P0V9_CPU1_RT_2D @T6G_MB_LIB.T6G(SCH_1):P0V9_CPU1_RT_2D    I95 @T6G_MB_LIB.T6G(SCH_1):PAGE478
     2    GND @T6G_MB_LIB.T6G(SCH_1):GND    I95 @T6G_MB_LIB.T6G(SCH_1):PAGE478

PC6631 Q_CAPP_SMLF-390UF,2.5V,20%,ALUM,CC7390JMZ13
     1 P0V9_CPU1_RT_2D @T6G_MB_LIB.T6G(SCH_1):P0V9_CPU1_RT_2D    I83 @T6G_MB_LIB.T6G(SCH_1):PAGE478
     2    GND @T6G_MB_LIB.T6G(SCH_1):GND    I83 @T6G_MB_LIB.T6G(SCH_1):PAGE478

PC6632 Q_CAPP_SMLF-390UF,2.5V,20%,ALUM,CC7390JMZ13
     1 P0V9_CPU1_RT_2D @T6G_MB_LIB.T6G(SCH_1):P0V9_CPU1_RT_2D    I84 @T6G_MB_LIB.T6G(SCH_1):PAGE478
     2    GND @T6G_MB_LIB.T6G(SCH_1):GND    I84 @T6G_MB_LIB.T6G(SCH_1):PAGE478

PC6633_2 Q_CAP_C0402-1UF,25V,10%,X6S,CH5104KEB02
     1 SW_P12V_AUX_P0V9_RETIMER_CPU1_FLT @T6G_MB_LIB.T6G(SCH_1):SW_P12V_AUX_P0V9_RETIMER_CPU1_FLT    I21 @T6G_MB_LIB.T6G(SCH_1):PAGE478
     2    GND @T6G_MB_LIB.T6G(SCH_1):GND    I21 @T6G_MB_LIB.T6G(SCH_1):PAGE478

PC6634_2 Q_CAP_0402-3300PF,50V,10%,X7R,TMP_QCH2336K1B12
     1 SW_P12V_AUX_P0V9_RETIMER_CPU1_FLT @T6G_MB_LIB.T6G(SCH_1):SW_P12V_AUX_P0V9_RETIMER_CPU1_FLT    I18 @T6G_MB_LIB.T6G(SCH_1):PAGE478
     2    GND @T6G_MB_LIB.T6G(SCH_1):GND    I18 @T6G_MB_LIB.T6G(SCH_1):PAGE478

PC6635_2 Q_CAP_C0805-22UF,16V,20%,X6S,CH6223MEA01
     1 SW_P12V_AUX_P0V9_RETIMER_CPU1_FLT @T6G_MB_LIB.T6G(SCH_1):SW_P12V_AUX_P0V9_RETIMER_CPU1_FLT    I25 @T6G_MB_LIB.T6G(SCH_1):PAGE478
     2    GND @T6G_MB_LIB.T6G(SCH_1):GND    I25 @T6G_MB_LIB.T6G(SCH_1):PAGE478

PC6636_2 Q_CAP_C0805-22UF,16V,20%,X6S,CH6223MEA01
     1 SW_P12V_AUX_P0V9_RETIMER_CPU1_FLT @T6G_MB_LIB.T6G(SCH_1):SW_P12V_AUX_P0V9_RETIMER_CPU1_FLT    I28 @T6G_MB_LIB.T6G(SCH_1):PAGE478
     2    GND @T6G_MB_LIB.T6G(SCH_1):GND    I28 @T6G_MB_LIB.T6G(SCH_1):PAGE478

PC6637_2 Q_CAP_C0805-22UF,16V,20%,X6S,CH6223MEA01
     1 SW_P12V_AUX_P0V9_RETIMER_CPU1_FLT @T6G_MB_LIB.T6G(SCH_1):SW_P12V_AUX_P0V9_RETIMER_CPU1_FLT    I35 @T6G_MB_LIB.T6G(SCH_1):PAGE478
     2    GND @T6G_MB_LIB.T6G(SCH_1):GND    I35 @T6G_MB_LIB.T6G(SCH_1):PAGE478

PC6638_2 Q_CAP_C0805-22UF,16V,20%,X6S,CH6223MEA01
     1 SW_P12V_AUX_P0V9_RETIMER_CPU1_FLT @T6G_MB_LIB.T6G(SCH_1):SW_P12V_AUX_P0V9_RETIMER_CPU1_FLT    I36 @T6G_MB_LIB.T6G(SCH_1):PAGE478
     2    GND @T6G_MB_LIB.T6G(SCH_1):GND    I36 @T6G_MB_LIB.T6G(SCH_1):PAGE478

PC6639 Q_CAP_C0805-22UF,16V,20%,X6S,CH6223MEA01
     1 SW_P12V_AUX_P0V9_RETIMER_CPU1_FLT @T6G_MB_LIB.T6G(SCH_1):SW_P12V_AUX_P0V9_RETIMER_CPU1_FLT    I38 @T6G_MB_LIB.T6G(SCH_1):PAGE478
     2    GND @T6G_MB_LIB.T6G(SCH_1):GND    I38 @T6G_MB_LIB.T6G(SCH_1):PAGE478

PC6640 Q_CAP_C0402-100NF,50V,10%,X7R,CH4106K1B01
     1 SW_P0V9_RETIMER_CPU1_BOOT2_RC @T6G_MB_LIB.T6G(SCH_1):SW_P0V9_RETIMER_CPU1_BOOT2_RC    I26 @T6G_MB_LIB.T6G(SCH_1):PAGE478
     2 SW_P0V9_RETIMER_CPU1_PH2 @T6G_MB_LIB.T6G(SCH_1):SW_P0V9_RETIMER_CPU1_PH2    I26 @T6G_MB_LIB.T6G(SCH_1):PAGE478

PC6641 Q_CAP_C0402-560PF,50V,10%,EMPTY,CH1566K1B09
     1 SW_P0V9_RETIMER_CPU1_SW2 @T6G_MB_LIB.T6G(SCH_1):SW_P0V9_RETIMER_CPU1_SW2   I109 @T6G_MB_LIB.T6G(SCH_1):PAGE478
     2 SW_P0V9_RETIMER_CPU1_SW2_RC @T6G_MB_LIB.T6G(SCH_1):SW_P0V9_RETIMER_CPU1_SW2_RC   I109 @T6G_MB_LIB.T6G(SCH_1):PAGE478

PC6642_2 Q_CAP_C0805-22UF,4V,20%,X6S,CH622KMEA03
     1 P0V9_CPU1_RT_2D @T6G_MB_LIB.T6G(SCH_1):P0V9_CPU1_RT_2D    I29 @T6G_MB_LIB.T6G(SCH_1):PAGE478
     2    GND @T6G_MB_LIB.T6G(SCH_1):GND    I29 @T6G_MB_LIB.T6G(SCH_1):PAGE478

PC6643_2 Q_CAP_C0805-22UF,4V,20%,X6S,CH622KMEA03
     1 P0V9_CPU1_RT_2D @T6G_MB_LIB.T6G(SCH_1):P0V9_CPU1_RT_2D    I30 @T6G_MB_LIB.T6G(SCH_1):PAGE478
     2    GND @T6G_MB_LIB.T6G(SCH_1):GND    I30 @T6G_MB_LIB.T6G(SCH_1):PAGE478

PC6644_09P1_2 Q_CAP_C0402-2.2UF,10V,10%,X6S,CH5222KEB01
     1 P0V9_RETIMER_CPU1_PVCC @T6G_MB_LIB.T6G(SCH_1):P0V9_RETIMER_CPU1_PVCC    I14 @T6G_MB_LIB.T6G(SCH_1):PAGE478
     2    GND @T6G_MB_LIB.T6G(SCH_1):GND    I14 @T6G_MB_LIB.T6G(SCH_1):PAGE478

PC6645 Q_CAP_C0402-2.2UF,10V,10%,X6S,CH5222KEB01
     1 P0V9_RETIMER_CPU1_VCC2 @T6G_MB_LIB.T6G(SCH_1):P0V9_RETIMER_CPU1_VCC2    I10 @T6G_MB_LIB.T6G(SCH_1):PAGE478
     2    GND @T6G_MB_LIB.T6G(SCH_1):GND    I10 @T6G_MB_LIB.T6G(SCH_1):PAGE478

PC6646 Q_CAP_C0402-100NF,50V,10%,X7R,CH4106K1B01
     1 PV09_RETIMER_CPU1_VCCS @T6G_MB_LIB.T6G(SCH_1):PV09_RETIMER_CPU1_VCCS     I2 @T6G_MB_LIB.T6G(SCH_1):PAGE478
     2    GND @T6G_MB_LIB.T6G(SCH_1):GND     I2 @T6G_MB_LIB.T6G(SCH_1):PAGE478

PC6800 Q_CAPP_SMLF-270UF,16V,20%,OSCON,CC72703MZ11
     1 SW_P12V_AUX_P1V8_RETIMER_CPU0_FLT @T6G_MB_LIB.T6G(SCH_1):SW_P12V_AUX_P1V8_RETIMER_CPU0_FLT     I6 @T6G_MB_LIB.T6G(SCH_1):PAGE469
     2    GND @T6G_MB_LIB.T6G(SCH_1):GND     I6 @T6G_MB_LIB.T6G(SCH_1):PAGE469

PC6801 Q_CAPP_SMLF-270UF,16V,20%,OSCON,CC72703MZ11
     1 SW_P12V_AUX_P1V8_RETIMER_CPU1_FLT @T6G_MB_LIB.T6G(SCH_1):SW_P12V_AUX_P1V8_RETIMER_CPU1_FLT     I6 @T6G_MB_LIB.T6G(SCH_1):PAGE470
     2    GND @T6G_MB_LIB.T6G(SCH_1):GND     I6 @T6G_MB_LIB.T6G(SCH_1):PAGE470

PC6802 Q_CAP_C0805-22UF,16V,20%,X6S,CH6223MEA01
     1 SW_P12V_AUX_P1V8_RETIMER_CPU0_FLT @T6G_MB_LIB.T6G(SCH_1):SW_P12V_AUX_P1V8_RETIMER_CPU0_FLT     I7 @T6G_MB_LIB.T6G(SCH_1):PAGE469
     2    GND @T6G_MB_LIB.T6G(SCH_1):GND     I7 @T6G_MB_LIB.T6G(SCH_1):PAGE469

PC6803 Q_CAP_C0805-22UF,16V,20%,X6S,CH6223MEA01
     1 SW_P12V_AUX_P1V8_RETIMER_CPU1_FLT @T6G_MB_LIB.T6G(SCH_1):SW_P12V_AUX_P1V8_RETIMER_CPU1_FLT     I7 @T6G_MB_LIB.T6G(SCH_1):PAGE470
     2    GND @T6G_MB_LIB.T6G(SCH_1):GND     I7 @T6G_MB_LIB.T6G(SCH_1):PAGE470

PC6804 Q_CAPP_SMLF-390UF,2.5V,20%,ALUM,CC7390JMZ13
     1 P1V8_CPU1_RT_1D @T6G_MB_LIB.T6G(SCH_1):P1V8_CPU1_RT_1D    I47 @T6G_MB_LIB.T6G(SCH_1):PAGE470
     2    GND @T6G_MB_LIB.T6G(SCH_1):GND    I47 @T6G_MB_LIB.T6G(SCH_1):PAGE470

PC6805 Q_CAPP_SMLF-390UF,2.5V,20%,ALUM,CC7390JMZ13
     1 P1V8_CPU0_RT_1D @T6G_MB_LIB.T6G(SCH_1):P1V8_CPU0_RT_1D    I48 @T6G_MB_LIB.T6G(SCH_1):PAGE469
     2    GND @T6G_MB_LIB.T6G(SCH_1):GND    I48 @T6G_MB_LIB.T6G(SCH_1):PAGE469

PC6806 Q_CAP_C0402-100NF,50V,10%,X7R,CH4106K1B01
     1 P0V9_CPU0_RT_2D @T6G_MB_LIB.T6G(SCH_1):P0V9_CPU0_RT_2D   I255 @T6G_MB_LIB.T6G(SCH_1):PAGE476
     2    GND @T6G_MB_LIB.T6G(SCH_1):GND   I255 @T6G_MB_LIB.T6G(SCH_1):PAGE476

PC6807 Q_CAP_C0402-100NF,50V,10%,X7R,CH4106K1B01
     1 P0V9_CPU1_RT_2D @T6G_MB_LIB.T6G(SCH_1):P0V9_CPU1_RT_2D    I23 @T6G_MB_LIB.T6G(SCH_1):PAGE478
     2    GND @T6G_MB_LIB.T6G(SCH_1):GND    I23 @T6G_MB_LIB.T6G(SCH_1):PAGE478

PC6810 Q_CAPP_SMLF-100UF,16V,20%,OSCON,CC71003MZ30
     1 SW_P12V_AUX_P0V9_RETIMER_CPU0_FLT @T6G_MB_LIB.T6G(SCH_1):SW_P12V_AUX_P0V9_RETIMER_CPU0_FLT   I231 @T6G_MB_LIB.T6G(SCH_1):PAGE476
     2    GND @T6G_MB_LIB.T6G(SCH_1):GND   I231 @T6G_MB_LIB.T6G(SCH_1):PAGE476

PC6811 Q_CAPP_SMLF-470UF,2.5V,20%,SPCAP,CH747LM8818
     1 P0V9_CPU0_RT_2D @T6G_MB_LIB.T6G(SCH_1):P0V9_CPU0_RT_2D   I247 @T6G_MB_LIB.T6G(SCH_1):PAGE476
     2    GND @T6G_MB_LIB.T6G(SCH_1):GND   I247 @T6G_MB_LIB.T6G(SCH_1):PAGE476

PC6812 Q_CAPP_SMLF-470UF,2.5V,20%,SPCAP,CH747LM8818
     1 P0V9_CPU0_RT_2D @T6G_MB_LIB.T6G(SCH_1):P0V9_CPU0_RT_2D   I248 @T6G_MB_LIB.T6G(SCH_1):PAGE476
     2    GND @T6G_MB_LIB.T6G(SCH_1):GND   I248 @T6G_MB_LIB.T6G(SCH_1):PAGE476

PC6813 Q_CAPP_SMLF-470UF,2.5V,20%,SPCAP,CH747LM8818
     1 P0V9_CPU1_RT_2D @T6G_MB_LIB.T6G(SCH_1):P0V9_CPU1_RT_2D    I31 @T6G_MB_LIB.T6G(SCH_1):PAGE478
     2    GND @T6G_MB_LIB.T6G(SCH_1):GND    I31 @T6G_MB_LIB.T6G(SCH_1):PAGE478

PC6814 Q_CAPP_SMLF-470UF,2.5V,20%,SPCAP,CH747LM8818
     1 P0V9_CPU1_RT_2D @T6G_MB_LIB.T6G(SCH_1):P0V9_CPU1_RT_2D    I32 @T6G_MB_LIB.T6G(SCH_1):PAGE478
     2    GND @T6G_MB_LIB.T6G(SCH_1):GND    I32 @T6G_MB_LIB.T6G(SCH_1):PAGE478

PC6815 Q_CAPP_SMLF-470UF,2.5V,20%,SPCAP,CH747LM8818
     1 P0V9_CPU1_RT_2D @T6G_MB_LIB.T6G(SCH_1):P0V9_CPU1_RT_2D    I82 @T6G_MB_LIB.T6G(SCH_1):PAGE478
     2    GND @T6G_MB_LIB.T6G(SCH_1):GND    I82 @T6G_MB_LIB.T6G(SCH_1):PAGE478

PC6816 Q_CAP_C0805-22UF,16V,20%,X6S,CH6223MEA01
     1 SW_P12V_AUX_P0V9_RETIMER_CPU0_FLT @T6G_MB_LIB.T6G(SCH_1):SW_P12V_AUX_P0V9_RETIMER_CPU0_FLT   I216 @T6G_MB_LIB.T6G(SCH_1):PAGE476
     2    GND @T6G_MB_LIB.T6G(SCH_1):GND   I216 @T6G_MB_LIB.T6G(SCH_1):PAGE476

PC6817 Q_CAP_C0805-22UF,16V,20%,X6S,CH6223MEA01
     1 SW_P12V_AUX_P0V9_RETIMER_CPU0_FLT @T6G_MB_LIB.T6G(SCH_1):SW_P12V_AUX_P0V9_RETIMER_CPU0_FLT   I232 @T6G_MB_LIB.T6G(SCH_1):PAGE476
     2    GND @T6G_MB_LIB.T6G(SCH_1):GND   I232 @T6G_MB_LIB.T6G(SCH_1):PAGE476

PC6818 Q_CAP_C0805-22UF,16V,20%,X6S,CH6223MEA01
     1 SW_P12V_AUX_P0V9_RETIMER_CPU1_FLT @T6G_MB_LIB.T6G(SCH_1):SW_P12V_AUX_P0V9_RETIMER_CPU1_FLT    I86 @T6G_MB_LIB.T6G(SCH_1):PAGE478
     2    GND @T6G_MB_LIB.T6G(SCH_1):GND    I86 @T6G_MB_LIB.T6G(SCH_1):PAGE478

PC6819 Q_CAP_C0805-22UF,16V,20%,X6S,CH6223MEA01
     1 SW_P12V_AUX_P0V9_RETIMER_CPU1_FLT @T6G_MB_LIB.T6G(SCH_1):SW_P12V_AUX_P0V9_RETIMER_CPU1_FLT   I100 @T6G_MB_LIB.T6G(SCH_1):PAGE478
     2    GND @T6G_MB_LIB.T6G(SCH_1):GND   I100 @T6G_MB_LIB.T6G(SCH_1):PAGE478

PC6900 Q_CAP_C0805-22UF,16V,20%,X6S,CH6223MEA01
     1 SW_P12V_AUX_P1V8_RETIMER_CPU0_FLT @T6G_MB_LIB.T6G(SCH_1):SW_P12V_AUX_P1V8_RETIMER_CPU0_FLT    I58 @T6G_MB_LIB.T6G(SCH_1):PAGE469
     2    GND @T6G_MB_LIB.T6G(SCH_1):GND    I58 @T6G_MB_LIB.T6G(SCH_1):PAGE469

PC6901 Q_CAP_C0805-22UF,16V,20%,X6S,CH6223MEA01
     1 SW_P12V_AUX_P1V8_RETIMER_CPU0_FLT @T6G_MB_LIB.T6G(SCH_1):SW_P12V_AUX_P1V8_RETIMER_CPU0_FLT    I57 @T6G_MB_LIB.T6G(SCH_1):PAGE469
     2    GND @T6G_MB_LIB.T6G(SCH_1):GND    I57 @T6G_MB_LIB.T6G(SCH_1):PAGE469

PC6902 Q_CAP_C0805-22UF,16V,20%,X6S,CH6223MEA01
     1 SW_P12V_AUX_P1V8_RETIMER_CPU0_FLT @T6G_MB_LIB.T6G(SCH_1):SW_P12V_AUX_P1V8_RETIMER_CPU0_FLT    I56 @T6G_MB_LIB.T6G(SCH_1):PAGE469
     2    GND @T6G_MB_LIB.T6G(SCH_1):GND    I56 @T6G_MB_LIB.T6G(SCH_1):PAGE469

PC6903 Q_CAP_C0805-22UF,16V,20%,X6S,CH6223MEA01
     1 SW_P12V_AUX_P1V8_RETIMER_CPU1_FLT @T6G_MB_LIB.T6G(SCH_1):SW_P12V_AUX_P1V8_RETIMER_CPU1_FLT    I57 @T6G_MB_LIB.T6G(SCH_1):PAGE470
     2    GND @T6G_MB_LIB.T6G(SCH_1):GND    I57 @T6G_MB_LIB.T6G(SCH_1):PAGE470

PC6904 Q_CAP_C0805-22UF,16V,20%,X6S,CH6223MEA01
     1 SW_P12V_AUX_P1V8_RETIMER_CPU1_FLT @T6G_MB_LIB.T6G(SCH_1):SW_P12V_AUX_P1V8_RETIMER_CPU1_FLT    I56 @T6G_MB_LIB.T6G(SCH_1):PAGE470
     2    GND @T6G_MB_LIB.T6G(SCH_1):GND    I56 @T6G_MB_LIB.T6G(SCH_1):PAGE470

PC6905 Q_CAP_C0805-22UF,16V,20%,X6S,CH6223MEA01
     1 SW_P12V_AUX_P1V8_RETIMER_CPU1_FLT @T6G_MB_LIB.T6G(SCH_1):SW_P12V_AUX_P1V8_RETIMER_CPU1_FLT    I55 @T6G_MB_LIB.T6G(SCH_1):PAGE470
     2    GND @T6G_MB_LIB.T6G(SCH_1):GND    I55 @T6G_MB_LIB.T6G(SCH_1):PAGE470

PC7000 Q_CAP_C0805-22UF,16V,20%,X6S,CH6223MEA01
     1 SW_P12V_AUX_PVDDIO_P0_FLT @T6G_MB_LIB.T6G(SCH_1):SW_P12V_AUX_PVDDIO_P0_FLT    I85 @T6G_MB_LIB.T6G(SCH_1):PAGE180
     2    GND @T6G_MB_LIB.T6G(SCH_1):GND    I85 @T6G_MB_LIB.T6G(SCH_1):PAGE180

PC7001 Q_CAP_C0805-22UF,16V,20%,X6S,CH6223MEA01
     1 SW_P12V_AUX_PVDDIO_P1_FLT @T6G_MB_LIB.T6G(SCH_1):SW_P12V_AUX_PVDDIO_P1_FLT    I86 @T6G_MB_LIB.T6G(SCH_1):PAGE197
     2    GND @T6G_MB_LIB.T6G(SCH_1):GND    I86 @T6G_MB_LIB.T6G(SCH_1):PAGE197

PC7002 Q_CAP_C0805-22UF,16V,20%,X6S,CH6223MEA01
     1 SW_P12V_AUX_PVDD11_S3_P0_FLT @T6G_MB_LIB.T6G(SCH_1):SW_P12V_AUX_PVDD11_S3_P0_FLT    I95 @T6G_MB_LIB.T6G(SCH_1):PAGE183
     2    GND @T6G_MB_LIB.T6G(SCH_1):GND    I95 @T6G_MB_LIB.T6G(SCH_1):PAGE183

PC7003 Q_CAP_C0805-22UF,16V,20%,X6S,CH6223MEA01
     1 SW_P12V_AUX_PVDD11_S3_P1_FLT @T6G_MB_LIB.T6G(SCH_1):SW_P12V_AUX_PVDD11_S3_P1_FLT    I95 @T6G_MB_LIB.T6G(SCH_1):PAGE200
     2    GND @T6G_MB_LIB.T6G(SCH_1):GND    I95 @T6G_MB_LIB.T6G(SCH_1):PAGE200

PC8000 Q_CAP_C0805-22UF,16V,20%,X6S,CH6223MEA01
     1 SW_P12V_AUX_PVDD_33_S5_FLT @T6G_MB_LIB.T6G(SCH_1):SW_P12V_AUX_PVDD_33_S5_FLT    I44 @T6G_MB_LIB.T6G(SCH_1):PAGE167
     2    GND @T6G_MB_LIB.T6G(SCH_1):GND    I44 @T6G_MB_LIB.T6G(SCH_1):PAGE167

PC8001 Q_CAP_C0805-22UF,16V,20%,X6S,CH6223MEA01
     1 SW_P12V_AUX_PVDD_33_S5_FLT @T6G_MB_LIB.T6G(SCH_1):SW_P12V_AUX_PVDD_33_S5_FLT    I45 @T6G_MB_LIB.T6G(SCH_1):PAGE167
     2    GND @T6G_MB_LIB.T6G(SCH_1):GND    I45 @T6G_MB_LIB.T6G(SCH_1):PAGE167

PC8002 Q_CAP_C0805-22UF,16V,20%,X6S,CH6223MEA01
     1 SW_P12V_AUX_PVDD18_S5_P0_FLT @T6G_MB_LIB.T6G(SCH_1):SW_P12V_AUX_PVDD18_S5_P0_FLT    I57 @T6G_MB_LIB.T6G(SCH_1):PAGE184
     2    GND @T6G_MB_LIB.T6G(SCH_1):GND    I57 @T6G_MB_LIB.T6G(SCH_1):PAGE184

PC8003 Q_CAP_C0805-22UF,16V,20%,X6S,CH6223MEA01
     1 SW_P12V_AUX_PVDD18_S5_P1_FLT @T6G_MB_LIB.T6G(SCH_1):SW_P12V_AUX_PVDD18_S5_P1_FLT    I57 @T6G_MB_LIB.T6G(SCH_1):PAGE201
     2    GND @T6G_MB_LIB.T6G(SCH_1):GND    I57 @T6G_MB_LIB.T6G(SCH_1):PAGE201

PC8004 Q_CAP_C0805-22UF,16V,20%,X6S,CH6223MEA01
     1 SW_P12V_AUX_PVDD11_S3_P0_FLT @T6G_MB_LIB.T6G(SCH_1):SW_P12V_AUX_PVDD11_S3_P0_FLT    I93 @T6G_MB_LIB.T6G(SCH_1):PAGE183
     2    GND @T6G_MB_LIB.T6G(SCH_1):GND    I93 @T6G_MB_LIB.T6G(SCH_1):PAGE183

PC8005 Q_CAP_C0805-22UF,16V,20%,X6S,CH6223MEA01
     1 SW_P12V_AUX_PVDD11_S3_P0_FLT @T6G_MB_LIB.T6G(SCH_1):SW_P12V_AUX_PVDD11_S3_P0_FLT    I94 @T6G_MB_LIB.T6G(SCH_1):PAGE183
     2    GND @T6G_MB_LIB.T6G(SCH_1):GND    I94 @T6G_MB_LIB.T6G(SCH_1):PAGE183

PC8006 Q_CAP_C0805-22UF,16V,20%,X6S,CH6223MEA01
     1 SW_P12V_AUX_PVDD11_S3_P1_FLT @T6G_MB_LIB.T6G(SCH_1):SW_P12V_AUX_PVDD11_S3_P1_FLT    I93 @T6G_MB_LIB.T6G(SCH_1):PAGE200
     2    GND @T6G_MB_LIB.T6G(SCH_1):GND    I93 @T6G_MB_LIB.T6G(SCH_1):PAGE200

PC8007 Q_CAP_C0805-22UF,16V,20%,X6S,CH6223MEA01
     1 SW_P12V_AUX_PVDD11_S3_P1_FLT @T6G_MB_LIB.T6G(SCH_1):SW_P12V_AUX_PVDD11_S3_P1_FLT    I94 @T6G_MB_LIB.T6G(SCH_1):PAGE200
     2    GND @T6G_MB_LIB.T6G(SCH_1):GND    I94 @T6G_MB_LIB.T6G(SCH_1):PAGE200

PC8008 Q_CAP_0603-1UF,16V,10%,X7R,TMP_QCH5103K1900
     1 P12V_AUX @T6G_MB_LIB.T6G(SCH_1):P12V_AUX    I44 @T6G_MB_LIB.T6G(SCH_1):PAGE245
     2    GND @T6G_MB_LIB.T6G(SCH_1):GND    I44 @T6G_MB_LIB.T6G(SCH_1):PAGE245

PC8009 Q_CAP_C0805-22UF,16V,20%,X6S,CH6223MEA01
     1 SW_P12V_AUX_PVDDCR_SOC_P0_FLT @T6G_MB_LIB.T6G(SCH_1):SW_P12V_AUX_PVDDCR_SOC_P0_FLT    I87 @T6G_MB_LIB.T6G(SCH_1):PAGE173
     2    GND @T6G_MB_LIB.T6G(SCH_1):GND    I87 @T6G_MB_LIB.T6G(SCH_1):PAGE173

PC8010 Q_CAP_C0805-22UF,16V,20%,X6S,CH6223MEA01
     1 SW_P12V_AUX_PVDDCR_SOC_P0_FLT @T6G_MB_LIB.T6G(SCH_1):SW_P12V_AUX_PVDDCR_SOC_P0_FLT    I88 @T6G_MB_LIB.T6G(SCH_1):PAGE173
     2    GND @T6G_MB_LIB.T6G(SCH_1):GND    I88 @T6G_MB_LIB.T6G(SCH_1):PAGE173

PC8011 Q_CAP_C0805-22UF,16V,20%,X6S,CH6223MEA01
     1 SW_P12V_AUX_PVDDCR_SOC_P1_FLT @T6G_MB_LIB.T6G(SCH_1):SW_P12V_AUX_PVDDCR_SOC_P1_FLT    I87 @T6G_MB_LIB.T6G(SCH_1):PAGE190
     2    GND @T6G_MB_LIB.T6G(SCH_1):GND    I87 @T6G_MB_LIB.T6G(SCH_1):PAGE190

PC8012 Q_CAP_C0805-22UF,16V,20%,X6S,CH6223MEA01
     1 SW_P12V_AUX_PVDDCR_SOC_P1_FLT @T6G_MB_LIB.T6G(SCH_1):SW_P12V_AUX_PVDDCR_SOC_P1_FLT    I88 @T6G_MB_LIB.T6G(SCH_1):PAGE190
     2    GND @T6G_MB_LIB.T6G(SCH_1):GND    I88 @T6G_MB_LIB.T6G(SCH_1):PAGE190

PC8013 Q_CAP_C0805-22UF,16V,20%,X6S,CH6223MEA01
     1 SW_P3V3_AUX_FLT @T6G_MB_LIB.T6G(SCH_1):SW_P3V3_AUX_FLT    I70 @T6G_MB_LIB.T6G(SCH_1):PAGE245
     2    GND @T6G_MB_LIB.T6G(SCH_1):GND    I70 @T6G_MB_LIB.T6G(SCH_1):PAGE245

PC8014 Q_CAP_C0805-22UF,16V,20%,X6S,CH6223MEA01
     1 SW_P3V3_AUX_FLT @T6G_MB_LIB.T6G(SCH_1):SW_P3V3_AUX_FLT    I71 @T6G_MB_LIB.T6G(SCH_1):PAGE245
     2    GND @T6G_MB_LIB.T6G(SCH_1):GND    I71 @T6G_MB_LIB.T6G(SCH_1):PAGE245

PC8071 Q_CAP_C0805-22UF,16V,20%,X6S,CH6223MEA01
     1 SW_P3V3_AUX_FLT @T6G_MB_LIB.T6G(SCH_1):SW_P3V3_AUX_FLT    I40 @T6G_MB_LIB.T6G(SCH_1):PAGE245
     2    GND @T6G_MB_LIB.T6G(SCH_1):GND    I40 @T6G_MB_LIB.T6G(SCH_1):PAGE245

PC8567 Q_CAP_C0805-22UF,16V,20%,X6S,CH6223MEA01
     1 SW_P3V3_AUX_FLT @T6G_MB_LIB.T6G(SCH_1):SW_P3V3_AUX_FLT    I32 @T6G_MB_LIB.T6G(SCH_1):PAGE245
     2    GND @T6G_MB_LIB.T6G(SCH_1):GND    I32 @T6G_MB_LIB.T6G(SCH_1):PAGE245

PD13 ZENER_AC-5.0SMDJ14A,SMLF,IC,BC0MDJ14000
     A    GND @T6G_MB_LIB.T6G(SCH_1):GND     I3 @T6G_MB_LIB.T6G(SCH_1):PAGE372
     C P12V_PSU_FUSE @T6G_MB_LIB.T6G(SCH_1):P12V_PSU_FUSE     I3 @T6G_MB_LIB.T6G(SCH_1):PAGE372

PD15 ZENER_AC-5.0SMDJ14A,SMLF,IC,BC0MDJ14000
     A    GND @T6G_MB_LIB.T6G(SCH_1):GND     I1 @T6G_MB_LIB.T6G(SCH_1):PAGE372
     C P12V_PSU_FUSE @T6G_MB_LIB.T6G(SCH_1):P12V_PSU_FUSE     I1 @T6G_MB_LIB.T6G(SCH_1):PAGE372

PD17 SS15P3SM386A-SS15P3S-M3/86A,SMLF,IC,BC015P3SZ00
     1    GND @T6G_MB_LIB.T6G(SCH_1):GND    I72 @T6G_MB_LIB.T6G(SCH_1):PAGE302
     K P12V_AUX @T6G_MB_LIB.T6G(SCH_1):P12V_AUX    I72 @T6G_MB_LIB.T6G(SCH_1):PAGE302
     2    GND @T6G_MB_LIB.T6G(SCH_1):GND    I72 @T6G_MB_LIB.T6G(SCH_1):PAGE302

PD101 DIODE_TVS-SMF14A,SMLF,IC,BCSMF14AZ01
     A    GND @T6G_MB_LIB.T6G(SCH_1):GND   I115 @T6G_MB_LIB.T6G(SCH_1):PAGE338
     C P12V_AUX @T6G_MB_LIB.T6G(SCH_1):P12V_AUX   I115 @T6G_MB_LIB.T6G(SCH_1):PAGE338

PD102 SCHOTTKY_AC-B340A-13-F,SMLF,IC,BC000340Z30
     A    GND @T6G_MB_LIB.T6G(SCH_1):GND    I79 @T6G_MB_LIB.T6G(SCH_1):PAGE338
     C P12V_OCP_SFF @T6G_MB_LIB.T6G(SCH_1):P12V_OCP_SFF    I79 @T6G_MB_LIB.T6G(SCH_1):PAGE338

PD103 SCHOTTKY_AC-B340A-13-F,SMLF,IC,BC000340Z30
     A    GND @T6G_MB_LIB.T6G(SCH_1):GND    I97 @T6G_MB_LIB.T6G(SCH_1):PAGE338
     C P3V3_OCP_SFF_R @T6G_MB_LIB.T6G(SCH_1):P3V3_OCP_SFF_R    I97 @T6G_MB_LIB.T6G(SCH_1):PAGE338

PD107 DIODE_TVS-SMF14A,SMLF,IC,BCSMF14AZ01
     A    GND @T6G_MB_LIB.T6G(SCH_1):GND    I47 @T6G_MB_LIB.T6G(SCH_1):PAGE343
     C P12V_AUX @T6G_MB_LIB.T6G(SCH_1):P12V_AUX    I47 @T6G_MB_LIB.T6G(SCH_1):PAGE343

PD108 SCHOTTKY_AC-B340A-13-F,SMLF,IC,BC000340Z30
     A    GND @T6G_MB_LIB.T6G(SCH_1):GND    I92 @T6G_MB_LIB.T6G(SCH_1):PAGE343
     C P12V_OCP_V3_2 @T6G_MB_LIB.T6G(SCH_1):P12V_OCP_V3_2    I92 @T6G_MB_LIB.T6G(SCH_1):PAGE343

PD109 SCHOTTKY_AC-B340A-13-F,SMLF,IC,BC000340Z30
     A    GND @T6G_MB_LIB.T6G(SCH_1):GND   I106 @T6G_MB_LIB.T6G(SCH_1):PAGE343
     C P3V3_OCP_V3_2_R @T6G_MB_LIB.T6G(SCH_1):P3V3_OCP_V3_2_R   I106 @T6G_MB_LIB.T6G(SCH_1):PAGE343

PD111 SS15P3SM386A-SS15P3S-M3/86A,SMLF,IC,BC015P3SZ00
     1    GND @T6G_MB_LIB.T6G(SCH_1):GND    I89 @T6G_MB_LIB.T6G(SCH_1):PAGE267
     K P12V_AUX @T6G_MB_LIB.T6G(SCH_1):P12V_AUX    I89 @T6G_MB_LIB.T6G(SCH_1):PAGE267
     2    GND @T6G_MB_LIB.T6G(SCH_1):GND    I89 @T6G_MB_LIB.T6G(SCH_1):PAGE267

PD112 SCHOTTKY_AC-B340A-13-F,SMLF,IC,BC000340Z30
     A    GND @T6G_MB_LIB.T6G(SCH_1):GND    I74 @T6G_MB_LIB.T6G(SCH_1):PAGE324
     C P12V_E1S_0 @T6G_MB_LIB.T6G(SCH_1):P12V_E1S_0    I74 @T6G_MB_LIB.T6G(SCH_1):PAGE324

PD113 SCHOTTKY_AC-B340A-13-F,SMLF,IC,BC000340Z30
     A    GND @T6G_MB_LIB.T6G(SCH_1):GND    I50 @T6G_MB_LIB.T6G(SCH_1):PAGE324
     C P3V3_E1S_0_R @T6G_MB_LIB.T6G(SCH_1):P3V3_E1S_0_R    I50 @T6G_MB_LIB.T6G(SCH_1):PAGE324

PD114 DIODE_TVS-SMF14A,SMLF,IC,BCSMF14AZ01
     A    GND @T6G_MB_LIB.T6G(SCH_1):GND    I33 @T6G_MB_LIB.T6G(SCH_1):PAGE324
     C P12V_AUX @T6G_MB_LIB.T6G(SCH_1):P12V_AUX    I33 @T6G_MB_LIB.T6G(SCH_1):PAGE324

PD115 DIODE_TVS-SMF14A,SMLF,IC,BCSMF14AZ01
     A    GND @T6G_MB_LIB.T6G(SCH_1):GND    I28 @T6G_MB_LIB.T6G(SCH_1):PAGE350
     C P12V_AUX @T6G_MB_LIB.T6G(SCH_1):P12V_AUX    I28 @T6G_MB_LIB.T6G(SCH_1):PAGE350

PD116 SCHOTTKY_AC-B340A-13-F,SMLF,IC,BC000340Z30
     A    GND @T6G_MB_LIB.T6G(SCH_1):GND    I79 @T6G_MB_LIB.T6G(SCH_1):PAGE350
     C P12V_SCM_R @T6G_MB_LIB.T6G(SCH_1):P12V_SCM_R    I79 @T6G_MB_LIB.T6G(SCH_1):PAGE350

 PJ1 CONN3_210HP1030BR1-CONN3_210-HP1-030BR1,THLF,IO,DFA
     3 SMB_SCM_2_R3_SCL @T6G_MB_LIB.T6G(SCH_1):SMB_SCM_2_R3_SCL   I143 @T6G_MB_LIB.T6G(SCH_1):PAGE168
     2 SMB_SCM_2_R3_SDA @T6G_MB_LIB.T6G(SCH_1):SMB_SCM_2_R3_SDA   I143 @T6G_MB_LIB.T6G(SCH_1):PAGE168
     1    GND @T6G_MB_LIB.T6G(SCH_1):GND   I143 @T6G_MB_LIB.T6G(SCH_1):PAGE168

PJ09_P0_N Q_SHORT_SM-EMPTY,SHORT16
     1    GND @T6G_MB_LIB.T6G(SCH_1):GND   I215 @T6G_MB_LIB.T6G(SCH_1):PAGE475
     2 P0V9_RETIMER_CPU0_SENSE_SH_N @T6G_MB_LIB.T6G(SCH_1):P0V9_RETIMER_CPU0_SENSE_SH_N   I215 @T6G_MB_LIB.T6G(SCH_1):PAGE475

PJ09_P0_P Q_SHORT_SM-EMPTY,SHORT16
     1 P0V9_CPU0_RT_2D @T6G_MB_LIB.T6G(SCH_1):P0V9_CPU0_RT_2D   I214 @T6G_MB_LIB.T6G(SCH_1):PAGE475
     2 P0V9_RETIMER_CPU0_SENSE_SH_P @T6G_MB_LIB.T6G(SCH_1):P0V9_RETIMER_CPU0_SENSE_SH_P   I214 @T6G_MB_LIB.T6G(SCH_1):PAGE475

PJ09_P1_N Q_SHORT_SM-EMPTY,SHORT16
     1    GND @T6G_MB_LIB.T6G(SCH_1):GND    I96 @T6G_MB_LIB.T6G(SCH_1):PAGE477
     2 P0V9_RETIMER_CPU1_SENSE_SH_N @T6G_MB_LIB.T6G(SCH_1):P0V9_RETIMER_CPU1_SENSE_SH_N    I96 @T6G_MB_LIB.T6G(SCH_1):PAGE477

PJ09_P1_P Q_SHORT_SM-EMPTY,SHORT16
     1 P0V9_CPU1_RT_2D @T6G_MB_LIB.T6G(SCH_1):P0V9_CPU1_RT_2D    I95 @T6G_MB_LIB.T6G(SCH_1):PAGE477
     2 P0V9_RETIMER_CPU1_SENSE_SH_P @T6G_MB_LIB.T6G(SCH_1):P0V9_RETIMER_CPU1_SENSE_SH_P    I95 @T6G_MB_LIB.T6G(SCH_1):PAGE477

PJ38 SCONN21_9193031121LF-SCONN21_91930-31121LF,SMLF,IOA
     1 P12V_PSU @T6G_MB_LIB.T6G(SCH_1):P12V_PSU    I42 @T6G_MB_LIB.T6G(SCH_1):PAGE371
     3 P12V_HSC_SENSE1_N @T6G_MB_LIB.T6G(SCH_1):P12V_HSC_SENSE1_N    I42 @T6G_MB_LIB.T6G(SCH_1):PAGE371
     4 P12V_HSC_SENSE2_P @T6G_MB_LIB.T6G(SCH_1):P12V_HSC_SENSE2_P    I42 @T6G_MB_LIB.T6G(SCH_1):PAGE371
     5 P12V_HSC_SENSE2_N @T6G_MB_LIB.T6G(SCH_1):P12V_HSC_SENSE2_N    I42 @T6G_MB_LIB.T6G(SCH_1):PAGE371
     2 P12V_HSC_SENSE1_P @T6G_MB_LIB.T6G(SCH_1):P12V_HSC_SENSE1_P    I42 @T6G_MB_LIB.T6G(SCH_1):PAGE371
    G1    GND @T6G_MB_LIB.T6G(SCH_1):GND    I42 @T6G_MB_LIB.T6G(SCH_1):PAGE371
    G2    GND @T6G_MB_LIB.T6G(SCH_1):GND    I42 @T6G_MB_LIB.T6G(SCH_1):PAGE371
     6 P12V_HSC_ADC_N @T6G_MB_LIB.T6G(SCH_1):P12V_HSC_ADC_N    I42 @T6G_MB_LIB.T6G(SCH_1):PAGE371
     7 P12V_HSC_ADC_P @T6G_MB_LIB.T6G(SCH_1):P12V_HSC_ADC_P    I42 @T6G_MB_LIB.T6G(SCH_1):PAGE371
     8 P12V_HSC_GATE1 @T6G_MB_LIB.T6G(SCH_1):P12V_HSC_GATE1    I42 @T6G_MB_LIB.T6G(SCH_1):PAGE371
     9 P12V_HSC_GATE2 @T6G_MB_LIB.T6G(SCH_1):P12V_HSC_GATE2    I42 @T6G_MB_LIB.T6G(SCH_1):PAGE371
    10 P12V_AUX @T6G_MB_LIB.T6G(SCH_1):P12V_AUX    I42 @T6G_MB_LIB.T6G(SCH_1):PAGE371
    11    GND @T6G_MB_LIB.T6G(SCH_1):GND    I42 @T6G_MB_LIB.T6G(SCH_1):PAGE371
    12 P3V3_AUX @T6G_MB_LIB.T6G(SCH_1):P3V3_AUX    I42 @T6G_MB_LIB.T6G(SCH_1):PAGE371
    13 IRQ_HSC_FAULT_N @T6G_MB_LIB.T6G(SCH_1):IRQ_HSC_FAULT_N    I42 @T6G_MB_LIB.T6G(SCH_1):PAGE371
    14 HSC_EN @T6G_MB_LIB.T6G(SCH_1):HSC_EN    I42 @T6G_MB_LIB.T6G(SCH_1):PAGE371
    15 MB0_P12V_STBY_PWRGD @T6G_MB_LIB.T6G(SCH_1):MB0_P12V_STBY_PWRGD    I42 @T6G_MB_LIB.T6G(SCH_1):PAGE371
    16 HSC_CSOUT @T6G_MB_LIB.T6G(SCH_1):HSC_CSOUT    I42 @T6G_MB_LIB.T6G(SCH_1):PAGE371
    17 HSC_TYPE_ADC @T6G_MB_LIB.T6G(SCH_1):HSC_TYPE_ADC    I42 @T6G_MB_LIB.T6G(SCH_1):PAGE371
    18 SMB_SML1_PMBUS_HSC_R1_SCL @T6G_MB_LIB.T6G(SCH_1):SMB_SML1_PMBUS_HSC_R1_SCL    I42 @T6G_MB_LIB.T6G(SCH_1):PAGE371
    19 SMB_SML1_PMBUS_HSC_R1_SDA @T6G_MB_LIB.T6G(SCH_1):SMB_SML1_PMBUS_HSC_R1_SDA    I42 @T6G_MB_LIB.T6G(SCH_1):PAGE371
    20 IRQ_SML1_PMBUS_ALERT_N @T6G_MB_LIB.T6G(SCH_1):IRQ_SML1_PMBUS_ALERT_N    I42 @T6G_MB_LIB.T6G(SCH_1):PAGE371
    21    GND @T6G_MB_LIB.T6G(SCH_1):GND    I42 @T6G_MB_LIB.T6G(SCH_1):PAGE371

 PL7 Q_INDUCTOR4P_14-150NH,SMLF,IND,CV+15^0TZ04
     2 IND_CPU1_P0_CPL0 @T6G_MB_LIB.T6G(SCH_1):IND_CPU1_P0_CPL0    I38 @T6G_MB_LIB.T6G(SCH_1):PAGE178
     3 IND_CPU1_P0_CPL6 @T6G_MB_LIB.T6G(SCH_1):IND_CPU1_P0_CPL6    I38 @T6G_MB_LIB.T6G(SCH_1):PAGE178
     4 PVDDCR_CPU1_P0 @T6G_MB_LIB.T6G(SCH_1):PVDDCR_CPU1_P0    I38 @T6G_MB_LIB.T6G(SCH_1):PAGE178
     1 SW_PVDDCR_CPU1_P0_SW6 @T6G_MB_LIB.T6G(SCH_1):SW_PVDDCR_CPU1_P0_SW6    I38 @T6G_MB_LIB.T6G(SCH_1):PAGE178

 PL8 Q_INDUCTOR4P_14-150NH,SMLF,IND,CV+15^0TZ04
     2 IND_CPU0_P1_CPL0 @T6G_MB_LIB.T6G(SCH_1):IND_CPU0_P1_CPL0    I53 @T6G_MB_LIB.T6G(SCH_1):PAGE188
     3 IND_CPU0_P1_CPL6 @T6G_MB_LIB.T6G(SCH_1):IND_CPU0_P1_CPL6    I53 @T6G_MB_LIB.T6G(SCH_1):PAGE188
     4 PVDDCR_CPU0_P1 @T6G_MB_LIB.T6G(SCH_1):PVDDCR_CPU0_P1    I53 @T6G_MB_LIB.T6G(SCH_1):PAGE188
     1 SW_PVDDCR_CPU0_P1_SW6 @T6G_MB_LIB.T6G(SCH_1):SW_PVDDCR_CPU0_P1_SW6    I53 @T6G_MB_LIB.T6G(SCH_1):PAGE188

 PL9 Q_INDUCTOR_SMLF-120NH/69A,IND,CV+12^0EZ03
     2    GND @T6G_MB_LIB.T6G(SCH_1):GND    I36 @T6G_MB_LIB.T6G(SCH_1):PAGE178
     1 IND_CPU1_P0_CPL0 @T6G_MB_LIB.T6G(SCH_1):IND_CPU1_P0_CPL0    I36 @T6G_MB_LIB.T6G(SCH_1):PAGE178

PL10 Q_INDUCTOR4P_14-150NH,SMLF,IND,CV+15^0TZ04
     2 IND_CPU1_P0_CPL5 @T6G_MB_LIB.T6G(SCH_1):IND_CPU1_P0_CPL5    I62 @T6G_MB_LIB.T6G(SCH_1):PAGE176
     3 IND_CPU1_P0_CPL1 @T6G_MB_LIB.T6G(SCH_1):IND_CPU1_P0_CPL1    I62 @T6G_MB_LIB.T6G(SCH_1):PAGE176
     4 PVDDCR_CPU1_P0 @T6G_MB_LIB.T6G(SCH_1):PVDDCR_CPU1_P0    I62 @T6G_MB_LIB.T6G(SCH_1):PAGE176
     1 SW_PVDDCR_CPU1_P0_SW1 @T6G_MB_LIB.T6G(SCH_1):SW_PVDDCR_CPU1_P0_SW1    I62 @T6G_MB_LIB.T6G(SCH_1):PAGE176

PL11 Q_INDUCTOR4P_14-150NH,SMLF,IND,CV+15^0TZ04
     2 IND_CPU1_P0_CPL1 @T6G_MB_LIB.T6G(SCH_1):IND_CPU1_P0_CPL1    I46 @T6G_MB_LIB.T6G(SCH_1):PAGE176
     3 IND_CPU1_P0_CPL2 @T6G_MB_LIB.T6G(SCH_1):IND_CPU1_P0_CPL2    I46 @T6G_MB_LIB.T6G(SCH_1):PAGE176
     4 PVDDCR_CPU1_P0 @T6G_MB_LIB.T6G(SCH_1):PVDDCR_CPU1_P0    I46 @T6G_MB_LIB.T6G(SCH_1):PAGE176
     1 SW_PVDDCR_CPU1_P0_SW2 @T6G_MB_LIB.T6G(SCH_1):SW_PVDDCR_CPU1_P0_SW2    I46 @T6G_MB_LIB.T6G(SCH_1):PAGE176

PL12 Q_INDUCTOR_SMLF-50NH/86A,IND,CVA50^0MZ09
     2 P12V_AUX @T6G_MB_LIB.T6G(SCH_1):P12V_AUX    I83 @T6G_MB_LIB.T6G(SCH_1):PAGE176
     1 SW_P12V_AUX_PVDDCR_CPU1_P0_FLT @T6G_MB_LIB.T6G(SCH_1):SW_P12V_AUX_PVDDCR_CPU1_P0_FLT    I83 @T6G_MB_LIB.T6G(SCH_1):PAGE176

PL13 Q_INDUCTOR4P_14-150NH,SMLF,IND,CV+15^0TZ04
     2 IND_CPU1_P0_CPL3 @T6G_MB_LIB.T6G(SCH_1):IND_CPU1_P0_CPL3    I42 @T6G_MB_LIB.T6G(SCH_1):PAGE177
     3    GND @T6G_MB_LIB.T6G(SCH_1):GND    I42 @T6G_MB_LIB.T6G(SCH_1):PAGE177
     4 PVDDCR_CPU1_P0 @T6G_MB_LIB.T6G(SCH_1):PVDDCR_CPU1_P0    I42 @T6G_MB_LIB.T6G(SCH_1):PAGE177
     1 SW_PVDDCR_CPU1_P0_SW4 @T6G_MB_LIB.T6G(SCH_1):SW_PVDDCR_CPU1_P0_SW4    I42 @T6G_MB_LIB.T6G(SCH_1):PAGE177

PL14 Q_INDUCTOR4P_14-150NH,SMLF,IND,CV+15^0TZ04
     2 IND_CPU1_P0_CPL2 @T6G_MB_LIB.T6G(SCH_1):IND_CPU1_P0_CPL2    I64 @T6G_MB_LIB.T6G(SCH_1):PAGE177
     3 IND_CPU1_P0_CPL3 @T6G_MB_LIB.T6G(SCH_1):IND_CPU1_P0_CPL3    I64 @T6G_MB_LIB.T6G(SCH_1):PAGE177
     4 PVDDCR_CPU1_P0 @T6G_MB_LIB.T6G(SCH_1):PVDDCR_CPU1_P0    I64 @T6G_MB_LIB.T6G(SCH_1):PAGE177
     1 SW_PVDDCR_CPU1_P0_SW3 @T6G_MB_LIB.T6G(SCH_1):SW_PVDDCR_CPU1_P0_SW3    I64 @T6G_MB_LIB.T6G(SCH_1):PAGE177

PL15 Q_INDUCTOR4P_14-150NH,SMLF,IND,CV+15^0TZ04
     2 IND_CPU1_P0_CPL6 @T6G_MB_LIB.T6G(SCH_1):IND_CPU1_P0_CPL6    I63 @T6G_MB_LIB.T6G(SCH_1):PAGE178
     3 IND_CPU1_P0_CPL5 @T6G_MB_LIB.T6G(SCH_1):IND_CPU1_P0_CPL5    I63 @T6G_MB_LIB.T6G(SCH_1):PAGE178
     4 PVDDCR_CPU1_P0 @T6G_MB_LIB.T6G(SCH_1):PVDDCR_CPU1_P0    I63 @T6G_MB_LIB.T6G(SCH_1):PAGE178
     1 SW_PVDDCR_CPU1_P0_SW5 @T6G_MB_LIB.T6G(SCH_1):SW_PVDDCR_CPU1_P0_SW5    I63 @T6G_MB_LIB.T6G(SCH_1):PAGE178

PL16 Q_INDUCTOR_SMLF-0.22UH/33A,IND,CV+22Y0EZ00
     2    GND @T6G_MB_LIB.T6G(SCH_1):GND    I43 @T6G_MB_LIB.T6G(SCH_1):PAGE181
     1 IND_PVDDIO_P0_CPL0 @T6G_MB_LIB.T6G(SCH_1):IND_PVDDIO_P0_CPL0    I43 @T6G_MB_LIB.T6G(SCH_1):PAGE181

PL17 Q_INDUCTOR4P_14-150NH,SMLF,IND,CV+15^0TZ04
     2 IND_PVDDIO_P0_CPL2 @T6G_MB_LIB.T6G(SCH_1):IND_PVDDIO_P0_CPL2    I64 @T6G_MB_LIB.T6G(SCH_1):PAGE180
     3    GND @T6G_MB_LIB.T6G(SCH_1):GND    I64 @T6G_MB_LIB.T6G(SCH_1):PAGE180
     4 PVDDIO_P0 @T6G_MB_LIB.T6G(SCH_1):PVDDIO_P0    I64 @T6G_MB_LIB.T6G(SCH_1):PAGE180
     1 SW_PVDDIO_P0_SW1 @T6G_MB_LIB.T6G(SCH_1):SW_PVDDIO_P0_SW1    I64 @T6G_MB_LIB.T6G(SCH_1):PAGE180

PL18 Q_INDUCTOR4P_14-150NH,SMLF,IND,CV+15^0TZ04
     2 IND_PVDDIO_P0_CPL3 @T6G_MB_LIB.T6G(SCH_1):IND_PVDDIO_P0_CPL3    I40 @T6G_MB_LIB.T6G(SCH_1):PAGE180
     3 IND_PVDDIO_P0_CPL2 @T6G_MB_LIB.T6G(SCH_1):IND_PVDDIO_P0_CPL2    I40 @T6G_MB_LIB.T6G(SCH_1):PAGE180
     4 PVDDIO_P0 @T6G_MB_LIB.T6G(SCH_1):PVDDIO_P0    I40 @T6G_MB_LIB.T6G(SCH_1):PAGE180
     1 SW_PVDDIO_P0_SW2 @T6G_MB_LIB.T6G(SCH_1):SW_PVDDIO_P0_SW2    I40 @T6G_MB_LIB.T6G(SCH_1):PAGE180

PL19 Q_INDUCTOR_SMLF-50NH/86A,IND,CVA50^0MZ09
     2 P12V_AUX @T6G_MB_LIB.T6G(SCH_1):P12V_AUX    I69 @T6G_MB_LIB.T6G(SCH_1):PAGE180
     1 SW_P12V_AUX_PVDDIO_P0_FLT @T6G_MB_LIB.T6G(SCH_1):SW_P12V_AUX_PVDDIO_P0_FLT    I69 @T6G_MB_LIB.T6G(SCH_1):PAGE180

PL20 Q_INDUCTOR4P_14-150NH,SMLF,IND,CV+15^0TZ04
     2 IND_PVDDIO_P0_CPL0 @T6G_MB_LIB.T6G(SCH_1):IND_PVDDIO_P0_CPL0    I42 @T6G_MB_LIB.T6G(SCH_1):PAGE181
     3 IND_PVDDIO_P0_CPL4 @T6G_MB_LIB.T6G(SCH_1):IND_PVDDIO_P0_CPL4    I42 @T6G_MB_LIB.T6G(SCH_1):PAGE181
     4 PVDDIO_P0 @T6G_MB_LIB.T6G(SCH_1):PVDDIO_P0    I42 @T6G_MB_LIB.T6G(SCH_1):PAGE181
     1 SW_PVDDIO_P0_SW4 @T6G_MB_LIB.T6G(SCH_1):SW_PVDDIO_P0_SW4    I42 @T6G_MB_LIB.T6G(SCH_1):PAGE181

PL21 Q_INDUCTOR4P_14-150NH,SMLF,IND,CV+15^0TZ04
     2 IND_PVDDIO_P0_CPL4 @T6G_MB_LIB.T6G(SCH_1):IND_PVDDIO_P0_CPL4    I61 @T6G_MB_LIB.T6G(SCH_1):PAGE181
     3 IND_PVDDIO_P0_CPL3 @T6G_MB_LIB.T6G(SCH_1):IND_PVDDIO_P0_CPL3    I61 @T6G_MB_LIB.T6G(SCH_1):PAGE181
     4 PVDDIO_P0 @T6G_MB_LIB.T6G(SCH_1):PVDDIO_P0    I61 @T6G_MB_LIB.T6G(SCH_1):PAGE181
     1 SW_PVDDIO_P0_SW3 @T6G_MB_LIB.T6G(SCH_1):SW_PVDDIO_P0_SW3    I61 @T6G_MB_LIB.T6G(SCH_1):PAGE181

PL22 Q_INDUCTOR_SMLF-90NH/155A,IND,CVA90^0KZ13
     2 PVDD11_S3_P0 @T6G_MB_LIB.T6G(SCH_1):PVDD11_S3_P0    I52 @T6G_MB_LIB.T6G(SCH_1):PAGE183
     1 SW_PVDD11_S3_P0_SW2 @T6G_MB_LIB.T6G(SCH_1):SW_PVDD11_S3_P0_SW2    I52 @T6G_MB_LIB.T6G(SCH_1):PAGE183

PL23 Q_INDUCTOR_SMLF-90NH/155A,IND,CVA90^0KZ13
     2 PVDD11_S3_P0 @T6G_MB_LIB.T6G(SCH_1):PVDD11_S3_P0    I73 @T6G_MB_LIB.T6G(SCH_1):PAGE183
     1 SW_PVDD11_S3_P0_SW1 @T6G_MB_LIB.T6G(SCH_1):SW_PVDD11_S3_P0_SW1    I73 @T6G_MB_LIB.T6G(SCH_1):PAGE183

PL24 Q_INDUCTOR_SMLF-100NH/16A,IND,CV+10G0MZ04
     2 P12V_AUX @T6G_MB_LIB.T6G(SCH_1):P12V_AUX    I78 @T6G_MB_LIB.T6G(SCH_1):PAGE183
     1 SW_P12V_AUX_PVDD11_S3_P0_FLT @T6G_MB_LIB.T6G(SCH_1):SW_P12V_AUX_PVDD11_S3_P0_FLT    I78 @T6G_MB_LIB.T6G(SCH_1):PAGE183

PL26 Q_INDUCTOR_SMLF-BLM18SN220TN1D/8000MA,IND,CX220TN1A
     2 SW_P12V_AUX_PVDD18_S5_P1_FLT @T6G_MB_LIB.T6G(SCH_1):SW_P12V_AUX_PVDD18_S5_P1_FLT     I4 @T6G_MB_LIB.T6G(SCH_1):PAGE201
     1 P12V_AUX @T6G_MB_LIB.T6G(SCH_1):P12V_AUX     I4 @T6G_MB_LIB.T6G(SCH_1):PAGE201

PL27 Q_INDUCTOR_SMLF-120NH/69A,IND,CV+12^0EZ03
     2 IND_CPU0_P1_CPL0 @T6G_MB_LIB.T6G(SCH_1):IND_CPU0_P1_CPL0    I51 @T6G_MB_LIB.T6G(SCH_1):PAGE188
     1    GND @T6G_MB_LIB.T6G(SCH_1):GND    I51 @T6G_MB_LIB.T6G(SCH_1):PAGE188

PL28 Q_INDUCTOR4P_14-150NH,SMLF,IND,CV+15^0TZ04
     2 IND_CPU0_P1_CPL5 @T6G_MB_LIB.T6G(SCH_1):IND_CPU0_P1_CPL5    I90 @T6G_MB_LIB.T6G(SCH_1):PAGE186
     3 IND_CPU0_P1_CPL1 @T6G_MB_LIB.T6G(SCH_1):IND_CPU0_P1_CPL1    I90 @T6G_MB_LIB.T6G(SCH_1):PAGE186
     4 PVDDCR_CPU0_P1 @T6G_MB_LIB.T6G(SCH_1):PVDDCR_CPU0_P1    I90 @T6G_MB_LIB.T6G(SCH_1):PAGE186
     1 SW_PVDDCR_CPU0_P1_SW1 @T6G_MB_LIB.T6G(SCH_1):SW_PVDDCR_CPU0_P1_SW1    I90 @T6G_MB_LIB.T6G(SCH_1):PAGE186

PL29 Q_INDUCTOR4P_14-150NH,SMLF,IND,CV+15^0TZ04
     2 IND_CPU0_P1_CPL1 @T6G_MB_LIB.T6G(SCH_1):IND_CPU0_P1_CPL1    I56 @T6G_MB_LIB.T6G(SCH_1):PAGE186
     3 IND_CPU0_P1_CPL2 @T6G_MB_LIB.T6G(SCH_1):IND_CPU0_P1_CPL2    I56 @T6G_MB_LIB.T6G(SCH_1):PAGE186
     4 PVDDCR_CPU0_P1 @T6G_MB_LIB.T6G(SCH_1):PVDDCR_CPU0_P1    I56 @T6G_MB_LIB.T6G(SCH_1):PAGE186
     1 SW_PVDDCR_CPU0_P1_SW2 @T6G_MB_LIB.T6G(SCH_1):SW_PVDDCR_CPU0_P1_SW2    I56 @T6G_MB_LIB.T6G(SCH_1):PAGE186

PL30 Q_INDUCTOR_SMLF-50NH/86A,IND,CVA50^0MZ09
     2 P12V_AUX @T6G_MB_LIB.T6G(SCH_1):P12V_AUX    I73 @T6G_MB_LIB.T6G(SCH_1):PAGE186
     1 SW_P12V_AUX_PVDDCR_CPU0_P1_FLT @T6G_MB_LIB.T6G(SCH_1):SW_P12V_AUX_PVDDCR_CPU0_P1_FLT    I73 @T6G_MB_LIB.T6G(SCH_1):PAGE186

PL31 Q_INDUCTOR4P_14-150NH,SMLF,IND,CV+15^0TZ04
     2 IND_CPU0_P1_CPL2 @T6G_MB_LIB.T6G(SCH_1):IND_CPU0_P1_CPL2    I67 @T6G_MB_LIB.T6G(SCH_1):PAGE187
     3 IND_CPU0_P1_CPL3 @T6G_MB_LIB.T6G(SCH_1):IND_CPU0_P1_CPL3    I67 @T6G_MB_LIB.T6G(SCH_1):PAGE187
     4 PVDDCR_CPU0_P1 @T6G_MB_LIB.T6G(SCH_1):PVDDCR_CPU0_P1    I67 @T6G_MB_LIB.T6G(SCH_1):PAGE187
     1 SW_PVDDCR_CPU0_P1_SW3 @T6G_MB_LIB.T6G(SCH_1):SW_PVDDCR_CPU0_P1_SW3    I67 @T6G_MB_LIB.T6G(SCH_1):PAGE187

PL32 Q_INDUCTOR4P_14-150NH,SMLF,IND,CV+15^0TZ04
     2 IND_CPU0_P1_CPL3 @T6G_MB_LIB.T6G(SCH_1):IND_CPU0_P1_CPL3    I53 @T6G_MB_LIB.T6G(SCH_1):PAGE187
     3    GND @T6G_MB_LIB.T6G(SCH_1):GND    I53 @T6G_MB_LIB.T6G(SCH_1):PAGE187
     4 PVDDCR_CPU0_P1 @T6G_MB_LIB.T6G(SCH_1):PVDDCR_CPU0_P1    I53 @T6G_MB_LIB.T6G(SCH_1):PAGE187
     1 SW_PVDDCR_CPU0_P1_SW4 @T6G_MB_LIB.T6G(SCH_1):SW_PVDDCR_CPU0_P1_SW4    I53 @T6G_MB_LIB.T6G(SCH_1):PAGE187

PL33 Q_INDUCTOR4P_14-150NH,SMLF,IND,CV+15^0TZ04
     2 IND_CPU0_P1_CPL6 @T6G_MB_LIB.T6G(SCH_1):IND_CPU0_P1_CPL6    I64 @T6G_MB_LIB.T6G(SCH_1):PAGE188
     3 IND_CPU0_P1_CPL5 @T6G_MB_LIB.T6G(SCH_1):IND_CPU0_P1_CPL5    I64 @T6G_MB_LIB.T6G(SCH_1):PAGE188
     4 PVDDCR_CPU0_P1 @T6G_MB_LIB.T6G(SCH_1):PVDDCR_CPU0_P1    I64 @T6G_MB_LIB.T6G(SCH_1):PAGE188
     1 SW_PVDDCR_CPU0_P1_SW5 @T6G_MB_LIB.T6G(SCH_1):SW_PVDDCR_CPU0_P1_SW5    I64 @T6G_MB_LIB.T6G(SCH_1):PAGE188

PL34 Q_INDUCTOR_SMLF-0.22UH/33A,IND,CV+22Y0EZ00
     2 IND_SOC_P1_CPL0 @T6G_MB_LIB.T6G(SCH_1):IND_SOC_P1_CPL0    I25 @T6G_MB_LIB.T6G(SCH_1):PAGE191
     1    GND @T6G_MB_LIB.T6G(SCH_1):GND    I25 @T6G_MB_LIB.T6G(SCH_1):PAGE191

PL35 Q_INDUCTOR4P_14-150NH,SMLF,IND,CV+15^0TZ04
     2 IND_SOC_P1_CPL2 @T6G_MB_LIB.T6G(SCH_1):IND_SOC_P1_CPL2    I69 @T6G_MB_LIB.T6G(SCH_1):PAGE190
     3    GND @T6G_MB_LIB.T6G(SCH_1):GND    I69 @T6G_MB_LIB.T6G(SCH_1):PAGE190
     4 PVDDCR_SOC_P1 @T6G_MB_LIB.T6G(SCH_1):PVDDCR_SOC_P1    I69 @T6G_MB_LIB.T6G(SCH_1):PAGE190
     1 SW_PVDDCR_SOC_P1_SW1 @T6G_MB_LIB.T6G(SCH_1):SW_PVDDCR_SOC_P1_SW1    I69 @T6G_MB_LIB.T6G(SCH_1):PAGE190

PL36 Q_INDUCTOR4P_14-150NH,SMLF,IND,CV+15^0TZ04
     2 IND_SOC_P1_CPL3 @T6G_MB_LIB.T6G(SCH_1):IND_SOC_P1_CPL3    I52 @T6G_MB_LIB.T6G(SCH_1):PAGE190
     3 IND_SOC_P1_CPL2 @T6G_MB_LIB.T6G(SCH_1):IND_SOC_P1_CPL2    I52 @T6G_MB_LIB.T6G(SCH_1):PAGE190
     4 PVDDCR_SOC_P1 @T6G_MB_LIB.T6G(SCH_1):PVDDCR_SOC_P1    I52 @T6G_MB_LIB.T6G(SCH_1):PAGE190
     1 SW_PVDDCR_SOC_P1_SW2 @T6G_MB_LIB.T6G(SCH_1):SW_PVDDCR_SOC_P1_SW2    I52 @T6G_MB_LIB.T6G(SCH_1):PAGE190

PL37 Q_INDUCTOR_SMLF-50NH/86A,IND,CVA50^0MZ09
     2 P12V_AUX @T6G_MB_LIB.T6G(SCH_1):P12V_AUX    I74 @T6G_MB_LIB.T6G(SCH_1):PAGE190
     1 SW_P12V_AUX_PVDDCR_SOC_P1_FLT @T6G_MB_LIB.T6G(SCH_1):SW_P12V_AUX_PVDDCR_SOC_P1_FLT    I74 @T6G_MB_LIB.T6G(SCH_1):PAGE190

PL38 Q_INDUCTOR4P_14-150NH,SMLF,IND,CV+15^0TZ04
     2 IND_SOC_P1_CPL0 @T6G_MB_LIB.T6G(SCH_1):IND_SOC_P1_CPL0    I26 @T6G_MB_LIB.T6G(SCH_1):PAGE191
     3 IND_SOC_P1_CPL3 @T6G_MB_LIB.T6G(SCH_1):IND_SOC_P1_CPL3    I26 @T6G_MB_LIB.T6G(SCH_1):PAGE191
     4 PVDDCR_SOC_P1 @T6G_MB_LIB.T6G(SCH_1):PVDDCR_SOC_P1    I26 @T6G_MB_LIB.T6G(SCH_1):PAGE191
     1 SW_PVDDCR_SOC_P1_SW3 @T6G_MB_LIB.T6G(SCH_1):SW_PVDDCR_SOC_P1_SW3    I26 @T6G_MB_LIB.T6G(SCH_1):PAGE191

PL39 Q_INDUCTOR_SMLF-120NH/69A,IND,CV+12^0EZ03
     2    GND @T6G_MB_LIB.T6G(SCH_1):GND    I37 @T6G_MB_LIB.T6G(SCH_1):PAGE195
     1 IND_CPU1_P1_CPL0 @T6G_MB_LIB.T6G(SCH_1):IND_CPU1_P1_CPL0    I37 @T6G_MB_LIB.T6G(SCH_1):PAGE195

PL40 Q_INDUCTOR4P_14-150NH,SMLF,IND,CV+15^0TZ04
     2 IND_CPU1_P1_CPL5 @T6G_MB_LIB.T6G(SCH_1):IND_CPU1_P1_CPL5    I77 @T6G_MB_LIB.T6G(SCH_1):PAGE193
     3 IND_CPU1_P1_CPL1 @T6G_MB_LIB.T6G(SCH_1):IND_CPU1_P1_CPL1    I77 @T6G_MB_LIB.T6G(SCH_1):PAGE193
     4 PVDDCR_CPU1_P1 @T6G_MB_LIB.T6G(SCH_1):PVDDCR_CPU1_P1    I77 @T6G_MB_LIB.T6G(SCH_1):PAGE193
     1 SW_PVDDCR_CPU1_P1_SW1 @T6G_MB_LIB.T6G(SCH_1):SW_PVDDCR_CPU1_P1_SW1    I77 @T6G_MB_LIB.T6G(SCH_1):PAGE193

PL41 Q_INDUCTOR4P_14-150NH,SMLF,IND,CV+15^0TZ04
     2 IND_CPU1_P1_CPL1 @T6G_MB_LIB.T6G(SCH_1):IND_CPU1_P1_CPL1    I62 @T6G_MB_LIB.T6G(SCH_1):PAGE193
     3 IND_CPU1_P1_CPL2 @T6G_MB_LIB.T6G(SCH_1):IND_CPU1_P1_CPL2    I62 @T6G_MB_LIB.T6G(SCH_1):PAGE193
     4 PVDDCR_CPU1_P1 @T6G_MB_LIB.T6G(SCH_1):PVDDCR_CPU1_P1    I62 @T6G_MB_LIB.T6G(SCH_1):PAGE193
     1 SW_PVDDCR_CPU1_P1_SW2 @T6G_MB_LIB.T6G(SCH_1):SW_PVDDCR_CPU1_P1_SW2    I62 @T6G_MB_LIB.T6G(SCH_1):PAGE193

PL42 Q_INDUCTOR_SMLF-50NH/86A,IND,CVA50^0MZ09
     2 P12V_AUX @T6G_MB_LIB.T6G(SCH_1):P12V_AUX    I79 @T6G_MB_LIB.T6G(SCH_1):PAGE193
     1 SW_P12V_AUX_PVDDCR_CPU1_P1_FLT @T6G_MB_LIB.T6G(SCH_1):SW_P12V_AUX_PVDDCR_CPU1_P1_FLT    I79 @T6G_MB_LIB.T6G(SCH_1):PAGE193

PL43 Q_INDUCTOR4P_14-150NH,SMLF,IND,CV+15^0TZ04
     2 IND_CPU1_P1_CPL3 @T6G_MB_LIB.T6G(SCH_1):IND_CPU1_P1_CPL3    I50 @T6G_MB_LIB.T6G(SCH_1):PAGE194
     3    GND @T6G_MB_LIB.T6G(SCH_1):GND    I50 @T6G_MB_LIB.T6G(SCH_1):PAGE194
     4 PVDDCR_CPU1_P1 @T6G_MB_LIB.T6G(SCH_1):PVDDCR_CPU1_P1    I50 @T6G_MB_LIB.T6G(SCH_1):PAGE194
     1 SW_PVDDCR_CPU1_P1_SW4 @T6G_MB_LIB.T6G(SCH_1):SW_PVDDCR_CPU1_P1_SW4    I50 @T6G_MB_LIB.T6G(SCH_1):PAGE194

PL44 Q_INDUCTOR4P_14-150NH,SMLF,IND,CV+15^0TZ04
     2 IND_CPU1_P1_CPL2 @T6G_MB_LIB.T6G(SCH_1):IND_CPU1_P1_CPL2    I62 @T6G_MB_LIB.T6G(SCH_1):PAGE194
     3 IND_CPU1_P1_CPL3 @T6G_MB_LIB.T6G(SCH_1):IND_CPU1_P1_CPL3    I62 @T6G_MB_LIB.T6G(SCH_1):PAGE194
     4 PVDDCR_CPU1_P1 @T6G_MB_LIB.T6G(SCH_1):PVDDCR_CPU1_P1    I62 @T6G_MB_LIB.T6G(SCH_1):PAGE194
     1 SW_PVDDCR_CPU1_P1_SW3 @T6G_MB_LIB.T6G(SCH_1):SW_PVDDCR_CPU1_P1_SW3    I62 @T6G_MB_LIB.T6G(SCH_1):PAGE194

PL45 Q_INDUCTOR4P_14-150NH,SMLF,IND,CV+15^0TZ04
     2 IND_CPU1_P1_CPL6 @T6G_MB_LIB.T6G(SCH_1):IND_CPU1_P1_CPL6    I63 @T6G_MB_LIB.T6G(SCH_1):PAGE195
     3 IND_CPU1_P1_CPL5 @T6G_MB_LIB.T6G(SCH_1):IND_CPU1_P1_CPL5    I63 @T6G_MB_LIB.T6G(SCH_1):PAGE195
     4 PVDDCR_CPU1_P1 @T6G_MB_LIB.T6G(SCH_1):PVDDCR_CPU1_P1    I63 @T6G_MB_LIB.T6G(SCH_1):PAGE195
     1 SW_PVDDCR_CPU1_P1_SW5 @T6G_MB_LIB.T6G(SCH_1):SW_PVDDCR_CPU1_P1_SW5    I63 @T6G_MB_LIB.T6G(SCH_1):PAGE195

PL46 Q_INDUCTOR_SMLF-0.22UH/33A,IND,CV+22Y0EZ00
     2    GND @T6G_MB_LIB.T6G(SCH_1):GND    I43 @T6G_MB_LIB.T6G(SCH_1):PAGE198
     1 IND_PVDDIO_P1_CPL0 @T6G_MB_LIB.T6G(SCH_1):IND_PVDDIO_P1_CPL0    I43 @T6G_MB_LIB.T6G(SCH_1):PAGE198

PL47 Q_INDUCTOR4P_14-150NH,SMLF,IND,CV+15^0TZ04
     2 IND_PVDDIO_P1_CPL2 @T6G_MB_LIB.T6G(SCH_1):IND_PVDDIO_P1_CPL2    I71 @T6G_MB_LIB.T6G(SCH_1):PAGE197
     3    GND @T6G_MB_LIB.T6G(SCH_1):GND    I71 @T6G_MB_LIB.T6G(SCH_1):PAGE197
     4 PVDDIO_P1 @T6G_MB_LIB.T6G(SCH_1):PVDDIO_P1    I71 @T6G_MB_LIB.T6G(SCH_1):PAGE197
     1 SW_PVDDIO_P1_SW1 @T6G_MB_LIB.T6G(SCH_1):SW_PVDDIO_P1_SW1    I71 @T6G_MB_LIB.T6G(SCH_1):PAGE197

PL48 Q_INDUCTOR4P_14-150NH,SMLF,IND,CV+15^0TZ04
     2 IND_PVDDIO_P1_CPL3 @T6G_MB_LIB.T6G(SCH_1):IND_PVDDIO_P1_CPL3    I83 @T6G_MB_LIB.T6G(SCH_1):PAGE197
     3 IND_PVDDIO_P1_CPL2 @T6G_MB_LIB.T6G(SCH_1):IND_PVDDIO_P1_CPL2    I83 @T6G_MB_LIB.T6G(SCH_1):PAGE197
     4 PVDDIO_P1 @T6G_MB_LIB.T6G(SCH_1):PVDDIO_P1    I83 @T6G_MB_LIB.T6G(SCH_1):PAGE197
     1 SW_PVDDIO_P1_SW2 @T6G_MB_LIB.T6G(SCH_1):SW_PVDDIO_P1_SW2    I83 @T6G_MB_LIB.T6G(SCH_1):PAGE197

PL49 Q_INDUCTOR_SMLF-50NH/86A,IND,CVA50^0MZ09
     2 P12V_AUX @T6G_MB_LIB.T6G(SCH_1):P12V_AUX    I72 @T6G_MB_LIB.T6G(SCH_1):PAGE197
     1 SW_P12V_AUX_PVDDIO_P1_FLT @T6G_MB_LIB.T6G(SCH_1):SW_P12V_AUX_PVDDIO_P1_FLT    I72 @T6G_MB_LIB.T6G(SCH_1):PAGE197

PL50 Q_INDUCTOR_SMLF-120NH/69A,IND,CV+12^0EZ03
     2 IND_CPU0_P0_CPL0 @T6G_MB_LIB.T6G(SCH_1):IND_CPU0_P0_CPL0    I51 @T6G_MB_LIB.T6G(SCH_1):PAGE171
     1    GND @T6G_MB_LIB.T6G(SCH_1):GND    I51 @T6G_MB_LIB.T6G(SCH_1):PAGE171

PL51 Q_INDUCTOR4P_14-150NH,SMLF,IND,CV+15^0TZ04
     2 IND_CPU0_P0_CPL5 @T6G_MB_LIB.T6G(SCH_1):IND_CPU0_P0_CPL5    I77 @T6G_MB_LIB.T6G(SCH_1):PAGE169
     3 IND_CPU0_P0_CPL1 @T6G_MB_LIB.T6G(SCH_1):IND_CPU0_P0_CPL1    I77 @T6G_MB_LIB.T6G(SCH_1):PAGE169
     4 PVDDCR_CPU0_P0 @T6G_MB_LIB.T6G(SCH_1):PVDDCR_CPU0_P0    I77 @T6G_MB_LIB.T6G(SCH_1):PAGE169
     1 SW_PVDDCR_CPU0_P0_SW1 @T6G_MB_LIB.T6G(SCH_1):SW_PVDDCR_CPU0_P0_SW1    I77 @T6G_MB_LIB.T6G(SCH_1):PAGE169

PL52 Q_INDUCTOR4P_14-150NH,SMLF,IND,CV+15^0TZ04
     2 IND_CPU0_P0_CPL1 @T6G_MB_LIB.T6G(SCH_1):IND_CPU0_P0_CPL1    I62 @T6G_MB_LIB.T6G(SCH_1):PAGE169
     3 IND_CPU0_P0_CPL2 @T6G_MB_LIB.T6G(SCH_1):IND_CPU0_P0_CPL2    I62 @T6G_MB_LIB.T6G(SCH_1):PAGE169
     4 PVDDCR_CPU0_P0 @T6G_MB_LIB.T6G(SCH_1):PVDDCR_CPU0_P0    I62 @T6G_MB_LIB.T6G(SCH_1):PAGE169
     1 SW_PVDDCR_CPU0_P0_SW2 @T6G_MB_LIB.T6G(SCH_1):SW_PVDDCR_CPU0_P0_SW2    I62 @T6G_MB_LIB.T6G(SCH_1):PAGE169

PL53 Q_INDUCTOR_SMLF-50NH/86A,IND,CVA50^0MZ09
     2 P12V_AUX @T6G_MB_LIB.T6G(SCH_1):P12V_AUX    I82 @T6G_MB_LIB.T6G(SCH_1):PAGE169
     1 SW_P12V_AUX_PVDDCR_CPU0_P0_FLT @T6G_MB_LIB.T6G(SCH_1):SW_P12V_AUX_PVDDCR_CPU0_P0_FLT    I82 @T6G_MB_LIB.T6G(SCH_1):PAGE169

PL54 Q_INDUCTOR_SMLF-90NH/155A,IND,CVA90^0KZ13
     2 PVDD11_S3_P1 @T6G_MB_LIB.T6G(SCH_1):PVDD11_S3_P1    I78 @T6G_MB_LIB.T6G(SCH_1):PAGE200
     1 SW_PVDD11_S3_P1_SW1 @T6G_MB_LIB.T6G(SCH_1):SW_PVDD11_S3_P1_SW1    I78 @T6G_MB_LIB.T6G(SCH_1):PAGE200

PL55 Q_INDUCTOR_SMLF-90NH/155A,IND,CVA90^0KZ13
     2 PVDD11_S3_P1 @T6G_MB_LIB.T6G(SCH_1):PVDD11_S3_P1    I55 @T6G_MB_LIB.T6G(SCH_1):PAGE200
     1 SW_PVDD11_S3_P1_SW2 @T6G_MB_LIB.T6G(SCH_1):SW_PVDD11_S3_P1_SW2    I55 @T6G_MB_LIB.T6G(SCH_1):PAGE200

PL56 Q_INDUCTOR_SMLF-100NH/16A,IND,CV+10G0MZ04
     2 P12V_AUX @T6G_MB_LIB.T6G(SCH_1):P12V_AUX    I84 @T6G_MB_LIB.T6G(SCH_1):PAGE200
     1 SW_P12V_AUX_PVDD11_S3_P1_FLT @T6G_MB_LIB.T6G(SCH_1):SW_P12V_AUX_PVDD11_S3_P1_FLT    I84 @T6G_MB_LIB.T6G(SCH_1):PAGE200

PL57 Q_INDUCTOR_SMLF-1.0UH/18A,IND,CV-10I0MZ01
     2 PVDD18_S5_P1 @T6G_MB_LIB.T6G(SCH_1):PVDD18_S5_P1    I33 @T6G_MB_LIB.T6G(SCH_1):PAGE201
     1 SW_PVDD18_S5_P1_SW @T6G_MB_LIB.T6G(SCH_1):SW_PVDD18_S5_P1_SW    I33 @T6G_MB_LIB.T6G(SCH_1):PAGE201

PL59 Q_INDUCTOR4P_14-150NH,SMLF,IND,CV+15^0TZ04
     2 IND_CPU0_P0_CPL2 @T6G_MB_LIB.T6G(SCH_1):IND_CPU0_P0_CPL2    I64 @T6G_MB_LIB.T6G(SCH_1):PAGE170
     3 IND_CPU0_P0_CPL3 @T6G_MB_LIB.T6G(SCH_1):IND_CPU0_P0_CPL3    I64 @T6G_MB_LIB.T6G(SCH_1):PAGE170
     4 PVDDCR_CPU0_P0 @T6G_MB_LIB.T6G(SCH_1):PVDDCR_CPU0_P0    I64 @T6G_MB_LIB.T6G(SCH_1):PAGE170
     1 SW_PVDDCR_CPU0_P0_SW3 @T6G_MB_LIB.T6G(SCH_1):SW_PVDDCR_CPU0_P0_SW3    I64 @T6G_MB_LIB.T6G(SCH_1):PAGE170

PL60 Q_INDUCTOR4P_14-150NH,SMLF,IND,CV+15^0TZ04
     2 IND_CPU0_P0_CPL3 @T6G_MB_LIB.T6G(SCH_1):IND_CPU0_P0_CPL3    I52 @T6G_MB_LIB.T6G(SCH_1):PAGE170
     3    GND @T6G_MB_LIB.T6G(SCH_1):GND    I52 @T6G_MB_LIB.T6G(SCH_1):PAGE170
     4 PVDDCR_CPU0_P0 @T6G_MB_LIB.T6G(SCH_1):PVDDCR_CPU0_P0    I52 @T6G_MB_LIB.T6G(SCH_1):PAGE170
     1 SW_PVDDCR_CPU0_P0_SW4 @T6G_MB_LIB.T6G(SCH_1):SW_PVDDCR_CPU0_P0_SW4    I52 @T6G_MB_LIB.T6G(SCH_1):PAGE170

PL61 Q_INDUCTOR4P_14-150NH,SMLF,IND,CV+15^0TZ04
     2 IND_CPU0_P0_CPL6 @T6G_MB_LIB.T6G(SCH_1):IND_CPU0_P0_CPL6    I64 @T6G_MB_LIB.T6G(SCH_1):PAGE171
     3 IND_CPU0_P0_CPL5 @T6G_MB_LIB.T6G(SCH_1):IND_CPU0_P0_CPL5    I64 @T6G_MB_LIB.T6G(SCH_1):PAGE171
     4 PVDDCR_CPU0_P0 @T6G_MB_LIB.T6G(SCH_1):PVDDCR_CPU0_P0    I64 @T6G_MB_LIB.T6G(SCH_1):PAGE171
     1 SW_PVDDCR_CPU0_P0_SW5 @T6G_MB_LIB.T6G(SCH_1):SW_PVDDCR_CPU0_P0_SW5    I64 @T6G_MB_LIB.T6G(SCH_1):PAGE171

PL62 Q_INDUCTOR_SMLF-0.22UH/33A,IND,CV+22Y0EZ00
     2 IND_SOC_P0_CPL0 @T6G_MB_LIB.T6G(SCH_1):IND_SOC_P0_CPL0    I24 @T6G_MB_LIB.T6G(SCH_1):PAGE174
     1    GND @T6G_MB_LIB.T6G(SCH_1):GND    I24 @T6G_MB_LIB.T6G(SCH_1):PAGE174

PL63 Q_INDUCTOR4P_14-150NH,SMLF,IND,CV+15^0TZ04
     2 IND_SOC_P0_CPL2 @T6G_MB_LIB.T6G(SCH_1):IND_SOC_P0_CPL2    I69 @T6G_MB_LIB.T6G(SCH_1):PAGE173
     3    GND @T6G_MB_LIB.T6G(SCH_1):GND    I69 @T6G_MB_LIB.T6G(SCH_1):PAGE173
     4 PVDDCR_SOC_P0 @T6G_MB_LIB.T6G(SCH_1):PVDDCR_SOC_P0    I69 @T6G_MB_LIB.T6G(SCH_1):PAGE173
     1 SW_PVDDCR_SOC_P0_SW1 @T6G_MB_LIB.T6G(SCH_1):SW_PVDDCR_SOC_P0_SW1    I69 @T6G_MB_LIB.T6G(SCH_1):PAGE173

PL64 Q_INDUCTOR4P_14-150NH,SMLF,IND,CV+15^0TZ04
     2 IND_SOC_P0_CPL3 @T6G_MB_LIB.T6G(SCH_1):IND_SOC_P0_CPL3    I53 @T6G_MB_LIB.T6G(SCH_1):PAGE173
     3 IND_SOC_P0_CPL2 @T6G_MB_LIB.T6G(SCH_1):IND_SOC_P0_CPL2    I53 @T6G_MB_LIB.T6G(SCH_1):PAGE173
     4 PVDDCR_SOC_P0 @T6G_MB_LIB.T6G(SCH_1):PVDDCR_SOC_P0    I53 @T6G_MB_LIB.T6G(SCH_1):PAGE173
     1 SW_PVDDCR_SOC_P0_SW2 @T6G_MB_LIB.T6G(SCH_1):SW_PVDDCR_SOC_P0_SW2    I53 @T6G_MB_LIB.T6G(SCH_1):PAGE173

PL65 Q_INDUCTOR_SMLF-50NH/86A,IND,CVA50^0MZ09
     2 P12V_AUX @T6G_MB_LIB.T6G(SCH_1):P12V_AUX    I74 @T6G_MB_LIB.T6G(SCH_1):PAGE173
     1 SW_P12V_AUX_PVDDCR_SOC_P0_FLT @T6G_MB_LIB.T6G(SCH_1):SW_P12V_AUX_PVDDCR_SOC_P0_FLT    I74 @T6G_MB_LIB.T6G(SCH_1):PAGE173

PL66 Q_INDUCTOR4P_14-150NH,SMLF,IND,CV+15^0TZ04
     2 IND_SOC_P0_CPL0 @T6G_MB_LIB.T6G(SCH_1):IND_SOC_P0_CPL0    I25 @T6G_MB_LIB.T6G(SCH_1):PAGE174
     3 IND_SOC_P0_CPL3 @T6G_MB_LIB.T6G(SCH_1):IND_SOC_P0_CPL3    I25 @T6G_MB_LIB.T6G(SCH_1):PAGE174
     4 PVDDCR_SOC_P0 @T6G_MB_LIB.T6G(SCH_1):PVDDCR_SOC_P0    I25 @T6G_MB_LIB.T6G(SCH_1):PAGE174
     1 SW_PVDDCR_SOC_P0_SW3 @T6G_MB_LIB.T6G(SCH_1):SW_PVDDCR_SOC_P0_SW3    I25 @T6G_MB_LIB.T6G(SCH_1):PAGE174

PL67 Q_INDUCTOR4P_14-150NH,SMLF,IND,CV+15^0TZ04
     2 IND_PVDDIO_P1_CPL0 @T6G_MB_LIB.T6G(SCH_1):IND_PVDDIO_P1_CPL0    I42 @T6G_MB_LIB.T6G(SCH_1):PAGE198
     3 IND_PVDDIO_P1_CPL4 @T6G_MB_LIB.T6G(SCH_1):IND_PVDDIO_P1_CPL4    I42 @T6G_MB_LIB.T6G(SCH_1):PAGE198
     4 PVDDIO_P1 @T6G_MB_LIB.T6G(SCH_1):PVDDIO_P1    I42 @T6G_MB_LIB.T6G(SCH_1):PAGE198
     1 SW_PVDDIO_P1_SW4 @T6G_MB_LIB.T6G(SCH_1):SW_PVDDIO_P1_SW4    I42 @T6G_MB_LIB.T6G(SCH_1):PAGE198

PL68 Q_INDUCTOR4P_14-150NH,SMLF,IND,CV+15^0TZ04
     2 IND_PVDDIO_P1_CPL4 @T6G_MB_LIB.T6G(SCH_1):IND_PVDDIO_P1_CPL4    I62 @T6G_MB_LIB.T6G(SCH_1):PAGE198
     3 IND_PVDDIO_P1_CPL3 @T6G_MB_LIB.T6G(SCH_1):IND_PVDDIO_P1_CPL3    I62 @T6G_MB_LIB.T6G(SCH_1):PAGE198
     4 PVDDIO_P1 @T6G_MB_LIB.T6G(SCH_1):PVDDIO_P1    I62 @T6G_MB_LIB.T6G(SCH_1):PAGE198
     1 SW_PVDDIO_P1_SW3 @T6G_MB_LIB.T6G(SCH_1):SW_PVDDIO_P1_SW3    I62 @T6G_MB_LIB.T6G(SCH_1):PAGE198

PL69 Q_INDUCTOR4P_14-150NH,SMLF,IND,CV+15^0TZ04
     2 IND_CPU1_P1_CPL0 @T6G_MB_LIB.T6G(SCH_1):IND_CPU1_P1_CPL0    I50 @T6G_MB_LIB.T6G(SCH_1):PAGE195
     3 IND_CPU1_P1_CPL6 @T6G_MB_LIB.T6G(SCH_1):IND_CPU1_P1_CPL6    I50 @T6G_MB_LIB.T6G(SCH_1):PAGE195
     4 PVDDCR_CPU1_P1 @T6G_MB_LIB.T6G(SCH_1):PVDDCR_CPU1_P1    I50 @T6G_MB_LIB.T6G(SCH_1):PAGE195
     1 SW_PVDDCR_CPU1_P1_SW6 @T6G_MB_LIB.T6G(SCH_1):SW_PVDDCR_CPU1_P1_SW6    I50 @T6G_MB_LIB.T6G(SCH_1):PAGE195

PL70 Q_INDUCTOR4P_14-150NH,SMLF,IND,CV+15^0TZ04
     2 IND_CPU0_P0_CPL0 @T6G_MB_LIB.T6G(SCH_1):IND_CPU0_P0_CPL0    I52 @T6G_MB_LIB.T6G(SCH_1):PAGE171
     3 IND_CPU0_P0_CPL6 @T6G_MB_LIB.T6G(SCH_1):IND_CPU0_P0_CPL6    I52 @T6G_MB_LIB.T6G(SCH_1):PAGE171
     4 PVDDCR_CPU0_P0 @T6G_MB_LIB.T6G(SCH_1):PVDDCR_CPU0_P0    I52 @T6G_MB_LIB.T6G(SCH_1):PAGE171
     1 SW_PVDDCR_CPU0_P0_SW6 @T6G_MB_LIB.T6G(SCH_1):SW_PVDDCR_CPU0_P0_SW6    I52 @T6G_MB_LIB.T6G(SCH_1):PAGE171

PL71 Q_INDUCTOR_SMLF-BLM18SN220TN1D/8000MA,IND,CX220TN1A
     2 SW_P12V_AUX_PVDD_33_S5_FLT @T6G_MB_LIB.T6G(SCH_1):SW_P12V_AUX_PVDD_33_S5_FLT    I10 @T6G_MB_LIB.T6G(SCH_1):PAGE167
     1 P12V_AUX @T6G_MB_LIB.T6G(SCH_1):P12V_AUX    I10 @T6G_MB_LIB.T6G(SCH_1):PAGE167

PL72 Q_INDUCTOR_SMLF-1.5UH,IND,CV-15I0MZ28
     2 PVDD_33_S5 @T6G_MB_LIB.T6G(SCH_1):PVDD_33_S5    I47 @T6G_MB_LIB.T6G(SCH_1):PAGE167
     1 SW_PVDD_33_S5_SW @T6G_MB_LIB.T6G(SCH_1):SW_PVDD_33_S5_SW    I47 @T6G_MB_LIB.T6G(SCH_1):PAGE167

PL77 Q_INDUCTOR_SMLF-BLM18SN220TN1D/8000MA,IND,CX220TN1A
     2 SW_P12V_AUX_PVDD18_S5_P0_FLT @T6G_MB_LIB.T6G(SCH_1):SW_P12V_AUX_PVDD18_S5_P0_FLT     I7 @T6G_MB_LIB.T6G(SCH_1):PAGE184
     1 P12V_AUX @T6G_MB_LIB.T6G(SCH_1):P12V_AUX     I7 @T6G_MB_LIB.T6G(SCH_1):PAGE184

PL78 Q_INDUCTOR_SMLF-1.0UH/18A,IND,CV-10I0MZ01
     2 PVDD18_S5_P0 @T6G_MB_LIB.T6G(SCH_1):PVDD18_S5_P0    I36 @T6G_MB_LIB.T6G(SCH_1):PAGE184
     1 SW_PVDD18_S5_P0_SW @T6G_MB_LIB.T6G(SCH_1):SW_PVDD18_S5_P0_SW    I36 @T6G_MB_LIB.T6G(SCH_1):PAGE184

PL6000 Q_INDUCTOR_SMLF-3.3UH/6A,IND,CV-3360MZ07
     2 P1V8_AUX @T6G_MB_LIB.T6G(SCH_1):P1V8_AUX    I25 @T6G_MB_LIB.T6G(SCH_1):PAGE315
     1 SW_P1V8_AUX_PH @T6G_MB_LIB.T6G(SCH_1):SW_P1V8_AUX_PH    I25 @T6G_MB_LIB.T6G(SCH_1):PAGE315

PL6001 Q_INDUCTOR_SMLF-2.2UH,IND,CV-2280MZ15
     2 P1V2_AUX @T6G_MB_LIB.T6G(SCH_1):P1V2_AUX    I24 @T6G_MB_LIB.T6G(SCH_1):PAGE380
     1 SW_P1V2_AUX_PH @T6G_MB_LIB.T6G(SCH_1):SW_P1V2_AUX_PH    I24 @T6G_MB_LIB.T6G(SCH_1):PAGE380

PL6002 Q_INDUCTOR_SMLF-BLM18SN220TN1D/8000MA,IND,CX220TN1A
     2 SW_P12V_AUX_P1V8_AUX_FLT @T6G_MB_LIB.T6G(SCH_1):SW_P12V_AUX_P1V8_AUX_FLT     I7 @T6G_MB_LIB.T6G(SCH_1):PAGE315
     1 P12V_AUX @T6G_MB_LIB.T6G(SCH_1):P12V_AUX     I7 @T6G_MB_LIB.T6G(SCH_1):PAGE315

PL6003 Q_INDUCTOR_SMLF-BLM18SN220TN1D/8000MA,IND,CX220TN1A
     2 SW_P12V_AUX_P1V2_AUX_FLT @T6G_MB_LIB.T6G(SCH_1):SW_P12V_AUX_P1V2_AUX_FLT     I2 @T6G_MB_LIB.T6G(SCH_1):PAGE380
     1 P12V_AUX @T6G_MB_LIB.T6G(SCH_1):P12V_AUX     I2 @T6G_MB_LIB.T6G(SCH_1):PAGE380

PL6500 Q_INDUCTOR_SMLF-100NH/16A,IND,CV+10G0MZ04
     2 SW_P12V_AUX_P1V8_RETIMER_CPU0_FLT @T6G_MB_LIB.T6G(SCH_1):SW_P12V_AUX_P1V8_RETIMER_CPU0_FLT     I9 @T6G_MB_LIB.T6G(SCH_1):PAGE469
     1 P12V_AUX @T6G_MB_LIB.T6G(SCH_1):P12V_AUX     I9 @T6G_MB_LIB.T6G(SCH_1):PAGE469

PL6501 Q_INDUCTOR_SMLF-1UH,IND,CV-10U0MZ01
     2 P1V8_CPU0_RT_1D @T6G_MB_LIB.T6G(SCH_1):P1V8_CPU0_RT_1D    I36 @T6G_MB_LIB.T6G(SCH_1):PAGE469
     1 SW_P1V8_RETIMER_CPU0_SW @T6G_MB_LIB.T6G(SCH_1):SW_P1V8_RETIMER_CPU0_SW    I36 @T6G_MB_LIB.T6G(SCH_1):PAGE469

PL6502 Q_INDUCTOR_SMLF-1UH,IND,CV-10U0MZ01
     2 P1V8_CPU1_RT_1D @T6G_MB_LIB.T6G(SCH_1):P1V8_CPU1_RT_1D    I37 @T6G_MB_LIB.T6G(SCH_1):PAGE470
     1 SW_P1V8_RETIMER_CPU1_SW @T6G_MB_LIB.T6G(SCH_1):SW_P1V8_RETIMER_CPU1_SW    I37 @T6G_MB_LIB.T6G(SCH_1):PAGE470

PL6503 Q_INDUCTOR_SMLF-100NH/16A,IND,CV+10G0MZ04
     2 SW_P12V_AUX_P1V8_RETIMER_CPU1_FLT @T6G_MB_LIB.T6G(SCH_1):SW_P12V_AUX_P1V8_RETIMER_CPU1_FLT     I9 @T6G_MB_LIB.T6G(SCH_1):PAGE470
     1 P12V_AUX @T6G_MB_LIB.T6G(SCH_1):P12V_AUX     I9 @T6G_MB_LIB.T6G(SCH_1):PAGE470

PL6504 Q_INDUCTOR_SMLF-100NH/16A,IND,CV+10G0MZ04
     2 P12V_AUX @T6G_MB_LIB.T6G(SCH_1):P12V_AUX   I182 @T6G_MB_LIB.T6G(SCH_1):PAGE476
     1 SW_P12V_AUX_P0V9_RETIMER_CPU0_FLT @T6G_MB_LIB.T6G(SCH_1):SW_P12V_AUX_P0V9_RETIMER_CPU0_FLT   I182 @T6G_MB_LIB.T6G(SCH_1):PAGE476

PL6505 Q_INDUCTOR_SMLF-120NH/69A,IND,CV+12^0EZ03
     2 P0V9_CPU0_RT_2D @T6G_MB_LIB.T6G(SCH_1):P0V9_CPU0_RT_2D    I34 @T6G_MB_LIB.T6G(SCH_1):PAGE476
     1 SW_P0V9_RETIMER_CPU0_SW1 @T6G_MB_LIB.T6G(SCH_1):SW_P0V9_RETIMER_CPU0_SW1    I34 @T6G_MB_LIB.T6G(SCH_1):PAGE476

PL6506 Q_INDUCTOR_SMLF-120NH/69A,IND,CV+12^0EZ03
     2 P0V9_CPU0_RT_2D @T6G_MB_LIB.T6G(SCH_1):P0V9_CPU0_RT_2D   I257 @T6G_MB_LIB.T6G(SCH_1):PAGE476
     1 SW_P0V9_RETIMER_CPU0_SW2 @T6G_MB_LIB.T6G(SCH_1):SW_P0V9_RETIMER_CPU0_SW2   I257 @T6G_MB_LIB.T6G(SCH_1):PAGE476

PL6510 Q_INDUCTOR_SMLF-100NH/16A,IND,CV+10G0MZ04
     2 P12V_AUX @T6G_MB_LIB.T6G(SCH_1):P12V_AUX   I104 @T6G_MB_LIB.T6G(SCH_1):PAGE478
     1 SW_P12V_AUX_P0V9_RETIMER_CPU1_FLT @T6G_MB_LIB.T6G(SCH_1):SW_P12V_AUX_P0V9_RETIMER_CPU1_FLT   I104 @T6G_MB_LIB.T6G(SCH_1):PAGE478

PL6511 Q_INDUCTOR_SMLF-120NH/69A,IND,CV+12^0EZ03
     2 P0V9_CPU1_RT_2D @T6G_MB_LIB.T6G(SCH_1):P0V9_CPU1_RT_2D    I65 @T6G_MB_LIB.T6G(SCH_1):PAGE478
     1 SW_P0V9_RETIMER_CPU1_SW1 @T6G_MB_LIB.T6G(SCH_1):SW_P0V9_RETIMER_CPU1_SW1    I65 @T6G_MB_LIB.T6G(SCH_1):PAGE478

PL6512 Q_INDUCTOR_SMLF-120NH/69A,IND,CV+12^0EZ03
     2 P0V9_CPU1_RT_2D @T6G_MB_LIB.T6G(SCH_1):P0V9_CPU1_RT_2D    I22 @T6G_MB_LIB.T6G(SCH_1):PAGE478
     1 SW_P0V9_RETIMER_CPU1_SW2 @T6G_MB_LIB.T6G(SCH_1):SW_P0V9_RETIMER_CPU1_SW2    I22 @T6G_MB_LIB.T6G(SCH_1):PAGE478

PL8045 Q_INDUCTOR_SMLF-100NH/16A,IND,CV+10G0MZ04
     2 SW_P3V3_AUX_FLT @T6G_MB_LIB.T6G(SCH_1):SW_P3V3_AUX_FLT    I24 @T6G_MB_LIB.T6G(SCH_1):PAGE245
     1 P12V_AUX @T6G_MB_LIB.T6G(SCH_1):P12V_AUX    I24 @T6G_MB_LIB.T6G(SCH_1):PAGE245

PL8064 Q_INDUCTOR_SMLF-BLM18SN220TN1D/8000MA,IND,CX220TN1A
     2 SW_P5V_AUX_FLT @T6G_MB_LIB.T6G(SCH_1):SW_P5V_AUX_FLT     I5 @T6G_MB_LIB.T6G(SCH_1):PAGE244
     1 P12V_AUX @T6G_MB_LIB.T6G(SCH_1):P12V_AUX     I5 @T6G_MB_LIB.T6G(SCH_1):PAGE244

PL8065 Q_INDUCTOR_SMLF-4.7UH,IND,CV-47A0MZ10
     2 P5V_AUX @T6G_MB_LIB.T6G(SCH_1):P5V_AUX    I28 @T6G_MB_LIB.T6G(SCH_1):PAGE244
     1 SW_P5V_AUX_SW @T6G_MB_LIB.T6G(SCH_1):SW_P5V_AUX_SW    I28 @T6G_MB_LIB.T6G(SCH_1):PAGE244

PL8066 Q_INDUCTOR_SMLF-1.5UH/53A,IND,CV-15^0MZ02
     2 P3V3_AUX @T6G_MB_LIB.T6G(SCH_1):P3V3_AUX    I55 @T6G_MB_LIB.T6G(SCH_1):PAGE245
     1 SW_P3V3_AUX_SW @T6G_MB_LIB.T6G(SCH_1):SW_P3V3_AUX_SW    I55 @T6G_MB_LIB.T6G(SCH_1):PAGE245

PPQ1 MOSFET_NCH_1D3S-PSMNR58-30YLH,SMLF,IC,BAMNR580000
     3 P12V_AUX @T6G_MB_LIB.T6G(SCH_1):P12V_AUX    I61 @T6G_MB_LIB.T6G(SCH_1):PAGE302
     5 P12V_MAIN_R @T6G_MB_LIB.T6G(SCH_1):P12V_MAIN_R    I61 @T6G_MB_LIB.T6G(SCH_1):PAGE302
     2 P12V_AUX @T6G_MB_LIB.T6G(SCH_1):P12V_AUX    I61 @T6G_MB_LIB.T6G(SCH_1):PAGE302
     4 P12V_HSC_GATE_G5 @T6G_MB_LIB.T6G(SCH_1):P12V_HSC_GATE_G5    I61 @T6G_MB_LIB.T6G(SCH_1):PAGE302
     1 P12V_AUX @T6G_MB_LIB.T6G(SCH_1):P12V_AUX    I61 @T6G_MB_LIB.T6G(SCH_1):PAGE302

PPQ2 MOSFET_NCH_1D3S-PSMNR58-30YLH,SMLF,IC,BAMNR580000
     3 P12V_AUX @T6G_MB_LIB.T6G(SCH_1):P12V_AUX    I64 @T6G_MB_LIB.T6G(SCH_1):PAGE302
     5 P12V_MAIN_R @T6G_MB_LIB.T6G(SCH_1):P12V_MAIN_R    I64 @T6G_MB_LIB.T6G(SCH_1):PAGE302
     2 P12V_AUX @T6G_MB_LIB.T6G(SCH_1):P12V_AUX    I64 @T6G_MB_LIB.T6G(SCH_1):PAGE302
     4 P12V_HSC_GATE_G6 @T6G_MB_LIB.T6G(SCH_1):P12V_HSC_GATE_G6    I64 @T6G_MB_LIB.T6G(SCH_1):PAGE302
     1 P12V_AUX @T6G_MB_LIB.T6G(SCH_1):P12V_AUX    I64 @T6G_MB_LIB.T6G(SCH_1):PAGE302

PPQ5 MOSFET_NCH_1D3S-PSMNR58-30YLH,SMLF,IC,BAMNR580000
     3 P12V_AUX @T6G_MB_LIB.T6G(SCH_1):P12V_AUX    I29 @T6G_MB_LIB.T6G(SCH_1):PAGE302
     5 P12V_MAIN_R @T6G_MB_LIB.T6G(SCH_1):P12V_MAIN_R    I29 @T6G_MB_LIB.T6G(SCH_1):PAGE302
     2 P12V_AUX @T6G_MB_LIB.T6G(SCH_1):P12V_AUX    I29 @T6G_MB_LIB.T6G(SCH_1):PAGE302
     4 P12V_HSC_GATE_G1 @T6G_MB_LIB.T6G(SCH_1):P12V_HSC_GATE_G1    I29 @T6G_MB_LIB.T6G(SCH_1):PAGE302
     1 P12V_AUX @T6G_MB_LIB.T6G(SCH_1):P12V_AUX    I29 @T6G_MB_LIB.T6G(SCH_1):PAGE302

PPQ6 MOSFET_NCH_1D3S-PSMNR58-30YLH,SMLF,IC,BAMNR580000
     3 P12V_AUX @T6G_MB_LIB.T6G(SCH_1):P12V_AUX    I46 @T6G_MB_LIB.T6G(SCH_1):PAGE302
     5 P12V_MAIN_R @T6G_MB_LIB.T6G(SCH_1):P12V_MAIN_R    I46 @T6G_MB_LIB.T6G(SCH_1):PAGE302
     2 P12V_AUX @T6G_MB_LIB.T6G(SCH_1):P12V_AUX    I46 @T6G_MB_LIB.T6G(SCH_1):PAGE302
     4 P12V_HSC_GATE_G2 @T6G_MB_LIB.T6G(SCH_1):P12V_HSC_GATE_G2    I46 @T6G_MB_LIB.T6G(SCH_1):PAGE302
     1 P12V_AUX @T6G_MB_LIB.T6G(SCH_1):P12V_AUX    I46 @T6G_MB_LIB.T6G(SCH_1):PAGE302

PPQ7 MOSFET_NCH_1D3S-PSMNR58-30YLH,SMLF,IC,BAMNR580000
     3 P12V_AUX @T6G_MB_LIB.T6G(SCH_1):P12V_AUX    I80 @T6G_MB_LIB.T6G(SCH_1):PAGE302
     5 P12V_MAIN_R @T6G_MB_LIB.T6G(SCH_1):P12V_MAIN_R    I80 @T6G_MB_LIB.T6G(SCH_1):PAGE302
     2 P12V_AUX @T6G_MB_LIB.T6G(SCH_1):P12V_AUX    I80 @T6G_MB_LIB.T6G(SCH_1):PAGE302
     4 P12V_HSC_GATE_G3 @T6G_MB_LIB.T6G(SCH_1):P12V_HSC_GATE_G3    I80 @T6G_MB_LIB.T6G(SCH_1):PAGE302
     1 P12V_AUX @T6G_MB_LIB.T6G(SCH_1):P12V_AUX    I80 @T6G_MB_LIB.T6G(SCH_1):PAGE302

PPQ8 MOSFET_NCH_1D3S-PSMNR58-30YLH,SMLF,IC,BAMNR580000
     3 P12V_AUX @T6G_MB_LIB.T6G(SCH_1):P12V_AUX    I79 @T6G_MB_LIB.T6G(SCH_1):PAGE302
     5 P12V_MAIN_R @T6G_MB_LIB.T6G(SCH_1):P12V_MAIN_R    I79 @T6G_MB_LIB.T6G(SCH_1):PAGE302
     2 P12V_AUX @T6G_MB_LIB.T6G(SCH_1):P12V_AUX    I79 @T6G_MB_LIB.T6G(SCH_1):PAGE302
     4 P12V_HSC_GATE_G4 @T6G_MB_LIB.T6G(SCH_1):P12V_HSC_GATE_G4    I79 @T6G_MB_LIB.T6G(SCH_1):PAGE302
     1 P12V_AUX @T6G_MB_LIB.T6G(SCH_1):P12V_AUX    I79 @T6G_MB_LIB.T6G(SCH_1):PAGE302

PPQ9 MOSFET_NCH_1D3S-PSMNR58-30YLH,SMLF,IC,BAMNR580000
     3 P12V_AUX @T6G_MB_LIB.T6G(SCH_1):P12V_AUX    I75 @T6G_MB_LIB.T6G(SCH_1):PAGE302
     5 P12V_MAIN_R_0 @T6G_MB_LIB.T6G(SCH_1):P12V_MAIN_R_0    I75 @T6G_MB_LIB.T6G(SCH_1):PAGE302
     2 P12V_AUX @T6G_MB_LIB.T6G(SCH_1):P12V_AUX    I75 @T6G_MB_LIB.T6G(SCH_1):PAGE302
     4 MB0_CM_GATE_G0 @T6G_MB_LIB.T6G(SCH_1):MB0_CM_GATE_G0    I75 @T6G_MB_LIB.T6G(SCH_1):PAGE302
     1 P12V_AUX @T6G_MB_LIB.T6G(SCH_1):P12V_AUX    I75 @T6G_MB_LIB.T6G(SCH_1):PAGE302

PQ10 MOSFET_PCH_GDS_ESD_PROTECTED-PJA3415AE,SMLF,IC,BAMA
     D PVDDCR_CPU1_P0_EN1_ADDR_CFG @T6G_MB_LIB.T6G(SCH_1):PVDDCR_CPU1_P0_EN1_ADDR_CFG    I13 @T6G_MB_LIB.T6G(SCH_1):PAGE175
     G PVDDIO_P0_EN_G @T6G_MB_LIB.T6G(SCH_1):PVDDIO_P0_EN_G    I13 @T6G_MB_LIB.T6G(SCH_1):PAGE175
     S P3V3_AUX @T6G_MB_LIB.T6G(SCH_1):P3V3_AUX    I13 @T6G_MB_LIB.T6G(SCH_1):PAGE175

PQ11 MOSFET_PCH_GDS_ESD_PROTECTED-PJA3415AE,SMLF,IC,BAMA
     D PVDDCR_SOC_P1_EN//ADDR_CFG @T6G_MB_LIB.T6G(SCH_1):PVDDCR_SOC_P1_EN//ADDR_CFG    I18 @T6G_MB_LIB.T6G(SCH_1):PAGE185
     G PVDDCR_SOC_P1_EN_GD @T6G_MB_LIB.T6G(SCH_1):PVDDCR_SOC_P1_EN_GD    I18 @T6G_MB_LIB.T6G(SCH_1):PAGE185
     S P3V3_AUX @T6G_MB_LIB.T6G(SCH_1):P3V3_AUX    I18 @T6G_MB_LIB.T6G(SCH_1):PAGE185

PQ12 MOSFET_PCH_GDS_ESD_PROTECTED-PJA3415AE,SMLF,IC,BAMA
     D PVDDCR_CPU1_P1_EN1_ADDR_CFG @T6G_MB_LIB.T6G(SCH_1):PVDDCR_CPU1_P1_EN1_ADDR_CFG    I13 @T6G_MB_LIB.T6G(SCH_1):PAGE192
     G PVDDIO_P1_EN_G @T6G_MB_LIB.T6G(SCH_1):PVDDIO_P1_EN_G    I13 @T6G_MB_LIB.T6G(SCH_1):PAGE192
     S P3V3_AUX @T6G_MB_LIB.T6G(SCH_1):P3V3_AUX    I13 @T6G_MB_LIB.T6G(SCH_1):PAGE192

PQ13 MOSFET_PCH_GDS_ESD_PROTECTED-PJA3415AE,SMLF,IC,BAMA
     D PVDDCR_SOC_P0_EN//ADDR_CFG @T6G_MB_LIB.T6G(SCH_1):PVDDCR_SOC_P0_EN//ADDR_CFG    I19 @T6G_MB_LIB.T6G(SCH_1):PAGE168
     G PVDDCR_SOC_P0_EN_GD @T6G_MB_LIB.T6G(SCH_1):PVDDCR_SOC_P0_EN_GD    I19 @T6G_MB_LIB.T6G(SCH_1):PAGE168
     S P3V3_AUX @T6G_MB_LIB.T6G(SCH_1):P3V3_AUX    I19 @T6G_MB_LIB.T6G(SCH_1):PAGE168

PQ14 MOSFET_N_SMLF-BSS138K,BSS138K,IC,BAM138K0000
     G PVDDIO_P0_EN_R @T6G_MB_LIB.T6G(SCH_1):PVDDIO_P0_EN_R     I6 @T6G_MB_LIB.T6G(SCH_1):PAGE175
     D PVDDIO_P0_EN_G @T6G_MB_LIB.T6G(SCH_1):PVDDIO_P0_EN_G     I6 @T6G_MB_LIB.T6G(SCH_1):PAGE175
     S    GND @T6G_MB_LIB.T6G(SCH_1):GND     I6 @T6G_MB_LIB.T6G(SCH_1):PAGE175

PQ15 MOSFET_N_SMLF-BSS138K,BSS138K,IC,BAM138K0000
     G PVDDCR_SOC_P1_EN_RC @T6G_MB_LIB.T6G(SCH_1):PVDDCR_SOC_P1_EN_RC    I16 @T6G_MB_LIB.T6G(SCH_1):PAGE185
     D PVDDCR_SOC_P1_EN_GD @T6G_MB_LIB.T6G(SCH_1):PVDDCR_SOC_P1_EN_GD    I16 @T6G_MB_LIB.T6G(SCH_1):PAGE185
     S    GND @T6G_MB_LIB.T6G(SCH_1):GND    I16 @T6G_MB_LIB.T6G(SCH_1):PAGE185

PQ16 MOSFET_N_SMLF-BSS138K,BSS138K,IC,BAM138K0000
     G PVDDIO_P1_EN_R @T6G_MB_LIB.T6G(SCH_1):PVDDIO_P1_EN_R     I6 @T6G_MB_LIB.T6G(SCH_1):PAGE192
     D PVDDIO_P1_EN_G @T6G_MB_LIB.T6G(SCH_1):PVDDIO_P1_EN_G     I6 @T6G_MB_LIB.T6G(SCH_1):PAGE192
     S    GND @T6G_MB_LIB.T6G(SCH_1):GND     I6 @T6G_MB_LIB.T6G(SCH_1):PAGE192

PQ17 MOSFET_N_SMLF-BSS138K,BSS138K,IC,BAM138K0000
     G PVDDCR_SOC_P0_EN_RC @T6G_MB_LIB.T6G(SCH_1):PVDDCR_SOC_P0_EN_RC    I17 @T6G_MB_LIB.T6G(SCH_1):PAGE168
     D PVDDCR_SOC_P0_EN_GD @T6G_MB_LIB.T6G(SCH_1):PVDDCR_SOC_P0_EN_GD    I17 @T6G_MB_LIB.T6G(SCH_1):PAGE168
     S    GND @T6G_MB_LIB.T6G(SCH_1):GND    I17 @T6G_MB_LIB.T6G(SCH_1):PAGE168

 PR3 Q_RES_0402LF-10K,1%,1/16W,CHIP,CS31002FB08
     1 PVDD11_S3_P0_VMON @T6G_MB_LIB.T6G(SCH_1):PVDD11_S3_P0_VMON     I6 @T6G_MB_LIB.T6G(SCH_1):PAGE182
     2    GND @T6G_MB_LIB.T6G(SCH_1):GND     I6 @T6G_MB_LIB.T6G(SCH_1):PAGE182

 PR4 Q_RES_0402LF-10K,1%,1/16W,CHIP,CS31002FB08
     1 PVDDCR_CPU0_P1_VMON @T6G_MB_LIB.T6G(SCH_1):PVDDCR_CPU0_P1_VMON    I20 @T6G_MB_LIB.T6G(SCH_1):PAGE185
     2    GND @T6G_MB_LIB.T6G(SCH_1):GND    I20 @T6G_MB_LIB.T6G(SCH_1):PAGE185

 PR5 Q_RES_0402LF-10K,1%,1/16W,CHIP,CS31002FB08
     1 PVDDCR_CPU0_P0_VMON @T6G_MB_LIB.T6G(SCH_1):PVDDCR_CPU0_P0_VMON    I21 @T6G_MB_LIB.T6G(SCH_1):PAGE168
     2    GND @T6G_MB_LIB.T6G(SCH_1):GND    I21 @T6G_MB_LIB.T6G(SCH_1):PAGE168

 PR6 Q_RES_0402LF-10K,1%,1/16W,CHIP,CS31002FB08
     1 PVDD11_S3_P1_VMON @T6G_MB_LIB.T6G(SCH_1):PVDD11_S3_P1_VMON     I6 @T6G_MB_LIB.T6G(SCH_1):PAGE199
     2    GND @T6G_MB_LIB.T6G(SCH_1):GND     I6 @T6G_MB_LIB.T6G(SCH_1):PAGE199

 PR7 Q_RES_0402LF-8.87K,1%,1/16W,EMPTY,CS28872FB01
     1 PVDDCR_CPU1_P0_LSET6 @T6G_MB_LIB.T6G(SCH_1):PVDDCR_CPU1_P0_LSET6     I4 @T6G_MB_LIB.T6G(SCH_1):PAGE178
     2    GND @T6G_MB_LIB.T6G(SCH_1):GND     I4 @T6G_MB_LIB.T6G(SCH_1):PAGE178

 PR8 Q_RES_0402LF-8.66K,1%,1/16W,CHIP,CS28662FB02
     1 PVDD18_S5_P1_CS @T6G_MB_LIB.T6G(SCH_1):PVDD18_S5_P1_CS    I11 @T6G_MB_LIB.T6G(SCH_1):PAGE201
     2    GND @T6G_MB_LIB.T6G(SCH_1):GND    I11 @T6G_MB_LIB.T6G(SCH_1):PAGE201

PR12 Q_RES_0402LF-0,5%,1/16W,CHIP,CS00002JB13
     1 NC_PVDDCR_CPU1_P1_IMON8 @T6G_MB_LIB.T6G(SCH_1):NC_PVDDCR_CPU1_P1_IMON8   I127 @T6G_MB_LIB.T6G(SCH_1):PAGE192
     2    GND @T6G_MB_LIB.T6G(SCH_1):GND   I127 @T6G_MB_LIB.T6G(SCH_1):PAGE192

PR13 Q_RES_0402LF-0,5%,1/16W,CHIP,CS00002JB13
     1 NC_PVDD11_S3_P1_IMON5 @T6G_MB_LIB.T6G(SCH_1):NC_PVDD11_S3_P1_IMON5    I59 @T6G_MB_LIB.T6G(SCH_1):PAGE199
     2    GND @T6G_MB_LIB.T6G(SCH_1):GND    I59 @T6G_MB_LIB.T6G(SCH_1):PAGE199

PR14 Q_RES_0402LF-0,5%,1/16W,CHIP,CS00002JB13
     1 NC_PVDD11_S3_P1_IMON6 @T6G_MB_LIB.T6G(SCH_1):NC_PVDD11_S3_P1_IMON6    I58 @T6G_MB_LIB.T6G(SCH_1):PAGE199
     2    GND @T6G_MB_LIB.T6G(SCH_1):GND    I58 @T6G_MB_LIB.T6G(SCH_1):PAGE199

PR32 Q_RES_0402LF-0,5%,1/16W,CHIP,CS00002JB13
     1 NC_PVDDCR_CPU1_P0_IMON8 @T6G_MB_LIB.T6G(SCH_1):NC_PVDDCR_CPU1_P0_IMON8    I77 @T6G_MB_LIB.T6G(SCH_1):PAGE175
     2    GND @T6G_MB_LIB.T6G(SCH_1):GND    I77 @T6G_MB_LIB.T6G(SCH_1):PAGE175

PR33 Q_RES_0402LF-0,5%,1/16W,CHIP,CS00002JB13
     1 NC_PVDD11_S3_P0_IMON4 @T6G_MB_LIB.T6G(SCH_1):NC_PVDD11_S3_P0_IMON4    I61 @T6G_MB_LIB.T6G(SCH_1):PAGE182
     2    GND @T6G_MB_LIB.T6G(SCH_1):GND    I61 @T6G_MB_LIB.T6G(SCH_1):PAGE182

PR34 Q_RES_0402LF-0,5%,1/16W,CHIP,CS00002JB13
     1 NC_PVDD11_S3_P0_IMON5 @T6G_MB_LIB.T6G(SCH_1):NC_PVDD11_S3_P0_IMON5    I60 @T6G_MB_LIB.T6G(SCH_1):PAGE182
     2    GND @T6G_MB_LIB.T6G(SCH_1):GND    I60 @T6G_MB_LIB.T6G(SCH_1):PAGE182

PR35 Q_RES_0402LF-0,5%,1/16W,CHIP,CS00002JB13
     1 NC_PVDD11_S3_P0_IMON6 @T6G_MB_LIB.T6G(SCH_1):NC_PVDD11_S3_P0_IMON6    I59 @T6G_MB_LIB.T6G(SCH_1):PAGE182
     2    GND @T6G_MB_LIB.T6G(SCH_1):GND    I59 @T6G_MB_LIB.T6G(SCH_1):PAGE182

PR36 Q_RES_0402LF-0,5%,1/16W,CHIP,CS00002JB13
     1 NC_PVDD11_S3_P0_IMON8 @T6G_MB_LIB.T6G(SCH_1):NC_PVDD11_S3_P0_IMON8    I53 @T6G_MB_LIB.T6G(SCH_1):PAGE182
     2    GND @T6G_MB_LIB.T6G(SCH_1):GND    I53 @T6G_MB_LIB.T6G(SCH_1):PAGE182

PR37 Q_RES_0402LF-0,5%,1/16W,CHIP,CS00002JB13
     1 NC_PVDD11_S3_P0_IMON3 @T6G_MB_LIB.T6G(SCH_1):NC_PVDD11_S3_P0_IMON3    I71 @T6G_MB_LIB.T6G(SCH_1):PAGE182
     2    GND @T6G_MB_LIB.T6G(SCH_1):GND    I71 @T6G_MB_LIB.T6G(SCH_1):PAGE182

PR40 Q_RES_0402LF-0,5%,1/16W,CHIP,CS00002JB13
     1 SVID_PVDDCR_CPU1_P0_SVTI @T6G_MB_LIB.T6G(SCH_1):SVID_PVDDCR_CPU1_P0_SVTI    I28 @T6G_MB_LIB.T6G(SCH_1):PAGE175
     2    GND @T6G_MB_LIB.T6G(SCH_1):GND    I28 @T6G_MB_LIB.T6G(SCH_1):PAGE175

PR41 Q_RES_0402LF-1K,1%,1/16W,EMPTY,CS21002FB06
     1 PVDD18_S5_P0 @T6G_MB_LIB.T6G(SCH_1):PVDD18_S5_P0    I40 @T6G_MB_LIB.T6G(SCH_1):PAGE175
     2 SVID_PVDDCR_CPU1_P0_SVTI @T6G_MB_LIB.T6G(SCH_1):SVID_PVDDCR_CPU1_P0_SVTI    I40 @T6G_MB_LIB.T6G(SCH_1):PAGE175

PR46 Q_RES_0402LF-1.5,1%,1/8W,EMPTY,CS-1504FB00
     1 SW_PVDDCR_CPU0_P1_SW5_RC @T6G_MB_LIB.T6G(SCH_1):SW_PVDDCR_CPU0_P1_SW5_RC    I32 @T6G_MB_LIB.T6G(SCH_1):PAGE188
     2    GND @T6G_MB_LIB.T6G(SCH_1):GND    I32 @T6G_MB_LIB.T6G(SCH_1):PAGE188

PR49 Q_RES_0402LF-49.9,1%,1/16W,CHIP,CS04992FB07
     1 VSENSE_VSS_SENSE_C_P0 @T6G_MB_LIB.T6G(SCH_1):VSENSE_VSS_SENSE_C_P0    I23 @T6G_MB_LIB.T6G(SCH_1):PAGE175
     2    GND @T6G_MB_LIB.T6G(SCH_1):GND    I23 @T6G_MB_LIB.T6G(SCH_1):PAGE175

PR50 Q_RES_0402LF-49.9,1%,1/16W,CHIP,CS04992FB07
     1 VSENSE_VSS_SENSE_B_P0 @T6G_MB_LIB.T6G(SCH_1):VSENSE_VSS_SENSE_B_P0    I19 @T6G_MB_LIB.T6G(SCH_1):PAGE175
     2    GND @T6G_MB_LIB.T6G(SCH_1):GND    I19 @T6G_MB_LIB.T6G(SCH_1):PAGE175

PR51 Q_RES_0402LF-49.9,1%,1/16W,CHIP,CS04992FB07
     1 VSENSE_PVDDCR_CPU1_P0_DP @T6G_MB_LIB.T6G(SCH_1):VSENSE_PVDDCR_CPU1_P0_DP    I36 @T6G_MB_LIB.T6G(SCH_1):PAGE175
     2 PVDDCR_CPU1_P0 @T6G_MB_LIB.T6G(SCH_1):PVDDCR_CPU1_P0    I36 @T6G_MB_LIB.T6G(SCH_1):PAGE175

PR52 Q_RES_0402LF-49.9,1%,1/16W,CHIP,CS04992FB07
     1 VSENSE_PVDDIO_P0_DP @T6G_MB_LIB.T6G(SCH_1):VSENSE_PVDDIO_P0_DP    I22 @T6G_MB_LIB.T6G(SCH_1):PAGE175
     2 PVDDIO_P0 @T6G_MB_LIB.T6G(SCH_1):PVDDIO_P0    I22 @T6G_MB_LIB.T6G(SCH_1):PAGE175

PR53 Q_RES_0402LF-40.2K,1%,1/16W,CHIP,CS34022FB04
     1 P5V_AUX @T6G_MB_LIB.T6G(SCH_1):P5V_AUX     I9 @T6G_MB_LIB.T6G(SCH_1):PAGE175
     2 PVDDCR_CPU1_P0_VMON @T6G_MB_LIB.T6G(SCH_1):PVDDCR_CPU1_P0_VMON     I9 @T6G_MB_LIB.T6G(SCH_1):PAGE175

PR54 Q_RES_0402LF-10K,1%,1/16W,CHIP,CS31002FB08
     1 PVDDCR_CPU1_P0_VMON @T6G_MB_LIB.T6G(SCH_1):PVDDCR_CPU1_P0_VMON     I8 @T6G_MB_LIB.T6G(SCH_1):PAGE175
     2    GND @T6G_MB_LIB.T6G(SCH_1):GND     I8 @T6G_MB_LIB.T6G(SCH_1):PAGE175

PR55 Q_RES_0402LF-1K,1%,1/16W,CHIP,CS21002FB06
     1 P3V3_AUX @T6G_MB_LIB.T6G(SCH_1):P3V3_AUX    I17 @T6G_MB_LIB.T6G(SCH_1):PAGE175
     2 PVDDIO_P0_EN_G @T6G_MB_LIB.T6G(SCH_1):PVDDIO_P0_EN_G    I17 @T6G_MB_LIB.T6G(SCH_1):PAGE175

PR59 Q_RES_0402LF-0,5%,1/16W,CHIP,CS00002JB13
     1 SVID_PVDDCR_CPU1_P0_SVC_R @T6G_MB_LIB.T6G(SCH_1):SVID_PVDDCR_CPU1_P0_SVC_R   I318 @T6G_MB_LIB.T6G(SCH_1):PAGE27
     2 SVID_PVDDCR_CPU1_P0_SVC @T6G_MB_LIB.T6G(SCH_1):SVID_PVDDCR_CPU1_P0_SVC   I318 @T6G_MB_LIB.T6G(SCH_1):PAGE27

PR60 Q_RES_0402LF-0,5%,1/16W,CHIP,CS00002JB13
     1 SVID_PVDDCR_CPU1_P0_SVD_R @T6G_MB_LIB.T6G(SCH_1):SVID_PVDDCR_CPU1_P0_SVD_R   I319 @T6G_MB_LIB.T6G(SCH_1):PAGE27
     2 SVID_PVDDCR_CPU1_P0_SVD @T6G_MB_LIB.T6G(SCH_1):SVID_PVDDCR_CPU1_P0_SVD   I319 @T6G_MB_LIB.T6G(SCH_1):PAGE27

PR62 Q_RES_0402LF-0,5%,1/16W,CHIP,CS00002JB13
     1 SVID_PVDDCR_CPU1_P0_SVTI @T6G_MB_LIB.T6G(SCH_1):SVID_PVDDCR_CPU1_P0_SVTI    I84 @T6G_MB_LIB.T6G(SCH_1):PAGE175
     2 SVID_PVDDCR_CPU1_P0_SVTI_R @T6G_MB_LIB.T6G(SCH_1):SVID_PVDDCR_CPU1_P0_SVTI_R    I84 @T6G_MB_LIB.T6G(SCH_1):PAGE175

PR67 Q_RES_0402LF-1.96K,1%,1/16W,CHIP,CS21962FB05
     1 PVDDCR_CPU1_P0_EN1_ADDR_CFG @T6G_MB_LIB.T6G(SCH_1):PVDDCR_CPU1_P0_EN1_ADDR_CFG    I12 @T6G_MB_LIB.T6G(SCH_1):PAGE175
     2    GND @T6G_MB_LIB.T6G(SCH_1):GND    I12 @T6G_MB_LIB.T6G(SCH_1):PAGE175

PR68 Q_RES_0402LF-0,5%,1/16W,CHIP,CS00002JB13
     1 VSENSE_PVDDCR_CPU1_P0_DP @T6G_MB_LIB.T6G(SCH_1):VSENSE_PVDDCR_CPU1_P0_DP    I78 @T6G_MB_LIB.T6G(SCH_1):PAGE175
     2 VSENSE_PVDDCR_CPU1_P0_VSEN0 @T6G_MB_LIB.T6G(SCH_1):VSENSE_PVDDCR_CPU1_P0_VSEN0    I78 @T6G_MB_LIB.T6G(SCH_1):PAGE175

PR69 Q_RES_0402LF-0,5%,1/16W,CHIP,CS00002JB13
     1 VSENSE_PVDDIO_P0_DP @T6G_MB_LIB.T6G(SCH_1):VSENSE_PVDDIO_P0_DP    I70 @T6G_MB_LIB.T6G(SCH_1):PAGE175
     2 VSENSE_PVDDIO_P0_VSEN1 @T6G_MB_LIB.T6G(SCH_1):VSENSE_PVDDIO_P0_VSEN1    I70 @T6G_MB_LIB.T6G(SCH_1):PAGE175

PR74 Q_RES_0402LF-0,5%,1/16W,CHIP,CS00002JB13
     1 P12V_AUX @T6G_MB_LIB.T6G(SCH_1):P12V_AUX    I51 @T6G_MB_LIB.T6G(SCH_1):PAGE175
     2 PVDDCR_CPU1_P0_VINSEN @T6G_MB_LIB.T6G(SCH_1):PVDDCR_CPU1_P0_VINSEN    I51 @T6G_MB_LIB.T6G(SCH_1):PAGE175

PR76 Q_RES_0402LF-1,1%,1/16W,CHIP,CS-1002FB04
     1 PVDDCR_CPU1_P0_VCC @T6G_MB_LIB.T6G(SCH_1):PVDDCR_CPU1_P0_VCC   I126 @T6G_MB_LIB.T6G(SCH_1):PAGE175
     2 P3V3_AUX @T6G_MB_LIB.T6G(SCH_1):P3V3_AUX   I126 @T6G_MB_LIB.T6G(SCH_1):PAGE175

PR77 Q_RES_0402LF-8.87K,1%,1/16W,EMPTY,CS28872FB01
     1 PVDDCR_CPU1_P0_LSET2 @T6G_MB_LIB.T6G(SCH_1):PVDDCR_CPU1_P0_LSET2     I4 @T6G_MB_LIB.T6G(SCH_1):PAGE176
     2    GND @T6G_MB_LIB.T6G(SCH_1):GND     I4 @T6G_MB_LIB.T6G(SCH_1):PAGE176

PR78 Q_RES_0402LF-8.87K,1%,1/16W,EMPTY,CS28872FB01
     1 PVDDCR_CPU1_P0_LSET1 @T6G_MB_LIB.T6G(SCH_1):PVDDCR_CPU1_P0_LSET1    I18 @T6G_MB_LIB.T6G(SCH_1):PAGE176
     2    GND @T6G_MB_LIB.T6G(SCH_1):GND    I18 @T6G_MB_LIB.T6G(SCH_1):PAGE176

PR79 Q_RES_0402LF-2.2,1%,1/16W,CHIP,CS-2202FB01
     1 PVDDCR_CPU1_P0_PVCC @T6G_MB_LIB.T6G(SCH_1):PVDDCR_CPU1_P0_PVCC    I29 @T6G_MB_LIB.T6G(SCH_1):PAGE176
     2 PVDDCR_CPU1_P0_VCC1 @T6G_MB_LIB.T6G(SCH_1):PVDDCR_CPU1_P0_VCC1    I29 @T6G_MB_LIB.T6G(SCH_1):PAGE176

PR80 Q_RES_0402LF-2.2,1%,1/16W,CHIP,CS-2202FB01
     1 PVDDCR_CPU1_P0_PVCC @T6G_MB_LIB.T6G(SCH_1):PVDDCR_CPU1_P0_PVCC    I13 @T6G_MB_LIB.T6G(SCH_1):PAGE176
     2 PVDDCR_CPU1_P0_VCC2 @T6G_MB_LIB.T6G(SCH_1):PVDDCR_CPU1_P0_VCC2    I13 @T6G_MB_LIB.T6G(SCH_1):PAGE176

PR81 Q_RES_0402LF-5.6,1%,1/16W,CHIP,CS-5602FB01
     1 SW_PVDDCR_CPU1_P0_BOOT2 @T6G_MB_LIB.T6G(SCH_1):SW_PVDDCR_CPU1_P0_BOOT2    I40 @T6G_MB_LIB.T6G(SCH_1):PAGE176
     2 SW_PVDDCR_CPU1_P0_BOOT2_R @T6G_MB_LIB.T6G(SCH_1):SW_PVDDCR_CPU1_P0_BOOT2_R    I40 @T6G_MB_LIB.T6G(SCH_1):PAGE176

PR82 Q_RES_0402LF-5.6,1%,1/16W,CHIP,CS-5602FB01
     1 SW_PVDDCR_CPU1_P0_BOOT1 @T6G_MB_LIB.T6G(SCH_1):SW_PVDDCR_CPU1_P0_BOOT1    I56 @T6G_MB_LIB.T6G(SCH_1):PAGE176
     2 SW_PVDDCR_CPU1_P0_BOOT1_R @T6G_MB_LIB.T6G(SCH_1):SW_PVDDCR_CPU1_P0_BOOT1_R    I56 @T6G_MB_LIB.T6G(SCH_1):PAGE176

PR83 Q_RES_0402LF-0,5%,1/16W,CHIP,CS00002JB13
     1 PVDDCR_CPU1_P0_VOS2 @T6G_MB_LIB.T6G(SCH_1):PVDDCR_CPU1_P0_VOS2    I42 @T6G_MB_LIB.T6G(SCH_1):PAGE176
     2 PVDDCR_CPU1_P0 @T6G_MB_LIB.T6G(SCH_1):PVDDCR_CPU1_P0    I42 @T6G_MB_LIB.T6G(SCH_1):PAGE176

PR84 Q_RES_0402LF-0,5%,1/16W,CHIP,CS00002JB13
     1 PVDDCR_CPU1_P0_VOS1 @T6G_MB_LIB.T6G(SCH_1):PVDDCR_CPU1_P0_VOS1    I54 @T6G_MB_LIB.T6G(SCH_1):PAGE176
     2 PVDDCR_CPU1_P0 @T6G_MB_LIB.T6G(SCH_1):PVDDCR_CPU1_P0    I54 @T6G_MB_LIB.T6G(SCH_1):PAGE176

PR85 Q_RES_0402LF-8.87K,1%,1/16W,EMPTY,CS28872FB01
     1 PVDDCR_CPU1_P0_LSET4 @T6G_MB_LIB.T6G(SCH_1):PVDDCR_CPU1_P0_LSET4     I4 @T6G_MB_LIB.T6G(SCH_1):PAGE177
     2    GND @T6G_MB_LIB.T6G(SCH_1):GND     I4 @T6G_MB_LIB.T6G(SCH_1):PAGE177

PR86 Q_RES_0402LF-8.87K,1%,1/16W,EMPTY,CS28872FB01
     1 PVDDCR_CPU1_P0_LSET3 @T6G_MB_LIB.T6G(SCH_1):PVDDCR_CPU1_P0_LSET3    I18 @T6G_MB_LIB.T6G(SCH_1):PAGE177
     2    GND @T6G_MB_LIB.T6G(SCH_1):GND    I18 @T6G_MB_LIB.T6G(SCH_1):PAGE177

PR87 Q_RES_0402LF-2.2,1%,1/16W,CHIP,CS-2202FB01
     1 PVDDCR_CPU1_P0_PVCC @T6G_MB_LIB.T6G(SCH_1):PVDDCR_CPU1_P0_PVCC    I13 @T6G_MB_LIB.T6G(SCH_1):PAGE177
     2 PVDDCR_CPU1_P0_VCC4 @T6G_MB_LIB.T6G(SCH_1):PVDDCR_CPU1_P0_VCC4    I13 @T6G_MB_LIB.T6G(SCH_1):PAGE177

PR88 Q_RES_0402LF-2.2,1%,1/16W,CHIP,CS-2202FB01
     1 PVDDCR_CPU1_P0_PVCC @T6G_MB_LIB.T6G(SCH_1):PVDDCR_CPU1_P0_PVCC    I30 @T6G_MB_LIB.T6G(SCH_1):PAGE177
     2 PVDDCR_CPU1_P0_VCC3 @T6G_MB_LIB.T6G(SCH_1):PVDDCR_CPU1_P0_VCC3    I30 @T6G_MB_LIB.T6G(SCH_1):PAGE177

PR89 Q_RES_0402LF-5.6,1%,1/16W,CHIP,CS-5602FB01
     1 SW_PVDDCR_CPU1_P0_BOOT4 @T6G_MB_LIB.T6G(SCH_1):SW_PVDDCR_CPU1_P0_BOOT4    I37 @T6G_MB_LIB.T6G(SCH_1):PAGE177
     2 SW_PVDDCR_CPU1_P0_BOOT4_R @T6G_MB_LIB.T6G(SCH_1):SW_PVDDCR_CPU1_P0_BOOT4_R    I37 @T6G_MB_LIB.T6G(SCH_1):PAGE177

PR90 Q_RES_0402LF-5.6,1%,1/16W,CHIP,CS-5602FB01
     1 SW_PVDDCR_CPU1_P0_BOOT3 @T6G_MB_LIB.T6G(SCH_1):SW_PVDDCR_CPU1_P0_BOOT3    I57 @T6G_MB_LIB.T6G(SCH_1):PAGE177
     2 SW_PVDDCR_CPU1_P0_BOOT3_R @T6G_MB_LIB.T6G(SCH_1):SW_PVDDCR_CPU1_P0_BOOT3_R    I57 @T6G_MB_LIB.T6G(SCH_1):PAGE177

PR91 Q_RES_0402LF-0,5%,1/16W,CHIP,CS00002JB13
     1 PVDDCR_CPU1_P0_VOS4 @T6G_MB_LIB.T6G(SCH_1):PVDDCR_CPU1_P0_VOS4    I40 @T6G_MB_LIB.T6G(SCH_1):PAGE177
     2 PVDDCR_CPU1_P0 @T6G_MB_LIB.T6G(SCH_1):PVDDCR_CPU1_P0    I40 @T6G_MB_LIB.T6G(SCH_1):PAGE177

PR92 Q_RES_0402LF-0,5%,1/16W,CHIP,CS00002JB13
     1 PVDDCR_CPU1_P0_VOS3 @T6G_MB_LIB.T6G(SCH_1):PVDDCR_CPU1_P0_VOS3    I51 @T6G_MB_LIB.T6G(SCH_1):PAGE177
     2 PVDDCR_CPU1_P0 @T6G_MB_LIB.T6G(SCH_1):PVDDCR_CPU1_P0    I51 @T6G_MB_LIB.T6G(SCH_1):PAGE177

PR93 Q_RES_0402LF-8.87K,1%,1/16W,EMPTY,CS28872FB01
     1 PVDDCR_CPU1_P0_LSET5 @T6G_MB_LIB.T6G(SCH_1):PVDDCR_CPU1_P0_LSET5    I15 @T6G_MB_LIB.T6G(SCH_1):PAGE178
     2    GND @T6G_MB_LIB.T6G(SCH_1):GND    I15 @T6G_MB_LIB.T6G(SCH_1):PAGE178

PR94 Q_RES_0402LF-2.2,1%,1/16W,CHIP,CS-2202FB01
     1 PVDDCR_CPU1_P0_PVCC @T6G_MB_LIB.T6G(SCH_1):PVDDCR_CPU1_P0_PVCC    I28 @T6G_MB_LIB.T6G(SCH_1):PAGE178
     2 PVDDCR_CPU1_P0_VCC5 @T6G_MB_LIB.T6G(SCH_1):PVDDCR_CPU1_P0_VCC5    I28 @T6G_MB_LIB.T6G(SCH_1):PAGE178

PR95 Q_RES_0402LF-5.6,1%,1/16W,CHIP,CS-5602FB01
     1 SW_PVDDCR_CPU1_P0_BOOT5 @T6G_MB_LIB.T6G(SCH_1):SW_PVDDCR_CPU1_P0_BOOT5    I56 @T6G_MB_LIB.T6G(SCH_1):PAGE178
     2 SW_PVDDCR_CPU1_P0_BOOT5_R @T6G_MB_LIB.T6G(SCH_1):SW_PVDDCR_CPU1_P0_BOOT5_R    I56 @T6G_MB_LIB.T6G(SCH_1):PAGE178

PR96 Q_RES_0402LF-0,5%,1/16W,CHIP,CS00002JB13
     1 PVDDCR_CPU1_P0_VOS5 @T6G_MB_LIB.T6G(SCH_1):PVDDCR_CPU1_P0_VOS5    I49 @T6G_MB_LIB.T6G(SCH_1):PAGE178
     2 PVDDCR_CPU1_P0 @T6G_MB_LIB.T6G(SCH_1):PVDDCR_CPU1_P0    I49 @T6G_MB_LIB.T6G(SCH_1):PAGE178

PR97 Q_RES_0402LF-8.87K,1%,1/16W,EMPTY,CS28872FB01
     1 PVDDIO_P0_LSET2 @T6G_MB_LIB.T6G(SCH_1):PVDDIO_P0_LSET2     I4 @T6G_MB_LIB.T6G(SCH_1):PAGE180
     2    GND @T6G_MB_LIB.T6G(SCH_1):GND     I4 @T6G_MB_LIB.T6G(SCH_1):PAGE180

PR98 Q_RES_0402LF-8.87K,1%,1/16W,EMPTY,CS28872FB01
     1 PVDDIO_P0_LSET1 @T6G_MB_LIB.T6G(SCH_1):PVDDIO_P0_LSET1    I22 @T6G_MB_LIB.T6G(SCH_1):PAGE180
     2    GND @T6G_MB_LIB.T6G(SCH_1):GND    I22 @T6G_MB_LIB.T6G(SCH_1):PAGE180

PR99 Q_RES_0402LF-2.2,1%,1/16W,CHIP,CS-2202FB01
     1 PVDDCR_CPU1_P0_PVCC @T6G_MB_LIB.T6G(SCH_1):PVDDCR_CPU1_P0_PVCC    I12 @T6G_MB_LIB.T6G(SCH_1):PAGE180
     2 PVDDIO_P0_VCC2 @T6G_MB_LIB.T6G(SCH_1):PVDDIO_P0_VCC2    I12 @T6G_MB_LIB.T6G(SCH_1):PAGE180

PR100 Q_RES_0402LF-2.2,1%,1/16W,CHIP,CS-2202FB01
     1 PVDDCR_CPU1_P0_PVCC @T6G_MB_LIB.T6G(SCH_1):PVDDCR_CPU1_P0_PVCC    I29 @T6G_MB_LIB.T6G(SCH_1):PAGE180
     2 PVDDIO_P0_VCC1 @T6G_MB_LIB.T6G(SCH_1):PVDDIO_P0_VCC1    I29 @T6G_MB_LIB.T6G(SCH_1):PAGE180

PR101 Q_RES_0402LF-5.6,1%,1/16W,CHIP,CS-5602FB01
     1 SW_PVDDIO_P0_BOOT1 @T6G_MB_LIB.T6G(SCH_1):SW_PVDDIO_P0_BOOT1    I34 @T6G_MB_LIB.T6G(SCH_1):PAGE180
     2 SW_PVDDIO_P0_BOOT1_R @T6G_MB_LIB.T6G(SCH_1):SW_PVDDIO_P0_BOOT1_R    I34 @T6G_MB_LIB.T6G(SCH_1):PAGE180

PR102 Q_RES_0402LF-5.6,1%,1/16W,CHIP,CS-5602FB01
     1 SW_PVDDIO_P0_BOOT2 @T6G_MB_LIB.T6G(SCH_1):SW_PVDDIO_P0_BOOT2    I17 @T6G_MB_LIB.T6G(SCH_1):PAGE180
     2 SW_PVDDIO_P0_BOOT2_R @T6G_MB_LIB.T6G(SCH_1):SW_PVDDIO_P0_BOOT2_R    I17 @T6G_MB_LIB.T6G(SCH_1):PAGE180

PR103 Q_RES_0402LF-0,5%,1/16W,CHIP,CS00002JB13
     1 PVDDIO_P0_VOS1 @T6G_MB_LIB.T6G(SCH_1):PVDDIO_P0_VOS1    I49 @T6G_MB_LIB.T6G(SCH_1):PAGE180
     2 PVDDIO_P0 @T6G_MB_LIB.T6G(SCH_1):PVDDIO_P0    I49 @T6G_MB_LIB.T6G(SCH_1):PAGE180

PR104 Q_RES_0402LF-0,5%,1/16W,CHIP,CS00002JB13
     1 PVDDIO_P0_VOS2 @T6G_MB_LIB.T6G(SCH_1):PVDDIO_P0_VOS2    I39 @T6G_MB_LIB.T6G(SCH_1):PAGE180
     2 PVDDIO_P0 @T6G_MB_LIB.T6G(SCH_1):PVDDIO_P0    I39 @T6G_MB_LIB.T6G(SCH_1):PAGE180

PR105 Q_RES_0402LF-8.87K,1%,1/16W,EMPTY,CS28872FB01
     1 PVDDIO_P0_LSET4 @T6G_MB_LIB.T6G(SCH_1):PVDDIO_P0_LSET4     I4 @T6G_MB_LIB.T6G(SCH_1):PAGE181
     2    GND @T6G_MB_LIB.T6G(SCH_1):GND     I4 @T6G_MB_LIB.T6G(SCH_1):PAGE181

PR106 Q_RES_0402LF-8.87K,1%,1/16W,EMPTY,CS28872FB01
     1 PVDDIO_P0_LSET3 @T6G_MB_LIB.T6G(SCH_1):PVDDIO_P0_LSET3    I21 @T6G_MB_LIB.T6G(SCH_1):PAGE181
     2    GND @T6G_MB_LIB.T6G(SCH_1):GND    I21 @T6G_MB_LIB.T6G(SCH_1):PAGE181

PR107 Q_RES_0402LF-2.2,1%,1/16W,CHIP,CS-2202FB01
     1 PVDDCR_CPU1_P0_PVCC @T6G_MB_LIB.T6G(SCH_1):PVDDCR_CPU1_P0_PVCC    I12 @T6G_MB_LIB.T6G(SCH_1):PAGE181
     2 PVDDIO_P0_VCC4 @T6G_MB_LIB.T6G(SCH_1):PVDDIO_P0_VCC4    I12 @T6G_MB_LIB.T6G(SCH_1):PAGE181

PR108 Q_RES_0402LF-2.2,1%,1/16W,CHIP,CS-2202FB01
     1 PVDDCR_CPU1_P0_PVCC @T6G_MB_LIB.T6G(SCH_1):PVDDCR_CPU1_P0_PVCC    I28 @T6G_MB_LIB.T6G(SCH_1):PAGE181
     2 PVDDIO_P0_VCC3 @T6G_MB_LIB.T6G(SCH_1):PVDDIO_P0_VCC3    I28 @T6G_MB_LIB.T6G(SCH_1):PAGE181

PR109 Q_RES_0402LF-5.6,1%,1/16W,CHIP,CS-5602FB01
     1 SW_PVDDIO_P0_BOOT4 @T6G_MB_LIB.T6G(SCH_1):SW_PVDDIO_P0_BOOT4    I16 @T6G_MB_LIB.T6G(SCH_1):PAGE181
     2 SW_PVDDIO_P0_BOOT4_R @T6G_MB_LIB.T6G(SCH_1):SW_PVDDIO_P0_BOOT4_R    I16 @T6G_MB_LIB.T6G(SCH_1):PAGE181

PR110 Q_RES_0402LF-5.6,1%,1/16W,CHIP,CS-5602FB01
     1 SW_PVDDIO_P0_BOOT3 @T6G_MB_LIB.T6G(SCH_1):SW_PVDDIO_P0_BOOT3    I34 @T6G_MB_LIB.T6G(SCH_1):PAGE181
     2 SW_PVDDIO_P0_BOOT3_R @T6G_MB_LIB.T6G(SCH_1):SW_PVDDIO_P0_BOOT3_R    I34 @T6G_MB_LIB.T6G(SCH_1):PAGE181

PR111 Q_RES_0402LF-0,5%,1/16W,CHIP,CS00002JB13
     1 PVDDIO_P0_VOS3 @T6G_MB_LIB.T6G(SCH_1):PVDDIO_P0_VOS3    I50 @T6G_MB_LIB.T6G(SCH_1):PAGE181
     2 PVDDIO_P0 @T6G_MB_LIB.T6G(SCH_1):PVDDIO_P0    I50 @T6G_MB_LIB.T6G(SCH_1):PAGE181

PR112 Q_RES_0402LF-0,5%,1/16W,CHIP,CS00002JB13
     1 PVDDIO_P0_VOS4 @T6G_MB_LIB.T6G(SCH_1):PVDDIO_P0_VOS4    I41 @T6G_MB_LIB.T6G(SCH_1):PAGE181
     2 PVDDIO_P0 @T6G_MB_LIB.T6G(SCH_1):PVDDIO_P0    I41 @T6G_MB_LIB.T6G(SCH_1):PAGE181

PR113 Q_RES_0402LF-40.2K,1%,1/16W,CHIP,CS34022FB04
     1 P5V_AUX @T6G_MB_LIB.T6G(SCH_1):P5V_AUX     I2 @T6G_MB_LIB.T6G(SCH_1):PAGE182
     2 PVDD11_S3_P0_VMON @T6G_MB_LIB.T6G(SCH_1):PVDD11_S3_P0_VMON     I2 @T6G_MB_LIB.T6G(SCH_1):PAGE182

PR114 Q_RES_0402LF-49.9,1%,1/16W,CHIP,CS04992FB07
     1 PVDD11_S3_P0 @T6G_MB_LIB.T6G(SCH_1):PVDD11_S3_P0    I30 @T6G_MB_LIB.T6G(SCH_1):PAGE182
     2 VSENSE_PVDD11_S3_P0_DP @T6G_MB_LIB.T6G(SCH_1):VSENSE_PVDD11_S3_P0_DP    I30 @T6G_MB_LIB.T6G(SCH_1):PAGE182

PR115 Q_RES_0402LF-49.9,1%,1/16W,CHIP,CS04992FB07
     1 VSENSE_VSS_SENSE_C_P0 @T6G_MB_LIB.T6G(SCH_1):VSENSE_VSS_SENSE_C_P0    I15 @T6G_MB_LIB.T6G(SCH_1):PAGE182
     2    GND @T6G_MB_LIB.T6G(SCH_1):GND    I15 @T6G_MB_LIB.T6G(SCH_1):PAGE182

PR121 Q_RES_0402LF-0,5%,1/16W,CHIP,CS00002JB13
     1 VSENSE_PVDD11_S3_P0_DP @T6G_MB_LIB.T6G(SCH_1):VSENSE_PVDD11_S3_P0_DP    I28 @T6G_MB_LIB.T6G(SCH_1):PAGE182
     2 VSENSE_PVDD11_S3_P0_R @T6G_MB_LIB.T6G(SCH_1):VSENSE_PVDD11_S3_P0_R    I28 @T6G_MB_LIB.T6G(SCH_1):PAGE182

PR125 Q_RES_0402LF-0,5%,1/16W,CHIP,CS00002JB13
     1 P12V_AUX @T6G_MB_LIB.T6G(SCH_1):P12V_AUX    I16 @T6G_MB_LIB.T6G(SCH_1):PAGE182
     2 PVDD11_S3_P0_VINSEN @T6G_MB_LIB.T6G(SCH_1):PVDD11_S3_P0_VINSEN    I16 @T6G_MB_LIB.T6G(SCH_1):PAGE182

PR126 Q_RES_0402LF-3.09K,1%,1/16W,CHIP,CS23092FB04
     1 PVDD11_S3_P0_ADDR_CFG @T6G_MB_LIB.T6G(SCH_1):PVDD11_S3_P0_ADDR_CFG    I22 @T6G_MB_LIB.T6G(SCH_1):PAGE182
     2    GND @T6G_MB_LIB.T6G(SCH_1):GND    I22 @T6G_MB_LIB.T6G(SCH_1):PAGE182

PR127 Q_RES_0402LF-0,5%,1/16W,EMPTY,CS00002JB13
     1 PVDD11_S3_P0_RESET_N_R @T6G_MB_LIB.T6G(SCH_1):PVDD11_S3_P0_RESET_N_R    I57 @T6G_MB_LIB.T6G(SCH_1):PAGE182
     2    GND @T6G_MB_LIB.T6G(SCH_1):GND    I57 @T6G_MB_LIB.T6G(SCH_1):PAGE182

PR128 Q_RES_0402LF-1K,1%,1/16W,EMPTY,CS21002FB06
     1 PVDD11_S3_P0_RESET_N_R @T6G_MB_LIB.T6G(SCH_1):PVDD11_S3_P0_RESET_N_R    I68 @T6G_MB_LIB.T6G(SCH_1):PAGE182
     2 PVDD18_S5_P0 @T6G_MB_LIB.T6G(SCH_1):PVDD18_S5_P0    I68 @T6G_MB_LIB.T6G(SCH_1):PAGE182

PR129 Q_RES_0402LF-0,5%,1/16W,EMPTY,CS00002JB13
     1 PVDD11_S3_P0_RESET_N_R @T6G_MB_LIB.T6G(SCH_1):PVDD11_S3_P0_RESET_N_R    I67 @T6G_MB_LIB.T6G(SCH_1):PAGE182
     2 PVDD11_S3_P0_RESET_N @T6G_MB_LIB.T6G(SCH_1):PVDD11_S3_P0_RESET_N    I67 @T6G_MB_LIB.T6G(SCH_1):PAGE182

PR130 Q_RES_0402LF-1,1%,1/16W,CHIP,CS-1002FB04
     1 PVDD11_S3_P0_VCC @T6G_MB_LIB.T6G(SCH_1):PVDD11_S3_P0_VCC    I85 @T6G_MB_LIB.T6G(SCH_1):PAGE182
     2 P3V3_AUX @T6G_MB_LIB.T6G(SCH_1):P3V3_AUX    I85 @T6G_MB_LIB.T6G(SCH_1):PAGE182

PR131 Q_RES_0402LF-2.2,1%,1/16W,CHIP,CS-2202FB01
     1 PVDD11_S3_P0_PVCC @T6G_MB_LIB.T6G(SCH_1):PVDD11_S3_P0_PVCC    I40 @T6G_MB_LIB.T6G(SCH_1):PAGE183
     2 PVDD11_S3_P0_VCC1 @T6G_MB_LIB.T6G(SCH_1):PVDD11_S3_P0_VCC1    I40 @T6G_MB_LIB.T6G(SCH_1):PAGE183

PR132 Q_RES_0402LF-2.2,1%,1/16W,CHIP,CS-2202FB01
     1 PVDD11_S3_P0_PVCC @T6G_MB_LIB.T6G(SCH_1):PVDD11_S3_P0_PVCC    I14 @T6G_MB_LIB.T6G(SCH_1):PAGE183
     2 PVDD11_S3_P0_VCC2 @T6G_MB_LIB.T6G(SCH_1):PVDD11_S3_P0_VCC2    I14 @T6G_MB_LIB.T6G(SCH_1):PAGE183

PR133 Q_RES_0402LF-4.87K,1%,1/16W,EMPTY,CS24872FB01
     1    GND @T6G_MB_LIB.T6G(SCH_1):GND    I37 @T6G_MB_LIB.T6G(SCH_1):PAGE183
     2 PVDD11_S3_P0_LSET1 @T6G_MB_LIB.T6G(SCH_1):PVDD11_S3_P0_LSET1    I37 @T6G_MB_LIB.T6G(SCH_1):PAGE183

PR134 Q_RES_0402LF-4.87K,1%,1/16W,EMPTY,CS24872FB01
     1    GND @T6G_MB_LIB.T6G(SCH_1):GND    I11 @T6G_MB_LIB.T6G(SCH_1):PAGE183
     2 PVDD11_S3_P0_LSET2 @T6G_MB_LIB.T6G(SCH_1):PVDD11_S3_P0_LSET2    I11 @T6G_MB_LIB.T6G(SCH_1):PAGE183

PR135 Q_RES_0402LF-5.6,1%,1/16W,CHIP,CS-5602FB01
     1 SW_PVDD11_S3_P0_BOOT1 @T6G_MB_LIB.T6G(SCH_1):SW_PVDD11_S3_P0_BOOT1    I46 @T6G_MB_LIB.T6G(SCH_1):PAGE183
     2 SW_PVDD11_S3_P0_BOOT1_RC @T6G_MB_LIB.T6G(SCH_1):SW_PVDD11_S3_P0_BOOT1_RC    I46 @T6G_MB_LIB.T6G(SCH_1):PAGE183

PR136 Q_RES_0402LF-5.6,1%,1/16W,CHIP,CS-5602FB01
     1 SW_PVDD11_S3_P0_BOOT2 @T6G_MB_LIB.T6G(SCH_1):SW_PVDD11_S3_P0_BOOT2    I25 @T6G_MB_LIB.T6G(SCH_1):PAGE183
     2 SW_PVDD11_S3_P0_BOOT2_RC @T6G_MB_LIB.T6G(SCH_1):SW_PVDD11_S3_P0_BOOT2_RC    I25 @T6G_MB_LIB.T6G(SCH_1):PAGE183

PR137 Q_RES_0402LF-0,5%,1/16W,CHIP,CS00002JB13
     1 PVDD11_S3_P0_VOS1 @T6G_MB_LIB.T6G(SCH_1):PVDD11_S3_P0_VOS1    I56 @T6G_MB_LIB.T6G(SCH_1):PAGE183
     2 PVDD11_S3_P0 @T6G_MB_LIB.T6G(SCH_1):PVDD11_S3_P0    I56 @T6G_MB_LIB.T6G(SCH_1):PAGE183

PR138 Q_RES_0402LF-0,5%,1/16W,CHIP,CS00002JB13
     1 PVDD11_S3_P0_VOS2 @T6G_MB_LIB.T6G(SCH_1):PVDD11_S3_P0_VOS2    I91 @T6G_MB_LIB.T6G(SCH_1):PAGE183
     2 PVDD11_S3_P0 @T6G_MB_LIB.T6G(SCH_1):PVDD11_S3_P0    I91 @T6G_MB_LIB.T6G(SCH_1):PAGE183

PR147 Q_RES_0402LF-10K,1%,1/16W,CHIP,CS31002FB08
     1 PVDD18_S5_P1_FB @T6G_MB_LIB.T6G(SCH_1):PVDD18_S5_P1_FB    I30 @T6G_MB_LIB.T6G(SCH_1):PAGE201
     2 PVDD18_SS_P1_RGND @T6G_MB_LIB.T6G(SCH_1):PVDD18_SS_P1_RGND    I30 @T6G_MB_LIB.T6G(SCH_1):PAGE201

PR148 Q_RES_0402LF-20K,1%,1/16W,CHIP,CS32002FB06
     1 PVDD18_S5_P1_FB @T6G_MB_LIB.T6G(SCH_1):PVDD18_S5_P1_FB    I32 @T6G_MB_LIB.T6G(SCH_1):PAGE201
     2 PVDD18_S5_P1_FB_RC @T6G_MB_LIB.T6G(SCH_1):PVDD18_S5_P1_FB_RC    I32 @T6G_MB_LIB.T6G(SCH_1):PAGE201

PR150 Q_RES_0402LF-0,5%,1/16W,CHIP,CS00002JB13
     1 SVID_PVDDCR_CPU0_P1_SVTI @T6G_MB_LIB.T6G(SCH_1):SVID_PVDDCR_CPU0_P1_SVTI     I4 @T6G_MB_LIB.T6G(SCH_1):PAGE185
     2    GND @T6G_MB_LIB.T6G(SCH_1):GND     I4 @T6G_MB_LIB.T6G(SCH_1):PAGE185

PR151 Q_RES_0402LF-1K,1%,1/16W,EMPTY,CS21002FB06
     1 PVDD18_S5_P1 @T6G_MB_LIB.T6G(SCH_1):PVDD18_S5_P1    I10 @T6G_MB_LIB.T6G(SCH_1):PAGE185
     2 SVID_PVDDCR_CPU0_P1_SVTI @T6G_MB_LIB.T6G(SCH_1):SVID_PVDDCR_CPU0_P1_SVTI    I10 @T6G_MB_LIB.T6G(SCH_1):PAGE185

PR152 Q_RES_0402LF-1K,1%,1/16W,CHIP,CS21002FB06
     1 P3V3_AUX @T6G_MB_LIB.T6G(SCH_1):P3V3_AUX    I17 @T6G_MB_LIB.T6G(SCH_1):PAGE185
     2 PVDDCR_SOC_P1_EN_GD @T6G_MB_LIB.T6G(SCH_1):PVDDCR_SOC_P1_EN_GD    I17 @T6G_MB_LIB.T6G(SCH_1):PAGE185

PR155 Q_RES_0402LF-1.5,1%,1/8W,EMPTY,CS-1504FB00
     1 SW_PVDDCR_CPU1_P0_SW6_RC @T6G_MB_LIB.T6G(SCH_1):SW_PVDDCR_CPU1_P0_SW6_RC    I33 @T6G_MB_LIB.T6G(SCH_1):PAGE178
     2    GND @T6G_MB_LIB.T6G(SCH_1):GND    I33 @T6G_MB_LIB.T6G(SCH_1):PAGE178

PR157 Q_RES_0402LF-40.2K,1%,1/16W,CHIP,CS34022FB04
     1 P5V_AUX @T6G_MB_LIB.T6G(SCH_1):P5V_AUX    I14 @T6G_MB_LIB.T6G(SCH_1):PAGE185
     2 PVDDCR_CPU0_P1_VMON @T6G_MB_LIB.T6G(SCH_1):PVDDCR_CPU0_P1_VMON    I14 @T6G_MB_LIB.T6G(SCH_1):PAGE185

PR158 Q_RES_0402LF-1.5,1%,1/8W,EMPTY,CS-1504FB00
     1 SW_PVDDCR_CPU1_P0_SW5_RC @T6G_MB_LIB.T6G(SCH_1):SW_PVDDCR_CPU1_P0_SW5_RC    I44 @T6G_MB_LIB.T6G(SCH_1):PAGE178
     2    GND @T6G_MB_LIB.T6G(SCH_1):GND    I44 @T6G_MB_LIB.T6G(SCH_1):PAGE178

PR159 Q_RES_0402LF-5.23K,1%,1/16W,CHIP,CS25232FB08
     1 PVDDCR_SOC_P1_EN//ADDR_CFG @T6G_MB_LIB.T6G(SCH_1):PVDDCR_SOC_P1_EN//ADDR_CFG   I142 @T6G_MB_LIB.T6G(SCH_1):PAGE185
     2    GND @T6G_MB_LIB.T6G(SCH_1):GND   I142 @T6G_MB_LIB.T6G(SCH_1):PAGE185

PR161 Q_RES_0402LF-49.9,1%,1/16W,CHIP,CS04992FB07
     1 PVDDCR_CPU0_P1 @T6G_MB_LIB.T6G(SCH_1):PVDDCR_CPU0_P1    I70 @T6G_MB_LIB.T6G(SCH_1):PAGE185
     2 VSENSE_PVDDCR_CPU0_P1_DP @T6G_MB_LIB.T6G(SCH_1):VSENSE_PVDDCR_CPU0_P1_DP    I70 @T6G_MB_LIB.T6G(SCH_1):PAGE185

PR162 Q_RES_0402LF-49.9,1%,1/16W,CHIP,CS04992FB07
     1 VSENSE_VSS_SENSE_A_P1 @T6G_MB_LIB.T6G(SCH_1):VSENSE_VSS_SENSE_A_P1    I45 @T6G_MB_LIB.T6G(SCH_1):PAGE185
     2    GND @T6G_MB_LIB.T6G(SCH_1):GND    I45 @T6G_MB_LIB.T6G(SCH_1):PAGE185

PR163 Q_RES_0402LF-49.9,1%,1/16W,CHIP,CS04992FB07
     1 PVDDCR_SOC_P1 @T6G_MB_LIB.T6G(SCH_1):PVDDCR_SOC_P1    I39 @T6G_MB_LIB.T6G(SCH_1):PAGE185
     2 VSENSE_PVDDCR_SOC_P1_DP @T6G_MB_LIB.T6G(SCH_1):VSENSE_PVDDCR_SOC_P1_DP    I39 @T6G_MB_LIB.T6G(SCH_1):PAGE185

PR164 Q_RES_0402LF-49.9,1%,1/16W,CHIP,CS04992FB07
     1 VSENSE_VSS_SENSE_A_P1 @T6G_MB_LIB.T6G(SCH_1):VSENSE_VSS_SENSE_A_P1    I36 @T6G_MB_LIB.T6G(SCH_1):PAGE185
     2    GND @T6G_MB_LIB.T6G(SCH_1):GND    I36 @T6G_MB_LIB.T6G(SCH_1):PAGE185

PR169 Q_RES_0402LF-0,5%,1/16W,CHIP,CS00002JB13
     1 SVID_PVDDCR_CPU0_P1_SVC_R @T6G_MB_LIB.T6G(SCH_1):SVID_PVDDCR_CPU0_P1_SVC_R   I334 @T6G_MB_LIB.T6G(SCH_1):PAGE54
     2 SVID_PVDDCR_CPU0_P1_SVC @T6G_MB_LIB.T6G(SCH_1):SVID_PVDDCR_CPU0_P1_SVC   I334 @T6G_MB_LIB.T6G(SCH_1):PAGE54

PR170 Q_RES_0402LF-0,5%,1/16W,CHIP,CS00002JB13
     1 SVID_PVDDCR_CPU0_P1_SVD_R @T6G_MB_LIB.T6G(SCH_1):SVID_PVDDCR_CPU0_P1_SVD_R   I333 @T6G_MB_LIB.T6G(SCH_1):PAGE54
     2 SVID_PVDDCR_CPU0_P1_SVD @T6G_MB_LIB.T6G(SCH_1):SVID_PVDDCR_CPU0_P1_SVD   I333 @T6G_MB_LIB.T6G(SCH_1):PAGE54

PR172 Q_RES_0402LF-0,5%,1/16W,CHIP,CS00002JB13
     1 SVID_PVDDCR_CPU0_P1_SVTI @T6G_MB_LIB.T6G(SCH_1):SVID_PVDDCR_CPU0_P1_SVTI    I82 @T6G_MB_LIB.T6G(SCH_1):PAGE185
     2 SVID_PVDDCR_CPU0_P1_SVTI_R @T6G_MB_LIB.T6G(SCH_1):SVID_PVDDCR_CPU0_P1_SVTI_R    I82 @T6G_MB_LIB.T6G(SCH_1):PAGE185

PR173 Q_RES_0402LF-0,5%,1/16W,CHIP,CS00002JB13
     1 VSENSE_PVDDCR_CPU0_P1_DP @T6G_MB_LIB.T6G(SCH_1):VSENSE_PVDDCR_CPU0_P1_DP    I59 @T6G_MB_LIB.T6G(SCH_1):PAGE185
     2 VSENSE_PVDDCR_CPU0_P1_VSEN0 @T6G_MB_LIB.T6G(SCH_1):VSENSE_PVDDCR_CPU0_P1_VSEN0    I59 @T6G_MB_LIB.T6G(SCH_1):PAGE185

PR174 Q_RES_0402LF-0,5%,1/16W,CHIP,CS00002JB13
     1 VSENSE_PVDDCR_SOC_P1_DP @T6G_MB_LIB.T6G(SCH_1):VSENSE_PVDDCR_SOC_P1_DP    I57 @T6G_MB_LIB.T6G(SCH_1):PAGE185
     2 VSENSE_PVDDCR_SOC_P1_VSEN1 @T6G_MB_LIB.T6G(SCH_1):VSENSE_PVDDCR_SOC_P1_VSEN1    I57 @T6G_MB_LIB.T6G(SCH_1):PAGE185

PR181 Q_RES_0402LF-0,5%,1/16W,CHIP,CS00002JB13
     1 P12V_AUX @T6G_MB_LIB.T6G(SCH_1):P12V_AUX    I47 @T6G_MB_LIB.T6G(SCH_1):PAGE185
     2 PVDDCR_CPU0_P1_VINSEN @T6G_MB_LIB.T6G(SCH_1):PVDDCR_CPU0_P1_VINSEN    I47 @T6G_MB_LIB.T6G(SCH_1):PAGE185

PR183 Q_RES_0402LF-1,1%,1/16W,CHIP,CS-1002FB04
     1 PVDDCR_CPU0_P1_VCC @T6G_MB_LIB.T6G(SCH_1):PVDDCR_CPU0_P1_VCC   I129 @T6G_MB_LIB.T6G(SCH_1):PAGE185
     2 P3V3_AUX @T6G_MB_LIB.T6G(SCH_1):P3V3_AUX   I129 @T6G_MB_LIB.T6G(SCH_1):PAGE185

PR185 Q_RES_0402LF-2.2,1%,1/16W,CHIP,CS-2202FB01
     1 PVDDCR_CPU0_P1_PVCC @T6G_MB_LIB.T6G(SCH_1):PVDDCR_CPU0_P1_PVCC    I43 @T6G_MB_LIB.T6G(SCH_1):PAGE186
     2 PVDDCR_CPU0_P1_VCC1 @T6G_MB_LIB.T6G(SCH_1):PVDDCR_CPU0_P1_VCC1    I43 @T6G_MB_LIB.T6G(SCH_1):PAGE186

PR186 Q_RES_0402LF-2.2,1%,1/16W,CHIP,CS-2202FB01
     1 PVDDCR_CPU0_P1_PVCC @T6G_MB_LIB.T6G(SCH_1):PVDDCR_CPU0_P1_PVCC    I11 @T6G_MB_LIB.T6G(SCH_1):PAGE186
     2 PVDDCR_CPU0_P1_VCC2 @T6G_MB_LIB.T6G(SCH_1):PVDDCR_CPU0_P1_VCC2    I11 @T6G_MB_LIB.T6G(SCH_1):PAGE186

PR187 Q_RES_0402LF-8.87K,1%,1/16W,EMPTY,CS28872FB01
     1    GND @T6G_MB_LIB.T6G(SCH_1):GND    I37 @T6G_MB_LIB.T6G(SCH_1):PAGE186
     2 PVDDCR_CPU0_P1_LSET1 @T6G_MB_LIB.T6G(SCH_1):PVDDCR_CPU0_P1_LSET1    I37 @T6G_MB_LIB.T6G(SCH_1):PAGE186

PR188 Q_RES_0402LF-8.87K,1%,1/16W,EMPTY,CS28872FB01
     1    GND @T6G_MB_LIB.T6G(SCH_1):GND    I80 @T6G_MB_LIB.T6G(SCH_1):PAGE186
     2 PVDDCR_CPU0_P1_LSET2 @T6G_MB_LIB.T6G(SCH_1):PVDDCR_CPU0_P1_LSET2    I80 @T6G_MB_LIB.T6G(SCH_1):PAGE186

PR189 Q_RES_0402LF-5.6,1%,1/16W,CHIP,CS-5602FB01
     1 SW_PVDDCR_CPU0_P1_BOOT1 @T6G_MB_LIB.T6G(SCH_1):SW_PVDDCR_CPU0_P1_BOOT1    I49 @T6G_MB_LIB.T6G(SCH_1):PAGE186
     2 SW_PVDDCR_CPU0_P1_BOOT1_RC @T6G_MB_LIB.T6G(SCH_1):SW_PVDDCR_CPU0_P1_BOOT1_RC    I49 @T6G_MB_LIB.T6G(SCH_1):PAGE186

PR190 Q_RES_0402LF-5.6,1%,1/16W,CHIP,CS-5602FB01
     1 SW_PVDDCR_CPU0_P1_BOOT2 @T6G_MB_LIB.T6G(SCH_1):SW_PVDDCR_CPU0_P1_BOOT2    I83 @T6G_MB_LIB.T6G(SCH_1):PAGE186
     2 SW_PVDDCR_CPU0_P1_BOOT2_RC @T6G_MB_LIB.T6G(SCH_1):SW_PVDDCR_CPU0_P1_BOOT2_RC    I83 @T6G_MB_LIB.T6G(SCH_1):PAGE186

PR191 Q_RES_0402LF-0,5%,1/16W,CHIP,CS00002JB13
     1 PVDDCR_CPU0_P1_VOS1 @T6G_MB_LIB.T6G(SCH_1):PVDDCR_CPU0_P1_VOS1    I35 @T6G_MB_LIB.T6G(SCH_1):PAGE186
     2 PVDDCR_CPU0_P1 @T6G_MB_LIB.T6G(SCH_1):PVDDCR_CPU0_P1    I35 @T6G_MB_LIB.T6G(SCH_1):PAGE186

PR192 Q_RES_0402LF-0,5%,1/16W,CHIP,CS00002JB13
     1 PVDDCR_CPU0_P1_VOS2 @T6G_MB_LIB.T6G(SCH_1):PVDDCR_CPU0_P1_VOS2    I23 @T6G_MB_LIB.T6G(SCH_1):PAGE186
     2 PVDDCR_CPU0_P1 @T6G_MB_LIB.T6G(SCH_1):PVDDCR_CPU0_P1    I23 @T6G_MB_LIB.T6G(SCH_1):PAGE186

PR193 Q_RES_0402LF-2.2,1%,1/16W,CHIP,CS-2202FB01
     1 PVDDCR_CPU0_P1_PVCC @T6G_MB_LIB.T6G(SCH_1):PVDDCR_CPU0_P1_PVCC    I38 @T6G_MB_LIB.T6G(SCH_1):PAGE187
     2 PVDDCR_CPU0_P1_VCC3 @T6G_MB_LIB.T6G(SCH_1):PVDDCR_CPU0_P1_VCC3    I38 @T6G_MB_LIB.T6G(SCH_1):PAGE187

PR194 Q_RES_0402LF-2.2,1%,1/16W,CHIP,CS-2202FB01
     1 PVDDCR_CPU0_P1_PVCC @T6G_MB_LIB.T6G(SCH_1):PVDDCR_CPU0_P1_PVCC    I12 @T6G_MB_LIB.T6G(SCH_1):PAGE187
     2 PVDDCR_CPU0_P1_VCC4 @T6G_MB_LIB.T6G(SCH_1):PVDDCR_CPU0_P1_VCC4    I12 @T6G_MB_LIB.T6G(SCH_1):PAGE187

PR195 Q_RES_0402LF-8.87K,1%,1/16W,EMPTY,CS28872FB01
     1    GND @T6G_MB_LIB.T6G(SCH_1):GND    I34 @T6G_MB_LIB.T6G(SCH_1):PAGE187
     2 PVDDCR_CPU0_P1_LSET3 @T6G_MB_LIB.T6G(SCH_1):PVDDCR_CPU0_P1_LSET3    I34 @T6G_MB_LIB.T6G(SCH_1):PAGE187

PR196 Q_RES_0402LF-8.87K,1%,1/16W,EMPTY,CS28872FB01
     1    GND @T6G_MB_LIB.T6G(SCH_1):GND    I11 @T6G_MB_LIB.T6G(SCH_1):PAGE187
     2 PVDDCR_CPU0_P1_LSET4 @T6G_MB_LIB.T6G(SCH_1):PVDDCR_CPU0_P1_LSET4    I11 @T6G_MB_LIB.T6G(SCH_1):PAGE187

PR197 Q_RES_0402LF-5.6,1%,1/16W,CHIP,CS-5602FB01
     1 SW_PVDDCR_CPU0_P1_BOOT3 @T6G_MB_LIB.T6G(SCH_1):SW_PVDDCR_CPU0_P1_BOOT3    I47 @T6G_MB_LIB.T6G(SCH_1):PAGE187
     2 SW_PVDDCR_CPU0_P1_BOOT3_RC @T6G_MB_LIB.T6G(SCH_1):SW_PVDDCR_CPU0_P1_BOOT3_RC    I47 @T6G_MB_LIB.T6G(SCH_1):PAGE187

PR198 Q_RES_0402LF-5.6,1%,1/16W,CHIP,CS-5602FB01
     1 SW_PVDDCR_CPU0_P1_BOOT4 @T6G_MB_LIB.T6G(SCH_1):SW_PVDDCR_CPU0_P1_BOOT4    I21 @T6G_MB_LIB.T6G(SCH_1):PAGE187
     2 SW_PVDDCR_CPU0_P1_BOOT4_RC @T6G_MB_LIB.T6G(SCH_1):SW_PVDDCR_CPU0_P1_BOOT4_RC    I21 @T6G_MB_LIB.T6G(SCH_1):PAGE187

PR199 Q_RES_0402LF-0,5%,1/16W,CHIP,CS00002JB13
     1 PVDDCR_CPU0_P1_VOS3 @T6G_MB_LIB.T6G(SCH_1):PVDDCR_CPU0_P1_VOS3    I27 @T6G_MB_LIB.T6G(SCH_1):PAGE187
     2 PVDDCR_CPU0_P1 @T6G_MB_LIB.T6G(SCH_1):PVDDCR_CPU0_P1    I27 @T6G_MB_LIB.T6G(SCH_1):PAGE187

PR200 Q_RES_0402LF-0,5%,1/16W,CHIP,CS00002JB13
     1 PVDDCR_CPU0_P1_VOS4 @T6G_MB_LIB.T6G(SCH_1):PVDDCR_CPU0_P1_VOS4    I17 @T6G_MB_LIB.T6G(SCH_1):PAGE187
     2 PVDDCR_CPU0_P1 @T6G_MB_LIB.T6G(SCH_1):PVDDCR_CPU0_P1    I17 @T6G_MB_LIB.T6G(SCH_1):PAGE187

PR201 Q_RES_0402LF-2.2,1%,1/16W,CHIP,CS-2202FB01
     1 PVDDCR_CPU0_P1_PVCC @T6G_MB_LIB.T6G(SCH_1):PVDDCR_CPU0_P1_PVCC    I41 @T6G_MB_LIB.T6G(SCH_1):PAGE188
     2 PVDDCR_CPU0_P1_VCC5 @T6G_MB_LIB.T6G(SCH_1):PVDDCR_CPU0_P1_VCC5    I41 @T6G_MB_LIB.T6G(SCH_1):PAGE188

PR202 Q_RES_0402LF-8.87K,1%,1/16W,EMPTY,CS28872FB01
     1    GND @T6G_MB_LIB.T6G(SCH_1):GND    I37 @T6G_MB_LIB.T6G(SCH_1):PAGE188
     2 PVDDCR_CPU0_P1_LSET5 @T6G_MB_LIB.T6G(SCH_1):PVDDCR_CPU0_P1_LSET5    I37 @T6G_MB_LIB.T6G(SCH_1):PAGE188

PR203 Q_RES_0402LF-5.6,1%,1/16W,CHIP,CS-5602FB01
     1 SW_PVDDCR_CPU0_P1_BOOT5 @T6G_MB_LIB.T6G(SCH_1):SW_PVDDCR_CPU0_P1_BOOT5    I47 @T6G_MB_LIB.T6G(SCH_1):PAGE188
     2 SW_PVDDCR_CPU0_P1_BOOT5_RC @T6G_MB_LIB.T6G(SCH_1):SW_PVDDCR_CPU0_P1_BOOT5_RC    I47 @T6G_MB_LIB.T6G(SCH_1):PAGE188

PR204 Q_RES_0402LF-0,5%,1/16W,CHIP,CS00002JB13
     1 PVDDCR_CPU0_P1_VOS5 @T6G_MB_LIB.T6G(SCH_1):PVDDCR_CPU0_P1_VOS5    I33 @T6G_MB_LIB.T6G(SCH_1):PAGE188
     2 PVDDCR_CPU0_P1 @T6G_MB_LIB.T6G(SCH_1):PVDDCR_CPU0_P1    I33 @T6G_MB_LIB.T6G(SCH_1):PAGE188

PR205 Q_RES_0402LF-2.2,1%,1/16W,CHIP,CS-2202FB01
     1 PVDDCR_CPU0_P1_PVCC @T6G_MB_LIB.T6G(SCH_1):PVDDCR_CPU0_P1_PVCC    I39 @T6G_MB_LIB.T6G(SCH_1):PAGE190
     2 PVDDCR_SOC_P1_VCC1 @T6G_MB_LIB.T6G(SCH_1):PVDDCR_SOC_P1_VCC1    I39 @T6G_MB_LIB.T6G(SCH_1):PAGE190

PR206 Q_RES_0402LF-2.2,1%,1/16W,CHIP,CS-2202FB01
     1 PVDDCR_CPU0_P1_PVCC @T6G_MB_LIB.T6G(SCH_1):PVDDCR_CPU0_P1_PVCC    I12 @T6G_MB_LIB.T6G(SCH_1):PAGE190
     2 PVDDCR_SOC_P1_VCC2 @T6G_MB_LIB.T6G(SCH_1):PVDDCR_SOC_P1_VCC2    I12 @T6G_MB_LIB.T6G(SCH_1):PAGE190

PR207 Q_RES_0402LF-8.87K,1%,1/16W,EMPTY,CS28872FB01
     1    GND @T6G_MB_LIB.T6G(SCH_1):GND    I35 @T6G_MB_LIB.T6G(SCH_1):PAGE190
     2 PVDDCR_SOC_P1_LSET1 @T6G_MB_LIB.T6G(SCH_1):PVDDCR_SOC_P1_LSET1    I35 @T6G_MB_LIB.T6G(SCH_1):PAGE190

PR208 Q_RES_0402LF-8.87K,1%,1/16W,EMPTY,CS28872FB01
     1    GND @T6G_MB_LIB.T6G(SCH_1):GND     I8 @T6G_MB_LIB.T6G(SCH_1):PAGE190
     2 PVDDCR_SOC_P1_LSET2 @T6G_MB_LIB.T6G(SCH_1):PVDDCR_SOC_P1_LSET2     I8 @T6G_MB_LIB.T6G(SCH_1):PAGE190

PR209 Q_RES_0402LF-5.6,1%,1/16W,CHIP,CS-5602FB01
     1 SW_PVDDCR_SOC_P1_BOOT1 @T6G_MB_LIB.T6G(SCH_1):SW_PVDDCR_SOC_P1_BOOT1    I46 @T6G_MB_LIB.T6G(SCH_1):PAGE190
     2 SW_PVDDCR_SOC_P1_BOOT1_RC @T6G_MB_LIB.T6G(SCH_1):SW_PVDDCR_SOC_P1_BOOT1_RC    I46 @T6G_MB_LIB.T6G(SCH_1):PAGE190

PR210 Q_RES_0402LF-5.6,1%,1/16W,CHIP,CS-5602FB01
     1 SW_PVDDCR_SOC_P1_BOOT2 @T6G_MB_LIB.T6G(SCH_1):SW_PVDDCR_SOC_P1_BOOT2    I24 @T6G_MB_LIB.T6G(SCH_1):PAGE190
     2 SW_PVDDCR_SOC_P1_BOOT2_RC @T6G_MB_LIB.T6G(SCH_1):SW_PVDDCR_SOC_P1_BOOT2_RC    I24 @T6G_MB_LIB.T6G(SCH_1):PAGE190

PR211 Q_RES_0402LF-0,5%,1/16W,CHIP,CS00002JB13
     1 PVDDCR_SOC_P1_VOS1 @T6G_MB_LIB.T6G(SCH_1):PVDDCR_SOC_P1_VOS1    I30 @T6G_MB_LIB.T6G(SCH_1):PAGE190
     2 PVDDCR_SOC_P1 @T6G_MB_LIB.T6G(SCH_1):PVDDCR_SOC_P1    I30 @T6G_MB_LIB.T6G(SCH_1):PAGE190

PR212 Q_RES_0402LF-0,5%,1/16W,CHIP,CS00002JB13
     1 PVDDCR_SOC_P1_VOS2 @T6G_MB_LIB.T6G(SCH_1):PVDDCR_SOC_P1_VOS2    I85 @T6G_MB_LIB.T6G(SCH_1):PAGE190
     2 PVDDCR_SOC_P1 @T6G_MB_LIB.T6G(SCH_1):PVDDCR_SOC_P1    I85 @T6G_MB_LIB.T6G(SCH_1):PAGE190

PR213 Q_RES_0402LF-2.2,1%,1/16W,CHIP,CS-2202FB01
     1 PVDDCR_CPU0_P1_PVCC @T6G_MB_LIB.T6G(SCH_1):PVDDCR_CPU0_P1_PVCC    I14 @T6G_MB_LIB.T6G(SCH_1):PAGE191
     2 PVDDCR_SOC_P1_VCC3 @T6G_MB_LIB.T6G(SCH_1):PVDDCR_SOC_P1_VCC3    I14 @T6G_MB_LIB.T6G(SCH_1):PAGE191

PR214 Q_RES_0402LF-8.87K,1%,1/16W,EMPTY,CS28872FB01
     1    GND @T6G_MB_LIB.T6G(SCH_1):GND     I7 @T6G_MB_LIB.T6G(SCH_1):PAGE191
     2 PVDDCR_SOC_P1_LSET3 @T6G_MB_LIB.T6G(SCH_1):PVDDCR_SOC_P1_LSET3     I7 @T6G_MB_LIB.T6G(SCH_1):PAGE191

PR215 Q_RES_0402LF-5.6,1%,1/16W,CHIP,CS-5602FB01
     1 SW_PVDDCR_SOC_P1_BOOT3 @T6G_MB_LIB.T6G(SCH_1):SW_PVDDCR_SOC_P1_BOOT3    I21 @T6G_MB_LIB.T6G(SCH_1):PAGE191
     2 SW_PVDDCR_SOC_P1_BOOT3_RC @T6G_MB_LIB.T6G(SCH_1):SW_PVDDCR_SOC_P1_BOOT3_RC    I21 @T6G_MB_LIB.T6G(SCH_1):PAGE191

PR216 Q_RES_0402LF-0,5%,1/16W,CHIP,CS00002JB13
     1 PVDDCR_SOC_P1_VOS3 @T6G_MB_LIB.T6G(SCH_1):PVDDCR_SOC_P1_VOS3    I23 @T6G_MB_LIB.T6G(SCH_1):PAGE191
     2 PVDDCR_SOC_P1 @T6G_MB_LIB.T6G(SCH_1):PVDDCR_SOC_P1    I23 @T6G_MB_LIB.T6G(SCH_1):PAGE191

PR217 Q_RES_0402LF-0,5%,1/16W,CHIP,CS00002JB13
     1 SVID_PVDDCR_CPU1_P1_SVTI @T6G_MB_LIB.T6G(SCH_1):SVID_PVDDCR_CPU1_P1_SVTI    I29 @T6G_MB_LIB.T6G(SCH_1):PAGE192
     2    GND @T6G_MB_LIB.T6G(SCH_1):GND    I29 @T6G_MB_LIB.T6G(SCH_1):PAGE192

PR218 Q_RES_0402LF-1K,1%,1/16W,EMPTY,CS21002FB06
     1 PVDD18_S5_P1 @T6G_MB_LIB.T6G(SCH_1):PVDD18_S5_P1    I38 @T6G_MB_LIB.T6G(SCH_1):PAGE192
     2 SVID_PVDDCR_CPU1_P1_SVTI @T6G_MB_LIB.T6G(SCH_1):SVID_PVDDCR_CPU1_P1_SVTI    I38 @T6G_MB_LIB.T6G(SCH_1):PAGE192

PR221 Q_RES_0402LF-1.5,1%,1/8W,EMPTY,CS-1504FB00
     1 SW_PVDDIO_P0_SW1_RC @T6G_MB_LIB.T6G(SCH_1):SW_PVDDIO_P0_SW1_RC    I60 @T6G_MB_LIB.T6G(SCH_1):PAGE180
     2    GND @T6G_MB_LIB.T6G(SCH_1):GND    I60 @T6G_MB_LIB.T6G(SCH_1):PAGE180

PR223 Q_RES_0402LF-1.5,1%,1/8W,EMPTY,CS-1504FB00
     1 SW_PVDDIO_P0_SW2_RC @T6G_MB_LIB.T6G(SCH_1):SW_PVDDIO_P0_SW2_RC    I36 @T6G_MB_LIB.T6G(SCH_1):PAGE180
     2    GND @T6G_MB_LIB.T6G(SCH_1):GND    I36 @T6G_MB_LIB.T6G(SCH_1):PAGE180

PR226 Q_RES_0402LF-49.9,1%,1/16W,CHIP,CS04992FB07
     1 VSENSE_VSS_SENSE_C_P1 @T6G_MB_LIB.T6G(SCH_1):VSENSE_VSS_SENSE_C_P1    I23 @T6G_MB_LIB.T6G(SCH_1):PAGE192
     2    GND @T6G_MB_LIB.T6G(SCH_1):GND    I23 @T6G_MB_LIB.T6G(SCH_1):PAGE192

PR227 Q_RES_0402LF-49.9,1%,1/16W,CHIP,CS04992FB07
     1 VSENSE_PVDDIO_P1_DP @T6G_MB_LIB.T6G(SCH_1):VSENSE_PVDDIO_P1_DP    I22 @T6G_MB_LIB.T6G(SCH_1):PAGE192
     2 PVDDIO_P1 @T6G_MB_LIB.T6G(SCH_1):PVDDIO_P1    I22 @T6G_MB_LIB.T6G(SCH_1):PAGE192

PR228 Q_RES_0402LF-49.9,1%,1/16W,CHIP,CS04992FB07
     1 VSENSE_PVDDCR_CPU1_P1_DP @T6G_MB_LIB.T6G(SCH_1):VSENSE_PVDDCR_CPU1_P1_DP    I34 @T6G_MB_LIB.T6G(SCH_1):PAGE192
     2 PVDDCR_CPU1_P1 @T6G_MB_LIB.T6G(SCH_1):PVDDCR_CPU1_P1    I34 @T6G_MB_LIB.T6G(SCH_1):PAGE192

PR229 Q_RES_0402LF-49.9,1%,1/16W,CHIP,CS04992FB07
     1 PVDD11_S3_P1 @T6G_MB_LIB.T6G(SCH_1):PVDD11_S3_P1    I29 @T6G_MB_LIB.T6G(SCH_1):PAGE199
     2 VSENSE_PVDD11_S3_P1_DP @T6G_MB_LIB.T6G(SCH_1):VSENSE_PVDD11_S3_P1_DP    I29 @T6G_MB_LIB.T6G(SCH_1):PAGE199

PR230 Q_RES_0402LF-40.2K,1%,1/16W,CHIP,CS34022FB04
     1 P5V_AUX @T6G_MB_LIB.T6G(SCH_1):P5V_AUX     I9 @T6G_MB_LIB.T6G(SCH_1):PAGE192
     2 PVDDCR_CPU1_P1_VMON @T6G_MB_LIB.T6G(SCH_1):PVDDCR_CPU1_P1_VMON     I9 @T6G_MB_LIB.T6G(SCH_1):PAGE192

PR231 Q_RES_0402LF-10K,1%,1/16W,CHIP,CS31002FB08
     1 PVDDCR_CPU1_P1_VMON @T6G_MB_LIB.T6G(SCH_1):PVDDCR_CPU1_P1_VMON     I8 @T6G_MB_LIB.T6G(SCH_1):PAGE192
     2    GND @T6G_MB_LIB.T6G(SCH_1):GND     I8 @T6G_MB_LIB.T6G(SCH_1):PAGE192

PR232 Q_RES_0402LF-1K,1%,1/16W,CHIP,CS21002FB06
     1 P3V3_AUX @T6G_MB_LIB.T6G(SCH_1):P3V3_AUX    I17 @T6G_MB_LIB.T6G(SCH_1):PAGE192
     2 PVDDIO_P1_EN_G @T6G_MB_LIB.T6G(SCH_1):PVDDIO_P1_EN_G    I17 @T6G_MB_LIB.T6G(SCH_1):PAGE192

PR236 Q_RES_0402LF-0,5%,1/16W,CHIP,CS00002JB13
     1 SVID_PVDDCR_CPU1_P1_SVC_R @T6G_MB_LIB.T6G(SCH_1):SVID_PVDDCR_CPU1_P1_SVC_R   I338 @T6G_MB_LIB.T6G(SCH_1):PAGE54
     2 SVID_PVDDCR_CPU1_P1_SVC @T6G_MB_LIB.T6G(SCH_1):SVID_PVDDCR_CPU1_P1_SVC   I338 @T6G_MB_LIB.T6G(SCH_1):PAGE54

PR237 Q_RES_0402LF-0,5%,1/16W,CHIP,CS00002JB13
     1 SVID_PVDDCR_CPU1_P1_SVD_R @T6G_MB_LIB.T6G(SCH_1):SVID_PVDDCR_CPU1_P1_SVD_R   I337 @T6G_MB_LIB.T6G(SCH_1):PAGE54
     2 SVID_PVDDCR_CPU1_P1_SVD @T6G_MB_LIB.T6G(SCH_1):SVID_PVDDCR_CPU1_P1_SVD   I337 @T6G_MB_LIB.T6G(SCH_1):PAGE54

PR239 Q_RES_0402LF-0,5%,1/16W,CHIP,CS00002JB13
     1 SVID_PVDDCR_CPU1_P1_SVTI @T6G_MB_LIB.T6G(SCH_1):SVID_PVDDCR_CPU1_P1_SVTI    I83 @T6G_MB_LIB.T6G(SCH_1):PAGE192
     2 SVID_PVDDCR_CPU1_P1_SVTI_R @T6G_MB_LIB.T6G(SCH_1):SVID_PVDDCR_CPU1_P1_SVTI_R    I83 @T6G_MB_LIB.T6G(SCH_1):PAGE192

PR244 Q_RES_0402LF-9.53K,1%,1/16W,CHIP,CS29532FB06
     1 PVDDCR_CPU1_P1_EN1_ADDR_CFG @T6G_MB_LIB.T6G(SCH_1):PVDDCR_CPU1_P1_EN1_ADDR_CFG    I12 @T6G_MB_LIB.T6G(SCH_1):PAGE192
     2    GND @T6G_MB_LIB.T6G(SCH_1):GND    I12 @T6G_MB_LIB.T6G(SCH_1):PAGE192

PR245 Q_RES_0402LF-0,5%,1/16W,CHIP,CS00002JB13
     1 VSENSE_PVDDCR_CPU1_P1_DP @T6G_MB_LIB.T6G(SCH_1):VSENSE_PVDDCR_CPU1_P1_DP    I77 @T6G_MB_LIB.T6G(SCH_1):PAGE192
     2 VSENSE_PVDDCR_CPU1_P1_VSEN0 @T6G_MB_LIB.T6G(SCH_1):VSENSE_PVDDCR_CPU1_P1_VSEN0    I77 @T6G_MB_LIB.T6G(SCH_1):PAGE192

PR246 Q_RES_0402LF-0,5%,1/16W,CHIP,CS00002JB13
     1 VSENSE_PVDDIO_P1_DP @T6G_MB_LIB.T6G(SCH_1):VSENSE_PVDDIO_P1_DP    I69 @T6G_MB_LIB.T6G(SCH_1):PAGE192
     2 VSENSE_PVDDIO_P1_VSEN1 @T6G_MB_LIB.T6G(SCH_1):VSENSE_PVDDIO_P1_VSEN1    I69 @T6G_MB_LIB.T6G(SCH_1):PAGE192

PR251 Q_RES_0402LF-0,5%,1/16W,CHIP,CS00002JB13
     1 P12V_AUX @T6G_MB_LIB.T6G(SCH_1):P12V_AUX    I49 @T6G_MB_LIB.T6G(SCH_1):PAGE192
     2 PVDDCR_CPU1_P1_VINSEN @T6G_MB_LIB.T6G(SCH_1):PVDDCR_CPU1_P1_VINSEN    I49 @T6G_MB_LIB.T6G(SCH_1):PAGE192

PR253 Q_RES_0402LF-1,1%,1/16W,CHIP,CS-1002FB04
     1 PVDDCR_CPU1_P1_VCC @T6G_MB_LIB.T6G(SCH_1):PVDDCR_CPU1_P1_VCC   I124 @T6G_MB_LIB.T6G(SCH_1):PAGE192
     2 P3V3_AUX @T6G_MB_LIB.T6G(SCH_1):P3V3_AUX   I124 @T6G_MB_LIB.T6G(SCH_1):PAGE192

PR254 Q_RES_0402LF-8.87K,1%,1/16W,EMPTY,CS28872FB01
     1 PVDDCR_CPU1_P1_LSET2 @T6G_MB_LIB.T6G(SCH_1):PVDDCR_CPU1_P1_LSET2     I4 @T6G_MB_LIB.T6G(SCH_1):PAGE193
     2    GND @T6G_MB_LIB.T6G(SCH_1):GND     I4 @T6G_MB_LIB.T6G(SCH_1):PAGE193

PR255 Q_RES_0402LF-8.87K,1%,1/16W,EMPTY,CS28872FB01
     1 PVDDCR_CPU1_P1_LSET1 @T6G_MB_LIB.T6G(SCH_1):PVDDCR_CPU1_P1_LSET1    I17 @T6G_MB_LIB.T6G(SCH_1):PAGE193
     2    GND @T6G_MB_LIB.T6G(SCH_1):GND    I17 @T6G_MB_LIB.T6G(SCH_1):PAGE193

PR256 Q_RES_0402LF-2.2,1%,1/16W,CHIP,CS-2202FB01
     1 PVDDCR_CPU1_P1_PVCC @T6G_MB_LIB.T6G(SCH_1):PVDDCR_CPU1_P1_PVCC    I27 @T6G_MB_LIB.T6G(SCH_1):PAGE193
     2 PVDDCR_CPU1_P1_VCC1 @T6G_MB_LIB.T6G(SCH_1):PVDDCR_CPU1_P1_VCC1    I27 @T6G_MB_LIB.T6G(SCH_1):PAGE193

PR257 Q_RES_0402LF-2.2,1%,1/16W,CHIP,CS-2202FB01
     1 PVDDCR_CPU1_P1_PVCC @T6G_MB_LIB.T6G(SCH_1):PVDDCR_CPU1_P1_PVCC    I14 @T6G_MB_LIB.T6G(SCH_1):PAGE193
     2 PVDDCR_CPU1_P1_VCC2 @T6G_MB_LIB.T6G(SCH_1):PVDDCR_CPU1_P1_VCC2    I14 @T6G_MB_LIB.T6G(SCH_1):PAGE193

PR258 Q_RES_0402LF-5.6,1%,1/16W,CHIP,CS-5602FB01
     1 SW_PVDDCR_CPU1_P1_BOOT1 @T6G_MB_LIB.T6G(SCH_1):SW_PVDDCR_CPU1_P1_BOOT1    I51 @T6G_MB_LIB.T6G(SCH_1):PAGE193
     2 SW_PVDDCR_CPU1_P1_BOOT1_R @T6G_MB_LIB.T6G(SCH_1):SW_PVDDCR_CPU1_P1_BOOT1_R    I51 @T6G_MB_LIB.T6G(SCH_1):PAGE193

PR259 Q_RES_0402LF-5.6,1%,1/16W,CHIP,CS-5602FB01
     1 SW_PVDDCR_CPU1_P1_BOOT2 @T6G_MB_LIB.T6G(SCH_1):SW_PVDDCR_CPU1_P1_BOOT2    I41 @T6G_MB_LIB.T6G(SCH_1):PAGE193
     2 SW_PVDDCR_CPU1_P1_BOOT2_R @T6G_MB_LIB.T6G(SCH_1):SW_PVDDCR_CPU1_P1_BOOT2_R    I41 @T6G_MB_LIB.T6G(SCH_1):PAGE193

PR260 Q_RES_0402LF-0,5%,1/16W,CHIP,CS00002JB13
     1 PVDDCR_CPU1_P1_VOS2 @T6G_MB_LIB.T6G(SCH_1):PVDDCR_CPU1_P1_VOS2    I38 @T6G_MB_LIB.T6G(SCH_1):PAGE193
     2 PVDDCR_CPU1_P1 @T6G_MB_LIB.T6G(SCH_1):PVDDCR_CPU1_P1    I38 @T6G_MB_LIB.T6G(SCH_1):PAGE193

PR261 Q_RES_0402LF-0,5%,1/16W,CHIP,CS00002JB13
     1 PVDDCR_CPU1_P1_VOS1 @T6G_MB_LIB.T6G(SCH_1):PVDDCR_CPU1_P1_VOS1    I64 @T6G_MB_LIB.T6G(SCH_1):PAGE193
     2 PVDDCR_CPU1_P1 @T6G_MB_LIB.T6G(SCH_1):PVDDCR_CPU1_P1    I64 @T6G_MB_LIB.T6G(SCH_1):PAGE193

PR262 Q_RES_0402LF-8.87K,1%,1/16W,EMPTY,CS28872FB01
     1 PVDDCR_CPU1_P1_LSET4 @T6G_MB_LIB.T6G(SCH_1):PVDDCR_CPU1_P1_LSET4     I4 @T6G_MB_LIB.T6G(SCH_1):PAGE194
     2    GND @T6G_MB_LIB.T6G(SCH_1):GND     I4 @T6G_MB_LIB.T6G(SCH_1):PAGE194

PR263 Q_RES_0402LF-8.87K,1%,1/16W,EMPTY,CS28872FB01
     1 PVDDCR_CPU1_P1_LSET3 @T6G_MB_LIB.T6G(SCH_1):PVDDCR_CPU1_P1_LSET3    I18 @T6G_MB_LIB.T6G(SCH_1):PAGE194
     2    GND @T6G_MB_LIB.T6G(SCH_1):GND    I18 @T6G_MB_LIB.T6G(SCH_1):PAGE194

PR264 Q_RES_0402LF-2.2,1%,1/16W,CHIP,CS-2202FB01
     1 PVDDCR_CPU1_P1_PVCC @T6G_MB_LIB.T6G(SCH_1):PVDDCR_CPU1_P1_PVCC    I13 @T6G_MB_LIB.T6G(SCH_1):PAGE194
     2 PVDDCR_CPU1_P1_VCC4 @T6G_MB_LIB.T6G(SCH_1):PVDDCR_CPU1_P1_VCC4    I13 @T6G_MB_LIB.T6G(SCH_1):PAGE194

PR265 Q_RES_0402LF-2.2,1%,1/16W,CHIP,CS-2202FB01
     1 PVDDCR_CPU1_P1_PVCC @T6G_MB_LIB.T6G(SCH_1):PVDDCR_CPU1_P1_PVCC    I29 @T6G_MB_LIB.T6G(SCH_1):PAGE194
     2 PVDDCR_CPU1_P1_VCC3 @T6G_MB_LIB.T6G(SCH_1):PVDDCR_CPU1_P1_VCC3    I29 @T6G_MB_LIB.T6G(SCH_1):PAGE194

PR266 Q_RES_0402LF-5.6,1%,1/16W,CHIP,CS-5602FB01
     1 SW_PVDDCR_CPU1_P1_BOOT4 @T6G_MB_LIB.T6G(SCH_1):SW_PVDDCR_CPU1_P1_BOOT4    I36 @T6G_MB_LIB.T6G(SCH_1):PAGE194
     2 SW_PVDDCR_CPU1_P1_BOOT4_R @T6G_MB_LIB.T6G(SCH_1):SW_PVDDCR_CPU1_P1_BOOT4_R    I36 @T6G_MB_LIB.T6G(SCH_1):PAGE194

PR267 Q_RES_0402LF-5.6,1%,1/16W,CHIP,CS-5602FB01
     1 SW_PVDDCR_CPU1_P1_BOOT3 @T6G_MB_LIB.T6G(SCH_1):SW_PVDDCR_CPU1_P1_BOOT3    I52 @T6G_MB_LIB.T6G(SCH_1):PAGE194
     2 SW_PVDDCR_CPU1_P1_BOOT3_R @T6G_MB_LIB.T6G(SCH_1):SW_PVDDCR_CPU1_P1_BOOT3_R    I52 @T6G_MB_LIB.T6G(SCH_1):PAGE194

PR268 Q_RES_0402LF-0,5%,1/16W,CHIP,CS00002JB13
     1 PVDDCR_CPU1_P1_VOS4 @T6G_MB_LIB.T6G(SCH_1):PVDDCR_CPU1_P1_VOS4    I38 @T6G_MB_LIB.T6G(SCH_1):PAGE194
     2 PVDDCR_CPU1_P1 @T6G_MB_LIB.T6G(SCH_1):PVDDCR_CPU1_P1    I38 @T6G_MB_LIB.T6G(SCH_1):PAGE194

PR269 Q_RES_0402LF-0,5%,1/16W,CHIP,CS00002JB13
     1 PVDDCR_CPU1_P1_VOS3 @T6G_MB_LIB.T6G(SCH_1):PVDDCR_CPU1_P1_VOS3    I49 @T6G_MB_LIB.T6G(SCH_1):PAGE194
     2 PVDDCR_CPU1_P1 @T6G_MB_LIB.T6G(SCH_1):PVDDCR_CPU1_P1    I49 @T6G_MB_LIB.T6G(SCH_1):PAGE194

PR270 Q_RES_0402LF-8.87K,1%,1/16W,EMPTY,CS28872FB01
     1 PVDDCR_CPU1_P1_LSET5 @T6G_MB_LIB.T6G(SCH_1):PVDDCR_CPU1_P1_LSET5    I15 @T6G_MB_LIB.T6G(SCH_1):PAGE195
     2    GND @T6G_MB_LIB.T6G(SCH_1):GND    I15 @T6G_MB_LIB.T6G(SCH_1):PAGE195

PR271 Q_RES_0402LF-2.2,1%,1/16W,CHIP,CS-2202FB01
     1 PVDDCR_CPU1_P1_PVCC @T6G_MB_LIB.T6G(SCH_1):PVDDCR_CPU1_P1_PVCC    I28 @T6G_MB_LIB.T6G(SCH_1):PAGE195
     2 PVDDCR_CPU1_P1_VCC5 @T6G_MB_LIB.T6G(SCH_1):PVDDCR_CPU1_P1_VCC5    I28 @T6G_MB_LIB.T6G(SCH_1):PAGE195

PR272 Q_RES_0402LF-5.6,1%,1/16W,CHIP,CS-5602FB01
     1 SW_PVDDCR_CPU1_P1_BOOT5 @T6G_MB_LIB.T6G(SCH_1):SW_PVDDCR_CPU1_P1_BOOT5    I52 @T6G_MB_LIB.T6G(SCH_1):PAGE195
     2 SW_PVDDCR_CPU1_P1_BOOT5_R @T6G_MB_LIB.T6G(SCH_1):SW_PVDDCR_CPU1_P1_BOOT5_R    I52 @T6G_MB_LIB.T6G(SCH_1):PAGE195

PR273 Q_RES_0402LF-0,5%,1/16W,CHIP,CS00002JB13
     1 PVDDCR_CPU1_P1_VOS5 @T6G_MB_LIB.T6G(SCH_1):PVDDCR_CPU1_P1_VOS5    I49 @T6G_MB_LIB.T6G(SCH_1):PAGE195
     2 PVDDCR_CPU1_P1 @T6G_MB_LIB.T6G(SCH_1):PVDDCR_CPU1_P1    I49 @T6G_MB_LIB.T6G(SCH_1):PAGE195

PR274 Q_RES_0402LF-8.87K,1%,1/16W,EMPTY,CS28872FB01
     1 PVDDIO_P1_LSET2 @T6G_MB_LIB.T6G(SCH_1):PVDDIO_P1_LSET2     I6 @T6G_MB_LIB.T6G(SCH_1):PAGE197
     2    GND @T6G_MB_LIB.T6G(SCH_1):GND     I6 @T6G_MB_LIB.T6G(SCH_1):PAGE197

PR275 Q_RES_0402LF-8.87K,1%,1/16W,EMPTY,CS28872FB01
     1 PVDDIO_P1_LSET1 @T6G_MB_LIB.T6G(SCH_1):PVDDIO_P1_LSET1    I28 @T6G_MB_LIB.T6G(SCH_1):PAGE197
     2    GND @T6G_MB_LIB.T6G(SCH_1):GND    I28 @T6G_MB_LIB.T6G(SCH_1):PAGE197

PR276 Q_RES_0402LF-2.2,1%,1/16W,CHIP,CS-2202FB01
     1 PVDDCR_CPU1_P1_PVCC @T6G_MB_LIB.T6G(SCH_1):PVDDCR_CPU1_P1_PVCC    I13 @T6G_MB_LIB.T6G(SCH_1):PAGE197
     2 PVDDIO_P1_VCC2 @T6G_MB_LIB.T6G(SCH_1):PVDDIO_P1_VCC2    I13 @T6G_MB_LIB.T6G(SCH_1):PAGE197

PR277 Q_RES_0402LF-2.2,1%,1/16W,CHIP,CS-2202FB01
     1 PVDDCR_CPU1_P1_PVCC @T6G_MB_LIB.T6G(SCH_1):PVDDCR_CPU1_P1_PVCC    I35 @T6G_MB_LIB.T6G(SCH_1):PAGE197
     2 PVDDIO_P1_VCC1 @T6G_MB_LIB.T6G(SCH_1):PVDDIO_P1_VCC1    I35 @T6G_MB_LIB.T6G(SCH_1):PAGE197

PR278 Q_RES_0402LF-5.6,1%,1/16W,CHIP,CS-5602FB01
     1 SW_PVDDIO_P1_BOOT2 @T6G_MB_LIB.T6G(SCH_1):SW_PVDDIO_P1_BOOT2    I22 @T6G_MB_LIB.T6G(SCH_1):PAGE197
     2 SW_PVDDIO_P1_BOOT2_R @T6G_MB_LIB.T6G(SCH_1):SW_PVDDIO_P1_BOOT2_R    I22 @T6G_MB_LIB.T6G(SCH_1):PAGE197

PR279 Q_RES_0402LF-5.6,1%,1/16W,CHIP,CS-5602FB01
     1 SW_PVDDIO_P1_BOOT1 @T6G_MB_LIB.T6G(SCH_1):SW_PVDDIO_P1_BOOT1    I43 @T6G_MB_LIB.T6G(SCH_1):PAGE197
     2 SW_PVDDIO_P1_BOOT1_R @T6G_MB_LIB.T6G(SCH_1):SW_PVDDIO_P1_BOOT1_R    I43 @T6G_MB_LIB.T6G(SCH_1):PAGE197

PR280 Q_RES_0402LF-0,5%,1/16W,CHIP,CS00002JB13
     1 PVDDIO_P1_VOS1 @T6G_MB_LIB.T6G(SCH_1):PVDDIO_P1_VOS1    I50 @T6G_MB_LIB.T6G(SCH_1):PAGE197
     2 PVDDIO_P1 @T6G_MB_LIB.T6G(SCH_1):PVDDIO_P1    I50 @T6G_MB_LIB.T6G(SCH_1):PAGE197

PR281 Q_RES_0402LF-0,5%,1/16W,CHIP,CS00002JB13
     1 PVDDIO_P1_VOS2 @T6G_MB_LIB.T6G(SCH_1):PVDDIO_P1_VOS2    I45 @T6G_MB_LIB.T6G(SCH_1):PAGE197
     2 PVDDIO_P1 @T6G_MB_LIB.T6G(SCH_1):PVDDIO_P1    I45 @T6G_MB_LIB.T6G(SCH_1):PAGE197

PR283 Q_RES_0402LF-0,5%,1/16W,CHIP,CS00002JB13
     1 SVID_PVDDCR_CPU0_P0_SVTI @T6G_MB_LIB.T6G(SCH_1):SVID_PVDDCR_CPU0_P0_SVTI     I4 @T6G_MB_LIB.T6G(SCH_1):PAGE168
     2    GND @T6G_MB_LIB.T6G(SCH_1):GND     I4 @T6G_MB_LIB.T6G(SCH_1):PAGE168

PR284 Q_RES_0402LF-1K,1%,1/16W,EMPTY,CS21002FB06
     1 PVDD18_S5_P0 @T6G_MB_LIB.T6G(SCH_1):PVDD18_S5_P0    I10 @T6G_MB_LIB.T6G(SCH_1):PAGE168
     2 SVID_PVDDCR_CPU0_P0_SVTI @T6G_MB_LIB.T6G(SCH_1):SVID_PVDDCR_CPU0_P0_SVTI    I10 @T6G_MB_LIB.T6G(SCH_1):PAGE168

PR285 Q_RES_0402LF-1K,1%,1/16W,CHIP,CS21002FB06
     1 P3V3_AUX @T6G_MB_LIB.T6G(SCH_1):P3V3_AUX    I18 @T6G_MB_LIB.T6G(SCH_1):PAGE168
     2 PVDDCR_SOC_P0_EN_GD @T6G_MB_LIB.T6G(SCH_1):PVDDCR_SOC_P0_EN_GD    I18 @T6G_MB_LIB.T6G(SCH_1):PAGE168

PR288 Q_RES_0402LF-49.9,1%,1/16W,CHIP,CS04992FB07
     1 VSENSE_VSS_SENSE_C_P1 @T6G_MB_LIB.T6G(SCH_1):VSENSE_VSS_SENSE_C_P1    I15 @T6G_MB_LIB.T6G(SCH_1):PAGE199
     2    GND @T6G_MB_LIB.T6G(SCH_1):GND    I15 @T6G_MB_LIB.T6G(SCH_1):PAGE199

PR290 Q_RES_0402LF-40.2K,1%,1/16W,CHIP,CS34022FB04
     1 P5V_AUX @T6G_MB_LIB.T6G(SCH_1):P5V_AUX    I15 @T6G_MB_LIB.T6G(SCH_1):PAGE168
     2 PVDDCR_CPU0_P0_VMON @T6G_MB_LIB.T6G(SCH_1):PVDDCR_CPU0_P0_VMON    I15 @T6G_MB_LIB.T6G(SCH_1):PAGE168

PR291 Q_RES_0402LF-1.5,1%,1/8W,EMPTY,CS-1504FB00
     1 SW_PVDDIO_P0_SW4_RC @T6G_MB_LIB.T6G(SCH_1):SW_PVDDIO_P0_SW4_RC    I38 @T6G_MB_LIB.T6G(SCH_1):PAGE181
     2    GND @T6G_MB_LIB.T6G(SCH_1):GND    I38 @T6G_MB_LIB.T6G(SCH_1):PAGE181

PR292 Q_RES_0402LF-681,1%,1/16W,CHIP,CS16812FB02
     1 PVDDCR_SOC_P0_EN//ADDR_CFG @T6G_MB_LIB.T6G(SCH_1):PVDDCR_SOC_P0_EN//ADDR_CFG    I27 @T6G_MB_LIB.T6G(SCH_1):PAGE168
     2    GND @T6G_MB_LIB.T6G(SCH_1):GND    I27 @T6G_MB_LIB.T6G(SCH_1):PAGE168

PR294 Q_RES_0402LF-49.9,1%,1/16W,CHIP,CS04992FB07
     1 PVDDCR_CPU0_P0 @T6G_MB_LIB.T6G(SCH_1):PVDDCR_CPU0_P0    I72 @T6G_MB_LIB.T6G(SCH_1):PAGE168
     2 VSENSE_PVDDCR_CPU0_P0_DP @T6G_MB_LIB.T6G(SCH_1):VSENSE_PVDDCR_CPU0_P0_DP    I72 @T6G_MB_LIB.T6G(SCH_1):PAGE168

PR295 Q_RES_0402LF-49.9,1%,1/16W,CHIP,CS04992FB07
     1 VSENSE_VSS_SENSE_A_P0 @T6G_MB_LIB.T6G(SCH_1):VSENSE_VSS_SENSE_A_P0    I44 @T6G_MB_LIB.T6G(SCH_1):PAGE168
     2    GND @T6G_MB_LIB.T6G(SCH_1):GND    I44 @T6G_MB_LIB.T6G(SCH_1):PAGE168

PR296 Q_RES_0402LF-49.9,1%,1/16W,CHIP,CS04992FB07
     1 PVDDCR_SOC_P0 @T6G_MB_LIB.T6G(SCH_1):PVDDCR_SOC_P0    I40 @T6G_MB_LIB.T6G(SCH_1):PAGE168
     2 VSENSE_PVDDCR_SOC_P0_DP @T6G_MB_LIB.T6G(SCH_1):VSENSE_PVDDCR_SOC_P0_DP    I40 @T6G_MB_LIB.T6G(SCH_1):PAGE168

PR297 Q_RES_0402LF-49.9,1%,1/16W,CHIP,CS04992FB07
     1 VSENSE_VSS_SENSE_A_P0 @T6G_MB_LIB.T6G(SCH_1):VSENSE_VSS_SENSE_A_P0    I36 @T6G_MB_LIB.T6G(SCH_1):PAGE168
     2    GND @T6G_MB_LIB.T6G(SCH_1):GND    I36 @T6G_MB_LIB.T6G(SCH_1):PAGE168

PR302 Q_RES_0402LF-0,5%,1/16W,CHIP,CS00002JB13
     1 SVID_PVDDCR_CPU0_P0_SVC_R @T6G_MB_LIB.T6G(SCH_1):SVID_PVDDCR_CPU0_P0_SVC_R   I323 @T6G_MB_LIB.T6G(SCH_1):PAGE27
     2 SVID_PVDDCR_CPU0_P0_SVC @T6G_MB_LIB.T6G(SCH_1):SVID_PVDDCR_CPU0_P0_SVC   I323 @T6G_MB_LIB.T6G(SCH_1):PAGE27

PR303 Q_RES_0402LF-0,5%,1/16W,CHIP,CS00002JB13
     1 SVID_PVDDCR_CPU0_P0_SVD_R @T6G_MB_LIB.T6G(SCH_1):SVID_PVDDCR_CPU0_P0_SVD_R   I322 @T6G_MB_LIB.T6G(SCH_1):PAGE27
     2 SVID_PVDDCR_CPU0_P0_SVD @T6G_MB_LIB.T6G(SCH_1):SVID_PVDDCR_CPU0_P0_SVD   I322 @T6G_MB_LIB.T6G(SCH_1):PAGE27

PR305 Q_RES_0402LF-0,5%,1/16W,CHIP,CS00002JB13
     1 SVID_PVDDCR_CPU0_P0_SVTI @T6G_MB_LIB.T6G(SCH_1):SVID_PVDDCR_CPU0_P0_SVTI    I86 @T6G_MB_LIB.T6G(SCH_1):PAGE168
     2 SVID_PVDDCR_CPU0_P0_SVTI_R @T6G_MB_LIB.T6G(SCH_1):SVID_PVDDCR_CPU0_P0_SVTI_R    I86 @T6G_MB_LIB.T6G(SCH_1):PAGE168

PR306 Q_RES_0402LF-0,5%,1/16W,CHIP,CS00002JB13
     1 VSENSE_PVDDCR_CPU0_P0_DP @T6G_MB_LIB.T6G(SCH_1):VSENSE_PVDDCR_CPU0_P0_DP    I61 @T6G_MB_LIB.T6G(SCH_1):PAGE168
     2 VSENSE_PVDDCR_CPU0_P0_VSEN0 @T6G_MB_LIB.T6G(SCH_1):VSENSE_PVDDCR_CPU0_P0_VSEN0    I61 @T6G_MB_LIB.T6G(SCH_1):PAGE168

PR307 Q_RES_0402LF-0,5%,1/16W,CHIP,CS00002JB13
     1 VSENSE_PVDDCR_SOC_P0_DP @T6G_MB_LIB.T6G(SCH_1):VSENSE_PVDDCR_SOC_P0_DP    I59 @T6G_MB_LIB.T6G(SCH_1):PAGE168
     2 VSENSE_PVDDCR_SOC_P0_VSEN1 @T6G_MB_LIB.T6G(SCH_1):VSENSE_PVDDCR_SOC_P0_VSEN1    I59 @T6G_MB_LIB.T6G(SCH_1):PAGE168

PR314 Q_RES_0402LF-0,5%,1/16W,CHIP,CS00002JB13
     1 P12V_AUX @T6G_MB_LIB.T6G(SCH_1):P12V_AUX    I48 @T6G_MB_LIB.T6G(SCH_1):PAGE168
     2 PVDDCR_CPU0_P0_VINSEN @T6G_MB_LIB.T6G(SCH_1):PVDDCR_CPU0_P0_VINSEN    I48 @T6G_MB_LIB.T6G(SCH_1):PAGE168

PR316 Q_RES_0402LF-1,1%,1/16W,CHIP,CS-1002FB04
     1 PVDDCR_CPU0_P0_VCC @T6G_MB_LIB.T6G(SCH_1):PVDDCR_CPU0_P0_VCC   I133 @T6G_MB_LIB.T6G(SCH_1):PAGE168
     2 P3V3_AUX @T6G_MB_LIB.T6G(SCH_1):P3V3_AUX   I133 @T6G_MB_LIB.T6G(SCH_1):PAGE168

PR318 Q_RES_0402LF-2.2,1%,1/16W,CHIP,CS-2202FB01
     1 PVDDCR_CPU0_P0_PVCC @T6G_MB_LIB.T6G(SCH_1):PVDDCR_CPU0_P0_PVCC    I49 @T6G_MB_LIB.T6G(SCH_1):PAGE169
     2 PVDDCR_CPU0_P0_VCC1 @T6G_MB_LIB.T6G(SCH_1):PVDDCR_CPU0_P0_VCC1    I49 @T6G_MB_LIB.T6G(SCH_1):PAGE169

PR319 Q_RES_0402LF-2.2,1%,1/16W,CHIP,CS-2202FB01
     1 PVDDCR_CPU0_P0_PVCC @T6G_MB_LIB.T6G(SCH_1):PVDDCR_CPU0_P0_PVCC    I17 @T6G_MB_LIB.T6G(SCH_1):PAGE169
     2 PVDDCR_CPU0_P0_VCC2 @T6G_MB_LIB.T6G(SCH_1):PVDDCR_CPU0_P0_VCC2    I17 @T6G_MB_LIB.T6G(SCH_1):PAGE169

PR320 Q_RES_0402LF-8.87K,1%,1/16W,EMPTY,CS28872FB01
     1    GND @T6G_MB_LIB.T6G(SCH_1):GND    I46 @T6G_MB_LIB.T6G(SCH_1):PAGE169
     2 PVDDCR_CPU0_P0_LSET1 @T6G_MB_LIB.T6G(SCH_1):PVDDCR_CPU0_P0_LSET1    I46 @T6G_MB_LIB.T6G(SCH_1):PAGE169

PR321 Q_RES_0402LF-8.87K,1%,1/16W,EMPTY,CS28872FB01
     1    GND @T6G_MB_LIB.T6G(SCH_1):GND    I10 @T6G_MB_LIB.T6G(SCH_1):PAGE169
     2 PVDDCR_CPU0_P0_LSET2 @T6G_MB_LIB.T6G(SCH_1):PVDDCR_CPU0_P0_LSET2    I10 @T6G_MB_LIB.T6G(SCH_1):PAGE169

PR322 Q_RES_0402LF-5.6,1%,1/16W,CHIP,CS-5602FB01
     1 SW_PVDDCR_CPU0_P0_BOOT1 @T6G_MB_LIB.T6G(SCH_1):SW_PVDDCR_CPU0_P0_BOOT1    I55 @T6G_MB_LIB.T6G(SCH_1):PAGE169
     2 SW_PVDDCR_CPU0_P0_BOOT1_RC @T6G_MB_LIB.T6G(SCH_1):SW_PVDDCR_CPU0_P0_BOOT1_RC    I55 @T6G_MB_LIB.T6G(SCH_1):PAGE169

PR323 Q_RES_0402LF-5.6,1%,1/16W,CHIP,CS-5602FB01
     1 SW_PVDDCR_CPU0_P0_BOOT2 @T6G_MB_LIB.T6G(SCH_1):SW_PVDDCR_CPU0_P0_BOOT2    I32 @T6G_MB_LIB.T6G(SCH_1):PAGE169
     2 SW_PVDDCR_CPU0_P0_BOOT2_RC @T6G_MB_LIB.T6G(SCH_1):SW_PVDDCR_CPU0_P0_BOOT2_RC    I32 @T6G_MB_LIB.T6G(SCH_1):PAGE169

PR324 Q_RES_0402LF-0,5%,1/16W,CHIP,CS00002JB13
     1 PVDDCR_CPU0_P0_VOS1 @T6G_MB_LIB.T6G(SCH_1):PVDDCR_CPU0_P0_VOS1    I43 @T6G_MB_LIB.T6G(SCH_1):PAGE169
     2 PVDDCR_CPU0_P0 @T6G_MB_LIB.T6G(SCH_1):PVDDCR_CPU0_P0    I43 @T6G_MB_LIB.T6G(SCH_1):PAGE169

PR325 Q_RES_0402LF-0,5%,1/16W,CHIP,CS00002JB13
     1 PVDDCR_CPU0_P0_VOS2 @T6G_MB_LIB.T6G(SCH_1):PVDDCR_CPU0_P0_VOS2    I30 @T6G_MB_LIB.T6G(SCH_1):PAGE169
     2 PVDDCR_CPU0_P0 @T6G_MB_LIB.T6G(SCH_1):PVDDCR_CPU0_P0    I30 @T6G_MB_LIB.T6G(SCH_1):PAGE169

PR326 Q_RES_0402LF-2.2,1%,1/16W,CHIP,CS-2202FB01
     1 PVDD11_S3_P1_PVCC @T6G_MB_LIB.T6G(SCH_1):PVDD11_S3_P1_PVCC    I40 @T6G_MB_LIB.T6G(SCH_1):PAGE200
     2 PVDD11_S3_P1_VCC1 @T6G_MB_LIB.T6G(SCH_1):PVDD11_S3_P1_VCC1    I40 @T6G_MB_LIB.T6G(SCH_1):PAGE200

PR327 Q_RES_0402LF-2.2,1%,1/16W,CHIP,CS-2202FB01
     1 PVDD11_S3_P1_PVCC @T6G_MB_LIB.T6G(SCH_1):PVDD11_S3_P1_PVCC    I14 @T6G_MB_LIB.T6G(SCH_1):PAGE200
     2 PVDD11_S3_P1_VCC2 @T6G_MB_LIB.T6G(SCH_1):PVDD11_S3_P1_VCC2    I14 @T6G_MB_LIB.T6G(SCH_1):PAGE200

PR328 Q_RES_0402LF-4.87K,1%,1/16W,EMPTY,CS24872FB07
     1    GND @T6G_MB_LIB.T6G(SCH_1):GND    I37 @T6G_MB_LIB.T6G(SCH_1):PAGE200
     2 PVDD11_S3_P1_LSET1 @T6G_MB_LIB.T6G(SCH_1):PVDD11_S3_P1_LSET1    I37 @T6G_MB_LIB.T6G(SCH_1):PAGE200

PR329 Q_RES_0402LF-4.87K,1%,1/16W,EMPTY,CS24872FB07
     1    GND @T6G_MB_LIB.T6G(SCH_1):GND    I12 @T6G_MB_LIB.T6G(SCH_1):PAGE200
     2 PVDD11_S3_P1_LSET2 @T6G_MB_LIB.T6G(SCH_1):PVDD11_S3_P1_LSET2    I12 @T6G_MB_LIB.T6G(SCH_1):PAGE200

PR330 Q_RES_0402LF-5.6,1%,1/16W,CHIP,CS-5602FB01
     1 SW_PVDD11_S3_P1_BOOT1 @T6G_MB_LIB.T6G(SCH_1):SW_PVDD11_S3_P1_BOOT1    I47 @T6G_MB_LIB.T6G(SCH_1):PAGE200
     2 SW_PVDD11_S3_P1_BOOT1_RC @T6G_MB_LIB.T6G(SCH_1):SW_PVDD11_S3_P1_BOOT1_RC    I47 @T6G_MB_LIB.T6G(SCH_1):PAGE200

PR331 Q_RES_0402LF-5.6,1%,1/16W,CHIP,CS-5602FB01
     1 SW_PVDD11_S3_P1_BOOT2 @T6G_MB_LIB.T6G(SCH_1):SW_PVDD11_S3_P1_BOOT2    I26 @T6G_MB_LIB.T6G(SCH_1):PAGE200
     2 SW_PVDD11_S3_P1_BOOT2_RC @T6G_MB_LIB.T6G(SCH_1):SW_PVDD11_S3_P1_BOOT2_RC    I26 @T6G_MB_LIB.T6G(SCH_1):PAGE200

PR332 Q_RES_0402LF-0,5%,1/16W,CHIP,CS00002JB13
     1 PVDD11_S3_P1_VOS1 @T6G_MB_LIB.T6G(SCH_1):PVDD11_S3_P1_VOS1    I60 @T6G_MB_LIB.T6G(SCH_1):PAGE200
     2 PVDD11_S3_P1 @T6G_MB_LIB.T6G(SCH_1):PVDD11_S3_P1    I60 @T6G_MB_LIB.T6G(SCH_1):PAGE200

PR333 Q_RES_0402LF-0,5%,1/16W,CHIP,CS00002JB13
     1 PVDD11_S3_P1_VOS2 @T6G_MB_LIB.T6G(SCH_1):PVDD11_S3_P1_VOS2    I53 @T6G_MB_LIB.T6G(SCH_1):PAGE200
     2 PVDD11_S3_P1 @T6G_MB_LIB.T6G(SCH_1):PVDD11_S3_P1    I53 @T6G_MB_LIB.T6G(SCH_1):PAGE200

PR334 Q_RES_0402LF-1K,1%,1/16W,CHIP,CS21002FB06
     1 PVDDCR_SOC_P0 @T6G_MB_LIB.T6G(SCH_1):PVDDCR_SOC_P0    I82 @T6G_MB_LIB.T6G(SCH_1):PAGE173
     2    GND @T6G_MB_LIB.T6G(SCH_1):GND    I82 @T6G_MB_LIB.T6G(SCH_1):PAGE173

PR335 Q_RES_0402LF-0,5%,1/16W,CHIP,CS00002JB13
     1 PVDDCR_CPU0_P1_PVCC @T6G_MB_LIB.T6G(SCH_1):PVDDCR_CPU0_P1_PVCC     I3 @T6G_MB_LIB.T6G(SCH_1):PAGE186
     2 P5V_AUX @T6G_MB_LIB.T6G(SCH_1):P5V_AUX     I3 @T6G_MB_LIB.T6G(SCH_1):PAGE186

PR336 Q_RES_0402LF-0,5%,1/16W,EMPTY,CS00002JB13
     1 PVDDCR_CPU0_P1_PVCC @T6G_MB_LIB.T6G(SCH_1):PVDDCR_CPU0_P1_PVCC    I41 @T6G_MB_LIB.T6G(SCH_1):PAGE186
     2 P3V3_AUX @T6G_MB_LIB.T6G(SCH_1):P3V3_AUX    I41 @T6G_MB_LIB.T6G(SCH_1):PAGE186

PR337 Q_RES_0402LF-1K,1%,1/16W,CHIP,CS21002FB06
     1 PVDDCR_CPU0_P1 @T6G_MB_LIB.T6G(SCH_1):PVDDCR_CPU0_P1    I78 @T6G_MB_LIB.T6G(SCH_1):PAGE186
     2    GND @T6G_MB_LIB.T6G(SCH_1):GND    I78 @T6G_MB_LIB.T6G(SCH_1):PAGE186

PR339 Q_RES_0402LF-1K,1%,1/16W,CHIP,CS21002FB06
     1 PVDDCR_SOC_P1 @T6G_MB_LIB.T6G(SCH_1):PVDDCR_SOC_P1    I83 @T6G_MB_LIB.T6G(SCH_1):PAGE190
     2    GND @T6G_MB_LIB.T6G(SCH_1):GND    I83 @T6G_MB_LIB.T6G(SCH_1):PAGE190

PR340 Q_RES_0402LF-0,5%,1/16W,CHIP,CS00002JB13
     1 PVDDCR_CPU1_P1_PVCC @T6G_MB_LIB.T6G(SCH_1):PVDDCR_CPU1_P1_PVCC    I89 @T6G_MB_LIB.T6G(SCH_1):PAGE193
     2 P5V_AUX @T6G_MB_LIB.T6G(SCH_1):P5V_AUX    I89 @T6G_MB_LIB.T6G(SCH_1):PAGE193

PR341 Q_RES_0402LF-0,5%,1/16W,EMPTY,CS00002JB13
     1 PVDDCR_CPU1_P1_PVCC @T6G_MB_LIB.T6G(SCH_1):PVDDCR_CPU1_P1_PVCC    I90 @T6G_MB_LIB.T6G(SCH_1):PAGE193
     2 P3V3_AUX @T6G_MB_LIB.T6G(SCH_1):P3V3_AUX    I90 @T6G_MB_LIB.T6G(SCH_1):PAGE193

PR342 Q_RES_0402LF-1K,1%,1/16W,CHIP,CS21002FB06
     1 PVDDCR_CPU1_P1 @T6G_MB_LIB.T6G(SCH_1):PVDDCR_CPU1_P1    I87 @T6G_MB_LIB.T6G(SCH_1):PAGE193
     2    GND @T6G_MB_LIB.T6G(SCH_1):GND    I87 @T6G_MB_LIB.T6G(SCH_1):PAGE193

PR344 Q_RES_0402LF-2.2,1%,1/16W,CHIP,CS-2202FB01
     1 PVDDCR_CPU0_P0_PVCC @T6G_MB_LIB.T6G(SCH_1):PVDDCR_CPU0_P0_PVCC    I37 @T6G_MB_LIB.T6G(SCH_1):PAGE170
     2 PVDDCR_CPU0_P0_VCC3 @T6G_MB_LIB.T6G(SCH_1):PVDDCR_CPU0_P0_VCC3    I37 @T6G_MB_LIB.T6G(SCH_1):PAGE170

PR345 Q_RES_0402LF-2.2,1%,1/16W,CHIP,CS-2202FB01
     1 PVDDCR_CPU0_P0_PVCC @T6G_MB_LIB.T6G(SCH_1):PVDDCR_CPU0_P0_PVCC    I12 @T6G_MB_LIB.T6G(SCH_1):PAGE170
     2 PVDDCR_CPU0_P0_VCC4 @T6G_MB_LIB.T6G(SCH_1):PVDDCR_CPU0_P0_VCC4    I12 @T6G_MB_LIB.T6G(SCH_1):PAGE170

PR346 Q_RES_0402LF-8.87K,1%,1/16W,EMPTY,CS28872FB01
     1    GND @T6G_MB_LIB.T6G(SCH_1):GND    I33 @T6G_MB_LIB.T6G(SCH_1):PAGE170
     2 PVDDCR_CPU0_P0_LSET3 @T6G_MB_LIB.T6G(SCH_1):PVDDCR_CPU0_P0_LSET3    I33 @T6G_MB_LIB.T6G(SCH_1):PAGE170

PR347 Q_RES_0402LF-8.87K,1%,1/16W,EMPTY,CS28872FB01
     1    GND @T6G_MB_LIB.T6G(SCH_1):GND    I11 @T6G_MB_LIB.T6G(SCH_1):PAGE170
     2 PVDDCR_CPU0_P0_LSET4 @T6G_MB_LIB.T6G(SCH_1):PVDDCR_CPU0_P0_LSET4    I11 @T6G_MB_LIB.T6G(SCH_1):PAGE170

PR348 Q_RES_0402LF-5.6,1%,1/16W,CHIP,CS-5602FB01
     1 SW_PVDDCR_CPU0_P0_BOOT3 @T6G_MB_LIB.T6G(SCH_1):SW_PVDDCR_CPU0_P0_BOOT3    I46 @T6G_MB_LIB.T6G(SCH_1):PAGE170
     2 SW_PVDDCR_CPU0_P0_BOOT3_RC @T6G_MB_LIB.T6G(SCH_1):SW_PVDDCR_CPU0_P0_BOOT3_RC    I46 @T6G_MB_LIB.T6G(SCH_1):PAGE170

PR349 Q_RES_0402LF-5.6,1%,1/16W,CHIP,CS-5602FB01
     1 SW_PVDDCR_CPU0_P0_BOOT4 @T6G_MB_LIB.T6G(SCH_1):SW_PVDDCR_CPU0_P0_BOOT4    I20 @T6G_MB_LIB.T6G(SCH_1):PAGE170
     2 SW_PVDDCR_CPU0_P0_BOOT4_RC @T6G_MB_LIB.T6G(SCH_1):SW_PVDDCR_CPU0_P0_BOOT4_RC    I20 @T6G_MB_LIB.T6G(SCH_1):PAGE170

PR350 Q_RES_0402LF-0,5%,1/16W,CHIP,CS00002JB13
     1 PVDDCR_CPU0_P0_VOS3 @T6G_MB_LIB.T6G(SCH_1):PVDDCR_CPU0_P0_VOS3    I26 @T6G_MB_LIB.T6G(SCH_1):PAGE170
     2 PVDDCR_CPU0_P0 @T6G_MB_LIB.T6G(SCH_1):PVDDCR_CPU0_P0    I26 @T6G_MB_LIB.T6G(SCH_1):PAGE170

PR351 Q_RES_0402LF-0,5%,1/16W,CHIP,CS00002JB13
     1 PVDDCR_CPU0_P0_VOS4 @T6G_MB_LIB.T6G(SCH_1):PVDDCR_CPU0_P0_VOS4    I50 @T6G_MB_LIB.T6G(SCH_1):PAGE170
     2 PVDDCR_CPU0_P0 @T6G_MB_LIB.T6G(SCH_1):PVDDCR_CPU0_P0    I50 @T6G_MB_LIB.T6G(SCH_1):PAGE170

PR352 Q_RES_0402LF-2.2,1%,1/16W,CHIP,CS-2202FB01
     1 PVDDCR_CPU0_P0_PVCC @T6G_MB_LIB.T6G(SCH_1):PVDDCR_CPU0_P0_PVCC    I40 @T6G_MB_LIB.T6G(SCH_1):PAGE171
     2 PVDDCR_CPU0_P0_VCC5 @T6G_MB_LIB.T6G(SCH_1):PVDDCR_CPU0_P0_VCC5    I40 @T6G_MB_LIB.T6G(SCH_1):PAGE171

PR353 Q_RES_0402LF-8.87K,1%,1/16W,EMPTY,CS28872FB01
     1    GND @T6G_MB_LIB.T6G(SCH_1):GND    I36 @T6G_MB_LIB.T6G(SCH_1):PAGE171
     2 PVDDCR_CPU0_P0_LSET5 @T6G_MB_LIB.T6G(SCH_1):PVDDCR_CPU0_P0_LSET5    I36 @T6G_MB_LIB.T6G(SCH_1):PAGE171

PR354 Q_RES_0402LF-5.6,1%,1/16W,CHIP,CS-5602FB01
     1 SW_PVDDCR_CPU0_P0_BOOT5 @T6G_MB_LIB.T6G(SCH_1):SW_PVDDCR_CPU0_P0_BOOT5    I45 @T6G_MB_LIB.T6G(SCH_1):PAGE171
     2 SW_PVDDCR_CPU0_P0_BOOT5_RC @T6G_MB_LIB.T6G(SCH_1):SW_PVDDCR_CPU0_P0_BOOT5_RC    I45 @T6G_MB_LIB.T6G(SCH_1):PAGE171

PR355 Q_RES_0402LF-0,5%,1/16W,CHIP,CS00002JB13
     1 PVDDCR_CPU0_P0_VOS5 @T6G_MB_LIB.T6G(SCH_1):PVDDCR_CPU0_P0_VOS5    I32 @T6G_MB_LIB.T6G(SCH_1):PAGE171
     2 PVDDCR_CPU0_P0 @T6G_MB_LIB.T6G(SCH_1):PVDDCR_CPU0_P0    I32 @T6G_MB_LIB.T6G(SCH_1):PAGE171

PR356 Q_RES_0402LF-2.2,1%,1/16W,CHIP,CS-2202FB01
     1 PVDDCR_CPU0_P0_PVCC @T6G_MB_LIB.T6G(SCH_1):PVDDCR_CPU0_P0_PVCC    I38 @T6G_MB_LIB.T6G(SCH_1):PAGE173
     2 PVDDCR_SOC_P0_VCC1 @T6G_MB_LIB.T6G(SCH_1):PVDDCR_SOC_P0_VCC1    I38 @T6G_MB_LIB.T6G(SCH_1):PAGE173

PR357 Q_RES_0402LF-2.2,1%,1/16W,CHIP,CS-2202FB01
     1 PVDDCR_CPU0_P0_PVCC @T6G_MB_LIB.T6G(SCH_1):PVDDCR_CPU0_P0_PVCC    I12 @T6G_MB_LIB.T6G(SCH_1):PAGE173
     2 PVDDCR_SOC_P0_VCC2 @T6G_MB_LIB.T6G(SCH_1):PVDDCR_SOC_P0_VCC2    I12 @T6G_MB_LIB.T6G(SCH_1):PAGE173

PR358 Q_RES_0402LF-8.87K,1%,1/16W,EMPTY,CS28872FB01
     1    GND @T6G_MB_LIB.T6G(SCH_1):GND    I32 @T6G_MB_LIB.T6G(SCH_1):PAGE173
     2 PVDDCR_SOC_P0_LSET1 @T6G_MB_LIB.T6G(SCH_1):PVDDCR_SOC_P0_LSET1    I32 @T6G_MB_LIB.T6G(SCH_1):PAGE173

PR359 Q_RES_0402LF-8.87K,1%,1/16W,EMPTY,CS28872FB01
     1    GND @T6G_MB_LIB.T6G(SCH_1):GND     I8 @T6G_MB_LIB.T6G(SCH_1):PAGE173
     2 PVDDCR_SOC_P0_LSET2 @T6G_MB_LIB.T6G(SCH_1):PVDDCR_SOC_P0_LSET2     I8 @T6G_MB_LIB.T6G(SCH_1):PAGE173

PR360 Q_RES_0402LF-5.6,1%,1/16W,CHIP,CS-5602FB01
     1 SW_PVDDCR_SOC_P0_BOOT1 @T6G_MB_LIB.T6G(SCH_1):SW_PVDDCR_SOC_P0_BOOT1    I48 @T6G_MB_LIB.T6G(SCH_1):PAGE173
     2 SW_PVDDCR_SOC_P0_BOOT1_RC @T6G_MB_LIB.T6G(SCH_1):SW_PVDDCR_SOC_P0_BOOT1_RC    I48 @T6G_MB_LIB.T6G(SCH_1):PAGE173

PR361 Q_RES_0402LF-5.6,1%,1/16W,CHIP,CS-5602FB01
     1 SW_PVDDCR_SOC_P0_BOOT2 @T6G_MB_LIB.T6G(SCH_1):SW_PVDDCR_SOC_P0_BOOT2    I22 @T6G_MB_LIB.T6G(SCH_1):PAGE173
     2 SW_PVDDCR_SOC_P0_BOOT2_RC @T6G_MB_LIB.T6G(SCH_1):SW_PVDDCR_SOC_P0_BOOT2_RC    I22 @T6G_MB_LIB.T6G(SCH_1):PAGE173

PR362 Q_RES_0402LF-0,5%,1/16W,CHIP,CS00002JB13
     1 PVDDCR_SOC_P0_VOS1 @T6G_MB_LIB.T6G(SCH_1):PVDDCR_SOC_P0_VOS1    I27 @T6G_MB_LIB.T6G(SCH_1):PAGE173
     2 PVDDCR_SOC_P0 @T6G_MB_LIB.T6G(SCH_1):PVDDCR_SOC_P0    I27 @T6G_MB_LIB.T6G(SCH_1):PAGE173

PR363 Q_RES_0402LF-0,5%,1/16W,CHIP,CS00002JB13
     1 PVDDCR_SOC_P0_VOS2 @T6G_MB_LIB.T6G(SCH_1):PVDDCR_SOC_P0_VOS2    I18 @T6G_MB_LIB.T6G(SCH_1):PAGE173
     2 PVDDCR_SOC_P0 @T6G_MB_LIB.T6G(SCH_1):PVDDCR_SOC_P0    I18 @T6G_MB_LIB.T6G(SCH_1):PAGE173

PR364 Q_RES_0402LF-2.2,1%,1/16W,CHIP,CS-2202FB01
     1 PVDDCR_CPU0_P0_PVCC @T6G_MB_LIB.T6G(SCH_1):PVDDCR_CPU0_P0_PVCC    I15 @T6G_MB_LIB.T6G(SCH_1):PAGE174
     2 PVDDCR_SOC_P0_VCC3 @T6G_MB_LIB.T6G(SCH_1):PVDDCR_SOC_P0_VCC3    I15 @T6G_MB_LIB.T6G(SCH_1):PAGE174

PR365 Q_RES_0402LF-8.87K,1%,1/16W,EMPTY,CS28872FB01
     1    GND @T6G_MB_LIB.T6G(SCH_1):GND     I7 @T6G_MB_LIB.T6G(SCH_1):PAGE174
     2 PVDDCR_SOC_P0_LSET3 @T6G_MB_LIB.T6G(SCH_1):PVDDCR_SOC_P0_LSET3     I7 @T6G_MB_LIB.T6G(SCH_1):PAGE174

PR366 Q_RES_0402LF-5.6,1%,1/16W,CHIP,CS-5602FB01
     1 SW_PVDDCR_SOC_P0_BOOT3 @T6G_MB_LIB.T6G(SCH_1):SW_PVDDCR_SOC_P0_BOOT3    I20 @T6G_MB_LIB.T6G(SCH_1):PAGE174
     2 SW_PVDDCR_SOC_P0_BOOT3_RC @T6G_MB_LIB.T6G(SCH_1):SW_PVDDCR_SOC_P0_BOOT3_RC    I20 @T6G_MB_LIB.T6G(SCH_1):PAGE174

PR367 Q_RES_0402LF-0,5%,1/16W,CHIP,CS00002JB13
     1 PVDDCR_SOC_P0_VOS3 @T6G_MB_LIB.T6G(SCH_1):PVDDCR_SOC_P0_VOS3    I11 @T6G_MB_LIB.T6G(SCH_1):PAGE174
     2 PVDDCR_SOC_P0 @T6G_MB_LIB.T6G(SCH_1):PVDDCR_SOC_P0    I11 @T6G_MB_LIB.T6G(SCH_1):PAGE174

PR368 Q_RES_0402LF-8.87K,1%,1/16W,EMPTY,CS28872FB01
     1 PVDDIO_P1_LSET4 @T6G_MB_LIB.T6G(SCH_1):PVDDIO_P1_LSET4     I4 @T6G_MB_LIB.T6G(SCH_1):PAGE198
     2    GND @T6G_MB_LIB.T6G(SCH_1):GND     I4 @T6G_MB_LIB.T6G(SCH_1):PAGE198

PR369 Q_RES_0402LF-8.87K,1%,1/16W,EMPTY,CS28872FB01
     1 PVDDIO_P1_LSET3 @T6G_MB_LIB.T6G(SCH_1):PVDDIO_P1_LSET3    I22 @T6G_MB_LIB.T6G(SCH_1):PAGE198
     2    GND @T6G_MB_LIB.T6G(SCH_1):GND    I22 @T6G_MB_LIB.T6G(SCH_1):PAGE198

PR370 Q_RES_0402LF-2.2,1%,1/16W,CHIP,CS-2202FB01
     1 PVDDCR_CPU1_P1_PVCC @T6G_MB_LIB.T6G(SCH_1):PVDDCR_CPU1_P1_PVCC    I12 @T6G_MB_LIB.T6G(SCH_1):PAGE198
     2 PVDDIO_P1_VCC4 @T6G_MB_LIB.T6G(SCH_1):PVDDIO_P1_VCC4    I12 @T6G_MB_LIB.T6G(SCH_1):PAGE198

PR371 Q_RES_0402LF-2.2,1%,1/16W,CHIP,CS-2202FB01
     1 PVDDCR_CPU1_P1_PVCC @T6G_MB_LIB.T6G(SCH_1):PVDDCR_CPU1_P1_PVCC    I29 @T6G_MB_LIB.T6G(SCH_1):PAGE198
     2 PVDDIO_P1_VCC3 @T6G_MB_LIB.T6G(SCH_1):PVDDIO_P1_VCC3    I29 @T6G_MB_LIB.T6G(SCH_1):PAGE198

PR372 Q_RES_0402LF-5.6,1%,1/16W,CHIP,CS-5602FB01
     1 SW_PVDDIO_P1_BOOT4 @T6G_MB_LIB.T6G(SCH_1):SW_PVDDIO_P1_BOOT4    I17 @T6G_MB_LIB.T6G(SCH_1):PAGE198
     2 SW_PVDDIO_P1_BOOT4_R @T6G_MB_LIB.T6G(SCH_1):SW_PVDDIO_P1_BOOT4_R    I17 @T6G_MB_LIB.T6G(SCH_1):PAGE198

PR373 Q_RES_0402LF-5.6,1%,1/16W,CHIP,CS-5602FB01
     1 SW_PVDDIO_P1_BOOT3 @T6G_MB_LIB.T6G(SCH_1):SW_PVDDIO_P1_BOOT3    I34 @T6G_MB_LIB.T6G(SCH_1):PAGE198
     2 SW_PVDDIO_P1_BOOT3_R @T6G_MB_LIB.T6G(SCH_1):SW_PVDDIO_P1_BOOT3_R    I34 @T6G_MB_LIB.T6G(SCH_1):PAGE198

PR374 Q_RES_0402LF-0,5%,1/16W,CHIP,CS00002JB13
     1 PVDDIO_P1_VOS3 @T6G_MB_LIB.T6G(SCH_1):PVDDIO_P1_VOS3    I55 @T6G_MB_LIB.T6G(SCH_1):PAGE198
     2 PVDDIO_P1 @T6G_MB_LIB.T6G(SCH_1):PVDDIO_P1    I55 @T6G_MB_LIB.T6G(SCH_1):PAGE198

PR375 Q_RES_0402LF-0,5%,1/16W,CHIP,CS00002JB13
     1 PVDDIO_P1_VOS4 @T6G_MB_LIB.T6G(SCH_1):PVDDIO_P1_VOS4    I41 @T6G_MB_LIB.T6G(SCH_1):PAGE198
     2 PVDDIO_P1 @T6G_MB_LIB.T6G(SCH_1):PVDDIO_P1    I41 @T6G_MB_LIB.T6G(SCH_1):PAGE198

PR376 Q_RES_0402LF-40.2K,1%,1/16W,CHIP,CS34022FB04
     1 P5V_AUX @T6G_MB_LIB.T6G(SCH_1):P5V_AUX     I2 @T6G_MB_LIB.T6G(SCH_1):PAGE199
     2 PVDD11_S3_P1_VMON @T6G_MB_LIB.T6G(SCH_1):PVDD11_S3_P1_VMON     I2 @T6G_MB_LIB.T6G(SCH_1):PAGE199

PR378 Q_RES_0402LF-1K,1%,1/16W,CHIP,CS21002FB06
     1 PVDDIO_P1 @T6G_MB_LIB.T6G(SCH_1):PVDDIO_P1    I81 @T6G_MB_LIB.T6G(SCH_1):PAGE197
     2    GND @T6G_MB_LIB.T6G(SCH_1):GND    I81 @T6G_MB_LIB.T6G(SCH_1):PAGE197

PR379 Q_RES_0402LF-1.5,1%,1/8W,EMPTY,CS-1504FB00
     1 SW_PVDDIO_P0_SW3_RC @T6G_MB_LIB.T6G(SCH_1):SW_PVDDIO_P0_SW3_RC    I55 @T6G_MB_LIB.T6G(SCH_1):PAGE181
     2    GND @T6G_MB_LIB.T6G(SCH_1):GND    I55 @T6G_MB_LIB.T6G(SCH_1):PAGE181

PR384 Q_RES_0402LF-0,5%,1/16W,CHIP,CS00002JB13
     1 VSENSE_PVDD11_S3_P1_DP @T6G_MB_LIB.T6G(SCH_1):VSENSE_PVDD11_S3_P1_DP    I27 @T6G_MB_LIB.T6G(SCH_1):PAGE199
     2 VSENSE_PVDD11_S3_P1_R @T6G_MB_LIB.T6G(SCH_1):VSENSE_PVDD11_S3_P1_R    I27 @T6G_MB_LIB.T6G(SCH_1):PAGE199

PR387 Q_RES_0402LF-0,5%,1/16W,CHIP,CS00002JB13
     1 PVDD11_S3_P1_PVCC @T6G_MB_LIB.T6G(SCH_1):PVDD11_S3_P1_PVCC     I3 @T6G_MB_LIB.T6G(SCH_1):PAGE200
     2 P5V_AUX @T6G_MB_LIB.T6G(SCH_1):P5V_AUX     I3 @T6G_MB_LIB.T6G(SCH_1):PAGE200

PR388 Q_RES_0402LF-0,5%,1/16W,CHIP,CS00002JB13
     1 P12V_AUX @T6G_MB_LIB.T6G(SCH_1):P12V_AUX    I18 @T6G_MB_LIB.T6G(SCH_1):PAGE199
     2 PVDD11_S3_P1_VINSEN @T6G_MB_LIB.T6G(SCH_1):PVDD11_S3_P1_VINSEN    I18 @T6G_MB_LIB.T6G(SCH_1):PAGE199

PR389 Q_RES_0402LF-1.5,1%,1/8W,EMPTY,CS-1504FB00
     1 SW_PVDD11_S3_P0_SW2_RC @T6G_MB_LIB.T6G(SCH_1):SW_PVDD11_S3_P0_SW2_RC    I24 @T6G_MB_LIB.T6G(SCH_1):PAGE183
     2    GND @T6G_MB_LIB.T6G(SCH_1):GND    I24 @T6G_MB_LIB.T6G(SCH_1):PAGE183

PR390 Q_RES_0402LF-0,5%,1/16W,EMPTY,CS00002JB13
     1 PVDD11_S3_P1_RESET_N_R @T6G_MB_LIB.T6G(SCH_1):PVDD11_S3_P1_RESET_N_R    I56 @T6G_MB_LIB.T6G(SCH_1):PAGE199
     2    GND @T6G_MB_LIB.T6G(SCH_1):GND    I56 @T6G_MB_LIB.T6G(SCH_1):PAGE199

PR391 Q_RES_0402LF-1K,1%,1/16W,EMPTY,CS21002FB06
     1 PVDD11_S3_P1_RESET_N_R @T6G_MB_LIB.T6G(SCH_1):PVDD11_S3_P1_RESET_N_R    I67 @T6G_MB_LIB.T6G(SCH_1):PAGE199
     2 PVDD18_S5_P1 @T6G_MB_LIB.T6G(SCH_1):PVDD18_S5_P1    I67 @T6G_MB_LIB.T6G(SCH_1):PAGE199

PR392 Q_RES_0402LF-0,5%,1/16W,EMPTY,CS00002JB13
     1 PVDD11_S3_P1_RESET_N_R @T6G_MB_LIB.T6G(SCH_1):PVDD11_S3_P1_RESET_N_R    I66 @T6G_MB_LIB.T6G(SCH_1):PAGE199
     2 PVDD11_S3_P1_RESET_N @T6G_MB_LIB.T6G(SCH_1):PVDD11_S3_P1_RESET_N    I66 @T6G_MB_LIB.T6G(SCH_1):PAGE199

PR393 Q_RES_0402LF-1,1%,1/16W,CHIP,CS-1002FB04
     1 PVDD11_S3_P1_VCC @T6G_MB_LIB.T6G(SCH_1):PVDD11_S3_P1_VCC    I84 @T6G_MB_LIB.T6G(SCH_1):PAGE199
     2 P3V3_AUX @T6G_MB_LIB.T6G(SCH_1):P3V3_AUX    I84 @T6G_MB_LIB.T6G(SCH_1):PAGE199

PR394 Q_RES_0402LF-0,5%,1/16W,EMPTY,CS00002JB13
     1 PVDD11_S3_P1_PVCC @T6G_MB_LIB.T6G(SCH_1):PVDD11_S3_P1_PVCC    I41 @T6G_MB_LIB.T6G(SCH_1):PAGE200
     2 P3V3_AUX @T6G_MB_LIB.T6G(SCH_1):P3V3_AUX    I41 @T6G_MB_LIB.T6G(SCH_1):PAGE200

PR395 Q_RES_0402LF-1K,1%,1/16W,CHIP,CS21002FB06
     1 PVDD11_S3_P1 @T6G_MB_LIB.T6G(SCH_1):PVDD11_S3_P1    I89 @T6G_MB_LIB.T6G(SCH_1):PAGE200
     2    GND @T6G_MB_LIB.T6G(SCH_1):GND    I89 @T6G_MB_LIB.T6G(SCH_1):PAGE200

PR397 Q_RES_0402LF-0,5%,1/16W,CHIP,CS00002JB13
     1 P3V3_AUX @T6G_MB_LIB.T6G(SCH_1):P3V3_AUX    I12 @T6G_MB_LIB.T6G(SCH_1):PAGE201
     2 PVDD18_S5_P1_VCC @T6G_MB_LIB.T6G(SCH_1):PVDD18_S5_P1_VCC    I12 @T6G_MB_LIB.T6G(SCH_1):PAGE201

PR398 Q_RES_0402LF-0,5%,1/16W,CHIP,CS00002JB13
     1    GND @T6G_MB_LIB.T6G(SCH_1):GND    I14 @T6G_MB_LIB.T6G(SCH_1):PAGE201
     2 PVDD18_S5_P1_MODE @T6G_MB_LIB.T6G(SCH_1):PVDD18_S5_P1_MODE    I14 @T6G_MB_LIB.T6G(SCH_1):PAGE201

PR399 Q_RES_0402LF-49.9,1%,1/16W,CHIP,CS04992FB07
     1    GND @T6G_MB_LIB.T6G(SCH_1):GND    I29 @T6G_MB_LIB.T6G(SCH_1):PAGE201
     2 PVDD18_SS_P1_RGND @T6G_MB_LIB.T6G(SCH_1):PVDD18_SS_P1_RGND    I29 @T6G_MB_LIB.T6G(SCH_1):PAGE201

PR400 Q_RES_0402LF-10,1%,1/16W,CHIP,CS01002FB07
     1 PVDD18_S5_P1_FB_RC @T6G_MB_LIB.T6G(SCH_1):PVDD18_S5_P1_FB_RC    I36 @T6G_MB_LIB.T6G(SCH_1):PAGE201
     2 VSENSE_PVDD18_S5_P1_DP @T6G_MB_LIB.T6G(SCH_1):VSENSE_PVDD18_S5_P1_DP    I36 @T6G_MB_LIB.T6G(SCH_1):PAGE201

PR401 Q_RES_0402LF-0,5%,1/16W,CHIP,CS00002JB13
     1 PVDD18_SS_P1_RGND @T6G_MB_LIB.T6G(SCH_1):PVDD18_SS_P1_RGND    I35 @T6G_MB_LIB.T6G(SCH_1):PAGE201
     2 VSENSE_PVDD18_S5_P1_DN @T6G_MB_LIB.T6G(SCH_1):VSENSE_PVDD18_S5_P1_DN    I35 @T6G_MB_LIB.T6G(SCH_1):PAGE201

PR402 Q_RES_0402LF-49.9,1%,1/16W,CHIP,CS04992FB07
     1 PVDD18_S5_P1 @T6G_MB_LIB.T6G(SCH_1):PVDD18_S5_P1    I39 @T6G_MB_LIB.T6G(SCH_1):PAGE201
     2 PVDD18_S5_P1_FB_RC @T6G_MB_LIB.T6G(SCH_1):PVDD18_S5_P1_FB_RC    I39 @T6G_MB_LIB.T6G(SCH_1):PAGE201

PR403 Q_RES_0402LF-1K,1%,1/16W,CHIP,CS21002FB06
     1 PVDD18_S5_P1 @T6G_MB_LIB.T6G(SCH_1):PVDD18_S5_P1    I50 @T6G_MB_LIB.T6G(SCH_1):PAGE201
     2    GND @T6G_MB_LIB.T6G(SCH_1):GND    I50 @T6G_MB_LIB.T6G(SCH_1):PAGE201

PR406 Q_RES_0402LF-0,5%,1/16W,CHIP,CS00002JB13
     1 NC_PVDD11_S3_P1_IMON3 @T6G_MB_LIB.T6G(SCH_1):NC_PVDD11_S3_P1_IMON3    I70 @T6G_MB_LIB.T6G(SCH_1):PAGE199
     2    GND @T6G_MB_LIB.T6G(SCH_1):GND    I70 @T6G_MB_LIB.T6G(SCH_1):PAGE199

PR407 Q_RES_0402LF-0,5%,1/16W,CHIP,CS00002JB13
     1 NC_PVDD11_S3_P1_IMON4 @T6G_MB_LIB.T6G(SCH_1):NC_PVDD11_S3_P1_IMON4    I60 @T6G_MB_LIB.T6G(SCH_1):PAGE199
     2    GND @T6G_MB_LIB.T6G(SCH_1):GND    I60 @T6G_MB_LIB.T6G(SCH_1):PAGE199

PR408 Q_RES_0402LF-0,5%,1/16W,CHIP,CS00002JB13
     1 NC_PVDD11_S3_P1_IMON7 @T6G_MB_LIB.T6G(SCH_1):NC_PVDD11_S3_P1_IMON7    I57 @T6G_MB_LIB.T6G(SCH_1):PAGE199
     2    GND @T6G_MB_LIB.T6G(SCH_1):GND    I57 @T6G_MB_LIB.T6G(SCH_1):PAGE199

PR409 Q_RES_0402LF-0,5%,1/16W,CHIP,CS00002JB13
     1 NC_PVDD11_S3_P1_IMON8 @T6G_MB_LIB.T6G(SCH_1):NC_PVDD11_S3_P1_IMON8    I52 @T6G_MB_LIB.T6G(SCH_1):PAGE199
     2    GND @T6G_MB_LIB.T6G(SCH_1):GND    I52 @T6G_MB_LIB.T6G(SCH_1):PAGE199

PR410 Q_RES_0402LF-1K,1%,1/16W,CHIP,CS21002FB06
     1 PVDDIO_P0 @T6G_MB_LIB.T6G(SCH_1):PVDDIO_P0    I78 @T6G_MB_LIB.T6G(SCH_1):PAGE180
     2    GND @T6G_MB_LIB.T6G(SCH_1):GND    I78 @T6G_MB_LIB.T6G(SCH_1):PAGE180

PR411 Q_RES_0402LF-0,5%,1/16W,CHIP,CS00002JB13
     1 PVDD11_S3_P0_PVCC @T6G_MB_LIB.T6G(SCH_1):PVDD11_S3_P0_PVCC    I85 @T6G_MB_LIB.T6G(SCH_1):PAGE183
     2 P5V_AUX @T6G_MB_LIB.T6G(SCH_1):P5V_AUX    I85 @T6G_MB_LIB.T6G(SCH_1):PAGE183

PR412 Q_RES_0402LF-0,5%,1/16W,CHIP,CS00002JB13
     1 PVDD11_S3_P0_TEMP1 @T6G_MB_LIB.T6G(SCH_1):PVDD11_S3_P0_TEMP1    I52 @T6G_MB_LIB.T6G(SCH_1):PAGE182
     2    GND @T6G_MB_LIB.T6G(SCH_1):GND    I52 @T6G_MB_LIB.T6G(SCH_1):PAGE182

PR413 Q_RES_0402LF-0,5%,1/16W,EMPTY,CS00002JB13
     1 PVDD11_S3_P0_PVCC @T6G_MB_LIB.T6G(SCH_1):PVDD11_S3_P0_PVCC    I86 @T6G_MB_LIB.T6G(SCH_1):PAGE183
     2 P3V3_AUX @T6G_MB_LIB.T6G(SCH_1):P3V3_AUX    I86 @T6G_MB_LIB.T6G(SCH_1):PAGE183

PR414 Q_RES_0402LF-1K,1%,1/16W,CHIP,CS21002FB06
     1 PVDD11_S3_P0 @T6G_MB_LIB.T6G(SCH_1):PVDD11_S3_P0    I83 @T6G_MB_LIB.T6G(SCH_1):PAGE183
     2    GND @T6G_MB_LIB.T6G(SCH_1):GND    I83 @T6G_MB_LIB.T6G(SCH_1):PAGE183

PR415 Q_RES_0402LF-0,5%,1/16W,CHIP,CS00002JB13
     1 PVDD11_S3_P1_TEMP1 @T6G_MB_LIB.T6G(SCH_1):PVDD11_S3_P1_TEMP1    I51 @T6G_MB_LIB.T6G(SCH_1):PAGE199
     2    GND @T6G_MB_LIB.T6G(SCH_1):GND    I51 @T6G_MB_LIB.T6G(SCH_1):PAGE199

PR416 Q_RES_0402LF-2.2,1%,1/16W,CHIP,CS-2202FB01
     1 PVDDCR_CPU1_P0_PVCC @T6G_MB_LIB.T6G(SCH_1):PVDDCR_CPU1_P0_PVCC    I13 @T6G_MB_LIB.T6G(SCH_1):PAGE178
     2 PVDDCR_CPU1_P0_VCC6 @T6G_MB_LIB.T6G(SCH_1):PVDDCR_CPU1_P0_VCC6    I13 @T6G_MB_LIB.T6G(SCH_1):PAGE178

PR417 Q_RES_0402LF-0,5%,1/16W,CHIP,CS00002JB13
     1    GND @T6G_MB_LIB.T6G(SCH_1):GND    I15 @T6G_MB_LIB.T6G(SCH_1):PAGE184
     2 PVDD18_S5_P0_MODE @T6G_MB_LIB.T6G(SCH_1):PVDD18_S5_P0_MODE    I15 @T6G_MB_LIB.T6G(SCH_1):PAGE184

PR418 Q_RES_0402LF-49.9,1%,1/16W,CHIP,CS04992FB07
     1    GND @T6G_MB_LIB.T6G(SCH_1):GND    I31 @T6G_MB_LIB.T6G(SCH_1):PAGE184
     2 PVDD18_S5_P0_RGND @T6G_MB_LIB.T6G(SCH_1):PVDD18_S5_P0_RGND    I31 @T6G_MB_LIB.T6G(SCH_1):PAGE184

PR419 Q_RES_0402LF-0,5%,1/16W,CHIP,CS00002JB13
     1 NC_PVDD11_S3_P0_IMON7 @T6G_MB_LIB.T6G(SCH_1):NC_PVDD11_S3_P0_IMON7    I58 @T6G_MB_LIB.T6G(SCH_1):PAGE182
     2    GND @T6G_MB_LIB.T6G(SCH_1):GND    I58 @T6G_MB_LIB.T6G(SCH_1):PAGE182

PR420 Q_RES_0402LF-5.6,1%,1/16W,CHIP,CS-5602FB01
     1 SW_PVDDCR_CPU1_P0_BOOT6 @T6G_MB_LIB.T6G(SCH_1):SW_PVDDCR_CPU1_P0_BOOT6    I39 @T6G_MB_LIB.T6G(SCH_1):PAGE178
     2 SW_PVDDCR_CPU1_P0_BOOT6_R @T6G_MB_LIB.T6G(SCH_1):SW_PVDDCR_CPU1_P0_BOOT6_R    I39 @T6G_MB_LIB.T6G(SCH_1):PAGE178

PR421 Q_RES_0402LF-0,5%,1/16W,CHIP,CS00002JB13
     1 PVDDCR_CPU1_P0_VOS6 @T6G_MB_LIB.T6G(SCH_1):PVDDCR_CPU1_P0_VOS6    I35 @T6G_MB_LIB.T6G(SCH_1):PAGE178
     2 PVDDCR_CPU1_P0 @T6G_MB_LIB.T6G(SCH_1):PVDDCR_CPU1_P0    I35 @T6G_MB_LIB.T6G(SCH_1):PAGE178

PR422 Q_RES_0402LF-2.2,1%,1/16W,CHIP,CS-2202FB01
     1 PVDDCR_CPU0_P1_PVCC @T6G_MB_LIB.T6G(SCH_1):PVDDCR_CPU0_P1_PVCC    I12 @T6G_MB_LIB.T6G(SCH_1):PAGE188
     2 PVDDCR_CPU0_P1_VCC6 @T6G_MB_LIB.T6G(SCH_1):PVDDCR_CPU0_P1_VCC6    I12 @T6G_MB_LIB.T6G(SCH_1):PAGE188

PR423 Q_RES_0402LF-8.87K,1%,1/16W,EMPTY,CS28872FB01
     1    GND @T6G_MB_LIB.T6G(SCH_1):GND     I8 @T6G_MB_LIB.T6G(SCH_1):PAGE188
     2 PVDDCR_CPU0_P1_LSET6 @T6G_MB_LIB.T6G(SCH_1):PVDDCR_CPU0_P1_LSET6     I8 @T6G_MB_LIB.T6G(SCH_1):PAGE188

PR424 Q_RES_0402LF-5.6,1%,1/16W,CHIP,CS-5602FB01
     1 SW_PVDDCR_CPU0_P1_BOOT6 @T6G_MB_LIB.T6G(SCH_1):SW_PVDDCR_CPU0_P1_BOOT6    I28 @T6G_MB_LIB.T6G(SCH_1):PAGE188
     2 SW_PVDDCR_CPU0_P1_BOOT6_RC @T6G_MB_LIB.T6G(SCH_1):SW_PVDDCR_CPU0_P1_BOOT6_RC    I28 @T6G_MB_LIB.T6G(SCH_1):PAGE188

PR425 Q_RES_0402LF-0,5%,1/16W,CHIP,CS00002JB13
     1 PVDDCR_CPU0_P1_VOS6 @T6G_MB_LIB.T6G(SCH_1):PVDDCR_CPU0_P1_VOS6    I22 @T6G_MB_LIB.T6G(SCH_1):PAGE188
     2 PVDDCR_CPU0_P1 @T6G_MB_LIB.T6G(SCH_1):PVDDCR_CPU0_P1    I22 @T6G_MB_LIB.T6G(SCH_1):PAGE188

PR426 Q_RES_0402LF-8.87K,1%,1/16W,EMPTY,CS28872FB01
     1 PVDDCR_CPU1_P1_LSET6 @T6G_MB_LIB.T6G(SCH_1):PVDDCR_CPU1_P1_LSET6     I4 @T6G_MB_LIB.T6G(SCH_1):PAGE195
     2    GND @T6G_MB_LIB.T6G(SCH_1):GND     I4 @T6G_MB_LIB.T6G(SCH_1):PAGE195

PR427 Q_RES_0402LF-2.2,1%,1/16W,CHIP,CS-2202FB01
     1 PVDDCR_CPU1_P1_PVCC @T6G_MB_LIB.T6G(SCH_1):PVDDCR_CPU1_P1_PVCC    I13 @T6G_MB_LIB.T6G(SCH_1):PAGE195
     2 PVDDCR_CPU1_P1_VCC6 @T6G_MB_LIB.T6G(SCH_1):PVDDCR_CPU1_P1_VCC6    I13 @T6G_MB_LIB.T6G(SCH_1):PAGE195

PR428 Q_RES_0402LF-5.6,1%,1/16W,CHIP,CS-5602FB01
     1 SW_PVDDCR_CPU1_P1_BOOT6 @T6G_MB_LIB.T6G(SCH_1):SW_PVDDCR_CPU1_P1_BOOT6    I39 @T6G_MB_LIB.T6G(SCH_1):PAGE195
     2 SW_PVDDCR_CPU1_P1_BOOT6_R @T6G_MB_LIB.T6G(SCH_1):SW_PVDDCR_CPU1_P1_BOOT6_R    I39 @T6G_MB_LIB.T6G(SCH_1):PAGE195

PR429 Q_RES_0402LF-0,5%,1/16W,CHIP,CS00002JB13
     1 PVDDCR_CPU1_P1_VOS6 @T6G_MB_LIB.T6G(SCH_1):PVDDCR_CPU1_P1_VOS6    I35 @T6G_MB_LIB.T6G(SCH_1):PAGE195
     2 PVDDCR_CPU1_P1 @T6G_MB_LIB.T6G(SCH_1):PVDDCR_CPU1_P1    I35 @T6G_MB_LIB.T6G(SCH_1):PAGE195

PR430 Q_RES_0402LF-2.2,1%,1/16W,CHIP,CS-2202FB01
     1 PVDDCR_CPU0_P0_PVCC @T6G_MB_LIB.T6G(SCH_1):PVDDCR_CPU0_P0_PVCC    I13 @T6G_MB_LIB.T6G(SCH_1):PAGE171
     2 PVDDCR_CPU0_P0_VCC6 @T6G_MB_LIB.T6G(SCH_1):PVDDCR_CPU0_P0_VCC6    I13 @T6G_MB_LIB.T6G(SCH_1):PAGE171

PR431 Q_RES_0402LF-8.87K,1%,1/16W,EMPTY,CS28872FB01
     1    GND @T6G_MB_LIB.T6G(SCH_1):GND     I8 @T6G_MB_LIB.T6G(SCH_1):PAGE171
     2 PVDDCR_CPU0_P0_LSET6 @T6G_MB_LIB.T6G(SCH_1):PVDDCR_CPU0_P0_LSET6     I8 @T6G_MB_LIB.T6G(SCH_1):PAGE171

PR432 Q_RES_0402LF-5.6,1%,1/16W,CHIP,CS-5602FB01
     1 SW_PVDDCR_CPU0_P0_BOOT6 @T6G_MB_LIB.T6G(SCH_1):SW_PVDDCR_CPU0_P0_BOOT6    I26 @T6G_MB_LIB.T6G(SCH_1):PAGE171
     2 SW_PVDDCR_CPU0_P0_BOOT6_RC @T6G_MB_LIB.T6G(SCH_1):SW_PVDDCR_CPU0_P0_BOOT6_RC    I26 @T6G_MB_LIB.T6G(SCH_1):PAGE171

PR433 Q_RES_0402LF-0,5%,1/16W,CHIP,CS00002JB13
     1 PVDDCR_CPU0_P0_VOS6 @T6G_MB_LIB.T6G(SCH_1):PVDDCR_CPU0_P0_VOS6    I21 @T6G_MB_LIB.T6G(SCH_1):PAGE171
     2 PVDDCR_CPU0_P0 @T6G_MB_LIB.T6G(SCH_1):PVDDCR_CPU0_P0    I21 @T6G_MB_LIB.T6G(SCH_1):PAGE171

PR434 Q_RES_0402LF-10,1%,1/16W,CHIP,CS01002FB07
     1 PVDD18_S5_P0_FB_RC @T6G_MB_LIB.T6G(SCH_1):PVDD18_S5_P0_FB_RC    I38 @T6G_MB_LIB.T6G(SCH_1):PAGE184
     2 VSENSE_PVDD18_S5_P0_DP @T6G_MB_LIB.T6G(SCH_1):VSENSE_PVDD18_S5_P0_DP    I38 @T6G_MB_LIB.T6G(SCH_1):PAGE184

PR435 Q_RES_0402LF-0,5%,1/16W,CHIP,CS00002JB13
     1 PVDD18_S5_P0_RGND @T6G_MB_LIB.T6G(SCH_1):PVDD18_S5_P0_RGND    I37 @T6G_MB_LIB.T6G(SCH_1):PAGE184
     2 VSENSE_PVDD18_S5_P0_DN @T6G_MB_LIB.T6G(SCH_1):VSENSE_PVDD18_S5_P0_DN    I37 @T6G_MB_LIB.T6G(SCH_1):PAGE184

PR436 Q_RES_0402LF-0,5%,1/16W,CHIP,CS00002JB13
     1 NC_PVDDCR_CPU0_P1_IMON8 @T6G_MB_LIB.T6G(SCH_1):NC_PVDDCR_CPU0_P1_IMON8   I103 @T6G_MB_LIB.T6G(SCH_1):PAGE185
     2    GND @T6G_MB_LIB.T6G(SCH_1):GND   I103 @T6G_MB_LIB.T6G(SCH_1):PAGE185

PR437 Q_RES_0402LF-0,5%,1/16W,CHIP,CS00002JB13
     1 NC_PVDDCR_CPU0_P1_IMON9 @T6G_MB_LIB.T6G(SCH_1):NC_PVDDCR_CPU0_P1_IMON9   I102 @T6G_MB_LIB.T6G(SCH_1):PAGE185
     2    GND @T6G_MB_LIB.T6G(SCH_1):GND   I102 @T6G_MB_LIB.T6G(SCH_1):PAGE185

PR438 Q_RES_0402LF-49.9,1%,1/16W,CHIP,CS04992FB07
     1 PVDD18_S5_P0_FB_RC @T6G_MB_LIB.T6G(SCH_1):PVDD18_S5_P0_FB_RC    I42 @T6G_MB_LIB.T6G(SCH_1):PAGE184
     2 PVDD18_S5_P0 @T6G_MB_LIB.T6G(SCH_1):PVDD18_S5_P0    I42 @T6G_MB_LIB.T6G(SCH_1):PAGE184

PR439 Q_RES_0402LF-1K,1%,1/16W,CHIP,CS21002FB06
     1 PVDD18_S5_P0 @T6G_MB_LIB.T6G(SCH_1):PVDD18_S5_P0    I51 @T6G_MB_LIB.T6G(SCH_1):PAGE184
     2    GND @T6G_MB_LIB.T6G(SCH_1):GND    I51 @T6G_MB_LIB.T6G(SCH_1):PAGE184

PR440 Q_RES_0402LF-0,5%,1/16W,CHIP,CS00002JB13
     1 NC_PVDDCR_CPU0_P0_IMON8 @T6G_MB_LIB.T6G(SCH_1):NC_PVDDCR_CPU0_P0_IMON8   I108 @T6G_MB_LIB.T6G(SCH_1):PAGE168
     2    GND @T6G_MB_LIB.T6G(SCH_1):GND   I108 @T6G_MB_LIB.T6G(SCH_1):PAGE168

PR441 Q_RES_0402LF-0,5%,1/16W,CHIP,CS00002JB13
     1 NC_PVDDCR_CPU0_P0_IMON9 @T6G_MB_LIB.T6G(SCH_1):NC_PVDDCR_CPU0_P0_IMON9   I107 @T6G_MB_LIB.T6G(SCH_1):PAGE168
     2    GND @T6G_MB_LIB.T6G(SCH_1):GND   I107 @T6G_MB_LIB.T6G(SCH_1):PAGE168

PR442 Q_RES_0402LF-0,5%,1/16W,CHIP,CS00002JB13
     1 PVDDCR_CPU1_P0_PVCC @T6G_MB_LIB.T6G(SCH_1):PVDDCR_CPU1_P0_PVCC    I21 @T6G_MB_LIB.T6G(SCH_1):PAGE176
     2 P5V_AUX @T6G_MB_LIB.T6G(SCH_1):P5V_AUX    I21 @T6G_MB_LIB.T6G(SCH_1):PAGE176

PR443 Q_RES_0402LF-0,5%,1/16W,EMPTY,CS00002JB13
     1 PVDDCR_CPU1_P0_PVCC @T6G_MB_LIB.T6G(SCH_1):PVDDCR_CPU1_P0_PVCC    I27 @T6G_MB_LIB.T6G(SCH_1):PAGE176
     2 P3V3_AUX @T6G_MB_LIB.T6G(SCH_1):P3V3_AUX    I27 @T6G_MB_LIB.T6G(SCH_1):PAGE176

PR444 Q_RES_0402LF-1K,1%,1/16W,CHIP,CS21002FB06
     1 PVDDCR_CPU1_P0 @T6G_MB_LIB.T6G(SCH_1):PVDDCR_CPU1_P0    I90 @T6G_MB_LIB.T6G(SCH_1):PAGE176
     2    GND @T6G_MB_LIB.T6G(SCH_1):GND    I90 @T6G_MB_LIB.T6G(SCH_1):PAGE176

PR445 Q_RES_0402LF-0,5%,1/16W,CHIP,CS00002JB13
     1 PVDDCR_CPU0_P0_PVCC @T6G_MB_LIB.T6G(SCH_1):PVDDCR_CPU0_P0_PVCC     I3 @T6G_MB_LIB.T6G(SCH_1):PAGE169
     2 P5V_AUX @T6G_MB_LIB.T6G(SCH_1):P5V_AUX     I3 @T6G_MB_LIB.T6G(SCH_1):PAGE169

PR446 Q_RES_0402LF-0,5%,1/16W,EMPTY,CS00002JB13
     1 PVDDCR_CPU0_P0_PVCC @T6G_MB_LIB.T6G(SCH_1):PVDDCR_CPU0_P0_PVCC     I4 @T6G_MB_LIB.T6G(SCH_1):PAGE169
     2 P3V3_AUX @T6G_MB_LIB.T6G(SCH_1):P3V3_AUX     I4 @T6G_MB_LIB.T6G(SCH_1):PAGE169

PR447 Q_RES_0402LF-1K,1%,1/16W,CHIP,CS21002FB06
     1 PVDDCR_CPU0_P0 @T6G_MB_LIB.T6G(SCH_1):PVDDCR_CPU0_P0    I90 @T6G_MB_LIB.T6G(SCH_1):PAGE169
     2    GND @T6G_MB_LIB.T6G(SCH_1):GND    I90 @T6G_MB_LIB.T6G(SCH_1):PAGE169

PR448 Q_RES_0402LF-8.66K,1%,1/16W,CHIP,CS28662FB02
     1 PVDD18_S5_P0_CS @T6G_MB_LIB.T6G(SCH_1):PVDD18_S5_P0_CS    I17 @T6G_MB_LIB.T6G(SCH_1):PAGE184
     2    GND @T6G_MB_LIB.T6G(SCH_1):GND    I17 @T6G_MB_LIB.T6G(SCH_1):PAGE184

PR452 Q_RES_0402LF-6.98K,1%,1/16W,CHIP,CS26982FB08
     1 PVDD_33_S5_CS @T6G_MB_LIB.T6G(SCH_1):PVDD_33_S5_CS    I15 @T6G_MB_LIB.T6G(SCH_1):PAGE167
     2    GND @T6G_MB_LIB.T6G(SCH_1):GND    I15 @T6G_MB_LIB.T6G(SCH_1):PAGE167

PR454 Q_RES_0402LF-12.4K,1%,1/16W,CHIP,CS31242FB02
     1 PVDD_33_S5_FB @T6G_MB_LIB.T6G(SCH_1):PVDD_33_S5_FB    I23 @T6G_MB_LIB.T6G(SCH_1):PAGE167
     2    GND @T6G_MB_LIB.T6G(SCH_1):GND    I23 @T6G_MB_LIB.T6G(SCH_1):PAGE167

PR455 Q_RES_0402LF-56K,1%,1/16W,CHIP,CS35602FB00
     1 PVDD_33_S5_FB @T6G_MB_LIB.T6G(SCH_1):PVDD_33_S5_FB    I25 @T6G_MB_LIB.T6G(SCH_1):PAGE167
     2 PVDD_33_S5 @T6G_MB_LIB.T6G(SCH_1):PVDD_33_S5    I25 @T6G_MB_LIB.T6G(SCH_1):PAGE167

PR460 Q_RES_0402LF-49.9,1%,1/16W,CHIP,CS04992FB07
     1 VSENSE_VSS_SENSE_B_P1 @T6G_MB_LIB.T6G(SCH_1):VSENSE_VSS_SENSE_B_P1    I19 @T6G_MB_LIB.T6G(SCH_1):PAGE192
     2    GND @T6G_MB_LIB.T6G(SCH_1):GND    I19 @T6G_MB_LIB.T6G(SCH_1):PAGE192

PR464 Q_RES_0402LF-13.7K,1%,1/16W,CHIP,CS31372FB03
     1    GND @T6G_MB_LIB.T6G(SCH_1):GND    I89 @T6G_MB_LIB.T6G(SCH_1):PAGE199
     2 PVDD11_S3_P1_ADDR_CFG @T6G_MB_LIB.T6G(SCH_1):PVDD11_S3_P1_ADDR_CFG    I89 @T6G_MB_LIB.T6G(SCH_1):PAGE199

PR470 Q_RES_0402LF-10K,1%,1/16W,CHIP,CS31002FB08
     1 PVDD18_S5_P0_FB @T6G_MB_LIB.T6G(SCH_1):PVDD18_S5_P0_FB    I23 @T6G_MB_LIB.T6G(SCH_1):PAGE184
     2 PVDD18_S5_P0_RGND @T6G_MB_LIB.T6G(SCH_1):PVDD18_S5_P0_RGND    I23 @T6G_MB_LIB.T6G(SCH_1):PAGE184

PR471 Q_RES_0402LF-20K,1%,1/16W,CHIP,CS32002FB06
     1 PVDD18_S5_P0_FB @T6G_MB_LIB.T6G(SCH_1):PVDD18_S5_P0_FB    I35 @T6G_MB_LIB.T6G(SCH_1):PAGE184
     2 PVDD18_S5_P0_FB_RC @T6G_MB_LIB.T6G(SCH_1):PVDD18_S5_P0_FB_RC    I35 @T6G_MB_LIB.T6G(SCH_1):PAGE184

PR477 Q_RES_0402LF-0,5%,1/16W,CHIP,CS00002JB13
     1 P3V3_AUX @T6G_MB_LIB.T6G(SCH_1):P3V3_AUX    I12 @T6G_MB_LIB.T6G(SCH_1):PAGE184
     2 PVDD18_S5_P0_VCC @T6G_MB_LIB.T6G(SCH_1):PVDD18_S5_P0_VCC    I12 @T6G_MB_LIB.T6G(SCH_1):PAGE184

PR482 Q_RES_0402LF-1.5,1%,1/8W,EMPTY,CS-1504FB00
     1 SW_PVDD11_S3_P0_SW1_RC @T6G_MB_LIB.T6G(SCH_1):SW_PVDD11_S3_P0_SW1_RC    I33 @T6G_MB_LIB.T6G(SCH_1):PAGE183
     2    GND @T6G_MB_LIB.T6G(SCH_1):GND    I33 @T6G_MB_LIB.T6G(SCH_1):PAGE183

PR485 Q_RES_0402LF-1.5,1%,1/8W,EMPTY,CS-1504FB00
     1 SW_PVDDCR_CPU0_P1_SW1_RC @T6G_MB_LIB.T6G(SCH_1):SW_PVDDCR_CPU0_P1_SW1_RC    I34 @T6G_MB_LIB.T6G(SCH_1):PAGE186
     2    GND @T6G_MB_LIB.T6G(SCH_1):GND    I34 @T6G_MB_LIB.T6G(SCH_1):PAGE186

PR486 Q_RES_0402LF-1.5,1%,1/8W,EMPTY,CS-1504FB00
     1 SW_PVDDCR_CPU0_P1_SW2_RC @T6G_MB_LIB.T6G(SCH_1):SW_PVDDCR_CPU0_P1_SW2_RC    I22 @T6G_MB_LIB.T6G(SCH_1):PAGE186
     2    GND @T6G_MB_LIB.T6G(SCH_1):GND    I22 @T6G_MB_LIB.T6G(SCH_1):PAGE186

PR488 Q_RES_0402LF-1.5,1%,1/8W,EMPTY,CS-1504FB00
     1 SW_PVDDIO_P1_SW1_RC @T6G_MB_LIB.T6G(SCH_1):SW_PVDDIO_P1_SW1_RC    I26 @T6G_MB_LIB.T6G(SCH_1):PAGE197
     2    GND @T6G_MB_LIB.T6G(SCH_1):GND    I26 @T6G_MB_LIB.T6G(SCH_1):PAGE197

PR489 Q_RES_0402LF-1.5,1%,1/8W,EMPTY,CS-1504FB00
     1 SW_PVDDIO_P1_SW2_RC @T6G_MB_LIB.T6G(SCH_1):SW_PVDDIO_P1_SW2_RC    I19 @T6G_MB_LIB.T6G(SCH_1):PAGE197
     2    GND @T6G_MB_LIB.T6G(SCH_1):GND    I19 @T6G_MB_LIB.T6G(SCH_1):PAGE197

PR491 Q_RES_0402LF-1.5,1%,1/8W,EMPTY,CS-1504FB00
     1 SW_PVDDIO_P1_SW4_RC @T6G_MB_LIB.T6G(SCH_1):SW_PVDDIO_P1_SW4_RC    I39 @T6G_MB_LIB.T6G(SCH_1):PAGE198
     2    GND @T6G_MB_LIB.T6G(SCH_1):GND    I39 @T6G_MB_LIB.T6G(SCH_1):PAGE198

PR492 Q_RES_0402LF-1.5,1%,1/8W,EMPTY,CS-1504FB00
     1 SW_PVDDIO_P1_SW3_RC @T6G_MB_LIB.T6G(SCH_1):SW_PVDDIO_P1_SW3_RC    I57 @T6G_MB_LIB.T6G(SCH_1):PAGE198
     2    GND @T6G_MB_LIB.T6G(SCH_1):GND    I57 @T6G_MB_LIB.T6G(SCH_1):PAGE198

PR495 Q_RES_0402LF-1.5,1%,1/8W,EMPTY,CS-1504FB00
     1 SW_PVDDCR_CPU0_P0_SW1_RC @T6G_MB_LIB.T6G(SCH_1):SW_PVDDCR_CPU0_P0_SW1_RC    I42 @T6G_MB_LIB.T6G(SCH_1):PAGE169
     2    GND @T6G_MB_LIB.T6G(SCH_1):GND    I42 @T6G_MB_LIB.T6G(SCH_1):PAGE169

PR496 Q_RES_0402LF-1.5,1%,1/8W,EMPTY,CS-1504FB00
     1 SW_PVDDCR_CPU0_P0_SW2_RC @T6G_MB_LIB.T6G(SCH_1):SW_PVDDCR_CPU0_P0_SW2_RC    I28 @T6G_MB_LIB.T6G(SCH_1):PAGE169
     2    GND @T6G_MB_LIB.T6G(SCH_1):GND    I28 @T6G_MB_LIB.T6G(SCH_1):PAGE169

PR498 Q_RES_0402LF-1.5,1%,1/8W,EMPTY,CS-1504FB00
     1 SW_PVDDCR_CPU0_P0_SW3_RC @T6G_MB_LIB.T6G(SCH_1):SW_PVDDCR_CPU0_P0_SW3_RC    I44 @T6G_MB_LIB.T6G(SCH_1):PAGE170
     2    GND @T6G_MB_LIB.T6G(SCH_1):GND    I44 @T6G_MB_LIB.T6G(SCH_1):PAGE170

PR499 Q_RES_0402LF-1.5,1%,1/8W,EMPTY,CS-1504FB00
     1 SW_PVDDCR_CPU0_P0_SW4_RC @T6G_MB_LIB.T6G(SCH_1):SW_PVDDCR_CPU0_P0_SW4_RC    I18 @T6G_MB_LIB.T6G(SCH_1):PAGE170
     2    GND @T6G_MB_LIB.T6G(SCH_1):GND    I18 @T6G_MB_LIB.T6G(SCH_1):PAGE170

PR500 Q_RES_0402LF-1.5,1%,1/8W,EMPTY,CS-1504FB00
     1 SW_PVDDCR_CPU0_P0_SW6_RC @T6G_MB_LIB.T6G(SCH_1):SW_PVDDCR_CPU0_P0_SW6_RC    I22 @T6G_MB_LIB.T6G(SCH_1):PAGE171
     2    GND @T6G_MB_LIB.T6G(SCH_1):GND    I22 @T6G_MB_LIB.T6G(SCH_1):PAGE171

PR501 Q_RES_0402LF-1.5,1%,1/8W,EMPTY,CS-1504FB00
     1 SW_PVDDCR_CPU0_P0_SW5_RC @T6G_MB_LIB.T6G(SCH_1):SW_PVDDCR_CPU0_P0_SW5_RC    I31 @T6G_MB_LIB.T6G(SCH_1):PAGE171
     2    GND @T6G_MB_LIB.T6G(SCH_1):GND    I31 @T6G_MB_LIB.T6G(SCH_1):PAGE171

PR502 Q_RES_0402LF-1.5,1%,1/8W,EMPTY,CS-1504FB00
     1 SW_PVDDCR_SOC_P0_SW1_RC @T6G_MB_LIB.T6G(SCH_1):SW_PVDDCR_SOC_P0_SW1_RC    I45 @T6G_MB_LIB.T6G(SCH_1):PAGE173
     2    GND @T6G_MB_LIB.T6G(SCH_1):GND    I45 @T6G_MB_LIB.T6G(SCH_1):PAGE173

PR503 Q_RES_0402LF-1.5,1%,1/8W,EMPTY,CS-1504FB00
     1 SW_PVDDCR_SOC_P0_SW2_RC @T6G_MB_LIB.T6G(SCH_1):SW_PVDDCR_SOC_P0_SW2_RC    I19 @T6G_MB_LIB.T6G(SCH_1):PAGE173
     2    GND @T6G_MB_LIB.T6G(SCH_1):GND    I19 @T6G_MB_LIB.T6G(SCH_1):PAGE173

PR505 Q_RES_0402LF-1.5,1%,1/8W,EMPTY,CS-1504FB00
     1 SW_PVDDCR_SOC_P0_SW3_RC @T6G_MB_LIB.T6G(SCH_1):SW_PVDDCR_SOC_P0_SW3_RC    I10 @T6G_MB_LIB.T6G(SCH_1):PAGE174
     2    GND @T6G_MB_LIB.T6G(SCH_1):GND    I10 @T6G_MB_LIB.T6G(SCH_1):PAGE174

PR506 Q_RES_0402LF-1.5,1%,1/8W,EMPTY,CS-1504FB00
     1 SW_PVDDCR_CPU1_P0_SW1_RC @T6G_MB_LIB.T6G(SCH_1):SW_PVDDCR_CPU1_P0_SW1_RC    I50 @T6G_MB_LIB.T6G(SCH_1):PAGE176
     2    GND @T6G_MB_LIB.T6G(SCH_1):GND    I50 @T6G_MB_LIB.T6G(SCH_1):PAGE176

PR507 Q_RES_0402LF-1.5,1%,1/8W,EMPTY,CS-1504FB00
     1 SW_PVDDCR_CPU1_P0_SW2_RC @T6G_MB_LIB.T6G(SCH_1):SW_PVDDCR_CPU1_P0_SW2_RC    I39 @T6G_MB_LIB.T6G(SCH_1):PAGE176
     2    GND @T6G_MB_LIB.T6G(SCH_1):GND    I39 @T6G_MB_LIB.T6G(SCH_1):PAGE176

PR509 Q_RES_0402LF-1.5,1%,1/8W,EMPTY,CS-1504FB00
     1 SW_PVDDCR_CPU1_P0_SW4_RC @T6G_MB_LIB.T6G(SCH_1):SW_PVDDCR_CPU1_P0_SW4_RC    I36 @T6G_MB_LIB.T6G(SCH_1):PAGE177
     2    GND @T6G_MB_LIB.T6G(SCH_1):GND    I36 @T6G_MB_LIB.T6G(SCH_1):PAGE177

PR510 Q_RES_0402LF-1.5,1%,1/8W,EMPTY,CS-1504FB00
     1 SW_PVDDCR_CPU1_P0_SW3_RC @T6G_MB_LIB.T6G(SCH_1):SW_PVDDCR_CPU1_P0_SW3_RC    I46 @T6G_MB_LIB.T6G(SCH_1):PAGE177
     2    GND @T6G_MB_LIB.T6G(SCH_1):GND    I46 @T6G_MB_LIB.T6G(SCH_1):PAGE177

PR511 Q_RES_0402LF-1.5,1%,1/8W,EMPTY,CS-1504FB00
     1 SW_PVDDCR_SOC_P1_SW3_RC @T6G_MB_LIB.T6G(SCH_1):SW_PVDDCR_SOC_P1_SW3_RC    I10 @T6G_MB_LIB.T6G(SCH_1):PAGE191
     2    GND @T6G_MB_LIB.T6G(SCH_1):GND    I10 @T6G_MB_LIB.T6G(SCH_1):PAGE191

PR512 Q_RES_0402LF-1.5,1%,1/8W,EMPTY,CS-1504FB00
     1 SW_PVDDCR_CPU1_P1_SW1_RC @T6G_MB_LIB.T6G(SCH_1):SW_PVDDCR_CPU1_P1_SW1_RC    I45 @T6G_MB_LIB.T6G(SCH_1):PAGE193
     2    GND @T6G_MB_LIB.T6G(SCH_1):GND    I45 @T6G_MB_LIB.T6G(SCH_1):PAGE193

PR513 Q_RES_0402LF-1.5,1%,1/8W,EMPTY,CS-1504FB00
     1 SW_PVDDCR_CPU1_P1_SW2_RC @T6G_MB_LIB.T6G(SCH_1):SW_PVDDCR_CPU1_P1_SW2_RC    I36 @T6G_MB_LIB.T6G(SCH_1):PAGE193
     2    GND @T6G_MB_LIB.T6G(SCH_1):GND    I36 @T6G_MB_LIB.T6G(SCH_1):PAGE193

PR515 Q_RES_0402LF-1.5,1%,1/8W,EMPTY,CS-1504FB00
     1 SW_PVDDCR_CPU1_P1_SW4_RC @T6G_MB_LIB.T6G(SCH_1):SW_PVDDCR_CPU1_P1_SW4_RC    I35 @T6G_MB_LIB.T6G(SCH_1):PAGE194
     2    GND @T6G_MB_LIB.T6G(SCH_1):GND    I35 @T6G_MB_LIB.T6G(SCH_1):PAGE194

PR516 Q_RES_0402LF-1.5,1%,1/8W,EMPTY,CS-1504FB00
     1 SW_PVDDCR_CPU1_P1_SW3_RC @T6G_MB_LIB.T6G(SCH_1):SW_PVDDCR_CPU1_P1_SW3_RC    I44 @T6G_MB_LIB.T6G(SCH_1):PAGE194
     2    GND @T6G_MB_LIB.T6G(SCH_1):GND    I44 @T6G_MB_LIB.T6G(SCH_1):PAGE194

PR517 Q_RES_0402LF-1.5,1%,1/8W,EMPTY,CS-1504FB00
     1 SW_PVDDCR_CPU1_P1_SW5_RC @T6G_MB_LIB.T6G(SCH_1):SW_PVDDCR_CPU1_P1_SW5_RC    I43 @T6G_MB_LIB.T6G(SCH_1):PAGE195
     2    GND @T6G_MB_LIB.T6G(SCH_1):GND    I43 @T6G_MB_LIB.T6G(SCH_1):PAGE195

PR518 Q_RES_0402LF-1.5,1%,1/8W,EMPTY,CS-1504FB00
     1 SW_PVDDCR_CPU1_P1_SW6_RC @T6G_MB_LIB.T6G(SCH_1):SW_PVDDCR_CPU1_P1_SW6_RC    I33 @T6G_MB_LIB.T6G(SCH_1):PAGE195
     2    GND @T6G_MB_LIB.T6G(SCH_1):GND    I33 @T6G_MB_LIB.T6G(SCH_1):PAGE195

PR519 Q_RES_0402LF-1.5,1%,1/8W,EMPTY,CS-1504FB00
     1 SW_PVDD11_S3_P1_SW2_RC @T6G_MB_LIB.T6G(SCH_1):SW_PVDD11_S3_P1_SW2_RC    I25 @T6G_MB_LIB.T6G(SCH_1):PAGE200
     2    GND @T6G_MB_LIB.T6G(SCH_1):GND    I25 @T6G_MB_LIB.T6G(SCH_1):PAGE200

PR520 Q_RES_0402LF-1.5,1%,1/8W,EMPTY,CS-1504FB00
     1 SW_PVDD11_S3_P1_SW1_RC @T6G_MB_LIB.T6G(SCH_1):SW_PVDD11_S3_P1_SW1_RC    I33 @T6G_MB_LIB.T6G(SCH_1):PAGE200
     2    GND @T6G_MB_LIB.T6G(SCH_1):GND    I33 @T6G_MB_LIB.T6G(SCH_1):PAGE200

PR522 Q_RES_0402LF-1.5,1%,1/8W,EMPTY,CS-1504FB00
     1 SW_PVDDCR_CPU0_P1_SW3_RC @T6G_MB_LIB.T6G(SCH_1):SW_PVDDCR_CPU0_P1_SW3_RC    I45 @T6G_MB_LIB.T6G(SCH_1):PAGE187
     2    GND @T6G_MB_LIB.T6G(SCH_1):GND    I45 @T6G_MB_LIB.T6G(SCH_1):PAGE187

PR523 Q_RES_0402LF-1.5,1%,1/8W,EMPTY,CS-1504FB00
     1 SW_PVDDCR_CPU0_P1_SW4_RC @T6G_MB_LIB.T6G(SCH_1):SW_PVDDCR_CPU0_P1_SW4_RC    I19 @T6G_MB_LIB.T6G(SCH_1):PAGE187
     2    GND @T6G_MB_LIB.T6G(SCH_1):GND    I19 @T6G_MB_LIB.T6G(SCH_1):PAGE187

PR524 Q_RES_0402LF-1.5,1%,1/8W,EMPTY,CS-1504FB00
     1 SW_PVDDCR_CPU0_P1_SW6_RC @T6G_MB_LIB.T6G(SCH_1):SW_PVDDCR_CPU0_P1_SW6_RC    I21 @T6G_MB_LIB.T6G(SCH_1):PAGE188
     2    GND @T6G_MB_LIB.T6G(SCH_1):GND    I21 @T6G_MB_LIB.T6G(SCH_1):PAGE188

PR525 Q_RES_0402LF-1.5,1%,1/8W,EMPTY,CS-1504FB00
     1 SW_PVDDCR_SOC_P1_SW1_RC @T6G_MB_LIB.T6G(SCH_1):SW_PVDDCR_SOC_P1_SW1_RC    I29 @T6G_MB_LIB.T6G(SCH_1):PAGE190
     2    GND @T6G_MB_LIB.T6G(SCH_1):GND    I29 @T6G_MB_LIB.T6G(SCH_1):PAGE190

PR526 Q_RES_0402LF-1.5,1%,1/8W,EMPTY,CS-1504FB00
     1 SW_PVDDCR_SOC_P1_SW2_RC @T6G_MB_LIB.T6G(SCH_1):SW_PVDDCR_SOC_P1_SW2_RC    I21 @T6G_MB_LIB.T6G(SCH_1):PAGE190
     2    GND @T6G_MB_LIB.T6G(SCH_1):GND    I21 @T6G_MB_LIB.T6G(SCH_1):PAGE190

PR530 Q_RES_0402LF-0,5%,1/16W,CHIP,CS00002JB13
     1 NC_PVDDCR_CPU0_P1_IMON7 @T6G_MB_LIB.T6G(SCH_1):NC_PVDDCR_CPU0_P1_IMON7   I107 @T6G_MB_LIB.T6G(SCH_1):PAGE185
     2    GND @T6G_MB_LIB.T6G(SCH_1):GND   I107 @T6G_MB_LIB.T6G(SCH_1):PAGE185

PR531 Q_RES_0402LF-0,5%,1/16W,CHIP,CS00002JB13
     1 NC_PVDDCR_CPU0_P0_IMON7 @T6G_MB_LIB.T6G(SCH_1):NC_PVDDCR_CPU0_P0_IMON7   I111 @T6G_MB_LIB.T6G(SCH_1):PAGE168
     2    GND @T6G_MB_LIB.T6G(SCH_1):GND   I111 @T6G_MB_LIB.T6G(SCH_1):PAGE168

PR532 Q_RES_0402LF-0,5%,1/16W,CHIP,CS00002JB13
     1 NC_PVDDCR_CPU1_P0_IMON7 @T6G_MB_LIB.T6G(SCH_1):NC_PVDDCR_CPU1_P0_IMON7    I76 @T6G_MB_LIB.T6G(SCH_1):PAGE175
     2    GND @T6G_MB_LIB.T6G(SCH_1):GND    I76 @T6G_MB_LIB.T6G(SCH_1):PAGE175

PR533 Q_RES_0402LF-0,5%,1/16W,CHIP,CS00002JB13
     1 NC_PVDDCR_CPU1_P1_IMON7 @T6G_MB_LIB.T6G(SCH_1):NC_PVDDCR_CPU1_P1_IMON7    I76 @T6G_MB_LIB.T6G(SCH_1):PAGE192
     2    GND @T6G_MB_LIB.T6G(SCH_1):GND    I76 @T6G_MB_LIB.T6G(SCH_1):PAGE192

PR599 Q_RES_0402LF-4.99K,1%,1/16W,EMPTY,CS24992FB07
     1 PVDDCR_CPU0_P0_VINSEN @T6G_MB_LIB.T6G(SCH_1):PVDDCR_CPU0_P0_VINSEN    I47 @T6G_MB_LIB.T6G(SCH_1):PAGE168
     2    GND @T6G_MB_LIB.T6G(SCH_1):GND    I47 @T6G_MB_LIB.T6G(SCH_1):PAGE168

PR600 Q_RES_0402LF-4.99K,1%,1/16W,EMPTY,CS24992FB07
     1 PVDDCR_CPU1_P0_VINSEN @T6G_MB_LIB.T6G(SCH_1):PVDDCR_CPU1_P0_VINSEN    I59 @T6G_MB_LIB.T6G(SCH_1):PAGE175
     2    GND @T6G_MB_LIB.T6G(SCH_1):GND    I59 @T6G_MB_LIB.T6G(SCH_1):PAGE175

PR601 Q_RES_0402LF-4.99K,1%,1/16W,EMPTY,CS24992FB07
     1 PVDD11_S3_P0_VINSEN @T6G_MB_LIB.T6G(SCH_1):PVDD11_S3_P0_VINSEN    I18 @T6G_MB_LIB.T6G(SCH_1):PAGE182
     2    GND @T6G_MB_LIB.T6G(SCH_1):GND    I18 @T6G_MB_LIB.T6G(SCH_1):PAGE182

PR602 Q_RES_0402LF-4.99K,1%,1/16W,EMPTY,CS24992FB07
     1 PVDDCR_CPU0_P1_VINSEN @T6G_MB_LIB.T6G(SCH_1):PVDDCR_CPU0_P1_VINSEN    I48 @T6G_MB_LIB.T6G(SCH_1):PAGE185
     2    GND @T6G_MB_LIB.T6G(SCH_1):GND    I48 @T6G_MB_LIB.T6G(SCH_1):PAGE185

PR603 Q_RES_0402LF-4.99K,1%,1/16W,EMPTY,CS24992FB07
     1 PVDDCR_CPU1_P1_VINSEN @T6G_MB_LIB.T6G(SCH_1):PVDDCR_CPU1_P1_VINSEN    I55 @T6G_MB_LIB.T6G(SCH_1):PAGE192
     2    GND @T6G_MB_LIB.T6G(SCH_1):GND    I55 @T6G_MB_LIB.T6G(SCH_1):PAGE192

PR604 Q_RES_0402LF-4.99K,1%,1/16W,EMPTY,CS24992FB07
     1 PVDD11_S3_P1_VINSEN @T6G_MB_LIB.T6G(SCH_1):PVDD11_S3_P1_VINSEN    I17 @T6G_MB_LIB.T6G(SCH_1):PAGE199
     2    GND @T6G_MB_LIB.T6G(SCH_1):GND    I17 @T6G_MB_LIB.T6G(SCH_1):PAGE199

PR830 Q_RES_0402LF-15K,0.1%,1/16W,CHIP,CS31502BB03
     1 P3V3_AUX_FB @T6G_MB_LIB.T6G(SCH_1):P3V3_AUX_FB    I51 @T6G_MB_LIB.T6G(SCH_1):PAGE245
     2    GND @T6G_MB_LIB.T6G(SCH_1):GND    I51 @T6G_MB_LIB.T6G(SCH_1):PAGE245

PR831 Q_RES_0402LF-47K,0.1%,1/16W,CHIP,CS34702BB05
     1 P3V3_AUX_FB @T6G_MB_LIB.T6G(SCH_1):P3V3_AUX_FB    I54 @T6G_MB_LIB.T6G(SCH_1):PAGE245
     2 P3V3_AUX @T6G_MB_LIB.T6G(SCH_1):P3V3_AUX    I54 @T6G_MB_LIB.T6G(SCH_1):PAGE245

PR832 Q_RES_0402LF-0,5%,1/16W,CHIP,CS00002JB13
     1 P3V3_AUX_MODE @T6G_MB_LIB.T6G(SCH_1):P3V3_AUX_MODE    I10 @T6G_MB_LIB.T6G(SCH_1):PAGE245
     2    GND @T6G_MB_LIB.T6G(SCH_1):GND    I10 @T6G_MB_LIB.T6G(SCH_1):PAGE245

PR833 Q_RES_0402LF-1.5K,1%,1/16W,EMPTY,CS21502FB07
     1 P3V3_AUX_SS @T6G_MB_LIB.T6G(SCH_1):P3V3_AUX_SS    I15 @T6G_MB_LIB.T6G(SCH_1):PAGE245
     2    GND @T6G_MB_LIB.T6G(SCH_1):GND    I15 @T6G_MB_LIB.T6G(SCH_1):PAGE245

PR834 Q_RES_0402LF-21.5K,1%,1/16W,CHIP,CS32152FB04
     1 P3V3_AUX_ILIM @T6G_MB_LIB.T6G(SCH_1):P3V3_AUX_ILIM    I17 @T6G_MB_LIB.T6G(SCH_1):PAGE245
     2    GND @T6G_MB_LIB.T6G(SCH_1):GND    I17 @T6G_MB_LIB.T6G(SCH_1):PAGE245

PR835 Q_RES_0402LF-0,5%,1/16W,CHIP,CS00002JB13
     1 SW_P3V3_AUX_BOOT @T6G_MB_LIB.T6G(SCH_1):SW_P3V3_AUX_BOOT    I49 @T6G_MB_LIB.T6G(SCH_1):PAGE245
     2 SW_P3V3_AUX_BOOT_R @T6G_MB_LIB.T6G(SCH_1):SW_P3V3_AUX_BOOT_R    I49 @T6G_MB_LIB.T6G(SCH_1):PAGE245

PR836 Q_RES_0402LF-1K,1%,1/16W,CHIP,CS21002FB06
     1 P3V3_AUX_VOS @T6G_MB_LIB.T6G(SCH_1):P3V3_AUX_VOS    I46 @T6G_MB_LIB.T6G(SCH_1):PAGE245
     2 P3V3_AUX @T6G_MB_LIB.T6G(SCH_1):P3V3_AUX    I46 @T6G_MB_LIB.T6G(SCH_1):PAGE245

PR883 Q_RES_0402LF-0,5%,1/16W,EMPTY,CS00002JB13
     1 TP_P0V9_RETIMER_CPU0_SVID_ALERT_N @T6G_MB_LIB.T6G(SCH_1):TP_P0V9_RETIMER_CPU0_SVID_ALERT_N   I210 @T6G_MB_LIB.T6G(SCH_1):PAGE475
     2    GND @T6G_MB_LIB.T6G(SCH_1):GND   I210 @T6G_MB_LIB.T6G(SCH_1):PAGE475

PR885 Q_RES_0402LF-5.36K,1%,1/16W,EMPTY,CS25362FB02
     1 P5V_AUX @T6G_MB_LIB.T6G(SCH_1):P5V_AUX     I7 @T6G_MB_LIB.T6G(SCH_1):PAGE477
     2 P0V9_RETIMER_CPU1_VMON @T6G_MB_LIB.T6G(SCH_1):P0V9_RETIMER_CPU1_VMON     I7 @T6G_MB_LIB.T6G(SCH_1):PAGE477

PR1101 Q_RES_0402LF-2K,0.1%,1/16W,CHIP,CS22002BB07
     1 HSC_IMON @T6G_MB_LIB.T6G(SCH_1):HSC_IMON    I15 @T6G_MB_LIB.T6G(SCH_1):PAGE301
     2 AGND_HSC @T6G_MB_LIB.T6G(SCH_1):AGND_HSC    I15 @T6G_MB_LIB.T6G(SCH_1):PAGE301

PR1131 Q_RES_0402LF-2K,0.1%,1/16W,CHIP,CS22002BB07
     1 HSC_CS @T6G_MB_LIB.T6G(SCH_1):HSC_CS    I65 @T6G_MB_LIB.T6G(SCH_1):PAGE267
     2 AGND_HSC @T6G_MB_LIB.T6G(SCH_1):AGND_HSC    I65 @T6G_MB_LIB.T6G(SCH_1):PAGE267

PR1133 Q_RES_0402LF-2K,0.1%,1/16W,CHIP,CS22002BB07
     1 HSC_IMON @T6G_MB_LIB.T6G(SCH_1):HSC_IMON    I86 @T6G_MB_LIB.T6G(SCH_1):PAGE267
     2 AGND_HSC @T6G_MB_LIB.T6G(SCH_1):AGND_HSC    I86 @T6G_MB_LIB.T6G(SCH_1):PAGE267

PR1134 Q_RES_0402LF-120K,1%,1/16W,CHIP,CS41202FB05
     1 AGND_HSC @T6G_MB_LIB.T6G(SCH_1):AGND_HSC    I29 @T6G_MB_LIB.T6G(SCH_1):PAGE301
     2 HSC_MODE_1 @T6G_MB_LIB.T6G(SCH_1):HSC_MODE_1    I29 @T6G_MB_LIB.T6G(SCH_1):PAGE301

PR2106 Q_RES_0402LF-10K,1%,1/16W,CHIP,CS31002FB08
     1 HSC_VDD @T6G_MB_LIB.T6G(SCH_1):HSC_VDD    I56 @T6G_MB_LIB.T6G(SCH_1):PAGE267
     2 HSC_VIN_UVW_N @T6G_MB_LIB.T6G(SCH_1):HSC_VIN_UVW_N    I56 @T6G_MB_LIB.T6G(SCH_1):PAGE267

PR2149 Q_RES_0402LF-0,5%,1/16W,CHIP,CS00002JB13
     1 HSC_VDD_R @T6G_MB_LIB.T6G(SCH_1):HSC_VDD_R    I39 @T6G_MB_LIB.T6G(SCH_1):PAGE267
     2 HSC_VDD @T6G_MB_LIB.T6G(SCH_1):HSC_VDD    I39 @T6G_MB_LIB.T6G(SCH_1):PAGE267

PR2510 Q_RES_0402LF-1,1%,1/16W,CHIP,CS-1002FB04
     1 P12V_HSC_ADC_P @T6G_MB_LIB.T6G(SCH_1):P12V_HSC_ADC_P    I18 @T6G_MB_LIB.T6G(SCH_1):PAGE302
     2 P12V_HSC_SENSE2_R1_P @T6G_MB_LIB.T6G(SCH_1):P12V_HSC_SENSE2_R1_P    I18 @T6G_MB_LIB.T6G(SCH_1):PAGE302

PR2511 Q_RES_0402LF-1,1%,1/16W,CHIP,CS-1002FB04
     1 P12V_HSC_ADC_P @T6G_MB_LIB.T6G(SCH_1):P12V_HSC_ADC_P    I17 @T6G_MB_LIB.T6G(SCH_1):PAGE302
     2 P12V_HSC_SENSE2_R2_P @T6G_MB_LIB.T6G(SCH_1):P12V_HSC_SENSE2_R2_P    I17 @T6G_MB_LIB.T6G(SCH_1):PAGE302

PR2512 Q_RES_0402LF-1,1%,1/16W,CHIP,CS-1002FB04
     1 P12V_HSC_ADC_P @T6G_MB_LIB.T6G(SCH_1):P12V_HSC_ADC_P    I16 @T6G_MB_LIB.T6G(SCH_1):PAGE302
     2 P12V_HSC_SENSE2_R3_P @T6G_MB_LIB.T6G(SCH_1):P12V_HSC_SENSE2_R3_P    I16 @T6G_MB_LIB.T6G(SCH_1):PAGE302

PR2513 Q_RES_0402LF-1,1%,1/16W,CHIP,CS-1002FB04
     1 P12V_HSC_ADC_P @T6G_MB_LIB.T6G(SCH_1):P12V_HSC_ADC_P    I15 @T6G_MB_LIB.T6G(SCH_1):PAGE302
     2 P12V_HSC_SENSE2_R4_P @T6G_MB_LIB.T6G(SCH_1):P12V_HSC_SENSE2_R4_P    I15 @T6G_MB_LIB.T6G(SCH_1):PAGE302

PR2514 Q_RES_0402LF-10,1%,1/16W,CHIP,CS01002FB07
     1 P12V_HSC_ADC_P @T6G_MB_LIB.T6G(SCH_1):P12V_HSC_ADC_P    I82 @T6G_MB_LIB.T6G(SCH_1):PAGE302
     2 P12V_HSC_SENSE1_P @T6G_MB_LIB.T6G(SCH_1):P12V_HSC_SENSE1_P    I82 @T6G_MB_LIB.T6G(SCH_1):PAGE302

PR2515 Q_RES_0402LF-10,1%,1/16W,CHIP,CS01002FB07
     1 P12V_HSC_ADC_N @T6G_MB_LIB.T6G(SCH_1):P12V_HSC_ADC_N    I83 @T6G_MB_LIB.T6G(SCH_1):PAGE302
     2 P12V_HSC_SENSE2_R1_N @T6G_MB_LIB.T6G(SCH_1):P12V_HSC_SENSE2_R1_N    I83 @T6G_MB_LIB.T6G(SCH_1):PAGE302

PR2516 Q_RES_0402LF-10,1%,1/16W,CHIP,CS01002FB07
     1 P12V_HSC_ADC_N @T6G_MB_LIB.T6G(SCH_1):P12V_HSC_ADC_N    I84 @T6G_MB_LIB.T6G(SCH_1):PAGE302
     2 P12V_HSC_SENSE2_R2_N @T6G_MB_LIB.T6G(SCH_1):P12V_HSC_SENSE2_R2_N    I84 @T6G_MB_LIB.T6G(SCH_1):PAGE302

PR2517 Q_RES_0402LF-10,1%,1/16W,CHIP,CS01002FB07
     1 P12V_HSC_ADC_N @T6G_MB_LIB.T6G(SCH_1):P12V_HSC_ADC_N    I85 @T6G_MB_LIB.T6G(SCH_1):PAGE302
     2 P12V_HSC_SENSE2_R3_N @T6G_MB_LIB.T6G(SCH_1):P12V_HSC_SENSE2_R3_N    I85 @T6G_MB_LIB.T6G(SCH_1):PAGE302

PR2518 Q_RES_0402LF-10,1%,1/16W,CHIP,CS01002FB07
     1 P12V_HSC_ADC_N @T6G_MB_LIB.T6G(SCH_1):P12V_HSC_ADC_N    I86 @T6G_MB_LIB.T6G(SCH_1):PAGE302
     2 P12V_HSC_SENSE2_R4_N @T6G_MB_LIB.T6G(SCH_1):P12V_HSC_SENSE2_R4_N    I86 @T6G_MB_LIB.T6G(SCH_1):PAGE302

PR2519 Q_RES_0402LF-100,1%,1/16W,CHIP,CS11002FB07
     1 P12V_HSC_ADC_N @T6G_MB_LIB.T6G(SCH_1):P12V_HSC_ADC_N    I87 @T6G_MB_LIB.T6G(SCH_1):PAGE302
     2 P12V_HSC_SENSE1_N @T6G_MB_LIB.T6G(SCH_1):P12V_HSC_SENSE1_N    I87 @T6G_MB_LIB.T6G(SCH_1):PAGE302

PR2520 Q_RES_0402LF-1,1%,1/16W,CHIP,CS-1002FB04
     1 P12V_HSC_SENSE2_P @T6G_MB_LIB.T6G(SCH_1):P12V_HSC_SENSE2_P     I8 @T6G_MB_LIB.T6G(SCH_1):PAGE302
     2 P12V_HSC_SENSE2_R1_P @T6G_MB_LIB.T6G(SCH_1):P12V_HSC_SENSE2_R1_P     I8 @T6G_MB_LIB.T6G(SCH_1):PAGE302

PR2521 Q_RES_0402LF-1,1%,1/16W,CHIP,CS-1002FB04
     1 P12V_HSC_SENSE2_P @T6G_MB_LIB.T6G(SCH_1):P12V_HSC_SENSE2_P     I6 @T6G_MB_LIB.T6G(SCH_1):PAGE302
     2 P12V_HSC_SENSE2_R2_P @T6G_MB_LIB.T6G(SCH_1):P12V_HSC_SENSE2_R2_P     I6 @T6G_MB_LIB.T6G(SCH_1):PAGE302

PR2522 Q_RES_0402LF-1,1%,1/16W,CHIP,CS-1002FB04
     1 P12V_HSC_SENSE2_P @T6G_MB_LIB.T6G(SCH_1):P12V_HSC_SENSE2_P     I7 @T6G_MB_LIB.T6G(SCH_1):PAGE302
     2 P12V_HSC_SENSE2_R3_P @T6G_MB_LIB.T6G(SCH_1):P12V_HSC_SENSE2_R3_P     I7 @T6G_MB_LIB.T6G(SCH_1):PAGE302

PR2523 Q_RES_0402LF-1,1%,1/16W,CHIP,CS-1002FB04
     1 P12V_HSC_SENSE2_P @T6G_MB_LIB.T6G(SCH_1):P12V_HSC_SENSE2_P     I5 @T6G_MB_LIB.T6G(SCH_1):PAGE302
     2 P12V_HSC_SENSE2_R4_P @T6G_MB_LIB.T6G(SCH_1):P12V_HSC_SENSE2_R4_P     I5 @T6G_MB_LIB.T6G(SCH_1):PAGE302

PR2524 Q_RES_0402LF-10,1%,1/16W,CHIP,CS01002FB07
     1 P12V_HSC_SENSE2_N @T6G_MB_LIB.T6G(SCH_1):P12V_HSC_SENSE2_N    I88 @T6G_MB_LIB.T6G(SCH_1):PAGE302
     2 P12V_HSC_SENSE2_R1_N @T6G_MB_LIB.T6G(SCH_1):P12V_HSC_SENSE2_R1_N    I88 @T6G_MB_LIB.T6G(SCH_1):PAGE302

PR2525 Q_RES_0402LF-10,1%,1/16W,CHIP,CS01002FB07
     1 P12V_HSC_SENSE2_N @T6G_MB_LIB.T6G(SCH_1):P12V_HSC_SENSE2_N    I89 @T6G_MB_LIB.T6G(SCH_1):PAGE302
     2 P12V_HSC_SENSE2_R2_N @T6G_MB_LIB.T6G(SCH_1):P12V_HSC_SENSE2_R2_N    I89 @T6G_MB_LIB.T6G(SCH_1):PAGE302

PR2526 Q_RES_0402LF-10,1%,1/16W,CHIP,CS01002FB07
     1 P12V_HSC_SENSE2_N @T6G_MB_LIB.T6G(SCH_1):P12V_HSC_SENSE2_N    I90 @T6G_MB_LIB.T6G(SCH_1):PAGE302
     2 P12V_HSC_SENSE2_R3_N @T6G_MB_LIB.T6G(SCH_1):P12V_HSC_SENSE2_R3_N    I90 @T6G_MB_LIB.T6G(SCH_1):PAGE302

PR2527 Q_RES_0402LF-10,1%,1/16W,CHIP,CS01002FB07
     1 P12V_HSC_SENSE2_N @T6G_MB_LIB.T6G(SCH_1):P12V_HSC_SENSE2_N    I91 @T6G_MB_LIB.T6G(SCH_1):PAGE302
     2 P12V_HSC_SENSE2_R4_N @T6G_MB_LIB.T6G(SCH_1):P12V_HSC_SENSE2_R4_N    I91 @T6G_MB_LIB.T6G(SCH_1):PAGE302

PR2528 Q_RES_0402LF-10,1%,1/16W,CHIP,CS01002FB07
     1 P12V_HSC_GATE_G1 @T6G_MB_LIB.T6G(SCH_1):P12V_HSC_GATE_G1    I27 @T6G_MB_LIB.T6G(SCH_1):PAGE302
     2 P12V_HSC_GATE2 @T6G_MB_LIB.T6G(SCH_1):P12V_HSC_GATE2    I27 @T6G_MB_LIB.T6G(SCH_1):PAGE302

PR2529 Q_RES_0402LF-10,1%,1/16W,CHIP,CS01002FB07
     1 P12V_HSC_GATE_G2 @T6G_MB_LIB.T6G(SCH_1):P12V_HSC_GATE_G2    I28 @T6G_MB_LIB.T6G(SCH_1):PAGE302
     2 P12V_HSC_GATE2 @T6G_MB_LIB.T6G(SCH_1):P12V_HSC_GATE2    I28 @T6G_MB_LIB.T6G(SCH_1):PAGE302

PR2530 Q_RES_0402LF-10,1%,1/16W,CHIP,CS01002FB07
     1 P12V_HSC_GATE_G3 @T6G_MB_LIB.T6G(SCH_1):P12V_HSC_GATE_G3    I45 @T6G_MB_LIB.T6G(SCH_1):PAGE302
     2 P12V_HSC_GATE2 @T6G_MB_LIB.T6G(SCH_1):P12V_HSC_GATE2    I45 @T6G_MB_LIB.T6G(SCH_1):PAGE302

PR2531 Q_RES_0402LF-10,1%,1/16W,CHIP,CS01002FB07
     1 P12V_HSC_GATE_G4 @T6G_MB_LIB.T6G(SCH_1):P12V_HSC_GATE_G4    I47 @T6G_MB_LIB.T6G(SCH_1):PAGE302
     2 P12V_HSC_GATE2 @T6G_MB_LIB.T6G(SCH_1):P12V_HSC_GATE2    I47 @T6G_MB_LIB.T6G(SCH_1):PAGE302

PR2532 Q_SP_RES4P-0.0003,1%,4W,SMLF,CHIP,SP_CS0000FFT09
    2B P12V_HSC_SENSE2_R2_N @T6G_MB_LIB.T6G(SCH_1):P12V_HSC_SENSE2_R2_N    I54 @T6G_MB_LIB.T6G(SCH_1):PAGE302
    1B P12V_HSC_SENSE2_R2_P @T6G_MB_LIB.T6G(SCH_1):P12V_HSC_SENSE2_R2_P    I54 @T6G_MB_LIB.T6G(SCH_1):PAGE302
    2A P12V_MAIN_R @T6G_MB_LIB.T6G(SCH_1):P12V_MAIN_R    I54 @T6G_MB_LIB.T6G(SCH_1):PAGE302
    1A P12V_PSU @T6G_MB_LIB.T6G(SCH_1):P12V_PSU    I54 @T6G_MB_LIB.T6G(SCH_1):PAGE302

PR2533 Q_SP_RES4P-0.0003,1%,4W,SMLF,CHIP,SP_CS0000FFT09
    2B P12V_HSC_SENSE2_R3_N @T6G_MB_LIB.T6G(SCH_1):P12V_HSC_SENSE2_R3_N    I53 @T6G_MB_LIB.T6G(SCH_1):PAGE302
    1B P12V_HSC_SENSE2_R3_P @T6G_MB_LIB.T6G(SCH_1):P12V_HSC_SENSE2_R3_P    I53 @T6G_MB_LIB.T6G(SCH_1):PAGE302
    2A P12V_MAIN_R @T6G_MB_LIB.T6G(SCH_1):P12V_MAIN_R    I53 @T6G_MB_LIB.T6G(SCH_1):PAGE302
    1A P12V_PSU @T6G_MB_LIB.T6G(SCH_1):P12V_PSU    I53 @T6G_MB_LIB.T6G(SCH_1):PAGE302

PR2534 Q_SP_RES4P-0.0003,1%,4W,SMLF,CHIP,SP_CS0000FFT09
    2B P12V_HSC_SENSE2_R4_N @T6G_MB_LIB.T6G(SCH_1):P12V_HSC_SENSE2_R4_N    I52 @T6G_MB_LIB.T6G(SCH_1):PAGE302
    1B P12V_HSC_SENSE2_R4_P @T6G_MB_LIB.T6G(SCH_1):P12V_HSC_SENSE2_R4_P    I52 @T6G_MB_LIB.T6G(SCH_1):PAGE302
    2A P12V_MAIN_R @T6G_MB_LIB.T6G(SCH_1):P12V_MAIN_R    I52 @T6G_MB_LIB.T6G(SCH_1):PAGE302
    1A P12V_PSU @T6G_MB_LIB.T6G(SCH_1):P12V_PSU    I52 @T6G_MB_LIB.T6G(SCH_1):PAGE302

PR2535 Q_RES_0402LF-10,1%,1/16W,CHIP,CS01002FB07
     1 P12V_HSC_GATE_G5 @T6G_MB_LIB.T6G(SCH_1):P12V_HSC_GATE_G5    I60 @T6G_MB_LIB.T6G(SCH_1):PAGE302
     2 P12V_HSC_GATE2 @T6G_MB_LIB.T6G(SCH_1):P12V_HSC_GATE2    I60 @T6G_MB_LIB.T6G(SCH_1):PAGE302

PR2536 Q_RES_0402LF-10,1%,1/16W,CHIP,CS01002FB07
     1 P12V_HSC_GATE_G6 @T6G_MB_LIB.T6G(SCH_1):P12V_HSC_GATE_G6    I62 @T6G_MB_LIB.T6G(SCH_1):PAGE302
     2 P12V_HSC_GATE2 @T6G_MB_LIB.T6G(SCH_1):P12V_HSC_GATE2    I62 @T6G_MB_LIB.T6G(SCH_1):PAGE302

PR2537 Q_RES_0402LF-10,1%,1/16W,EMPTY,CS01002FB07
     1 P12V_AUX @T6G_MB_LIB.T6G(SCH_1):P12V_AUX    I71 @T6G_MB_LIB.T6G(SCH_1):PAGE302
     2 P12V_HSC_GATE_RC @T6G_MB_LIB.T6G(SCH_1):P12V_HSC_GATE_RC    I71 @T6G_MB_LIB.T6G(SCH_1):PAGE302

PR2538 Q_RES_0402LF-10,1%,1/16W,CHIP,CS01002FB07
     1 MB0_CM_GATE_G0 @T6G_MB_LIB.T6G(SCH_1):MB0_CM_GATE_G0    I74 @T6G_MB_LIB.T6G(SCH_1):PAGE302
     2 P12V_HSC_GATE1 @T6G_MB_LIB.T6G(SCH_1):P12V_HSC_GATE1    I74 @T6G_MB_LIB.T6G(SCH_1):PAGE302

PR3002 Q_RES_0402LF-0,5%,1/16W,CHIP,CS00002JB13
     1    GND @T6G_MB_LIB.T6G(SCH_1):GND    I27 @T6G_MB_LIB.T6G(SCH_1):PAGE372
     2 AGND_HSC @T6G_MB_LIB.T6G(SCH_1):AGND_HSC    I27 @T6G_MB_LIB.T6G(SCH_1):PAGE372

PR3337 Q_RES_0402LF-0,5%,1/16W,CHIP,CS00002JB13
     1 P5V_AUX_MODE @T6G_MB_LIB.T6G(SCH_1):P5V_AUX_MODE    I37 @T6G_MB_LIB.T6G(SCH_1):PAGE244
     2    GND @T6G_MB_LIB.T6G(SCH_1):GND    I37 @T6G_MB_LIB.T6G(SCH_1):PAGE244

PR3780 Q_RES_0402LF-5.36K,1%,1/16W,CHIP,CS25362FB02
     1 P3V3_OCP_CB_1 @T6G_MB_LIB.T6G(SCH_1):P3V3_OCP_CB_1   I111 @T6G_MB_LIB.T6G(SCH_1):PAGE338
     2    GND @T6G_MB_LIB.T6G(SCH_1):GND   I111 @T6G_MB_LIB.T6G(SCH_1):PAGE338

PR3781 Q_RES_0402LF-845,1%,1/16W,CHIP,CS18452FB01
     1 P12V_OCP_SENSE_1 @T6G_MB_LIB.T6G(SCH_1):P12V_OCP_SENSE_1    I73 @T6G_MB_LIB.T6G(SCH_1):PAGE338
     2    GND @T6G_MB_LIB.T6G(SCH_1):GND    I73 @T6G_MB_LIB.T6G(SCH_1):PAGE338

PR3782 Q_RES_0402LF-10,1%,1/16W,CHIP,CS01002FB07
     1 P3V3_AUX @T6G_MB_LIB.T6G(SCH_1):P3V3_AUX    I91 @T6G_MB_LIB.T6G(SCH_1):PAGE343
     2 P3V3_OCP_VCC_2 @T6G_MB_LIB.T6G(SCH_1):P3V3_OCP_VCC_2    I91 @T6G_MB_LIB.T6G(SCH_1):PAGE343

PR3786 Q_RES_0402LF-160K,1%,1/16W,CHIP,CS41602FB05
     1 P12V_AUX @T6G_MB_LIB.T6G(SCH_1):P12V_AUX    I43 @T6G_MB_LIB.T6G(SCH_1):PAGE338
     2 P12V_OCP_UV_1 @T6G_MB_LIB.T6G(SCH_1):P12V_OCP_UV_1    I43 @T6G_MB_LIB.T6G(SCH_1):PAGE338

PR3787 Q_RES_0402LF-6.8K,1%,1/16W,CHIP,CS26802FB02
     1 P12V_OCP_UV_1 @T6G_MB_LIB.T6G(SCH_1):P12V_OCP_UV_1    I42 @T6G_MB_LIB.T6G(SCH_1):PAGE338
     2 P12V_OCP_OV_1 @T6G_MB_LIB.T6G(SCH_1):P12V_OCP_OV_1    I42 @T6G_MB_LIB.T6G(SCH_1):PAGE338

PR3788 Q_RES_0402LF-15K,1%,1/16W,CHIP,CS31502FB05
     1 P12V_OCP_OV_1 @T6G_MB_LIB.T6G(SCH_1):P12V_OCP_OV_1    I36 @T6G_MB_LIB.T6G(SCH_1):PAGE338
     2    GND @T6G_MB_LIB.T6G(SCH_1):GND    I36 @T6G_MB_LIB.T6G(SCH_1):PAGE338

PR3789 Q_RES_0402LF-25.5K,1%,1/16W,CHIP,CS32552FB06
     1 P3V3_AUX @T6G_MB_LIB.T6G(SCH_1):P3V3_AUX    I66 @T6G_MB_LIB.T6G(SCH_1):PAGE338
     2 P3V3_OCP_UV_1 @T6G_MB_LIB.T6G(SCH_1):P3V3_OCP_UV_1    I66 @T6G_MB_LIB.T6G(SCH_1):PAGE338

PR3790 Q_RES_0402LF-7.15K,1%,1/16W,CHIP,CS27152FB03
     1 P3V3_OCP_UV_1 @T6G_MB_LIB.T6G(SCH_1):P3V3_OCP_UV_1    I64 @T6G_MB_LIB.T6G(SCH_1):PAGE338
     2 P3V3_OCP_OV_1 @T6G_MB_LIB.T6G(SCH_1):P3V3_OCP_OV_1    I64 @T6G_MB_LIB.T6G(SCH_1):PAGE338

PR3791 Q_RES_0402LF-15K,1%,1/16W,CHIP,CS31502FB05
     1 P3V3_OCP_OV_1 @T6G_MB_LIB.T6G(SCH_1):P3V3_OCP_OV_1   I114 @T6G_MB_LIB.T6G(SCH_1):PAGE338
     2    GND @T6G_MB_LIB.T6G(SCH_1):GND   I114 @T6G_MB_LIB.T6G(SCH_1):PAGE338

PR3792 Q_RES_0402LF-10,1%,1/16W,CHIP,CS01002FB07
     1 P12V_AUX @T6G_MB_LIB.T6G(SCH_1):P12V_AUX    I56 @T6G_MB_LIB.T6G(SCH_1):PAGE338
     2 P12V_OCP_VCC_1 @T6G_MB_LIB.T6G(SCH_1):P12V_OCP_VCC_1    I56 @T6G_MB_LIB.T6G(SCH_1):PAGE338

PR3795 Q_RES_0402LF-25.5K,1%,1/16W,CHIP,CS32552FB06
     1 P3V3_AUX @T6G_MB_LIB.T6G(SCH_1):P3V3_AUX    I56 @T6G_MB_LIB.T6G(SCH_1):PAGE343
     2 P3V3_OCP_UV_2 @T6G_MB_LIB.T6G(SCH_1):P3V3_OCP_UV_2    I56 @T6G_MB_LIB.T6G(SCH_1):PAGE343

PR3798 Q_RES_0402LF-10,1%,1/16W,CHIP,CS01002FB07
     1 P3V3_AUX @T6G_MB_LIB.T6G(SCH_1):P3V3_AUX    I68 @T6G_MB_LIB.T6G(SCH_1):PAGE338
     2 P3V3_OCP_VCC_1 @T6G_MB_LIB.T6G(SCH_1):P3V3_OCP_VCC_1    I68 @T6G_MB_LIB.T6G(SCH_1):PAGE338

PR3805 Q_RES_0402LF-160K,1%,1/16W,CHIP,CS41602FB05
     1 P12V_AUX @T6G_MB_LIB.T6G(SCH_1):P12V_AUX    I36 @T6G_MB_LIB.T6G(SCH_1):PAGE343
     2 P12V_OCP_UV_2 @T6G_MB_LIB.T6G(SCH_1):P12V_OCP_UV_2    I36 @T6G_MB_LIB.T6G(SCH_1):PAGE343

PR3806 Q_RES_0402LF-6.8K,1%,1/16W,CHIP,CS26802FB02
     1 P12V_OCP_UV_2 @T6G_MB_LIB.T6G(SCH_1):P12V_OCP_UV_2    I35 @T6G_MB_LIB.T6G(SCH_1):PAGE343
     2 P12V_OCP_OV_2 @T6G_MB_LIB.T6G(SCH_1):P12V_OCP_OV_2    I35 @T6G_MB_LIB.T6G(SCH_1):PAGE343

PR3812 Q_RES_0402LF-15K,1%,1/16W,CHIP,CS31502FB05
     1 P3V3_OCP_OV_2 @T6G_MB_LIB.T6G(SCH_1):P3V3_OCP_OV_2    I51 @T6G_MB_LIB.T6G(SCH_1):PAGE343
     2    GND @T6G_MB_LIB.T6G(SCH_1):GND    I51 @T6G_MB_LIB.T6G(SCH_1):PAGE343

PR3821 Q_RES_0402LF-30.1K,1%,1/16W,CHIP,CS33012FB03
     1 P12V_OCP_CB_2 @T6G_MB_LIB.T6G(SCH_1):P12V_OCP_CB_2    I63 @T6G_MB_LIB.T6G(SCH_1):PAGE343
     2    GND @T6G_MB_LIB.T6G(SCH_1):GND    I63 @T6G_MB_LIB.T6G(SCH_1):PAGE343

PR3822 Q_RES_0402LF-5.36K,1%,1/16W,CHIP,CS25362FB02
     1 P3V3_OCP_CB_2 @T6G_MB_LIB.T6G(SCH_1):P3V3_OCP_CB_2    I88 @T6G_MB_LIB.T6G(SCH_1):PAGE343
     2    GND @T6G_MB_LIB.T6G(SCH_1):GND    I88 @T6G_MB_LIB.T6G(SCH_1):PAGE343

PR3823 Q_RES_0402LF-845,1%,1/16W,CHIP,CS18452FB01
     1 P12V_OCP_SENSE_2 @T6G_MB_LIB.T6G(SCH_1):P12V_OCP_SENSE_2    I71 @T6G_MB_LIB.T6G(SCH_1):PAGE343
     2    GND @T6G_MB_LIB.T6G(SCH_1):GND    I71 @T6G_MB_LIB.T6G(SCH_1):PAGE343

PR3824 Q_RES_0402LF-4.53K,1%,1/16W,CHIP,CS24532FB03
     1 P3V3_OCP_SENSE_2 @T6G_MB_LIB.T6G(SCH_1):P3V3_OCP_SENSE_2    I94 @T6G_MB_LIB.T6G(SCH_1):PAGE343
     2    GND @T6G_MB_LIB.T6G(SCH_1):GND    I94 @T6G_MB_LIB.T6G(SCH_1):PAGE343

PR3828 Q_RES_0402LF-15K,1%,1/16W,CHIP,CS31502FB05
     1 P12V_OCP_OV_2 @T6G_MB_LIB.T6G(SCH_1):P12V_OCP_OV_2    I31 @T6G_MB_LIB.T6G(SCH_1):PAGE343
     2    GND @T6G_MB_LIB.T6G(SCH_1):GND    I31 @T6G_MB_LIB.T6G(SCH_1):PAGE343

PR3829 Q_RES_0402LF-7.15K,1%,1/16W,CHIP,CS27152FB03
     1 P3V3_OCP_UV_2 @T6G_MB_LIB.T6G(SCH_1):P3V3_OCP_UV_2    I53 @T6G_MB_LIB.T6G(SCH_1):PAGE343
     2 P3V3_OCP_OV_2 @T6G_MB_LIB.T6G(SCH_1):P3V3_OCP_OV_2    I53 @T6G_MB_LIB.T6G(SCH_1):PAGE343

PR3830 Q_RES_0402LF-10,1%,1/16W,CHIP,CS01002FB07
     1 P12V_AUX @T6G_MB_LIB.T6G(SCH_1):P12V_AUX    I84 @T6G_MB_LIB.T6G(SCH_1):PAGE343
     2 P12V_OCP_VCC_2 @T6G_MB_LIB.T6G(SCH_1):P12V_OCP_VCC_2    I84 @T6G_MB_LIB.T6G(SCH_1):PAGE343

PR3835 Q_RES_0402LF-14.3K,1%,1/16W,CHIP,CS31432FB02
     1 P12V_OCP_ISET_1 @T6G_MB_LIB.T6G(SCH_1):P12V_OCP_ISET_1    I63 @T6G_MB_LIB.T6G(SCH_1):PAGE339
     2    GND @T6G_MB_LIB.T6G(SCH_1):GND    I63 @T6G_MB_LIB.T6G(SCH_1):PAGE339

PR3837 Q_RES_0402LF-17.4K,1%,1/16W,CHIP,CS31742FB04
     1 P12V_OCP_IMON_1 @T6G_MB_LIB.T6G(SCH_1):P12V_OCP_IMON_1    I71 @T6G_MB_LIB.T6G(SCH_1):PAGE339
     2    GND @T6G_MB_LIB.T6G(SCH_1):GND    I71 @T6G_MB_LIB.T6G(SCH_1):PAGE339

PR3838 Q_RES_0402LF-100,1%,1/16W,EMPTY,CS11002FB07
     1 P12V_OCP_SFF @T6G_MB_LIB.T6G(SCH_1):P12V_OCP_SFF    I76 @T6G_MB_LIB.T6G(SCH_1):PAGE339
     2 P12V_OCP_AVIN_PD_1 @T6G_MB_LIB.T6G(SCH_1):P12V_OCP_AVIN_PD_1    I76 @T6G_MB_LIB.T6G(SCH_1):PAGE339

PR3839 Q_RES_0402LF-10K,1%,1/16W,CHIP,CS31002FB08
     1 P12V_OCP_FLTB_1 @T6G_MB_LIB.T6G(SCH_1):P12V_OCP_FLTB_1    I74 @T6G_MB_LIB.T6G(SCH_1):PAGE339
     2 P3V3_AUX @T6G_MB_LIB.T6G(SCH_1):P3V3_AUX    I74 @T6G_MB_LIB.T6G(SCH_1):PAGE339

PR3840 Q_RES_0402LF-71.5K,1%,1/16W,EMPTY,CS37152FB05
     1 P12V_OCP_SFF @T6G_MB_LIB.T6G(SCH_1):P12V_OCP_SFF    I81 @T6G_MB_LIB.T6G(SCH_1):PAGE339
     2 P12V_OCP_OV_FB_1 @T6G_MB_LIB.T6G(SCH_1):P12V_OCP_OV_FB_1    I81 @T6G_MB_LIB.T6G(SCH_1):PAGE339

PR3841 Q_RES_0402LF-120K,1%,1/16W,CHIP,CS41202FB05
     1 P12V_AUX @T6G_MB_LIB.T6G(SCH_1):P12V_AUX    I82 @T6G_MB_LIB.T6G(SCH_1):PAGE339
     2 P12V_OCP_OV_FB_1 @T6G_MB_LIB.T6G(SCH_1):P12V_OCP_OV_FB_1    I82 @T6G_MB_LIB.T6G(SCH_1):PAGE339

PR3842 Q_RES_0402LF-10K,1%,1/16W,CHIP,CS31002FB08
     1 P12V_OCP_OV_FB_1 @T6G_MB_LIB.T6G(SCH_1):P12V_OCP_OV_FB_1    I80 @T6G_MB_LIB.T6G(SCH_1):PAGE339
     2    GND @T6G_MB_LIB.T6G(SCH_1):GND    I80 @T6G_MB_LIB.T6G(SCH_1):PAGE339

PR3843 Q_RES_0603LF-49.9,1%,1/10W,CHIP,CS04993F909
     1 P12V_AUX @T6G_MB_LIB.T6G(SCH_1):P12V_AUX    I88 @T6G_MB_LIB.T6G(SCH_1):PAGE339
     2 P12V_OCP_AVIN_PD_1 @T6G_MB_LIB.T6G(SCH_1):P12V_OCP_AVIN_PD_1    I88 @T6G_MB_LIB.T6G(SCH_1):PAGE339

PR3844 Q_RES_0402LF-71.5K,1%,1/16W,CHIP,CS37152FB05
     1 P3V3_OCP_MODE_1 @T6G_MB_LIB.T6G(SCH_1):P3V3_OCP_MODE_1   I100 @T6G_MB_LIB.T6G(SCH_1):PAGE339
     2    GND @T6G_MB_LIB.T6G(SCH_1):GND   I100 @T6G_MB_LIB.T6G(SCH_1):PAGE339

PR3846 Q_RES_0402LF-1.33K,1%,1/16W,CHIP,CS21332FB05
     1    GND @T6G_MB_LIB.T6G(SCH_1):GND   I102 @T6G_MB_LIB.T6G(SCH_1):PAGE339
     2 P3V3_OCP_ILIMIT_1 @T6G_MB_LIB.T6G(SCH_1):P3V3_OCP_ILIMIT_1   I102 @T6G_MB_LIB.T6G(SCH_1):PAGE339

PR3847 Q_RES_0402LF-14.3K,1%,1/16W,CHIP,CS31432FB02
     1 P12V_OCP_ISET_2 @T6G_MB_LIB.T6G(SCH_1):P12V_OCP_ISET_2     I4 @T6G_MB_LIB.T6G(SCH_1):PAGE344
     2    GND @T6G_MB_LIB.T6G(SCH_1):GND     I4 @T6G_MB_LIB.T6G(SCH_1):PAGE344

PR3849 Q_RES_0402LF-17.4K,1%,1/16W,CHIP,CS31742FB04
     1 P12V_OCP_IMON_2 @T6G_MB_LIB.T6G(SCH_1):P12V_OCP_IMON_2    I15 @T6G_MB_LIB.T6G(SCH_1):PAGE344
     2    GND @T6G_MB_LIB.T6G(SCH_1):GND    I15 @T6G_MB_LIB.T6G(SCH_1):PAGE344

PR3850 Q_RES_0402LF-100,1%,1/16W,EMPTY,CS11002FB07
     1 P12V_OCP_V3_2 @T6G_MB_LIB.T6G(SCH_1):P12V_OCP_V3_2    I30 @T6G_MB_LIB.T6G(SCH_1):PAGE344
     2 P12V_OCP_AVIN_PD_2 @T6G_MB_LIB.T6G(SCH_1):P12V_OCP_AVIN_PD_2    I30 @T6G_MB_LIB.T6G(SCH_1):PAGE344

PR3851 Q_RES_0402LF-10K,1%,1/16W,CHIP,CS31002FB08
     1 P12V_OCP_FLTB_2 @T6G_MB_LIB.T6G(SCH_1):P12V_OCP_FLTB_2    I18 @T6G_MB_LIB.T6G(SCH_1):PAGE344
     2 P3V3_AUX @T6G_MB_LIB.T6G(SCH_1):P3V3_AUX    I18 @T6G_MB_LIB.T6G(SCH_1):PAGE344

PR3852 Q_RES_0402LF-71.5K,1%,1/16W,EMPTY,CS37152FB05
     1 P12V_OCP_V3_2 @T6G_MB_LIB.T6G(SCH_1):P12V_OCP_V3_2    I31 @T6G_MB_LIB.T6G(SCH_1):PAGE344
     2 P12V_OCP_OV_FB_2 @T6G_MB_LIB.T6G(SCH_1):P12V_OCP_OV_FB_2    I31 @T6G_MB_LIB.T6G(SCH_1):PAGE344

PR3853 Q_RES_0402LF-120K,1%,1/16W,CHIP,CS41202FB05
     1 P12V_AUX @T6G_MB_LIB.T6G(SCH_1):P12V_AUX    I36 @T6G_MB_LIB.T6G(SCH_1):PAGE344
     2 P12V_OCP_OV_FB_2 @T6G_MB_LIB.T6G(SCH_1):P12V_OCP_OV_FB_2    I36 @T6G_MB_LIB.T6G(SCH_1):PAGE344

PR3854 Q_RES_0402LF-10K,1%,1/16W,CHIP,CS31002FB08
     1 P12V_OCP_OV_FB_2 @T6G_MB_LIB.T6G(SCH_1):P12V_OCP_OV_FB_2    I20 @T6G_MB_LIB.T6G(SCH_1):PAGE344
     2    GND @T6G_MB_LIB.T6G(SCH_1):GND    I20 @T6G_MB_LIB.T6G(SCH_1):PAGE344

PR3855 Q_RES_0402LF-71.5K,1%,1/16W,CHIP,CS37152FB05
     1 P3V3_OCP_MODE_2 @T6G_MB_LIB.T6G(SCH_1):P3V3_OCP_MODE_2    I43 @T6G_MB_LIB.T6G(SCH_1):PAGE344
     2    GND @T6G_MB_LIB.T6G(SCH_1):GND    I43 @T6G_MB_LIB.T6G(SCH_1):PAGE344

PR3856 Q_RES_0402LF-1.33K,1%,1/16W,CHIP,CS21332FB05
     1    GND @T6G_MB_LIB.T6G(SCH_1):GND    I46 @T6G_MB_LIB.T6G(SCH_1):PAGE344
     2 P3V3_OCP_ILIMIT_2 @T6G_MB_LIB.T6G(SCH_1):P3V3_OCP_ILIMIT_2    I46 @T6G_MB_LIB.T6G(SCH_1):PAGE344

PR3857 Q_RES_0603LF-49.9,1%,1/10W,CHIP,CS04993F909
     1 P12V_AUX @T6G_MB_LIB.T6G(SCH_1):P12V_AUX    I37 @T6G_MB_LIB.T6G(SCH_1):PAGE344
     2 P12V_OCP_AVIN_PD_2 @T6G_MB_LIB.T6G(SCH_1):P12V_OCP_AVIN_PD_2    I37 @T6G_MB_LIB.T6G(SCH_1):PAGE344

PR3910 Q_RES_0402LF-0,5%,1/16W,CHIP,CS00002JB13
     1 HSC_VDD_R_1 @T6G_MB_LIB.T6G(SCH_1):HSC_VDD_R_1    I21 @T6G_MB_LIB.T6G(SCH_1):PAGE301
     2 HSC_VDD @T6G_MB_LIB.T6G(SCH_1):HSC_VDD    I21 @T6G_MB_LIB.T6G(SCH_1):PAGE301

PR3911 Q_RES_0402LF-0,5%,1/16W,CHIP,CS00002JB13
     1 HSC_VDD_R_2 @T6G_MB_LIB.T6G(SCH_1):HSC_VDD_R_2     I5 @T6G_MB_LIB.T6G(SCH_1):PAGE301
     2 HSC_VDD @T6G_MB_LIB.T6G(SCH_1):HSC_VDD     I5 @T6G_MB_LIB.T6G(SCH_1):PAGE301

PR3912 Q_RES_0402LF-120K,1%,1/16W,CHIP,CS41202FB05
     1 AGND_HSC @T6G_MB_LIB.T6G(SCH_1):AGND_HSC    I11 @T6G_MB_LIB.T6G(SCH_1):PAGE301
     2 HSC_MODE_2 @T6G_MB_LIB.T6G(SCH_1):HSC_MODE_2    I11 @T6G_MB_LIB.T6G(SCH_1):PAGE301

PR3914 Q_RES_0402LF-2K,0.1%,1/16W,CHIP,CS22002BB07
     1 HSC_CS_1 @T6G_MB_LIB.T6G(SCH_1):HSC_CS_1    I31 @T6G_MB_LIB.T6G(SCH_1):PAGE301
     2 AGND_HSC @T6G_MB_LIB.T6G(SCH_1):AGND_HSC    I31 @T6G_MB_LIB.T6G(SCH_1):PAGE301

PR3915 Q_RES_0402LF-2K,0.1%,1/16W,CHIP,CS22002BB07
     1 HSC_CS_2 @T6G_MB_LIB.T6G(SCH_1):HSC_CS_2    I13 @T6G_MB_LIB.T6G(SCH_1):PAGE301
     2 AGND_HSC @T6G_MB_LIB.T6G(SCH_1):AGND_HSC    I13 @T6G_MB_LIB.T6G(SCH_1):PAGE301

PR3916 Q_RES_0402LF-0,5%,1/16W,CHIP,CS00002JB13
     1 HSC_SCREF @T6G_MB_LIB.T6G(SCH_1):HSC_SCREF    I33 @T6G_MB_LIB.T6G(SCH_1):PAGE301
     2 HSC_SCREF_1 @T6G_MB_LIB.T6G(SCH_1):HSC_SCREF_1    I33 @T6G_MB_LIB.T6G(SCH_1):PAGE301

PR3917 Q_RES_0402LF-0,5%,1/16W,CHIP,CS00002JB13
     1 HSC_SCREF @T6G_MB_LIB.T6G(SCH_1):HSC_SCREF    I17 @T6G_MB_LIB.T6G(SCH_1):PAGE301
     2 HSC_SCREF_2 @T6G_MB_LIB.T6G(SCH_1):HSC_SCREF_2    I17 @T6G_MB_LIB.T6G(SCH_1):PAGE301

PR3918 Q_RES_0402LF-2K,0.1%,1/16W,CHIP,CS22002BB07
     1 HSC_IMON @T6G_MB_LIB.T6G(SCH_1):HSC_IMON    I34 @T6G_MB_LIB.T6G(SCH_1):PAGE301
     2 AGND_HSC @T6G_MB_LIB.T6G(SCH_1):AGND_HSC    I34 @T6G_MB_LIB.T6G(SCH_1):PAGE301

PR3919 Q_RES_0402LF-0,5%,1/16W,CHIP,CS00002JB13
     1 HSC_D_OC_1 @T6G_MB_LIB.T6G(SCH_1):HSC_D_OC_1    I50 @T6G_MB_LIB.T6G(SCH_1):PAGE301
     2 HSC_D_OC_R @T6G_MB_LIB.T6G(SCH_1):HSC_D_OC_R    I50 @T6G_MB_LIB.T6G(SCH_1):PAGE301

PR3920 Q_RES_0402LF-0,5%,1/16W,CHIP,CS00002JB13
     1 HSC_FLT_TYPE_1 @T6G_MB_LIB.T6G(SCH_1):HSC_FLT_TYPE_1    I49 @T6G_MB_LIB.T6G(SCH_1):PAGE301
     2 HSC_FLT_TYPE @T6G_MB_LIB.T6G(SCH_1):HSC_FLT_TYPE    I49 @T6G_MB_LIB.T6G(SCH_1):PAGE301

PR3921 Q_RES_0402LF-0,5%,1/16W,CHIP,CS00002JB13
     1 HSC_D_OC_2 @T6G_MB_LIB.T6G(SCH_1):HSC_D_OC_2    I40 @T6G_MB_LIB.T6G(SCH_1):PAGE301
     2 HSC_D_OC_R @T6G_MB_LIB.T6G(SCH_1):HSC_D_OC_R    I40 @T6G_MB_LIB.T6G(SCH_1):PAGE301

PR3922 Q_RES_0402LF-0,5%,1/16W,CHIP,CS00002JB13
     1 HSC_FLT_TYPE_2 @T6G_MB_LIB.T6G(SCH_1):HSC_FLT_TYPE_2    I39 @T6G_MB_LIB.T6G(SCH_1):PAGE301
     2 HSC_FLT_TYPE @T6G_MB_LIB.T6G(SCH_1):HSC_FLT_TYPE    I39 @T6G_MB_LIB.T6G(SCH_1):PAGE301

PR3926 Q_RES_0402LF-75K,0.1%,1/16W,CHIP,CS37502BB01
     1 P12V_PSU @T6G_MB_LIB.T6G(SCH_1):P12V_PSU    I48 @T6G_MB_LIB.T6G(SCH_1):PAGE267
     2 HSC_VSENSE @T6G_MB_LIB.T6G(SCH_1):HSC_VSENSE    I48 @T6G_MB_LIB.T6G(SCH_1):PAGE267

PR3927 Q_RES_0402LF-4.99K,0.1%,1/16W,CHIP,CS24992BB04
     1 HSC_VSENSE @T6G_MB_LIB.T6G(SCH_1):HSC_VSENSE    I47 @T6G_MB_LIB.T6G(SCH_1):PAGE267
     2 AGND_HSC @T6G_MB_LIB.T6G(SCH_1):AGND_HSC    I47 @T6G_MB_LIB.T6G(SCH_1):PAGE267

PR3928 Q_RES_0402LF-0,5%,1/16W,CHIP,CS00002JB13
     1 HSC_ON @T6G_MB_LIB.T6G(SCH_1):HSC_ON    I51 @T6G_MB_LIB.T6G(SCH_1):PAGE267
     2 HSC_ON_R @T6G_MB_LIB.T6G(SCH_1):HSC_ON_R    I51 @T6G_MB_LIB.T6G(SCH_1):PAGE267

PR3929 Q_RES_0402LF-1K,1%,1/16W,EMPTY,CS21002FB06
     1 HSC_ADDR @T6G_MB_LIB.T6G(SCH_1):HSC_ADDR    I53 @T6G_MB_LIB.T6G(SCH_1):PAGE267
     2 HSC_VDD18 @T6G_MB_LIB.T6G(SCH_1):HSC_VDD18    I53 @T6G_MB_LIB.T6G(SCH_1):PAGE267

PR3930 Q_RES_0402LF-0,5%,1/16W,CHIP,CS00002JB13
     1 AGND_HSC @T6G_MB_LIB.T6G(SCH_1):AGND_HSC    I52 @T6G_MB_LIB.T6G(SCH_1):PAGE267
     2 HSC_ADDR @T6G_MB_LIB.T6G(SCH_1):HSC_ADDR    I52 @T6G_MB_LIB.T6G(SCH_1):PAGE267

PR3931 Q_RES_0402LF-75K,0.1%,1/16W,CHIP,CS37502BB01
     1 P12V_AUX @T6G_MB_LIB.T6G(SCH_1):P12V_AUX    I71 @T6G_MB_LIB.T6G(SCH_1):PAGE267
     2 HSC_VOSEN @T6G_MB_LIB.T6G(SCH_1):HSC_VOSEN    I71 @T6G_MB_LIB.T6G(SCH_1):PAGE267

PR3932 Q_RES_0402LF-4.99K,0.1%,1/16W,CHIP,CS24992BB04
     1 HSC_VOSEN @T6G_MB_LIB.T6G(SCH_1):HSC_VOSEN    I70 @T6G_MB_LIB.T6G(SCH_1):PAGE267
     2 AGND_HSC @T6G_MB_LIB.T6G(SCH_1):AGND_HSC    I70 @T6G_MB_LIB.T6G(SCH_1):PAGE267

PR3935 Q_RES_0402LF-10K,1%,1/16W,CHIP,CS31002FB08
     1 HSC_VTEMP @T6G_MB_LIB.T6G(SCH_1):HSC_VTEMP    I81 @T6G_MB_LIB.T6G(SCH_1):PAGE267
     2 AGND_HSC @T6G_MB_LIB.T6G(SCH_1):AGND_HSC    I81 @T6G_MB_LIB.T6G(SCH_1):PAGE267

PR3937 Q_RES_0402LF-120K,1%,1/16W,CHIP,CS41202FB05
     1 HSC_MODE @T6G_MB_LIB.T6G(SCH_1):HSC_MODE    I85 @T6G_MB_LIB.T6G(SCH_1):PAGE267
     2 AGND_HSC @T6G_MB_LIB.T6G(SCH_1):AGND_HSC    I85 @T6G_MB_LIB.T6G(SCH_1):PAGE267

PR3944 Q_RES_0402LF-46.4K,1%,1/16W,CHIP,CS34642FB02
     1 P12V_E1S_ISET_0 @T6G_MB_LIB.T6G(SCH_1):P12V_E1S_ISET_0    I15 @T6G_MB_LIB.T6G(SCH_1):PAGE323
     2    GND @T6G_MB_LIB.T6G(SCH_1):GND    I15 @T6G_MB_LIB.T6G(SCH_1):PAGE323

PR3945 Q_RES_0402LF-71.5K,1%,1/16W,CHIP,CS37152FB05
     1 P3V3_E1S_MODE_0 @T6G_MB_LIB.T6G(SCH_1):P3V3_E1S_MODE_0     I4 @T6G_MB_LIB.T6G(SCH_1):PAGE323
     2    GND @T6G_MB_LIB.T6G(SCH_1):GND     I4 @T6G_MB_LIB.T6G(SCH_1):PAGE323

PR3947 Q_RES_0402LF-2.8K,1%,1/16W,CHIP,CS22802FB04
     1    GND @T6G_MB_LIB.T6G(SCH_1):GND     I6 @T6G_MB_LIB.T6G(SCH_1):PAGE323
     2 P3V3_E1S_ILIMIT_0 @T6G_MB_LIB.T6G(SCH_1):P3V3_E1S_ILIMIT_0     I6 @T6G_MB_LIB.T6G(SCH_1):PAGE323

PR3949 Q_RES_0402LF-56K,1%,1/16W,CHIP,CS35602FB00
     1 P12V_E1S_IMON_0 @T6G_MB_LIB.T6G(SCH_1):P12V_E1S_IMON_0    I36 @T6G_MB_LIB.T6G(SCH_1):PAGE323
     2    GND @T6G_MB_LIB.T6G(SCH_1):GND    I36 @T6G_MB_LIB.T6G(SCH_1):PAGE323

PR3950 Q_RES_0402LF-100,1%,1/16W,EMPTY,CS11002FB07
     1 P12V_E1S_0 @T6G_MB_LIB.T6G(SCH_1):P12V_E1S_0    I42 @T6G_MB_LIB.T6G(SCH_1):PAGE323
     2 P12V_E1S_AVIN_PD_0 @T6G_MB_LIB.T6G(SCH_1):P12V_E1S_AVIN_PD_0    I42 @T6G_MB_LIB.T6G(SCH_1):PAGE323

PR3951 Q_RES_0402LF-10K,1%,1/16W,CHIP,CS31002FB08
     1 P12V_E1S_FLTB_0 @T6G_MB_LIB.T6G(SCH_1):P12V_E1S_FLTB_0    I40 @T6G_MB_LIB.T6G(SCH_1):PAGE323
     2 P3V3_AUX @T6G_MB_LIB.T6G(SCH_1):P3V3_AUX    I40 @T6G_MB_LIB.T6G(SCH_1):PAGE323

PR3952 Q_RES_0402LF-71.5K,1%,1/16W,EMPTY,CS37152FB05
     1 P12V_E1S_0 @T6G_MB_LIB.T6G(SCH_1):P12V_E1S_0    I45 @T6G_MB_LIB.T6G(SCH_1):PAGE323
     2 P12V_E1S_OV_FB_0 @T6G_MB_LIB.T6G(SCH_1):P12V_E1S_OV_FB_0    I45 @T6G_MB_LIB.T6G(SCH_1):PAGE323

PR3953 Q_RES_0402LF-120K,1%,1/16W,CHIP,CS41202FB05
     1 P12V_AUX @T6G_MB_LIB.T6G(SCH_1):P12V_AUX    I52 @T6G_MB_LIB.T6G(SCH_1):PAGE323
     2 P12V_E1S_OV_FB_0 @T6G_MB_LIB.T6G(SCH_1):P12V_E1S_OV_FB_0    I52 @T6G_MB_LIB.T6G(SCH_1):PAGE323

PR3954 Q_RES_0402LF-10K,1%,1/16W,CHIP,CS31002FB08
     1 P12V_E1S_OV_FB_0 @T6G_MB_LIB.T6G(SCH_1):P12V_E1S_OV_FB_0    I49 @T6G_MB_LIB.T6G(SCH_1):PAGE323
     2    GND @T6G_MB_LIB.T6G(SCH_1):GND    I49 @T6G_MB_LIB.T6G(SCH_1):PAGE323

PR3957 Q_RES_0603LF-49.9,1%,1/10W,CHIP,CS04993F909
     1 P12V_AUX @T6G_MB_LIB.T6G(SCH_1):P12V_AUX    I54 @T6G_MB_LIB.T6G(SCH_1):PAGE323
     2 P12V_E1S_AVIN_PD_0 @T6G_MB_LIB.T6G(SCH_1):P12V_E1S_AVIN_PD_0    I54 @T6G_MB_LIB.T6G(SCH_1):PAGE323

PR3960 Q_RES_0402LF-160K,1%,1/16W,CHIP,CS41602FB05
     1 P12V_AUX @T6G_MB_LIB.T6G(SCH_1):P12V_AUX    I37 @T6G_MB_LIB.T6G(SCH_1):PAGE324
     2 P12V_E1S_UV_0 @T6G_MB_LIB.T6G(SCH_1):P12V_E1S_UV_0    I37 @T6G_MB_LIB.T6G(SCH_1):PAGE324

PR3961 Q_RES_0402LF-6.8K,1%,1/16W,CHIP,CS26802FB02
     1 P12V_E1S_UV_0 @T6G_MB_LIB.T6G(SCH_1):P12V_E1S_UV_0    I32 @T6G_MB_LIB.T6G(SCH_1):PAGE324
     2 P12V_E1S_OV_0 @T6G_MB_LIB.T6G(SCH_1):P12V_E1S_OV_0    I32 @T6G_MB_LIB.T6G(SCH_1):PAGE324

PR3962 Q_RES_0402LF-15K,1%,1/16W,CHIP,CS31502FB05
     1 P12V_E1S_OV_0 @T6G_MB_LIB.T6G(SCH_1):P12V_E1S_OV_0    I31 @T6G_MB_LIB.T6G(SCH_1):PAGE324
     2    GND @T6G_MB_LIB.T6G(SCH_1):GND    I31 @T6G_MB_LIB.T6G(SCH_1):PAGE324

PR3963 Q_RES_0402LF-25.5K,1%,1/16W,CHIP,CS32552FB06
     1 P3V3_AUX @T6G_MB_LIB.T6G(SCH_1):P3V3_AUX    I21 @T6G_MB_LIB.T6G(SCH_1):PAGE324
     2 P3V3_E1S_UV_0 @T6G_MB_LIB.T6G(SCH_1):P3V3_E1S_UV_0    I21 @T6G_MB_LIB.T6G(SCH_1):PAGE324

PR3964 Q_RES_0402LF-7.15K,1%,1/16W,CHIP,CS27152FB03
     1 P3V3_E1S_UV_0 @T6G_MB_LIB.T6G(SCH_1):P3V3_E1S_UV_0    I17 @T6G_MB_LIB.T6G(SCH_1):PAGE324
     2 P3V3_E1S_OV_0 @T6G_MB_LIB.T6G(SCH_1):P3V3_E1S_OV_0    I17 @T6G_MB_LIB.T6G(SCH_1):PAGE324

PR3965 Q_RES_0402LF-15K,1%,1/16W,CHIP,CS31502FB05
     1 P3V3_E1S_OV_0 @T6G_MB_LIB.T6G(SCH_1):P3V3_E1S_OV_0    I16 @T6G_MB_LIB.T6G(SCH_1):PAGE324
     2    GND @T6G_MB_LIB.T6G(SCH_1):GND    I16 @T6G_MB_LIB.T6G(SCH_1):PAGE324

PR3966 Q_RES_0402LF-10,1%,1/16W,CHIP,CS01002FB07
     1 P12V_AUX @T6G_MB_LIB.T6G(SCH_1):P12V_AUX    I65 @T6G_MB_LIB.T6G(SCH_1):PAGE324
     2 P12V_E1S_VCC_0 @T6G_MB_LIB.T6G(SCH_1):P12V_E1S_VCC_0    I65 @T6G_MB_LIB.T6G(SCH_1):PAGE324

PR3967 Q_RES_0402LF-10,1%,1/16W,CHIP,CS01002FB07
     1 P3V3_AUX @T6G_MB_LIB.T6G(SCH_1):P3V3_AUX    I43 @T6G_MB_LIB.T6G(SCH_1):PAGE324
     2 P3V3_E1S_VCC_0 @T6G_MB_LIB.T6G(SCH_1):P3V3_E1S_VCC_0    I43 @T6G_MB_LIB.T6G(SCH_1):PAGE324

PR3968 Q_RES_0402LF-9.31K,1%,1/16W,CHIP,CS29312FB02
     1 P12V_E1S_CB_0 @T6G_MB_LIB.T6G(SCH_1):P12V_E1S_CB_0    I63 @T6G_MB_LIB.T6G(SCH_1):PAGE324
     2    GND @T6G_MB_LIB.T6G(SCH_1):GND    I63 @T6G_MB_LIB.T6G(SCH_1):PAGE324

PR3969 Q_RES_0402LF-2.49K,1%,1/16W,CHIP,CS22492FB05
     1 P3V3_E1S_CB_0 @T6G_MB_LIB.T6G(SCH_1):P3V3_E1S_CB_0    I39 @T6G_MB_LIB.T6G(SCH_1):PAGE324
     2    GND @T6G_MB_LIB.T6G(SCH_1):GND    I39 @T6G_MB_LIB.T6G(SCH_1):PAGE324

PR3970 Q_RES_0402LF-2.67K,1%,1/16W,CHIP,CS22672FB03
     1 P12V_E1S_SENSE_0 @T6G_MB_LIB.T6G(SCH_1):P12V_E1S_SENSE_0    I68 @T6G_MB_LIB.T6G(SCH_1):PAGE324
     2    GND @T6G_MB_LIB.T6G(SCH_1):GND    I68 @T6G_MB_LIB.T6G(SCH_1):PAGE324

PR3971 Q_RES_0402LF-9.76K,1%,1/16W,CHIP,CS29762FB05
     1 P3V3_E1S_SENSE_0 @T6G_MB_LIB.T6G(SCH_1):P3V3_E1S_SENSE_0    I45 @T6G_MB_LIB.T6G(SCH_1):PAGE324
     2    GND @T6G_MB_LIB.T6G(SCH_1):GND    I45 @T6G_MB_LIB.T6G(SCH_1):PAGE324

PR3980 Q_RES_0402LF-0,5%,1/16W,CHIP,CS00002JB13
     1 HSC_VDD_R_3 @T6G_MB_LIB.T6G(SCH_1):HSC_VDD_R_3    I21 @T6G_MB_LIB.T6G(SCH_1):PAGE325
     2 HSC_VDD @T6G_MB_LIB.T6G(SCH_1):HSC_VDD    I21 @T6G_MB_LIB.T6G(SCH_1):PAGE325

PR3981 Q_RES_0402LF-0,5%,1/16W,CHIP,CS00002JB13
     1 HSC_VDD_R_4 @T6G_MB_LIB.T6G(SCH_1):HSC_VDD_R_4     I6 @T6G_MB_LIB.T6G(SCH_1):PAGE325
     2 HSC_VDD @T6G_MB_LIB.T6G(SCH_1):HSC_VDD     I6 @T6G_MB_LIB.T6G(SCH_1):PAGE325

PR3982 Q_RES_0402LF-120K,1%,1/16W,CHIP,CS41202FB05
     1 AGND_HSC @T6G_MB_LIB.T6G(SCH_1):AGND_HSC    I28 @T6G_MB_LIB.T6G(SCH_1):PAGE325
     2 HSC_MODE_3 @T6G_MB_LIB.T6G(SCH_1):HSC_MODE_3    I28 @T6G_MB_LIB.T6G(SCH_1):PAGE325

PR3984 Q_RES_0402LF-120K,1%,1/16W,CHIP,CS41202FB05
     1 AGND_HSC @T6G_MB_LIB.T6G(SCH_1):AGND_HSC    I11 @T6G_MB_LIB.T6G(SCH_1):PAGE325
     2 HSC_MODE_4 @T6G_MB_LIB.T6G(SCH_1):HSC_MODE_4    I11 @T6G_MB_LIB.T6G(SCH_1):PAGE325

PR3986 Q_RES_0402LF-2K,0.1%,1/16W,CHIP,CS22002BB07
     1 HSC_CS_3 @T6G_MB_LIB.T6G(SCH_1):HSC_CS_3    I31 @T6G_MB_LIB.T6G(SCH_1):PAGE325
     2 AGND_HSC @T6G_MB_LIB.T6G(SCH_1):AGND_HSC    I31 @T6G_MB_LIB.T6G(SCH_1):PAGE325

PR3987 Q_RES_0402LF-2K,0.1%,1/16W,CHIP,CS22002BB07
     1 HSC_CS_4 @T6G_MB_LIB.T6G(SCH_1):HSC_CS_4    I13 @T6G_MB_LIB.T6G(SCH_1):PAGE325
     2 AGND_HSC @T6G_MB_LIB.T6G(SCH_1):AGND_HSC    I13 @T6G_MB_LIB.T6G(SCH_1):PAGE325

PR3988 Q_RES_0402LF-0,5%,1/16W,CHIP,CS00002JB13
     1 HSC_SCREF @T6G_MB_LIB.T6G(SCH_1):HSC_SCREF    I33 @T6G_MB_LIB.T6G(SCH_1):PAGE325
     2 HSC_SCREF_3 @T6G_MB_LIB.T6G(SCH_1):HSC_SCREF_3    I33 @T6G_MB_LIB.T6G(SCH_1):PAGE325

PR3989 Q_RES_0402LF-0,5%,1/16W,CHIP,CS00002JB13
     1 HSC_SCREF @T6G_MB_LIB.T6G(SCH_1):HSC_SCREF    I16 @T6G_MB_LIB.T6G(SCH_1):PAGE325
     2 HSC_SCREF_4 @T6G_MB_LIB.T6G(SCH_1):HSC_SCREF_4    I16 @T6G_MB_LIB.T6G(SCH_1):PAGE325

PR3990 Q_RES_0402LF-2K,0.1%,1/16W,CHIP,CS22002BB07
     1 HSC_IMON @T6G_MB_LIB.T6G(SCH_1):HSC_IMON    I34 @T6G_MB_LIB.T6G(SCH_1):PAGE325
     2 AGND_HSC @T6G_MB_LIB.T6G(SCH_1):AGND_HSC    I34 @T6G_MB_LIB.T6G(SCH_1):PAGE325

PR3991 Q_RES_0402LF-2K,0.1%,1/16W,CHIP,CS22002BB07
     1 HSC_IMON @T6G_MB_LIB.T6G(SCH_1):HSC_IMON    I14 @T6G_MB_LIB.T6G(SCH_1):PAGE325
     2 AGND_HSC @T6G_MB_LIB.T6G(SCH_1):AGND_HSC    I14 @T6G_MB_LIB.T6G(SCH_1):PAGE325

PR3992 Q_RES_0402LF-0,5%,1/16W,CHIP,CS00002JB13
     1 HSC_D_OC_3 @T6G_MB_LIB.T6G(SCH_1):HSC_D_OC_3    I50 @T6G_MB_LIB.T6G(SCH_1):PAGE325
     2 HSC_D_OC_R @T6G_MB_LIB.T6G(SCH_1):HSC_D_OC_R    I50 @T6G_MB_LIB.T6G(SCH_1):PAGE325

PR3993 Q_RES_0402LF-0,5%,1/16W,CHIP,CS00002JB13
     1 HSC_FLT_TYPE_3 @T6G_MB_LIB.T6G(SCH_1):HSC_FLT_TYPE_3    I49 @T6G_MB_LIB.T6G(SCH_1):PAGE325
     2 HSC_FLT_TYPE @T6G_MB_LIB.T6G(SCH_1):HSC_FLT_TYPE    I49 @T6G_MB_LIB.T6G(SCH_1):PAGE325

PR3994 Q_RES_0402LF-0,5%,1/16W,CHIP,CS00002JB13
     1 HSC_D_OC_4 @T6G_MB_LIB.T6G(SCH_1):HSC_D_OC_4    I40 @T6G_MB_LIB.T6G(SCH_1):PAGE325
     2 HSC_D_OC_R @T6G_MB_LIB.T6G(SCH_1):HSC_D_OC_R    I40 @T6G_MB_LIB.T6G(SCH_1):PAGE325

PR3995 Q_RES_0402LF-0,5%,1/16W,CHIP,CS00002JB13
     1 HSC_FLT_TYPE_4 @T6G_MB_LIB.T6G(SCH_1):HSC_FLT_TYPE_4    I39 @T6G_MB_LIB.T6G(SCH_1):PAGE325
     2 HSC_FLT_TYPE @T6G_MB_LIB.T6G(SCH_1):HSC_FLT_TYPE    I39 @T6G_MB_LIB.T6G(SCH_1):PAGE325

PR3999 Q_RES_0402LF-24.3K,1%,1/16W,CHIP,CS32432FB03
     1 P12V_SCM_ISET @T6G_MB_LIB.T6G(SCH_1):P12V_SCM_ISET    I11 @T6G_MB_LIB.T6G(SCH_1):PAGE350
     2    GND @T6G_MB_LIB.T6G(SCH_1):GND    I11 @T6G_MB_LIB.T6G(SCH_1):PAGE350

PR4000 Q_RES_0402LF-160K,1%,1/16W,CHIP,CS41602FB05
     1 P12V_AUX @T6G_MB_LIB.T6G(SCH_1):P12V_AUX    I65 @T6G_MB_LIB.T6G(SCH_1):PAGE350
     2 P12V_SCM_UV @T6G_MB_LIB.T6G(SCH_1):P12V_SCM_UV    I65 @T6G_MB_LIB.T6G(SCH_1):PAGE350

PR4001 Q_RES_0402LF-6.8K,1%,1/16W,CHIP,CS26802FB02
     1 P12V_SCM_UV @T6G_MB_LIB.T6G(SCH_1):P12V_SCM_UV    I63 @T6G_MB_LIB.T6G(SCH_1):PAGE350
     2 P12V_SCM_OV @T6G_MB_LIB.T6G(SCH_1):P12V_SCM_OV    I63 @T6G_MB_LIB.T6G(SCH_1):PAGE350

PR4002 Q_RES_0402LF-15K,1%,1/16W,CHIP,CS31502FB05
     1 P12V_SCM_OV @T6G_MB_LIB.T6G(SCH_1):P12V_SCM_OV    I60 @T6G_MB_LIB.T6G(SCH_1):PAGE350
     2    GND @T6G_MB_LIB.T6G(SCH_1):GND    I60 @T6G_MB_LIB.T6G(SCH_1):PAGE350

PR4003 Q_RES_0402LF-10,1%,1/16W,CHIP,CS01002FB07
     1 P12V_AUX @T6G_MB_LIB.T6G(SCH_1):P12V_AUX    I68 @T6G_MB_LIB.T6G(SCH_1):PAGE350
     2 P12V_SCM_VCC @T6G_MB_LIB.T6G(SCH_1):P12V_SCM_VCC    I68 @T6G_MB_LIB.T6G(SCH_1):PAGE350

PR4004 Q_RES_0402LF-17.8K,1%,1/16W,CHIP,CS31782FB04
     1 P12V_SCM_CB @T6G_MB_LIB.T6G(SCH_1):P12V_SCM_CB    I62 @T6G_MB_LIB.T6G(SCH_1):PAGE350
     2    GND @T6G_MB_LIB.T6G(SCH_1):GND    I62 @T6G_MB_LIB.T6G(SCH_1):PAGE350

PR4005 Q_RES_0402LF-30.1K,1%,1/16W,CHIP,CS33012FB03
     1 P12V_SCM_IMON @T6G_MB_LIB.T6G(SCH_1):P12V_SCM_IMON    I35 @T6G_MB_LIB.T6G(SCH_1):PAGE350
     2    GND @T6G_MB_LIB.T6G(SCH_1):GND    I35 @T6G_MB_LIB.T6G(SCH_1):PAGE350

PR4006 Q_RES_0402LF-100,1%,1/16W,EMPTY,CS11002FB07
     1 P12V_SCM_R @T6G_MB_LIB.T6G(SCH_1):P12V_SCM_R    I41 @T6G_MB_LIB.T6G(SCH_1):PAGE350
     2 P12V_SCM_AVIN_PD @T6G_MB_LIB.T6G(SCH_1):P12V_SCM_AVIN_PD    I41 @T6G_MB_LIB.T6G(SCH_1):PAGE350

PR4007 Q_RES_0402LF-10K,1%,1/16W,CHIP,CS31002FB08
     1 P12V_SCM_FLTB_N @T6G_MB_LIB.T6G(SCH_1):P12V_SCM_FLTB_N    I40 @T6G_MB_LIB.T6G(SCH_1):PAGE350
     2 P3V3_AUX @T6G_MB_LIB.T6G(SCH_1):P3V3_AUX    I40 @T6G_MB_LIB.T6G(SCH_1):PAGE350

PR4008 Q_RES_0402LF-1.33K,1%,1/16W,CHIP,CS21332FB05
     1 P12V_SCM_SENSE @T6G_MB_LIB.T6G(SCH_1):P12V_SCM_SENSE    I70 @T6G_MB_LIB.T6G(SCH_1):PAGE350
     2    GND @T6G_MB_LIB.T6G(SCH_1):GND    I70 @T6G_MB_LIB.T6G(SCH_1):PAGE350

PR4009 Q_RES_0402LF-71.5K,1%,1/16W,EMPTY,CS37152FB05
     1 P12V_SCM_R @T6G_MB_LIB.T6G(SCH_1):P12V_SCM_R    I50 @T6G_MB_LIB.T6G(SCH_1):PAGE350
     2 P12V_SCM_OV_FB @T6G_MB_LIB.T6G(SCH_1):P12V_SCM_OV_FB    I50 @T6G_MB_LIB.T6G(SCH_1):PAGE350

PR4010 Q_RES_0402LF-120K,1%,1/16W,CHIP,CS41202FB05
     1 P12V_AUX @T6G_MB_LIB.T6G(SCH_1):P12V_AUX    I51 @T6G_MB_LIB.T6G(SCH_1):PAGE350
     2 P12V_SCM_OV_FB @T6G_MB_LIB.T6G(SCH_1):P12V_SCM_OV_FB    I51 @T6G_MB_LIB.T6G(SCH_1):PAGE350

PR4011 Q_RES_0402LF-10K,1%,1/16W,CHIP,CS31002FB08
     1 P12V_SCM_OV_FB @T6G_MB_LIB.T6G(SCH_1):P12V_SCM_OV_FB    I49 @T6G_MB_LIB.T6G(SCH_1):PAGE350
     2    GND @T6G_MB_LIB.T6G(SCH_1):GND    I49 @T6G_MB_LIB.T6G(SCH_1):PAGE350

PR4012 Q_RES_0402LF-0,5%,1/16W,CHIP,CS00002JB13
     1 P12V_SCM_PWRGD @T6G_MB_LIB.T6G(SCH_1):P12V_SCM_PWRGD    I73 @T6G_MB_LIB.T6G(SCH_1):PAGE350
     2 HP_LVC3_SCM_HSC_PWRGD @T6G_MB_LIB.T6G(SCH_1):HP_LVC3_SCM_HSC_PWRGD    I73 @T6G_MB_LIB.T6G(SCH_1):PAGE350

PR4014 Q_RES_0603LF-49.9,1%,1/10W,CHIP,CS04993F909
     1 P12V_AUX @T6G_MB_LIB.T6G(SCH_1):P12V_AUX    I53 @T6G_MB_LIB.T6G(SCH_1):PAGE350
     2 P12V_SCM_AVIN_PD @T6G_MB_LIB.T6G(SCH_1):P12V_SCM_AVIN_PD    I53 @T6G_MB_LIB.T6G(SCH_1):PAGE350

PR4522 Q_RES_0402LF-10M,1%,1/16W,CHIP,CS61002FB02
     1 P12V_OCP_V3_2 @T6G_MB_LIB.T6G(SCH_1):P12V_OCP_V3_2    I76 @T6G_MB_LIB.T6G(SCH_1):PAGE343
     2 P12V_OCP_GATE_2 @T6G_MB_LIB.T6G(SCH_1):P12V_OCP_GATE_2    I76 @T6G_MB_LIB.T6G(SCH_1):PAGE343

PR4523 Q_RES_0402LF-10M,1%,1/16W,CHIP,CS61002FB02
     1 P3V3_OCP_V3_2_R @T6G_MB_LIB.T6G(SCH_1):P3V3_OCP_V3_2_R   I105 @T6G_MB_LIB.T6G(SCH_1):PAGE343
     2 P3V3_OCP_GATE_2 @T6G_MB_LIB.T6G(SCH_1):P3V3_OCP_GATE_2   I105 @T6G_MB_LIB.T6G(SCH_1):PAGE343

PR4524 Q_RES_0402LF-10M,1%,1/16W,CHIP,CS61002FB02
     1 P12V_OCP_SFF @T6G_MB_LIB.T6G(SCH_1):P12V_OCP_SFF    I76 @T6G_MB_LIB.T6G(SCH_1):PAGE338
     2 P12V_OCP_GATE_1 @T6G_MB_LIB.T6G(SCH_1):P12V_OCP_GATE_1    I76 @T6G_MB_LIB.T6G(SCH_1):PAGE338

PR4525 Q_RES_0402LF-10M,1%,1/16W,CHIP,CS61002FB02
     1 P3V3_OCP_SFF_R @T6G_MB_LIB.T6G(SCH_1):P3V3_OCP_SFF_R    I96 @T6G_MB_LIB.T6G(SCH_1):PAGE338
     2 P3V3_OCP_GATE_PU202_1 @T6G_MB_LIB.T6G(SCH_1):P3V3_OCP_GATE_PU202_1    I96 @T6G_MB_LIB.T6G(SCH_1):PAGE338

PR4526 Q_RES_0402LF-10M,1%,1/16W,CHIP,CS61002FB02
     1 P12V_SCM_R @T6G_MB_LIB.T6G(SCH_1):P12V_SCM_R    I74 @T6G_MB_LIB.T6G(SCH_1):PAGE350
     2 P12V_SCM_GATE @T6G_MB_LIB.T6G(SCH_1):P12V_SCM_GATE    I74 @T6G_MB_LIB.T6G(SCH_1):PAGE350

PR4527 Q_RES_0402LF-10M,1%,1/16W,CHIP,CS61002FB02
     1 P3V3_E1S_0_R @T6G_MB_LIB.T6G(SCH_1):P3V3_E1S_0_R    I47 @T6G_MB_LIB.T6G(SCH_1):PAGE324
     2 P3V3_E1S_GATE_0 @T6G_MB_LIB.T6G(SCH_1):P3V3_E1S_GATE_0    I47 @T6G_MB_LIB.T6G(SCH_1):PAGE324

PR4528 Q_RES_0402LF-10M,1%,1/16W,CHIP,CS61002FB02
     1 P12V_E1S_0 @T6G_MB_LIB.T6G(SCH_1):P12V_E1S_0    I73 @T6G_MB_LIB.T6G(SCH_1):PAGE324
     2 P12V_E1S_GATE_0 @T6G_MB_LIB.T6G(SCH_1):P12V_E1S_GATE_0    I73 @T6G_MB_LIB.T6G(SCH_1):PAGE324

PR4540 Q_RES_0402LF-20K,1%,1/16W,CHIP,CS32002FB06
     1 P12V_SCM_ISET @T6G_MB_LIB.T6G(SCH_1):P12V_SCM_ISET    I12 @T6G_MB_LIB.T6G(SCH_1):PAGE350
     2 P12V_SCM_ISET_R @T6G_MB_LIB.T6G(SCH_1):P12V_SCM_ISET_R    I12 @T6G_MB_LIB.T6G(SCH_1):PAGE350

PR4541 Q_RES_0402LF-20K,1%,1/16W,CHIP,CS32002FB06
     1 P12V_E1S_ISET_0 @T6G_MB_LIB.T6G(SCH_1):P12V_E1S_ISET_0    I18 @T6G_MB_LIB.T6G(SCH_1):PAGE323
     2 P12V_E1S_ISET_0_R @T6G_MB_LIB.T6G(SCH_1):P12V_E1S_ISET_0_R    I18 @T6G_MB_LIB.T6G(SCH_1):PAGE323

PR5481 Q_RES_0402LF-4.53K,1%,1/16W,CHIP,CS24532FB03
     1 P3V3_OCP_SENSE_1 @T6G_MB_LIB.T6G(SCH_1):P3V3_OCP_SENSE_1    I95 @T6G_MB_LIB.T6G(SCH_1):PAGE338
     2    GND @T6G_MB_LIB.T6G(SCH_1):GND    I95 @T6G_MB_LIB.T6G(SCH_1):PAGE338

PR5484 Q_RES_0402LF-30.1K,1%,1/16W,CHIP,CS33012FB03
     1 P12V_OCP_CB_1 @T6G_MB_LIB.T6G(SCH_1):P12V_OCP_CB_1    I48 @T6G_MB_LIB.T6G(SCH_1):PAGE338
     2    GND @T6G_MB_LIB.T6G(SCH_1):GND    I48 @T6G_MB_LIB.T6G(SCH_1):PAGE338

PR6000 Q_RES_0402LF-0,5%,1/16W,CHIP,CS00002JB13
     1    GND @T6G_MB_LIB.T6G(SCH_1):GND    I17 @T6G_MB_LIB.T6G(SCH_1):PAGE167
     2 PVDD_33_S5_MODE @T6G_MB_LIB.T6G(SCH_1):PVDD_33_S5_MODE    I17 @T6G_MB_LIB.T6G(SCH_1):PAGE167

PR6001 Q_SP_RES4P-0.0003,1%,4W,SMLF,CHIP,SP_CS0000FFT09
    2B P12V_HSC_SENSE2_R1_N @T6G_MB_LIB.T6G(SCH_1):P12V_HSC_SENSE2_R1_N    I55 @T6G_MB_LIB.T6G(SCH_1):PAGE302
    1B P12V_HSC_SENSE2_R1_P @T6G_MB_LIB.T6G(SCH_1):P12V_HSC_SENSE2_R1_P    I55 @T6G_MB_LIB.T6G(SCH_1):PAGE302
    2A P12V_MAIN_R @T6G_MB_LIB.T6G(SCH_1):P12V_MAIN_R    I55 @T6G_MB_LIB.T6G(SCH_1):PAGE302
    1A P12V_PSU @T6G_MB_LIB.T6G(SCH_1):P12V_PSU    I55 @T6G_MB_LIB.T6G(SCH_1):PAGE302

PR6002 Q_SP_RES4P-0.003,1%,2W,SMLF,CHIP,SP_CS+003AFR00_1
    2B P12V_HSC_SENSE1_N @T6G_MB_LIB.T6G(SCH_1):P12V_HSC_SENSE1_N    I81 @T6G_MB_LIB.T6G(SCH_1):PAGE302
    1B P12V_HSC_SENSE1_P @T6G_MB_LIB.T6G(SCH_1):P12V_HSC_SENSE1_P    I81 @T6G_MB_LIB.T6G(SCH_1):PAGE302
    2A P12V_MAIN_R_0 @T6G_MB_LIB.T6G(SCH_1):P12V_MAIN_R_0    I81 @T6G_MB_LIB.T6G(SCH_1):PAGE302
    1A P12V_PSU @T6G_MB_LIB.T6G(SCH_1):P12V_PSU    I81 @T6G_MB_LIB.T6G(SCH_1):PAGE302

PR6003 Q_RES_0402LF-10K,1%,1/16W,CHIP,CS31002FB08
     1 P1V8_AUX_CS @T6G_MB_LIB.T6G(SCH_1):P1V8_AUX_CS    I12 @T6G_MB_LIB.T6G(SCH_1):PAGE315
     2    GND @T6G_MB_LIB.T6G(SCH_1):GND    I12 @T6G_MB_LIB.T6G(SCH_1):PAGE315

PR6004 Q_RES_0402LF-11.5K,1%,1/16W,CHIP,CS31152FB03
     1 P1V2_AUX_CS @T6G_MB_LIB.T6G(SCH_1):P1V2_AUX_CS     I6 @T6G_MB_LIB.T6G(SCH_1):PAGE380
     2    GND @T6G_MB_LIB.T6G(SCH_1):GND     I6 @T6G_MB_LIB.T6G(SCH_1):PAGE380

PR6005 Q_RES_0402LF-60.4K,1%,1/16W,CHIP,CS36042FB04
     1    GND @T6G_MB_LIB.T6G(SCH_1):GND    I11 @T6G_MB_LIB.T6G(SCH_1):PAGE380
     2 P1V2_AUX_MODE @T6G_MB_LIB.T6G(SCH_1):P1V2_AUX_MODE    I11 @T6G_MB_LIB.T6G(SCH_1):PAGE380

PR6006 Q_RES_0402LF-60.4K,1%,1/16W,CHIP,CS36042FB04
     1    GND @T6G_MB_LIB.T6G(SCH_1):GND    I15 @T6G_MB_LIB.T6G(SCH_1):PAGE315
     2 P1V8_AUX_MODE @T6G_MB_LIB.T6G(SCH_1):P1V8_AUX_MODE    I15 @T6G_MB_LIB.T6G(SCH_1):PAGE315

PR6007 Q_RES_0402LF-20K,1%,1/16W,CHIP,CS32002FB06
     1 P1V8_AUX_FB @T6G_MB_LIB.T6G(SCH_1):P1V8_AUX_FB    I28 @T6G_MB_LIB.T6G(SCH_1):PAGE315
     2 P1V8_AUX @T6G_MB_LIB.T6G(SCH_1):P1V8_AUX    I28 @T6G_MB_LIB.T6G(SCH_1):PAGE315

PR6008 Q_RES_0402LF-10K,1%,1/16W,CHIP,CS31002FB08
     1 P1V2_AUX_FB @T6G_MB_LIB.T6G(SCH_1):P1V2_AUX_FB    I27 @T6G_MB_LIB.T6G(SCH_1):PAGE380
     2 P1V2_AUX @T6G_MB_LIB.T6G(SCH_1):P1V2_AUX    I27 @T6G_MB_LIB.T6G(SCH_1):PAGE380

PR6010 Q_RES_0402LF-10K,1%,1/16W,CHIP,CS31002FB08
     1 P1V8_AUX_FB @T6G_MB_LIB.T6G(SCH_1):P1V8_AUX_FB    I23 @T6G_MB_LIB.T6G(SCH_1):PAGE315
     2    GND @T6G_MB_LIB.T6G(SCH_1):GND    I23 @T6G_MB_LIB.T6G(SCH_1):PAGE315

PR6011 Q_RES_0402LF-10K,1%,1/16W,CHIP,CS31002FB08
     1 P1V2_AUX_FB @T6G_MB_LIB.T6G(SCH_1):P1V2_AUX_FB    I21 @T6G_MB_LIB.T6G(SCH_1):PAGE380
     2    GND @T6G_MB_LIB.T6G(SCH_1):GND    I21 @T6G_MB_LIB.T6G(SCH_1):PAGE380

PR6500 Q_RES_0402LF-0,5%,1/16W,CHIP,CS00002JB13
     1    GND @T6G_MB_LIB.T6G(SCH_1):GND    I21 @T6G_MB_LIB.T6G(SCH_1):PAGE469
     2 P1V8_RETIMER_CPU0_MODE @T6G_MB_LIB.T6G(SCH_1):P1V8_RETIMER_CPU0_MODE    I21 @T6G_MB_LIB.T6G(SCH_1):PAGE469

PR6501 Q_RES_0402LF-0,5%,1/16W,CHIP,CS00002JB13
     1 P3V3_AUX @T6G_MB_LIB.T6G(SCH_1):P3V3_AUX    I13 @T6G_MB_LIB.T6G(SCH_1):PAGE469
     2 P1V8_RETIMER_CPU0_VCC @T6G_MB_LIB.T6G(SCH_1):P1V8_RETIMER_CPU0_VCC    I13 @T6G_MB_LIB.T6G(SCH_1):PAGE469

PR6502 Q_RES_0402LF-7.15K,1%,1/16W,CHIP,CS27152FB03
     1 P1V8_RETIMER_CPU0_CS @T6G_MB_LIB.T6G(SCH_1):P1V8_RETIMER_CPU0_CS    I20 @T6G_MB_LIB.T6G(SCH_1):PAGE469
     2    GND @T6G_MB_LIB.T6G(SCH_1):GND    I20 @T6G_MB_LIB.T6G(SCH_1):PAGE469

PR6505 Q_RES_0402LF-20K,1%,1/16W,CHIP,CS32002FB06
     1 P1V8_RETIMER_CPU0_FB @T6G_MB_LIB.T6G(SCH_1):P1V8_RETIMER_CPU0_FB    I35 @T6G_MB_LIB.T6G(SCH_1):PAGE469
     2 P1V8_CPU0_RT_1D @T6G_MB_LIB.T6G(SCH_1):P1V8_CPU0_RT_1D    I35 @T6G_MB_LIB.T6G(SCH_1):PAGE469

PR6507 Q_RES_0402LF-10K,1%,1/16W,CHIP,CS31002FB08
     1 P1V8_RETIMER_CPU0_FB @T6G_MB_LIB.T6G(SCH_1):P1V8_RETIMER_CPU0_FB    I33 @T6G_MB_LIB.T6G(SCH_1):PAGE469
     2    GND @T6G_MB_LIB.T6G(SCH_1):GND    I33 @T6G_MB_LIB.T6G(SCH_1):PAGE469

PR6520 Q_RES_0402LF-0,5%,1/16W,CHIP,CS00002JB13
     1    GND @T6G_MB_LIB.T6G(SCH_1):GND    I21 @T6G_MB_LIB.T6G(SCH_1):PAGE470
     2 P1V8_RETIMER_CPU1_MODE @T6G_MB_LIB.T6G(SCH_1):P1V8_RETIMER_CPU1_MODE    I21 @T6G_MB_LIB.T6G(SCH_1):PAGE470

PR6521 Q_RES_0402LF-0,5%,1/16W,CHIP,CS00002JB13
     1 P3V3_AUX @T6G_MB_LIB.T6G(SCH_1):P3V3_AUX    I13 @T6G_MB_LIB.T6G(SCH_1):PAGE470
     2 P1V8_RETIMER_CPU1_VCC @T6G_MB_LIB.T6G(SCH_1):P1V8_RETIMER_CPU1_VCC    I13 @T6G_MB_LIB.T6G(SCH_1):PAGE470

PR6522 Q_RES_0402LF-7.15K,1%,1/16W,CHIP,CS27152FB03
     1 P1V8_RETIMER_CPU1_CS @T6G_MB_LIB.T6G(SCH_1):P1V8_RETIMER_CPU1_CS    I20 @T6G_MB_LIB.T6G(SCH_1):PAGE470
     2    GND @T6G_MB_LIB.T6G(SCH_1):GND    I20 @T6G_MB_LIB.T6G(SCH_1):PAGE470

PR6524 Q_RES_0402LF-20K,1%,1/16W,CHIP,CS32002FB06
     1 P1V8_RETIMER_CPU1_FB @T6G_MB_LIB.T6G(SCH_1):P1V8_RETIMER_CPU1_FB    I34 @T6G_MB_LIB.T6G(SCH_1):PAGE470
     2 P1V8_CPU1_RT_1D @T6G_MB_LIB.T6G(SCH_1):P1V8_CPU1_RT_1D    I34 @T6G_MB_LIB.T6G(SCH_1):PAGE470

PR6526 Q_RES_0402LF-10K,1%,1/16W,CHIP,CS31002FB08
     1 P1V8_RETIMER_CPU1_FB @T6G_MB_LIB.T6G(SCH_1):P1V8_RETIMER_CPU1_FB    I32 @T6G_MB_LIB.T6G(SCH_1):PAGE470
     2    GND @T6G_MB_LIB.T6G(SCH_1):GND    I32 @T6G_MB_LIB.T6G(SCH_1):PAGE470

PR6530 Q_RES_0402LF-49.9,1%,1/16W,CHIP,CS04992FB07
     1 P0V9_RETIMER_CPU0_SENSE_SH_P @T6G_MB_LIB.T6G(SCH_1):P0V9_RETIMER_CPU0_SENSE_SH_P    I34 @T6G_MB_LIB.T6G(SCH_1):PAGE475
     2 P0V9_CPU0_RT_2D @T6G_MB_LIB.T6G(SCH_1):P0V9_CPU0_RT_2D    I34 @T6G_MB_LIB.T6G(SCH_1):PAGE475

PR6531 Q_RES_0402LF-0,5%,1/16W,CHIP,CS00002JB13
     1 P0V9_RETIMER_CPU0_SENSE_SH_P @T6G_MB_LIB.T6G(SCH_1):P0V9_RETIMER_CPU0_SENSE_SH_P   I105 @T6G_MB_LIB.T6G(SCH_1):PAGE475
     2 P0V9_RETIMER_CPU0_SENSE_R_P @T6G_MB_LIB.T6G(SCH_1):P0V9_RETIMER_CPU0_SENSE_R_P   I105 @T6G_MB_LIB.T6G(SCH_1):PAGE475

PR6532 Q_RES_0402LF-49.9,1%,1/16W,CHIP,CS04992FB07
     1 P0V9_RETIMER_CPU0_SENSE_SH_N @T6G_MB_LIB.T6G(SCH_1):P0V9_RETIMER_CPU0_SENSE_SH_N    I32 @T6G_MB_LIB.T6G(SCH_1):PAGE475
     2    GND @T6G_MB_LIB.T6G(SCH_1):GND    I32 @T6G_MB_LIB.T6G(SCH_1):PAGE475

PR6533 Q_RES_0402LF-22.1K,1%,1/16W,CHIP,CS32212FB02
     1    GND @T6G_MB_LIB.T6G(SCH_1):GND    I13 @T6G_MB_LIB.T6G(SCH_1):PAGE477
     2 P0V9_RETIMER_CPU1_ADDR @T6G_MB_LIB.T6G(SCH_1):P0V9_RETIMER_CPU1_ADDR    I13 @T6G_MB_LIB.T6G(SCH_1):PAGE477

PR6538 Q_RES_0402LF-1,1%,1/16W,CHIP,CS-1002FB04
     1 P0V9_RETIMER_CPU1_VCC @T6G_MB_LIB.T6G(SCH_1):P0V9_RETIMER_CPU1_VCC    I83 @T6G_MB_LIB.T6G(SCH_1):PAGE477
     2 P3V3_AUX @T6G_MB_LIB.T6G(SCH_1):P3V3_AUX    I83 @T6G_MB_LIB.T6G(SCH_1):PAGE477

PR6539 Q_RES_0402LF-0,5%,1/16W,CHIP,CS00002JB13
     1 NC_P0V9_RETIMER_CPU1_IMON3 @T6G_MB_LIB.T6G(SCH_1):NC_P0V9_RETIMER_CPU1_IMON3    I69 @T6G_MB_LIB.T6G(SCH_1):PAGE477
     2    GND @T6G_MB_LIB.T6G(SCH_1):GND    I69 @T6G_MB_LIB.T6G(SCH_1):PAGE477

PR6540 Q_RES_0402LF-0,5%,1/16W,CHIP,CS00002JB13
     1 NC_P0V9_RETIMER_CPU1_IMON4 @T6G_MB_LIB.T6G(SCH_1):NC_P0V9_RETIMER_CPU1_IMON4    I68 @T6G_MB_LIB.T6G(SCH_1):PAGE477
     2    GND @T6G_MB_LIB.T6G(SCH_1):GND    I68 @T6G_MB_LIB.T6G(SCH_1):PAGE477

PR6541 Q_RES_0402LF-0,5%,1/16W,CHIP,CS00002JB13
     1 NC_P0V9_RETIMER_CPU1_IMON5 @T6G_MB_LIB.T6G(SCH_1):NC_P0V9_RETIMER_CPU1_IMON5    I65 @T6G_MB_LIB.T6G(SCH_1):PAGE477
     2    GND @T6G_MB_LIB.T6G(SCH_1):GND    I65 @T6G_MB_LIB.T6G(SCH_1):PAGE477

PR6542 Q_RES_0402LF-0,5%,1/16W,CHIP,CS00002JB13
     1 NC_P0V9_RETIMER_CPU1_IMON6 @T6G_MB_LIB.T6G(SCH_1):NC_P0V9_RETIMER_CPU1_IMON6    I64 @T6G_MB_LIB.T6G(SCH_1):PAGE477
     2    GND @T6G_MB_LIB.T6G(SCH_1):GND    I64 @T6G_MB_LIB.T6G(SCH_1):PAGE477

PR6543 Q_RES_0402LF-0,5%,1/16W,CHIP,CS00002JB13
     1 NC_P0V9_RETIMER_CPU1_IMON7 @T6G_MB_LIB.T6G(SCH_1):NC_P0V9_RETIMER_CPU1_IMON7    I58 @T6G_MB_LIB.T6G(SCH_1):PAGE477
     2    GND @T6G_MB_LIB.T6G(SCH_1):GND    I58 @T6G_MB_LIB.T6G(SCH_1):PAGE477

PR6544 Q_RES_0402LF-0,5%,1/16W,CHIP,CS00002JB13
     1 NC_P0V9_RETIMER_CPU1_IMON8 @T6G_MB_LIB.T6G(SCH_1):NC_P0V9_RETIMER_CPU1_IMON8    I57 @T6G_MB_LIB.T6G(SCH_1):PAGE477
     2    GND @T6G_MB_LIB.T6G(SCH_1):GND    I57 @T6G_MB_LIB.T6G(SCH_1):PAGE477

PR6548 Q_RES_0402LF-0,5%,1/16W,CHIP,CS00002JB13
     1 P0V9_RETIMER_CPU1_TEMP1_R @T6G_MB_LIB.T6G(SCH_1):P0V9_RETIMER_CPU1_TEMP1_R    I52 @T6G_MB_LIB.T6G(SCH_1):PAGE477
     2    GND @T6G_MB_LIB.T6G(SCH_1):GND    I52 @T6G_MB_LIB.T6G(SCH_1):PAGE477

PR6550 Q_RES_0402LF-0,5%,1/16W,CHIP,CS00002JB13
     1 P5V_AUX @T6G_MB_LIB.T6G(SCH_1):P5V_AUX   I183 @T6G_MB_LIB.T6G(SCH_1):PAGE476
     2 P0V9_RETIMER_CPU0_PVCC @T6G_MB_LIB.T6G(SCH_1):P0V9_RETIMER_CPU0_PVCC   I183 @T6G_MB_LIB.T6G(SCH_1):PAGE476

PR6551 Q_RES_0402LF-0,5%,1/16W,EMPTY,CS00002JB13
     1 P3V3_AUX @T6G_MB_LIB.T6G(SCH_1):P3V3_AUX   I185 @T6G_MB_LIB.T6G(SCH_1):PAGE476
     2 P0V9_RETIMER_CPU0_PVCC @T6G_MB_LIB.T6G(SCH_1):P0V9_RETIMER_CPU0_PVCC   I185 @T6G_MB_LIB.T6G(SCH_1):PAGE476

PR6552 Q_RES_0402LF-2.2,5%,1/16W,CHIP,TMP_QCS-2202JB25
     1 P0V9_RETIMER_CPU0_PVCC @T6G_MB_LIB.T6G(SCH_1):P0V9_RETIMER_CPU0_PVCC    I58 @T6G_MB_LIB.T6G(SCH_1):PAGE476
     2 P0V9_RETIMER_CPU0_VCC1 @T6G_MB_LIB.T6G(SCH_1):P0V9_RETIMER_CPU0_VCC1    I58 @T6G_MB_LIB.T6G(SCH_1):PAGE476

PR6553 Q_RES_0402LF-8.87K,1%,1/16W,EMPTY,CS28872FB01
     1 P0V9_RETIMER_CPU0_LSET1 @T6G_MB_LIB.T6G(SCH_1):P0V9_RETIMER_CPU0_LSET1   I220 @T6G_MB_LIB.T6G(SCH_1):PAGE476
     2    GND @T6G_MB_LIB.T6G(SCH_1):GND   I220 @T6G_MB_LIB.T6G(SCH_1):PAGE476

PR6554 Q_RES_0402LF-5.6,1%,1/16W,CHIP,CS-5602FB01
     1 SW_P0V9_RETIMER_CPU0_BOOT1 @T6G_MB_LIB.T6G(SCH_1):SW_P0V9_RETIMER_CPU0_BOOT1   I221 @T6G_MB_LIB.T6G(SCH_1):PAGE476
     2 SW_P0V9_RETIMER_CPU0_BOOT1_RC @T6G_MB_LIB.T6G(SCH_1):SW_P0V9_RETIMER_CPU0_BOOT1_RC   I221 @T6G_MB_LIB.T6G(SCH_1):PAGE476

PR6555 Q_RES_0402LF-1.5,1%,1/8W,EMPTY,CS-1504FB00
     1 SW_P0V9_RETIMER_CPU0_SW1_RC @T6G_MB_LIB.T6G(SCH_1):SW_P0V9_RETIMER_CPU0_SW1_RC   I283 @T6G_MB_LIB.T6G(SCH_1):PAGE476
     2    GND @T6G_MB_LIB.T6G(SCH_1):GND   I283 @T6G_MB_LIB.T6G(SCH_1):PAGE476

PR6556 Q_RES_0402LF-0,5%,1/16W,CHIP,CS00002JB13
     1 P0V9_RETIMER_CPU0_VOS1 @T6G_MB_LIB.T6G(SCH_1):P0V9_RETIMER_CPU0_VOS1    I42 @T6G_MB_LIB.T6G(SCH_1):PAGE476
     2 P0V9_CPU0_RT_2D @T6G_MB_LIB.T6G(SCH_1):P0V9_CPU0_RT_2D    I42 @T6G_MB_LIB.T6G(SCH_1):PAGE476

PR6557 Q_RES_0603LF-499,1%,1/10W,CHIP,CS14993F901
     1 P0V9_CPU0_RT_2D @T6G_MB_LIB.T6G(SCH_1):P0V9_CPU0_RT_2D   I187 @T6G_MB_LIB.T6G(SCH_1):PAGE476
     2    GND @T6G_MB_LIB.T6G(SCH_1):GND   I187 @T6G_MB_LIB.T6G(SCH_1):PAGE476

PR6560 Q_RES_0402LF-2.2,5%,1/16W,CHIP,TMP_QCS-2202JB25
     1 P0V9_RETIMER_CPU0_PVCC @T6G_MB_LIB.T6G(SCH_1):P0V9_RETIMER_CPU0_PVCC   I269 @T6G_MB_LIB.T6G(SCH_1):PAGE476
     2 P0V9_RETIMER_CPU0_VCC2 @T6G_MB_LIB.T6G(SCH_1):P0V9_RETIMER_CPU0_VCC2   I269 @T6G_MB_LIB.T6G(SCH_1):PAGE476

PR6561 Q_RES_0402LF-8.87K,1%,1/16W,EMPTY,CS28872FB01
     1 P0V9_RETIMER_CPU0_LSET2 @T6G_MB_LIB.T6G(SCH_1):P0V9_RETIMER_CPU0_LSET2   I276 @T6G_MB_LIB.T6G(SCH_1):PAGE476
     2    GND @T6G_MB_LIB.T6G(SCH_1):GND   I276 @T6G_MB_LIB.T6G(SCH_1):PAGE476

PR6562 Q_RES_0402LF-5.6,1%,1/16W,CHIP,CS-5602FB01
     1 SW_P0V9_RETIMER_CPU0_BOOT2 @T6G_MB_LIB.T6G(SCH_1):SW_P0V9_RETIMER_CPU0_BOOT2   I262 @T6G_MB_LIB.T6G(SCH_1):PAGE476
     2 SW_P0V9_RETIMER_CPU0_BOOT2_RC @T6G_MB_LIB.T6G(SCH_1):SW_P0V9_RETIMER_CPU0_BOOT2_RC   I262 @T6G_MB_LIB.T6G(SCH_1):PAGE476

PR6563 Q_RES_0402LF-1.5,1%,1/8W,EMPTY,CS-1504FB00
     1 SW_P0V9_RETIMER_CPU0_SW2_RC @T6G_MB_LIB.T6G(SCH_1):SW_P0V9_RETIMER_CPU0_SW2_RC   I286 @T6G_MB_LIB.T6G(SCH_1):PAGE476
     2    GND @T6G_MB_LIB.T6G(SCH_1):GND   I286 @T6G_MB_LIB.T6G(SCH_1):PAGE476

PR6564 Q_RES_0402LF-0,5%,1/16W,CHIP,CS00002JB13
     1 P0V9_RETIMER_CPU0_VOS2 @T6G_MB_LIB.T6G(SCH_1):P0V9_RETIMER_CPU0_VOS2   I263 @T6G_MB_LIB.T6G(SCH_1):PAGE476
     2 P0V9_CPU0_RT_2D @T6G_MB_LIB.T6G(SCH_1):P0V9_CPU0_RT_2D   I263 @T6G_MB_LIB.T6G(SCH_1):PAGE476

PR6600 Q_RES_0402LF-49.9,1%,1/16W,CHIP,CS04992FB07
     1 P0V9_RETIMER_CPU1_SENSE_SH_P @T6G_MB_LIB.T6G(SCH_1):P0V9_RETIMER_CPU1_SENSE_SH_P    I23 @T6G_MB_LIB.T6G(SCH_1):PAGE477
     2 P0V9_CPU1_RT_2D @T6G_MB_LIB.T6G(SCH_1):P0V9_CPU1_RT_2D    I23 @T6G_MB_LIB.T6G(SCH_1):PAGE477

PR6601 Q_RES_0402LF-0,5%,1/16W,CHIP,CS00002JB13
     1 P0V9_RETIMER_CPU1_SENSE_SH_P @T6G_MB_LIB.T6G(SCH_1):P0V9_RETIMER_CPU1_SENSE_SH_P    I27 @T6G_MB_LIB.T6G(SCH_1):PAGE477
     2 P0V9_RETIMER_CPU1_SENSE_R_P @T6G_MB_LIB.T6G(SCH_1):P0V9_RETIMER_CPU1_SENSE_R_P    I27 @T6G_MB_LIB.T6G(SCH_1):PAGE477

PR6602 Q_RES_0402LF-49.9,1%,1/16W,CHIP,CS04992FB07
     1 P0V9_RETIMER_CPU1_SENSE_SH_N @T6G_MB_LIB.T6G(SCH_1):P0V9_RETIMER_CPU1_SENSE_SH_N    I22 @T6G_MB_LIB.T6G(SCH_1):PAGE477
     2    GND @T6G_MB_LIB.T6G(SCH_1):GND    I22 @T6G_MB_LIB.T6G(SCH_1):PAGE477

PR6603 Q_RES_0402LF-0,5%,1/16W,CHIP,CS00002JB13
     1    GND @T6G_MB_LIB.T6G(SCH_1):GND   I183 @T6G_MB_LIB.T6G(SCH_1):PAGE475
     2 P0V9_RETIMER_CPU0_ADDR @T6G_MB_LIB.T6G(SCH_1):P0V9_RETIMER_CPU0_ADDR   I183 @T6G_MB_LIB.T6G(SCH_1):PAGE475

PR6604 Q_RES_0402LF-5.36K,1%,1/16W,EMPTY,CS25362FB02
     1 P5V_AUX @T6G_MB_LIB.T6G(SCH_1):P5V_AUX   I178 @T6G_MB_LIB.T6G(SCH_1):PAGE475
     2 P0V9_RETIMER_CPU0_VMON @T6G_MB_LIB.T6G(SCH_1):P0V9_RETIMER_CPU0_VMON   I178 @T6G_MB_LIB.T6G(SCH_1):PAGE475

PR6605 Q_RES_0402LF-0,5%,1/16W,CHIP,CS00002JB13
     1 P0V9_RETIMER_CPU0_VMON @T6G_MB_LIB.T6G(SCH_1):P0V9_RETIMER_CPU0_VMON   I150 @T6G_MB_LIB.T6G(SCH_1):PAGE475
     2    GND @T6G_MB_LIB.T6G(SCH_1):GND   I150 @T6G_MB_LIB.T6G(SCH_1):PAGE475

PR6606 Q_RES_0402LF-0,5%,1/16W,CHIP,CS00002JB13
     1 P12V_AUX @T6G_MB_LIB.T6G(SCH_1):P12V_AUX   I160 @T6G_MB_LIB.T6G(SCH_1):PAGE475
     2 P0V9_RETIMER_CPU0_VINSEN @T6G_MB_LIB.T6G(SCH_1):P0V9_RETIMER_CPU0_VINSEN   I160 @T6G_MB_LIB.T6G(SCH_1):PAGE475

PR6607 Q_RES_0402LF-1K,1%,1/16W,EMPTY,CS21002FB06
     1 P0V9_RETIMER_CPU0_VINSEN @T6G_MB_LIB.T6G(SCH_1):P0V9_RETIMER_CPU0_VINSEN   I125 @T6G_MB_LIB.T6G(SCH_1):PAGE475
     2    GND @T6G_MB_LIB.T6G(SCH_1):GND   I125 @T6G_MB_LIB.T6G(SCH_1):PAGE475

PR6608 Q_RES_0402LF-1,1%,1/16W,CHIP,CS-1002FB04
     1 P0V9_RETIMER_CPU0_VCC @T6G_MB_LIB.T6G(SCH_1):P0V9_RETIMER_CPU0_VCC   I131 @T6G_MB_LIB.T6G(SCH_1):PAGE475
     2 P3V3_AUX @T6G_MB_LIB.T6G(SCH_1):P3V3_AUX   I131 @T6G_MB_LIB.T6G(SCH_1):PAGE475

PR6609 Q_RES_0402LF-0,5%,1/16W,CHIP,CS00002JB13
     1 NC_P0V9_RETIMER_CPU0_IMON3 @T6G_MB_LIB.T6G(SCH_1):NC_P0V9_RETIMER_CPU0_IMON3   I188 @T6G_MB_LIB.T6G(SCH_1):PAGE475
     2    GND @T6G_MB_LIB.T6G(SCH_1):GND   I188 @T6G_MB_LIB.T6G(SCH_1):PAGE475

PR6610 Q_RES_0402LF-0,5%,1/16W,CHIP,CS00002JB13
     1 NC_P0V9_RETIMER_CPU0_IMON4 @T6G_MB_LIB.T6G(SCH_1):NC_P0V9_RETIMER_CPU0_IMON4   I190 @T6G_MB_LIB.T6G(SCH_1):PAGE475
     2    GND @T6G_MB_LIB.T6G(SCH_1):GND   I190 @T6G_MB_LIB.T6G(SCH_1):PAGE475

PR6611 Q_RES_0402LF-0,5%,1/16W,CHIP,CS00002JB13
     1 NC_P0V9_RETIMER_CPU0_IMON5 @T6G_MB_LIB.T6G(SCH_1):NC_P0V9_RETIMER_CPU0_IMON5   I191 @T6G_MB_LIB.T6G(SCH_1):PAGE475
     2    GND @T6G_MB_LIB.T6G(SCH_1):GND   I191 @T6G_MB_LIB.T6G(SCH_1):PAGE475

PR6612 Q_RES_0402LF-0,5%,1/16W,CHIP,CS00002JB13
     1 NC_P0V9_RETIMER_CPU0_IMON6 @T6G_MB_LIB.T6G(SCH_1):NC_P0V9_RETIMER_CPU0_IMON6   I192 @T6G_MB_LIB.T6G(SCH_1):PAGE475
     2    GND @T6G_MB_LIB.T6G(SCH_1):GND   I192 @T6G_MB_LIB.T6G(SCH_1):PAGE475

PR6613 Q_RES_0402LF-0,5%,1/16W,CHIP,CS00002JB13
     1 NC_P0V9_RETIMER_CPU0_IMON7 @T6G_MB_LIB.T6G(SCH_1):NC_P0V9_RETIMER_CPU0_IMON7   I193 @T6G_MB_LIB.T6G(SCH_1):PAGE475
     2    GND @T6G_MB_LIB.T6G(SCH_1):GND   I193 @T6G_MB_LIB.T6G(SCH_1):PAGE475

PR6614 Q_RES_0402LF-0,5%,1/16W,CHIP,CS00002JB13
     1 NC_P0V9_RETIMER_CPU0_IMON8 @T6G_MB_LIB.T6G(SCH_1):NC_P0V9_RETIMER_CPU0_IMON8   I198 @T6G_MB_LIB.T6G(SCH_1):PAGE475
     2    GND @T6G_MB_LIB.T6G(SCH_1):GND   I198 @T6G_MB_LIB.T6G(SCH_1):PAGE475

PR6615 Q_RES_0402LF-1K,1%,1/16W,CHIP,CS21002FB06
     1 P3V3_AUX @T6G_MB_LIB.T6G(SCH_1):P3V3_AUX   I135 @T6G_MB_LIB.T6G(SCH_1):PAGE475
     2 TP_P0V9_RETIMER_CPU0_VRHOT @T6G_MB_LIB.T6G(SCH_1):TP_P0V9_RETIMER_CPU0_VRHOT   I135 @T6G_MB_LIB.T6G(SCH_1):PAGE475

PR6616 Q_RES_0402LF-0,5%,1/16W,CHIP,CS00002JB13
     1 P0V9_RETIMER_CPU0_VRHOT @T6G_MB_LIB.T6G(SCH_1):P0V9_RETIMER_CPU0_VRHOT   I136 @T6G_MB_LIB.T6G(SCH_1):PAGE475
     2 TP_P0V9_RETIMER_CPU0_VRHOT @T6G_MB_LIB.T6G(SCH_1):TP_P0V9_RETIMER_CPU0_VRHOT   I136 @T6G_MB_LIB.T6G(SCH_1):PAGE475

PR6618 Q_RES_0402LF-0,5%,1/16W,CHIP,CS00002JB13
     1 P0V9_RETIMER_CPU0_TEMP1_R @T6G_MB_LIB.T6G(SCH_1):P0V9_RETIMER_CPU0_TEMP1_R   I204 @T6G_MB_LIB.T6G(SCH_1):PAGE475
     2    GND @T6G_MB_LIB.T6G(SCH_1):GND   I204 @T6G_MB_LIB.T6G(SCH_1):PAGE475

PR6619 Q_RES_0402LF-0,5%,1/16W,CHIP,CS00002JB13
     1 P5V_AUX @T6G_MB_LIB.T6G(SCH_1):P5V_AUX    I42 @T6G_MB_LIB.T6G(SCH_1):PAGE478
     2 P0V9_RETIMER_CPU1_PVCC @T6G_MB_LIB.T6G(SCH_1):P0V9_RETIMER_CPU1_PVCC    I42 @T6G_MB_LIB.T6G(SCH_1):PAGE478

PR6620 Q_RES_0402LF-0,5%,1/16W,EMPTY,CS00002JB13
     1 P3V3_AUX @T6G_MB_LIB.T6G(SCH_1):P3V3_AUX    I56 @T6G_MB_LIB.T6G(SCH_1):PAGE478
     2 P0V9_RETIMER_CPU1_PVCC @T6G_MB_LIB.T6G(SCH_1):P0V9_RETIMER_CPU1_PVCC    I56 @T6G_MB_LIB.T6G(SCH_1):PAGE478

PR6621 Q_RES_0402LF-2.2,5%,1/16W,CHIP,TMP_QCS-2202JB25
     1 P0V9_RETIMER_CPU1_PVCC @T6G_MB_LIB.T6G(SCH_1):P0V9_RETIMER_CPU1_PVCC    I53 @T6G_MB_LIB.T6G(SCH_1):PAGE478
     2 P0V9_RETIMER_CPU1_VCC1 @T6G_MB_LIB.T6G(SCH_1):P0V9_RETIMER_CPU1_VCC1    I53 @T6G_MB_LIB.T6G(SCH_1):PAGE478

PR6622 Q_RES_0402LF-8.87K,1%,1/16W,EMPTY,CS28872FB01
     1 P0V9_RETIMER_CPU1_LSET1 @T6G_MB_LIB.T6G(SCH_1):P0V9_RETIMER_CPU1_LSET1    I46 @T6G_MB_LIB.T6G(SCH_1):PAGE478
     2    GND @T6G_MB_LIB.T6G(SCH_1):GND    I46 @T6G_MB_LIB.T6G(SCH_1):PAGE478

PR6623 Q_RES_0402LF-5.6,1%,1/16W,CHIP,CS-5602FB01
     1 SW_P0V9_RETIMER_CPU1_BOOT1 @T6G_MB_LIB.T6G(SCH_1):SW_P0V9_RETIMER_CPU1_BOOT1    I62 @T6G_MB_LIB.T6G(SCH_1):PAGE478
     2 SW_P0V9_RETIMER_CPU1_BOOT1_RC @T6G_MB_LIB.T6G(SCH_1):SW_P0V9_RETIMER_CPU1_BOOT1_RC    I62 @T6G_MB_LIB.T6G(SCH_1):PAGE478

PR6624 Q_RES_0402LF-1.5,1%,1/8W,EMPTY,CS-1504FB00
     1 SW_P0V9_RETIMER_CPU1_SW1_RC @T6G_MB_LIB.T6G(SCH_1):SW_P0V9_RETIMER_CPU1_SW1_RC   I106 @T6G_MB_LIB.T6G(SCH_1):PAGE478
     2    GND @T6G_MB_LIB.T6G(SCH_1):GND   I106 @T6G_MB_LIB.T6G(SCH_1):PAGE478

PR6625 Q_RES_0603LF-499,1%,1/10W,CHIP,CS14993F901
     1 P0V9_CPU1_RT_2D @T6G_MB_LIB.T6G(SCH_1):P0V9_CPU1_RT_2D    I97 @T6G_MB_LIB.T6G(SCH_1):PAGE478
     2    GND @T6G_MB_LIB.T6G(SCH_1):GND    I97 @T6G_MB_LIB.T6G(SCH_1):PAGE478

PR6626 Q_RES_0402LF-0,5%,1/16W,CHIP,CS00002JB13
     1 P0V9_RETIMER_CPU1_VOS1 @T6G_MB_LIB.T6G(SCH_1):P0V9_RETIMER_CPU1_VOS1    I59 @T6G_MB_LIB.T6G(SCH_1):PAGE478
     2 P0V9_CPU1_RT_2D @T6G_MB_LIB.T6G(SCH_1):P0V9_CPU1_RT_2D    I59 @T6G_MB_LIB.T6G(SCH_1):PAGE478

PR6627 Q_RES_0402LF-2.2,5%,1/16W,CHIP,TMP_QCS-2202JB25
     1 P0V9_RETIMER_CPU1_PVCC @T6G_MB_LIB.T6G(SCH_1):P0V9_RETIMER_CPU1_PVCC    I11 @T6G_MB_LIB.T6G(SCH_1):PAGE478
     2 P0V9_RETIMER_CPU1_VCC2 @T6G_MB_LIB.T6G(SCH_1):P0V9_RETIMER_CPU1_VCC2    I11 @T6G_MB_LIB.T6G(SCH_1):PAGE478

PR6628 Q_RES_0402LF-8.87K,1%,1/16W,EMPTY,CS28872FB01
     1 P0V9_RETIMER_CPU1_LSET2 @T6G_MB_LIB.T6G(SCH_1):P0V9_RETIMER_CPU1_LSET2     I5 @T6G_MB_LIB.T6G(SCH_1):PAGE478
     2    GND @T6G_MB_LIB.T6G(SCH_1):GND     I5 @T6G_MB_LIB.T6G(SCH_1):PAGE478

PR6629 Q_RES_0402LF-5.6,1%,1/16W,CHIP,CS-5602FB01
     1 SW_P0V9_RETIMER_CPU1_BOOT2 @T6G_MB_LIB.T6G(SCH_1):SW_P0V9_RETIMER_CPU1_BOOT2    I19 @T6G_MB_LIB.T6G(SCH_1):PAGE478
     2 SW_P0V9_RETIMER_CPU1_BOOT2_RC @T6G_MB_LIB.T6G(SCH_1):SW_P0V9_RETIMER_CPU1_BOOT2_RC    I19 @T6G_MB_LIB.T6G(SCH_1):PAGE478

PR6630 Q_RES_0402LF-1.5,1%,1/8W,EMPTY,CS-1504FB00
     1 SW_P0V9_RETIMER_CPU1_SW2_RC @T6G_MB_LIB.T6G(SCH_1):SW_P0V9_RETIMER_CPU1_SW2_RC   I110 @T6G_MB_LIB.T6G(SCH_1):PAGE478
     2    GND @T6G_MB_LIB.T6G(SCH_1):GND   I110 @T6G_MB_LIB.T6G(SCH_1):PAGE478

PR6631 Q_RES_0402LF-0,5%,1/16W,CHIP,CS00002JB13
     1 P0V9_RETIMER_CPU1_VOS2 @T6G_MB_LIB.T6G(SCH_1):P0V9_RETIMER_CPU1_VOS2    I16 @T6G_MB_LIB.T6G(SCH_1):PAGE478
     2 P0V9_CPU1_RT_2D @T6G_MB_LIB.T6G(SCH_1):P0V9_CPU1_RT_2D    I16 @T6G_MB_LIB.T6G(SCH_1):PAGE478

PR6800 Q_RES_0402LF-2.2,1%,1/16W,CHIP,CS-2202FB01
     1 SW_P1V8_RETIMER_CPU0_BST @T6G_MB_LIB.T6G(SCH_1):SW_P1V8_RETIMER_CPU0_BST    I29 @T6G_MB_LIB.T6G(SCH_1):PAGE469
     2 SW_P1V8_RETIMER_CPU0_BST_R @T6G_MB_LIB.T6G(SCH_1):SW_P1V8_RETIMER_CPU0_BST_R    I29 @T6G_MB_LIB.T6G(SCH_1):PAGE469

PR6801 Q_RES_0402LF-2.2,1%,1/16W,CHIP,CS-2202FB01
     1 SW_P1V8_RETIMER_CPU1_BST @T6G_MB_LIB.T6G(SCH_1):SW_P1V8_RETIMER_CPU1_BST    I28 @T6G_MB_LIB.T6G(SCH_1):PAGE470
     2 SW_P1V8_RETIMER_CPU1_BST_R @T6G_MB_LIB.T6G(SCH_1):SW_P1V8_RETIMER_CPU1_BST_R    I28 @T6G_MB_LIB.T6G(SCH_1):PAGE470

PR6802 Q_RES_0402LF-0,5%,1/16W,EMPTY,CS00002JB13
     1 TP_P0V9_RETIMER_CPU1_SVID_ALERT_N @T6G_MB_LIB.T6G(SCH_1):TP_P0V9_RETIMER_CPU1_SVID_ALERT_N    I44 @T6G_MB_LIB.T6G(SCH_1):PAGE477
     2    GND @T6G_MB_LIB.T6G(SCH_1):GND    I44 @T6G_MB_LIB.T6G(SCH_1):PAGE477

PR6803 Q_RES_0402LF-1K,1%,1/16W,EMPTY,CS21002FB06
     1 P3V3_AUX @T6G_MB_LIB.T6G(SCH_1):P3V3_AUX   I167 @T6G_MB_LIB.T6G(SCH_1):PAGE475
     2 P0V9_RETIMER_CPU0_SVID_SDA @T6G_MB_LIB.T6G(SCH_1):P0V9_RETIMER_CPU0_SVID_SDA   I167 @T6G_MB_LIB.T6G(SCH_1):PAGE475

PR6804 Q_RES_0402LF-1K,1%,1/16W,EMPTY,CS21002FB06
     1 P3V3_AUX @T6G_MB_LIB.T6G(SCH_1):P3V3_AUX    I36 @T6G_MB_LIB.T6G(SCH_1):PAGE477
     2 P0V9_RETIMER_CPU1_SVID_SDA @T6G_MB_LIB.T6G(SCH_1):P0V9_RETIMER_CPU1_SVID_SDA    I36 @T6G_MB_LIB.T6G(SCH_1):PAGE477

PR6805 Q_RES_0402LF-1K,1%,1/16W,EMPTY,CS21002FB06
     1 P3V3_AUX @T6G_MB_LIB.T6G(SCH_1):P3V3_AUX   I166 @T6G_MB_LIB.T6G(SCH_1):PAGE475
     2 P0V9_RETIMER_CPU0_SVID_CLK @T6G_MB_LIB.T6G(SCH_1):P0V9_RETIMER_CPU0_SVID_CLK   I166 @T6G_MB_LIB.T6G(SCH_1):PAGE475

PR6806 Q_RES_0402LF-1K,1%,1/16W,EMPTY,CS21002FB06
     1 P3V3_AUX @T6G_MB_LIB.T6G(SCH_1):P3V3_AUX    I37 @T6G_MB_LIB.T6G(SCH_1):PAGE477
     2 P0V9_RETIMER_CPU1_SVID_CLK @T6G_MB_LIB.T6G(SCH_1):P0V9_RETIMER_CPU1_SVID_CLK    I37 @T6G_MB_LIB.T6G(SCH_1):PAGE477

PR6807 Q_RES_0402LF-0,5%,1/16W,EMPTY,CS00002JB13
     1 P12V_AUX @T6G_MB_LIB.T6G(SCH_1):P12V_AUX   I158 @T6G_MB_LIB.T6G(SCH_1):PAGE475
     2 P0V9_RETIMER_CPU0_VMON @T6G_MB_LIB.T6G(SCH_1):P0V9_RETIMER_CPU0_VMON   I158 @T6G_MB_LIB.T6G(SCH_1):PAGE475

PR6808 Q_RES_0402LF-0,5%,1/16W,EMPTY,CS00002JB13
     1 P12V_AUX @T6G_MB_LIB.T6G(SCH_1):P12V_AUX    I11 @T6G_MB_LIB.T6G(SCH_1):PAGE477
     2 P0V9_RETIMER_CPU1_VMON @T6G_MB_LIB.T6G(SCH_1):P0V9_RETIMER_CPU1_VMON    I11 @T6G_MB_LIB.T6G(SCH_1):PAGE477

PR6809 Q_RES_0402LF-0,5%,1/16W,CHIP,CS00002JB13
     1 P12V_AUX @T6G_MB_LIB.T6G(SCH_1):P12V_AUX    I10 @T6G_MB_LIB.T6G(SCH_1):PAGE477
     2 P0V9_RETIMER_CPU1_VINSEN @T6G_MB_LIB.T6G(SCH_1):P0V9_RETIMER_CPU1_VINSEN    I10 @T6G_MB_LIB.T6G(SCH_1):PAGE477

PR6810 Q_RES_0402LF-0,5%,1/16W,CHIP,CS00002JB13
     1 P0V9_RETIMER_CPU0_SVID_CLK @T6G_MB_LIB.T6G(SCH_1):P0V9_RETIMER_CPU0_SVID_CLK   I165 @T6G_MB_LIB.T6G(SCH_1):PAGE475
     2    GND @T6G_MB_LIB.T6G(SCH_1):GND   I165 @T6G_MB_LIB.T6G(SCH_1):PAGE475

PR6811 Q_RES_0402LF-0,5%,1/16W,CHIP,CS00002JB13
     1 P0V9_RETIMER_CPU1_SVID_CLK @T6G_MB_LIB.T6G(SCH_1):P0V9_RETIMER_CPU1_SVID_CLK    I42 @T6G_MB_LIB.T6G(SCH_1):PAGE477
     2    GND @T6G_MB_LIB.T6G(SCH_1):GND    I42 @T6G_MB_LIB.T6G(SCH_1):PAGE477

PR6812 Q_RES_0402LF-1K,1%,1/16W,CHIP,CS21002FB06
     1 P3V3_AUX @T6G_MB_LIB.T6G(SCH_1):P3V3_AUX    I86 @T6G_MB_LIB.T6G(SCH_1):PAGE477
     2 TP_P0V9_RETIMER_CPU1_VRHOT @T6G_MB_LIB.T6G(SCH_1):TP_P0V9_RETIMER_CPU1_VRHOT    I86 @T6G_MB_LIB.T6G(SCH_1):PAGE477

PR6813 Q_RES_0402LF-1K,1%,1/16W,EMPTY,CS21002FB06
     1 P0V9_RETIMER_CPU1_VINSEN @T6G_MB_LIB.T6G(SCH_1):P0V9_RETIMER_CPU1_VINSEN    I46 @T6G_MB_LIB.T6G(SCH_1):PAGE477
     2    GND @T6G_MB_LIB.T6G(SCH_1):GND    I46 @T6G_MB_LIB.T6G(SCH_1):PAGE477

PR6814 Q_RES_0402LF-10K,1%,1/16W,EMPTY,CS31002FB08
     1 P0V9_RETIMER_CPU0_TEMP0 @T6G_MB_LIB.T6G(SCH_1):P0V9_RETIMER_CPU0_TEMP0   I138 @T6G_MB_LIB.T6G(SCH_1):PAGE475
     2    GND @T6G_MB_LIB.T6G(SCH_1):GND   I138 @T6G_MB_LIB.T6G(SCH_1):PAGE475

PR6815 Q_RES_0402LF-10K,1%,1/16W,EMPTY,CS31002FB08
     1 P0V9_RETIMER_CPU1_TEMP0 @T6G_MB_LIB.T6G(SCH_1):P0V9_RETIMER_CPU1_TEMP0    I54 @T6G_MB_LIB.T6G(SCH_1):PAGE477
     2    GND @T6G_MB_LIB.T6G(SCH_1):GND    I54 @T6G_MB_LIB.T6G(SCH_1):PAGE477

PR6816 Q_RES_0402LF-0,5%,1/16W,CHIP,CS00002JB13
     1 P0V9_RETIMER_CPU1_VRHOT @T6G_MB_LIB.T6G(SCH_1):P0V9_RETIMER_CPU1_VRHOT    I56 @T6G_MB_LIB.T6G(SCH_1):PAGE477
     2 TP_P0V9_RETIMER_CPU1_VRHOT @T6G_MB_LIB.T6G(SCH_1):TP_P0V9_RETIMER_CPU1_VRHOT    I56 @T6G_MB_LIB.T6G(SCH_1):PAGE477

PR6817 Q_RES_0402LF-1K,1%,1/16W,EMPTY,CS21002FB06
     1 P3V3_AUX @T6G_MB_LIB.T6G(SCH_1):P3V3_AUX   I169 @T6G_MB_LIB.T6G(SCH_1):PAGE475
     2 TP_P0V9_RETIMER_CPU0_SVID_ALERT_N @T6G_MB_LIB.T6G(SCH_1):TP_P0V9_RETIMER_CPU0_SVID_ALERT_N   I169 @T6G_MB_LIB.T6G(SCH_1):PAGE475

PR6818 Q_RES_0402LF-1K,1%,1/16W,EMPTY,CS21002FB06
     1 P3V3_AUX @T6G_MB_LIB.T6G(SCH_1):P3V3_AUX    I32 @T6G_MB_LIB.T6G(SCH_1):PAGE477
     2 TP_P0V9_RETIMER_CPU1_SVID_ALERT_N @T6G_MB_LIB.T6G(SCH_1):TP_P0V9_RETIMER_CPU1_SVID_ALERT_N    I32 @T6G_MB_LIB.T6G(SCH_1):PAGE477

PR6819 Q_RES_0402LF-0,5%,1/16W,CHIP,CS00002JB13
     1 P0V9_RETIMER_CPU0_SVID_SDA @T6G_MB_LIB.T6G(SCH_1):P0V9_RETIMER_CPU0_SVID_SDA   I168 @T6G_MB_LIB.T6G(SCH_1):PAGE475
     2    GND @T6G_MB_LIB.T6G(SCH_1):GND   I168 @T6G_MB_LIB.T6G(SCH_1):PAGE475

PR6820 Q_RES_0402LF-0,5%,1/16W,CHIP,CS00002JB13
     1 P0V9_RETIMER_CPU1_SVID_SDA @T6G_MB_LIB.T6G(SCH_1):P0V9_RETIMER_CPU1_SVID_SDA    I43 @T6G_MB_LIB.T6G(SCH_1):PAGE477
     2    GND @T6G_MB_LIB.T6G(SCH_1):GND    I43 @T6G_MB_LIB.T6G(SCH_1):PAGE477

PR6821 Q_RES_0402LF-0,5%,1/16W,CHIP,CS00002JB13
     1 P0V9_RETIMER_CPU1_VMON @T6G_MB_LIB.T6G(SCH_1):P0V9_RETIMER_CPU1_VMON     I3 @T6G_MB_LIB.T6G(SCH_1):PAGE477
     2    GND @T6G_MB_LIB.T6G(SCH_1):GND     I3 @T6G_MB_LIB.T6G(SCH_1):PAGE477

PR8000 Q_RES_0402LF-0,5%,1/16W,CHIP,CS00002JB13
     1 SW_PVDD_33_S5_BST @T6G_MB_LIB.T6G(SCH_1):SW_PVDD_33_S5_BST    I46 @T6G_MB_LIB.T6G(SCH_1):PAGE167
     2 SW_PVDD_33_S5_BST_R @T6G_MB_LIB.T6G(SCH_1):SW_PVDD_33_S5_BST_R    I46 @T6G_MB_LIB.T6G(SCH_1):PAGE167

PR8001 Q_RES_0402LF-2.2,1%,1/16W,CHIP,CS-2202FB01
     1 SW_PVDD18_S5_P0_BST @T6G_MB_LIB.T6G(SCH_1):SW_PVDD18_S5_P0_BST    I58 @T6G_MB_LIB.T6G(SCH_1):PAGE184
     2 SW_PVDD18_S5_P0_BST_R @T6G_MB_LIB.T6G(SCH_1):SW_PVDD18_S5_P0_BST_R    I58 @T6G_MB_LIB.T6G(SCH_1):PAGE184

PR8002 Q_RES_0402LF-2.2,1%,1/16W,CHIP,CS-2202FB01
     1 SW_PVDD18_S5_P1_BST @T6G_MB_LIB.T6G(SCH_1):SW_PVDD18_S5_P1_BST    I58 @T6G_MB_LIB.T6G(SCH_1):PAGE201
     2 SW_PVDD18_S5_P1_BST_R @T6G_MB_LIB.T6G(SCH_1):SW_PVDD18_S5_P1_BST_R    I58 @T6G_MB_LIB.T6G(SCH_1):PAGE201

PR8003 Q_RES_0402LF-2.2,1%,1/16W,CHIP,CS-2202FB01
     1 SW_P1V8_AUX_BT @T6G_MB_LIB.T6G(SCH_1):SW_P1V8_AUX_BT    I45 @T6G_MB_LIB.T6G(SCH_1):PAGE315
     2 SW_P1V8_AUX_BT_R @T6G_MB_LIB.T6G(SCH_1):SW_P1V8_AUX_BT_R    I45 @T6G_MB_LIB.T6G(SCH_1):PAGE315

PR8004 Q_RES_0402LF-2.2,1%,1/16W,CHIP,CS-2202FB01
     1 SW_P1V2_AUX_BT @T6G_MB_LIB.T6G(SCH_1):SW_P1V2_AUX_BT    I45 @T6G_MB_LIB.T6G(SCH_1):PAGE380
     2 SW_P1V2_AUX_BT_R @T6G_MB_LIB.T6G(SCH_1):SW_P1V2_AUX_BT_R    I45 @T6G_MB_LIB.T6G(SCH_1):PAGE380

PR8005 Q_RES_0402LF-0,5%,1/16W,CHIP,CS00002JB13
     1 SVID_PVDDCR_CPU0_P0_SVC_R @T6G_MB_LIB.T6G(SCH_1):SVID_PVDDCR_CPU0_P0_SVC_R   I147 @T6G_MB_LIB.T6G(SCH_1):PAGE168
     2 SVID_PVDDCR_CPU0_P0_SVC_R1 @T6G_MB_LIB.T6G(SCH_1):SVID_PVDDCR_CPU0_P0_SVC_R1   I147 @T6G_MB_LIB.T6G(SCH_1):PAGE168

PR8006 Q_RES_0402LF-0,5%,1/16W,CHIP,CS00002JB13
     1 SVID_PVDDCR_CPU0_P0_SVD_R @T6G_MB_LIB.T6G(SCH_1):SVID_PVDDCR_CPU0_P0_SVD_R   I148 @T6G_MB_LIB.T6G(SCH_1):PAGE168
     2 SVID_PVDDCR_CPU0_P0_SVD_R1 @T6G_MB_LIB.T6G(SCH_1):SVID_PVDDCR_CPU0_P0_SVD_R1   I148 @T6G_MB_LIB.T6G(SCH_1):PAGE168

PR8007 Q_RES_0402LF-0,5%,1/16W,CHIP,CS00002JB13
     1 SVID_PVDDCR_CPU1_P0_SVC_R @T6G_MB_LIB.T6G(SCH_1):SVID_PVDDCR_CPU1_P0_SVC_R   I137 @T6G_MB_LIB.T6G(SCH_1):PAGE175
     2 SVID_PVDDCR_CPU1_P0_SVC_R1 @T6G_MB_LIB.T6G(SCH_1):SVID_PVDDCR_CPU1_P0_SVC_R1   I137 @T6G_MB_LIB.T6G(SCH_1):PAGE175

PR8008 Q_RES_0402LF-0,5%,1/16W,CHIP,CS00002JB13
     1 SVID_PVDDCR_CPU1_P0_SVD_R @T6G_MB_LIB.T6G(SCH_1):SVID_PVDDCR_CPU1_P0_SVD_R   I136 @T6G_MB_LIB.T6G(SCH_1):PAGE175
     2 SVID_PVDDCR_CPU1_P0_SVD_R1 @T6G_MB_LIB.T6G(SCH_1):SVID_PVDDCR_CPU1_P0_SVD_R1   I136 @T6G_MB_LIB.T6G(SCH_1):PAGE175

PR8009 Q_RES_0402LF-0,5%,1/16W,CHIP,CS00002JB13
     1 SVID_PVDDCR_CPU0_P1_SVC_R @T6G_MB_LIB.T6G(SCH_1):SVID_PVDDCR_CPU0_P1_SVC_R   I143 @T6G_MB_LIB.T6G(SCH_1):PAGE185
     2 SVID_PVDDCR_CPU0_P1_SVC_R1 @T6G_MB_LIB.T6G(SCH_1):SVID_PVDDCR_CPU0_P1_SVC_R1   I143 @T6G_MB_LIB.T6G(SCH_1):PAGE185

PR8010 Q_RES_0402LF-0,5%,1/16W,CHIP,CS00002JB13
     1 SVID_PVDDCR_CPU0_P1_SVD_R @T6G_MB_LIB.T6G(SCH_1):SVID_PVDDCR_CPU0_P1_SVD_R   I144 @T6G_MB_LIB.T6G(SCH_1):PAGE185
     2 SVID_PVDDCR_CPU0_P1_SVD_R1 @T6G_MB_LIB.T6G(SCH_1):SVID_PVDDCR_CPU0_P1_SVD_R1   I144 @T6G_MB_LIB.T6G(SCH_1):PAGE185

PR8011 Q_RES_0402LF-0,5%,1/16W,CHIP,CS00002JB13
     1 SVID_PVDDCR_CPU1_P1_SVC_R @T6G_MB_LIB.T6G(SCH_1):SVID_PVDDCR_CPU1_P1_SVC_R   I137 @T6G_MB_LIB.T6G(SCH_1):PAGE192
     2 SVID_PVDDCR_CPU1_P1_SVC_R1 @T6G_MB_LIB.T6G(SCH_1):SVID_PVDDCR_CPU1_P1_SVC_R1   I137 @T6G_MB_LIB.T6G(SCH_1):PAGE192

PR8012 Q_RES_0402LF-0,5%,1/16W,CHIP,CS00002JB13
     1 SVID_PVDDCR_CPU1_P1_SVD_R @T6G_MB_LIB.T6G(SCH_1):SVID_PVDDCR_CPU1_P1_SVD_R   I138 @T6G_MB_LIB.T6G(SCH_1):PAGE192
     2 SVID_PVDDCR_CPU1_P1_SVD_R1 @T6G_MB_LIB.T6G(SCH_1):SVID_PVDDCR_CPU1_P1_SVD_R1   I138 @T6G_MB_LIB.T6G(SCH_1):PAGE192

PR8073 Q_RES_0402LF-1K,1%,1/16W,CHIP,CS21002FB06
     1 P3V3_AUX @T6G_MB_LIB.T6G(SCH_1):P3V3_AUX    I65 @T6G_MB_LIB.T6G(SCH_1):PAGE245
     2 PWRGD_P3V3_AUX_R1 @T6G_MB_LIB.T6G(SCH_1):PWRGD_P3V3_AUX_R1    I65 @T6G_MB_LIB.T6G(SCH_1):PAGE245

PR8089 Q_RES_0402LF-16.9K,1%,1/16W,CHIP,CS31692FB03
     1 P5V_AUX_CS @T6G_MB_LIB.T6G(SCH_1):P5V_AUX_CS    I15 @T6G_MB_LIB.T6G(SCH_1):PAGE244
     2    GND @T6G_MB_LIB.T6G(SCH_1):GND    I15 @T6G_MB_LIB.T6G(SCH_1):PAGE244

PR8091 Q_RES_0402LF-11.8K,0.1%,1/16W,CHIP,CS31182BB06
     1 P5V_AUX_FB @T6G_MB_LIB.T6G(SCH_1):P5V_AUX_FB    I23 @T6G_MB_LIB.T6G(SCH_1):PAGE244
     2    GND @T6G_MB_LIB.T6G(SCH_1):GND    I23 @T6G_MB_LIB.T6G(SCH_1):PAGE244

PR8092 Q_RES_0402LF-86.6K,1%,1/16W,CHIP,CS38662FB05
     1 P5V_AUX_FB @T6G_MB_LIB.T6G(SCH_1):P5V_AUX_FB    I27 @T6G_MB_LIB.T6G(SCH_1):PAGE244
     2 P5V_AUX @T6G_MB_LIB.T6G(SCH_1):P5V_AUX    I27 @T6G_MB_LIB.T6G(SCH_1):PAGE244

PR8389 Q_RES_0402LF-1,1%,1/16W,CHIP,CS-1002FB04
     1 P3V3_AUX_VDRV @T6G_MB_LIB.T6G(SCH_1):P3V3_AUX_VDRV    I20 @T6G_MB_LIB.T6G(SCH_1):PAGE245
     2 P3V3_AUX_VCC @T6G_MB_LIB.T6G(SCH_1):P3V3_AUX_VCC    I20 @T6G_MB_LIB.T6G(SCH_1):PAGE245

 PU2 ISL99390FRZTR5935-ISL99390FRZ-TR5935,SMLF,IC,AL099A
    34 PVDDCR_CPU1_P0_PWM2 @T6G_MB_LIB.T6G(SCH_1):PVDDCR_CPU1_P0_PWM2    I33 @T6G_MB_LIB.T6G(SCH_1):PAGE176
    39 PVDDCR_CPU1_P0_VCCS @T6G_MB_LIB.T6G(SCH_1):PVDDCR_CPU1_P0_VCCS    I33 @T6G_MB_LIB.T6G(SCH_1):PAGE176
     3 PVDDCR_CPU1_P0_VCC2 @T6G_MB_LIB.T6G(SCH_1):PVDDCR_CPU1_P0_VCC2    I33 @T6G_MB_LIB.T6G(SCH_1):PAGE176
     2    GND @T6G_MB_LIB.T6G(SCH_1):GND    I33 @T6G_MB_LIB.T6G(SCH_1):PAGE176
    33 SW_PVDDCR_CPU1_P0_BOOT2 @T6G_MB_LIB.T6G(SCH_1):SW_PVDDCR_CPU1_P0_BOOT2    I33 @T6G_MB_LIB.T6G(SCH_1):PAGE176
 25_29 SW_P12V_AUX_PVDDCR_CPU1_P0_FLT @T6G_MB_LIB.T6G(SCH_1):SW_P12V_AUX_PVDDCR_CPU1_P0_FLT    I33 @T6G_MB_LIB.T6G(SCH_1):PAGE176
    32 SW_PVDDCR_CPU1_P0_BOOTR2 @T6G_MB_LIB.T6G(SCH_1):SW_PVDDCR_CPU1_P0_BOOTR2    I33 @T6G_MB_LIB.T6G(SCH_1):PAGE176
     4 PVDDCR_CPU1_P0_PVCC @T6G_MB_LIB.T6G(SCH_1):PVDDCR_CPU1_P0_PVCC    I33 @T6G_MB_LIB.T6G(SCH_1):PAGE176
    36 PVDDCR_CPU1_P0_TEMP0 @T6G_MB_LIB.T6G(SCH_1):PVDDCR_CPU1_P0_TEMP0    I33 @T6G_MB_LIB.T6G(SCH_1):PAGE176
    38 PVDDCR_CPU1_P0_IMON2 @T6G_MB_LIB.T6G(SCH_1):PVDDCR_CPU1_P0_IMON2    I33 @T6G_MB_LIB.T6G(SCH_1):PAGE176
    37 PVDDCR_CPU1_P0_LSET2 @T6G_MB_LIB.T6G(SCH_1):PVDDCR_CPU1_P0_LSET2    I33 @T6G_MB_LIB.T6G(SCH_1):PAGE176
 10_19 SW_PVDDCR_CPU1_P0_SW2 @T6G_MB_LIB.T6G(SCH_1):SW_PVDDCR_CPU1_P0_SW2    I33 @T6G_MB_LIB.T6G(SCH_1):PAGE176
     5    GND @T6G_MB_LIB.T6G(SCH_1):GND    I33 @T6G_MB_LIB.T6G(SCH_1):PAGE176
    30 SW_P12V_AUX_PVDDCR_CPU1_P0_FLT @T6G_MB_LIB.T6G(SCH_1):SW_P12V_AUX_PVDDCR_CPU1_P0_FLT    I33 @T6G_MB_LIB.T6G(SCH_1):PAGE176
     1 PVDDCR_CPU1_P0_VOS2 @T6G_MB_LIB.T6G(SCH_1):PVDDCR_CPU1_P0_VOS2    I33 @T6G_MB_LIB.T6G(SCH_1):PAGE176
    40    GND @T6G_MB_LIB.T6G(SCH_1):GND    I33 @T6G_MB_LIB.T6G(SCH_1):PAGE176
    35 PVDDCR_CPU1_P0_VCC2 @T6G_MB_LIB.T6G(SCH_1):PVDDCR_CPU1_P0_VCC2    I33 @T6G_MB_LIB.T6G(SCH_1):PAGE176
    31 NC_PVDDCR_CPU1_P0_DNC2 @T6G_MB_LIB.T6G(SCH_1):NC_PVDDCR_CPU1_P0_DNC2    I33 @T6G_MB_LIB.T6G(SCH_1):PAGE176
     6 NC_PVDDCR_CPU1_P0_GL1_2 @T6G_MB_LIB.T6G(SCH_1):NC_PVDDCR_CPU1_P0_GL1_2    I33 @T6G_MB_LIB.T6G(SCH_1):PAGE176
    41 NC_PVDDCR_CPU1_P0_GL2_2 @T6G_MB_LIB.T6G(SCH_1):NC_PVDDCR_CPU1_P0_GL2_2    I33 @T6G_MB_LIB.T6G(SCH_1):PAGE176
7_9-20_24    GND @T6G_MB_LIB.T6G(SCH_1):GND    I33 @T6G_MB_LIB.T6G(SCH_1):PAGE176

 PU3 MPQ8633BGLEC838Z-MPQ8633BGLE-C838-Z,SMLF,IC,AL0086A
    10 SW_P12V_AUX_PVDD18_S5_P1_FLT @T6G_MB_LIB.T6G(SCH_1):SW_P12V_AUX_PVDD18_S5_P1_FLT    I15 @T6G_MB_LIB.T6G(SCH_1):PAGE201
     9 PWRGD_PVDD18_S5_P1 @T6G_MB_LIB.T6G(SCH_1):PWRGD_PVDD18_S5_P1    I15 @T6G_MB_LIB.T6G(SCH_1):PAGE201
 11_18    GND @T6G_MB_LIB.T6G(SCH_1):GND    I15 @T6G_MB_LIB.T6G(SCH_1):PAGE201
     8 PVDD18_S5_P1_EN @T6G_MB_LIB.T6G(SCH_1):PVDD18_S5_P1_EN    I15 @T6G_MB_LIB.T6G(SCH_1):PAGE201
     1 SW_PVDD18_S5_P1_BST @T6G_MB_LIB.T6G(SCH_1):SW_PVDD18_S5_P1_BST    I15 @T6G_MB_LIB.T6G(SCH_1):PAGE201
     7 PVDD18_S5_P1_FB @T6G_MB_LIB.T6G(SCH_1):PVDD18_S5_P1_FB    I15 @T6G_MB_LIB.T6G(SCH_1):PAGE201
     2    GND @T6G_MB_LIB.T6G(SCH_1):GND    I15 @T6G_MB_LIB.T6G(SCH_1):PAGE201
    19 PVDD18_S5_P1_VCC @T6G_MB_LIB.T6G(SCH_1):PVDD18_S5_P1_VCC    I15 @T6G_MB_LIB.T6G(SCH_1):PAGE201
     6 PVDD18_SS_P1_RGND @T6G_MB_LIB.T6G(SCH_1):PVDD18_SS_P1_RGND    I15 @T6G_MB_LIB.T6G(SCH_1):PAGE201
    20 SW_PVDD18_S5_P1_SW @T6G_MB_LIB.T6G(SCH_1):SW_PVDD18_S5_P1_SW    I15 @T6G_MB_LIB.T6G(SCH_1):PAGE201
     5 PVDD18_S5_P1_REF @T6G_MB_LIB.T6G(SCH_1):PVDD18_S5_P1_REF    I15 @T6G_MB_LIB.T6G(SCH_1):PAGE201
     4 PVDD18_S5_P1_MODE @T6G_MB_LIB.T6G(SCH_1):PVDD18_S5_P1_MODE    I15 @T6G_MB_LIB.T6G(SCH_1):PAGE201
     3 PVDD18_S5_P1_CS @T6G_MB_LIB.T6G(SCH_1):PVDD18_S5_P1_CS    I15 @T6G_MB_LIB.T6G(SCH_1):PAGE201
    21 SW_P12V_AUX_PVDD18_S5_P1_FLT @T6G_MB_LIB.T6G(SCH_1):SW_P12V_AUX_PVDD18_S5_P1_FLT    I15 @T6G_MB_LIB.T6G(SCH_1):PAGE201

 PU4 ISL99390FRZTR5935-ISL99390FRZ-TR5935,SMLF,IC,AL099A
    34 PVDDCR_CPU0_P1_PWM1 @T6G_MB_LIB.T6G(SCH_1):PVDDCR_CPU0_P1_PWM1    I88 @T6G_MB_LIB.T6G(SCH_1):PAGE186
    39 PVDDCR_CPU0_P1_VCCS @T6G_MB_LIB.T6G(SCH_1):PVDDCR_CPU0_P1_VCCS    I88 @T6G_MB_LIB.T6G(SCH_1):PAGE186
     3 PVDDCR_CPU0_P1_VCC1 @T6G_MB_LIB.T6G(SCH_1):PVDDCR_CPU0_P1_VCC1    I88 @T6G_MB_LIB.T6G(SCH_1):PAGE186
     2    GND @T6G_MB_LIB.T6G(SCH_1):GND    I88 @T6G_MB_LIB.T6G(SCH_1):PAGE186
    33 SW_PVDDCR_CPU0_P1_BOOT1 @T6G_MB_LIB.T6G(SCH_1):SW_PVDDCR_CPU0_P1_BOOT1    I88 @T6G_MB_LIB.T6G(SCH_1):PAGE186
 25_29 SW_P12V_AUX_PVDDCR_CPU0_P1_FLT @T6G_MB_LIB.T6G(SCH_1):SW_P12V_AUX_PVDDCR_CPU0_P1_FLT    I88 @T6G_MB_LIB.T6G(SCH_1):PAGE186
    32 SW_PVDDCR_CPU0_P1_PH1 @T6G_MB_LIB.T6G(SCH_1):SW_PVDDCR_CPU0_P1_PH1    I88 @T6G_MB_LIB.T6G(SCH_1):PAGE186
     4 PVDDCR_CPU0_P1_PVCC @T6G_MB_LIB.T6G(SCH_1):PVDDCR_CPU0_P1_PVCC    I88 @T6G_MB_LIB.T6G(SCH_1):PAGE186
    36 PVDDCR_CPU0_P1_TEMP0 @T6G_MB_LIB.T6G(SCH_1):PVDDCR_CPU0_P1_TEMP0    I88 @T6G_MB_LIB.T6G(SCH_1):PAGE186
    38 PVDDCR_CPU0_P1_IMON1 @T6G_MB_LIB.T6G(SCH_1):PVDDCR_CPU0_P1_IMON1    I88 @T6G_MB_LIB.T6G(SCH_1):PAGE186
    37 PVDDCR_CPU0_P1_LSET1 @T6G_MB_LIB.T6G(SCH_1):PVDDCR_CPU0_P1_LSET1    I88 @T6G_MB_LIB.T6G(SCH_1):PAGE186
 10_19 SW_PVDDCR_CPU0_P1_SW1 @T6G_MB_LIB.T6G(SCH_1):SW_PVDDCR_CPU0_P1_SW1    I88 @T6G_MB_LIB.T6G(SCH_1):PAGE186
     5    GND @T6G_MB_LIB.T6G(SCH_1):GND    I88 @T6G_MB_LIB.T6G(SCH_1):PAGE186
    30 SW_P12V_AUX_PVDDCR_CPU0_P1_FLT @T6G_MB_LIB.T6G(SCH_1):SW_P12V_AUX_PVDDCR_CPU0_P1_FLT    I88 @T6G_MB_LIB.T6G(SCH_1):PAGE186
     1 PVDDCR_CPU0_P1_VOS1 @T6G_MB_LIB.T6G(SCH_1):PVDDCR_CPU0_P1_VOS1    I88 @T6G_MB_LIB.T6G(SCH_1):PAGE186
    40    GND @T6G_MB_LIB.T6G(SCH_1):GND    I88 @T6G_MB_LIB.T6G(SCH_1):PAGE186
    35 PVDDCR_CPU0_P1_VCC1 @T6G_MB_LIB.T6G(SCH_1):PVDDCR_CPU0_P1_VCC1    I88 @T6G_MB_LIB.T6G(SCH_1):PAGE186
    31 NC_PVDDCR_CPU0_P1_DNC1 @T6G_MB_LIB.T6G(SCH_1):NC_PVDDCR_CPU0_P1_DNC1    I88 @T6G_MB_LIB.T6G(SCH_1):PAGE186
     6 NC_PVDDCR_CPU0_P1_GL1_1 @T6G_MB_LIB.T6G(SCH_1):NC_PVDDCR_CPU0_P1_GL1_1    I88 @T6G_MB_LIB.T6G(SCH_1):PAGE186
    41 NC_PVDDCR_CPU0_P1_GL2_1 @T6G_MB_LIB.T6G(SCH_1):NC_PVDDCR_CPU0_P1_GL2_1    I88 @T6G_MB_LIB.T6G(SCH_1):PAGE186
7_9-20_24    GND @T6G_MB_LIB.T6G(SCH_1):GND    I88 @T6G_MB_LIB.T6G(SCH_1):PAGE186

 PU5 ISL99390FRZTR5935-ISL99390FRZ-TR5935,SMLF,IC,AL099A
    34 PVDDCR_CPU1_P1_PWM2 @T6G_MB_LIB.T6G(SCH_1):PVDDCR_CPU1_P1_PWM2    I31 @T6G_MB_LIB.T6G(SCH_1):PAGE193
    39 PVDDCR_CPU1_P1_VCCS @T6G_MB_LIB.T6G(SCH_1):PVDDCR_CPU1_P1_VCCS    I31 @T6G_MB_LIB.T6G(SCH_1):PAGE193
     3 PVDDCR_CPU1_P1_VCC2 @T6G_MB_LIB.T6G(SCH_1):PVDDCR_CPU1_P1_VCC2    I31 @T6G_MB_LIB.T6G(SCH_1):PAGE193
     2    GND @T6G_MB_LIB.T6G(SCH_1):GND    I31 @T6G_MB_LIB.T6G(SCH_1):PAGE193
    33 SW_PVDDCR_CPU1_P1_BOOT2 @T6G_MB_LIB.T6G(SCH_1):SW_PVDDCR_CPU1_P1_BOOT2    I31 @T6G_MB_LIB.T6G(SCH_1):PAGE193
 25_29 SW_P12V_AUX_PVDDCR_CPU1_P1_FLT @T6G_MB_LIB.T6G(SCH_1):SW_P12V_AUX_PVDDCR_CPU1_P1_FLT    I31 @T6G_MB_LIB.T6G(SCH_1):PAGE193
    32 SW_PVDDCR_CPU1_P1_BOOTR2 @T6G_MB_LIB.T6G(SCH_1):SW_PVDDCR_CPU1_P1_BOOTR2    I31 @T6G_MB_LIB.T6G(SCH_1):PAGE193
     4 PVDDCR_CPU1_P1_PVCC @T6G_MB_LIB.T6G(SCH_1):PVDDCR_CPU1_P1_PVCC    I31 @T6G_MB_LIB.T6G(SCH_1):PAGE193
    36 PVDDCR_CPU1_P1_TEMP0 @T6G_MB_LIB.T6G(SCH_1):PVDDCR_CPU1_P1_TEMP0    I31 @T6G_MB_LIB.T6G(SCH_1):PAGE193
    38 PVDDCR_CPU1_P1_IMON2 @T6G_MB_LIB.T6G(SCH_1):PVDDCR_CPU1_P1_IMON2    I31 @T6G_MB_LIB.T6G(SCH_1):PAGE193
    37 PVDDCR_CPU1_P1_LSET2 @T6G_MB_LIB.T6G(SCH_1):PVDDCR_CPU1_P1_LSET2    I31 @T6G_MB_LIB.T6G(SCH_1):PAGE193
 10_19 SW_PVDDCR_CPU1_P1_SW2 @T6G_MB_LIB.T6G(SCH_1):SW_PVDDCR_CPU1_P1_SW2    I31 @T6G_MB_LIB.T6G(SCH_1):PAGE193
     5    GND @T6G_MB_LIB.T6G(SCH_1):GND    I31 @T6G_MB_LIB.T6G(SCH_1):PAGE193
    30 SW_P12V_AUX_PVDDCR_CPU1_P1_FLT @T6G_MB_LIB.T6G(SCH_1):SW_P12V_AUX_PVDDCR_CPU1_P1_FLT    I31 @T6G_MB_LIB.T6G(SCH_1):PAGE193
     1 PVDDCR_CPU1_P1_VOS2 @T6G_MB_LIB.T6G(SCH_1):PVDDCR_CPU1_P1_VOS2    I31 @T6G_MB_LIB.T6G(SCH_1):PAGE193
    40    GND @T6G_MB_LIB.T6G(SCH_1):GND    I31 @T6G_MB_LIB.T6G(SCH_1):PAGE193
    35 PVDDCR_CPU1_P1_VCC2 @T6G_MB_LIB.T6G(SCH_1):PVDDCR_CPU1_P1_VCC2    I31 @T6G_MB_LIB.T6G(SCH_1):PAGE193
    31 NC_PVDDCR_CPU1_P1_DNC2 @T6G_MB_LIB.T6G(SCH_1):NC_PVDDCR_CPU1_P1_DNC2    I31 @T6G_MB_LIB.T6G(SCH_1):PAGE193
     6 NC_PVDDCR_CPU1_P1_GL1_2 @T6G_MB_LIB.T6G(SCH_1):NC_PVDDCR_CPU1_P1_GL1_2    I31 @T6G_MB_LIB.T6G(SCH_1):PAGE193
    41 NC_PVDDCR_CPU1_P1_GL2_2 @T6G_MB_LIB.T6G(SCH_1):NC_PVDDCR_CPU1_P1_GL2_2    I31 @T6G_MB_LIB.T6G(SCH_1):PAGE193
7_9-20_24    GND @T6G_MB_LIB.T6G(SCH_1):GND    I31 @T6G_MB_LIB.T6G(SCH_1):PAGE193

 PU6 ISL99390FRZTR5935-ISL99390FRZ-TR5935,SMLF,IC,AL099A
    34 PVDDCR_CPU0_P0_PWM1 @T6G_MB_LIB.T6G(SCH_1):PVDDCR_CPU0_P0_PWM1    I26 @T6G_MB_LIB.T6G(SCH_1):PAGE169
    39 PVDDCR_CPU0_P0_VCCS @T6G_MB_LIB.T6G(SCH_1):PVDDCR_CPU0_P0_VCCS    I26 @T6G_MB_LIB.T6G(SCH_1):PAGE169
     3 PVDDCR_CPU0_P0_VCC1 @T6G_MB_LIB.T6G(SCH_1):PVDDCR_CPU0_P0_VCC1    I26 @T6G_MB_LIB.T6G(SCH_1):PAGE169
     2    GND @T6G_MB_LIB.T6G(SCH_1):GND    I26 @T6G_MB_LIB.T6G(SCH_1):PAGE169
    33 SW_PVDDCR_CPU0_P0_BOOT1 @T6G_MB_LIB.T6G(SCH_1):SW_PVDDCR_CPU0_P0_BOOT1    I26 @T6G_MB_LIB.T6G(SCH_1):PAGE169
 25_29 SW_P12V_AUX_PVDDCR_CPU0_P0_FLT @T6G_MB_LIB.T6G(SCH_1):SW_P12V_AUX_PVDDCR_CPU0_P0_FLT    I26 @T6G_MB_LIB.T6G(SCH_1):PAGE169
    32 SW_PVDDCR_CPU0_P0_PH1 @T6G_MB_LIB.T6G(SCH_1):SW_PVDDCR_CPU0_P0_PH1    I26 @T6G_MB_LIB.T6G(SCH_1):PAGE169
     4 PVDDCR_CPU0_P0_PVCC @T6G_MB_LIB.T6G(SCH_1):PVDDCR_CPU0_P0_PVCC    I26 @T6G_MB_LIB.T6G(SCH_1):PAGE169
    36 PVDDCR_CPU0_P0_TEMP0 @T6G_MB_LIB.T6G(SCH_1):PVDDCR_CPU0_P0_TEMP0    I26 @T6G_MB_LIB.T6G(SCH_1):PAGE169
    38 PVDDCR_CPU0_P0_IMON1 @T6G_MB_LIB.T6G(SCH_1):PVDDCR_CPU0_P0_IMON1    I26 @T6G_MB_LIB.T6G(SCH_1):PAGE169
    37 PVDDCR_CPU0_P0_LSET1 @T6G_MB_LIB.T6G(SCH_1):PVDDCR_CPU0_P0_LSET1    I26 @T6G_MB_LIB.T6G(SCH_1):PAGE169
 10_19 SW_PVDDCR_CPU0_P0_SW1 @T6G_MB_LIB.T6G(SCH_1):SW_PVDDCR_CPU0_P0_SW1    I26 @T6G_MB_LIB.T6G(SCH_1):PAGE169
     5    GND @T6G_MB_LIB.T6G(SCH_1):GND    I26 @T6G_MB_LIB.T6G(SCH_1):PAGE169
    30 SW_P12V_AUX_PVDDCR_CPU0_P0_FLT @T6G_MB_LIB.T6G(SCH_1):SW_P12V_AUX_PVDDCR_CPU0_P0_FLT    I26 @T6G_MB_LIB.T6G(SCH_1):PAGE169
     1 PVDDCR_CPU0_P0_VOS1 @T6G_MB_LIB.T6G(SCH_1):PVDDCR_CPU0_P0_VOS1    I26 @T6G_MB_LIB.T6G(SCH_1):PAGE169
    40    GND @T6G_MB_LIB.T6G(SCH_1):GND    I26 @T6G_MB_LIB.T6G(SCH_1):PAGE169
    35 PVDDCR_CPU0_P0_VCC1 @T6G_MB_LIB.T6G(SCH_1):PVDDCR_CPU0_P0_VCC1    I26 @T6G_MB_LIB.T6G(SCH_1):PAGE169
    31 NC_PVDDCR_CPU0_P0_DNC1 @T6G_MB_LIB.T6G(SCH_1):NC_PVDDCR_CPU0_P0_DNC1    I26 @T6G_MB_LIB.T6G(SCH_1):PAGE169
     6 NC_PVDDCR_CPU0_P0_GL1_1 @T6G_MB_LIB.T6G(SCH_1):NC_PVDDCR_CPU0_P0_GL1_1    I26 @T6G_MB_LIB.T6G(SCH_1):PAGE169
    41 NC_PVDDCR_CPU0_P0_GL2_1 @T6G_MB_LIB.T6G(SCH_1):NC_PVDDCR_CPU0_P0_GL2_1    I26 @T6G_MB_LIB.T6G(SCH_1):PAGE169
7_9-20_24    GND @T6G_MB_LIB.T6G(SCH_1):GND    I26 @T6G_MB_LIB.T6G(SCH_1):PAGE169

 PU9 NCP3284AMNTXG-NCP3284AMNTXG,SMLF,IC,AL003284002
    34 NC_PU9_2 @T6G_MB_LIB.T6G(SCH_1):NC_PU9_2    I21 @T6G_MB_LIB.T6G(SCH_1):PAGE245
    36 P3V3_AUX_MODE @T6G_MB_LIB.T6G(SCH_1):P3V3_AUX_MODE    I21 @T6G_MB_LIB.T6G(SCH_1):PAGE245
     3 P12V_AUX @T6G_MB_LIB.T6G(SCH_1):P12V_AUX    I21 @T6G_MB_LIB.T6G(SCH_1):PAGE245
    30 P3V3_AUX_FB @T6G_MB_LIB.T6G(SCH_1):P3V3_AUX_FB    I21 @T6G_MB_LIB.T6G(SCH_1):PAGE245
    26 SW_P3V3_AUX_BOOT @T6G_MB_LIB.T6G(SCH_1):SW_P3V3_AUX_BOOT    I21 @T6G_MB_LIB.T6G(SCH_1):PAGE245
     1 P3V3_AUX_ILIM @T6G_MB_LIB.T6G(SCH_1):P3V3_AUX_ILIM    I21 @T6G_MB_LIB.T6G(SCH_1):PAGE245
    25 SW_P3V3_AUX_BOOTR @T6G_MB_LIB.T6G(SCH_1):SW_P3V3_AUX_BOOTR    I21 @T6G_MB_LIB.T6G(SCH_1):PAGE245
     4 P3V3_AUX_VCC @T6G_MB_LIB.T6G(SCH_1):P3V3_AUX_VCC    I21 @T6G_MB_LIB.T6G(SCH_1):PAGE245
    31    GND @T6G_MB_LIB.T6G(SCH_1):GND    I21 @T6G_MB_LIB.T6G(SCH_1):PAGE245
    35 NC_HICCUP @T6G_MB_LIB.T6G(SCH_1):NC_HICCUP    I21 @T6G_MB_LIB.T6G(SCH_1):PAGE245
7_10-19    GND @T6G_MB_LIB.T6G(SCH_1):GND    I21 @T6G_MB_LIB.T6G(SCH_1):PAGE245
    33 NC_PU9_1 @T6G_MB_LIB.T6G(SCH_1):NC_PU9_1    I21 @T6G_MB_LIB.T6G(SCH_1):PAGE245
 11_18 SW_P3V3_AUX_SW @T6G_MB_LIB.T6G(SCH_1):SW_P3V3_AUX_SW    I21 @T6G_MB_LIB.T6G(SCH_1):PAGE245
 20_24 SW_P3V3_AUX_FLT @T6G_MB_LIB.T6G(SCH_1):SW_P3V3_AUX_FLT    I21 @T6G_MB_LIB.T6G(SCH_1):PAGE245
     2 PWRGD_P3V3_AUX_R1 @T6G_MB_LIB.T6G(SCH_1):PWRGD_P3V3_AUX_R1    I21 @T6G_MB_LIB.T6G(SCH_1):PAGE245
    28 P3V3_AUX_VOS @T6G_MB_LIB.T6G(SCH_1):P3V3_AUX_VOS    I21 @T6G_MB_LIB.T6G(SCH_1):PAGE245
    32    GND @T6G_MB_LIB.T6G(SCH_1):GND    I21 @T6G_MB_LIB.T6G(SCH_1):PAGE245
    27 P3V3_AUX_EN @T6G_MB_LIB.T6G(SCH_1):P3V3_AUX_EN    I21 @T6G_MB_LIB.T6G(SCH_1):PAGE245
     5 P3V3_AUX_VDRV @T6G_MB_LIB.T6G(SCH_1):P3V3_AUX_VDRV    I21 @T6G_MB_LIB.T6G(SCH_1):PAGE245
     6 NC_PU9_3 @T6G_MB_LIB.T6G(SCH_1):NC_PU9_3    I21 @T6G_MB_LIB.T6G(SCH_1):PAGE245
    29 P3V3_AUX_SS @T6G_MB_LIB.T6G(SCH_1):P3V3_AUX_SS    I21 @T6G_MB_LIB.T6G(SCH_1):PAGE245
    37 NC_PU9_4 @T6G_MB_LIB.T6G(SCH_1):NC_PU9_4    I21 @T6G_MB_LIB.T6G(SCH_1):PAGE245

PU10 ISL99390FRZTR5935-ISL99390FRZ-TR5935,SMLF,IC,AL099A
    34 PVDDCR_CPU0_P0_PWM6 @T6G_MB_LIB.T6G(SCH_1):PVDDCR_CPU0_P0_PWM6    I73 @T6G_MB_LIB.T6G(SCH_1):PAGE171
    39 PVDDCR_CPU0_P0_VCCS @T6G_MB_LIB.T6G(SCH_1):PVDDCR_CPU0_P0_VCCS    I73 @T6G_MB_LIB.T6G(SCH_1):PAGE171
     3 PVDDCR_CPU0_P0_VCC6 @T6G_MB_LIB.T6G(SCH_1):PVDDCR_CPU0_P0_VCC6    I73 @T6G_MB_LIB.T6G(SCH_1):PAGE171
     2    GND @T6G_MB_LIB.T6G(SCH_1):GND    I73 @T6G_MB_LIB.T6G(SCH_1):PAGE171
    33 SW_PVDDCR_CPU0_P0_BOOT6 @T6G_MB_LIB.T6G(SCH_1):SW_PVDDCR_CPU0_P0_BOOT6    I73 @T6G_MB_LIB.T6G(SCH_1):PAGE171
 25_29 SW_P12V_AUX_PVDDCR_CPU0_P0_FLT @T6G_MB_LIB.T6G(SCH_1):SW_P12V_AUX_PVDDCR_CPU0_P0_FLT    I73 @T6G_MB_LIB.T6G(SCH_1):PAGE171
    32 SW_PVDDCR_CPU0_P0_PH6 @T6G_MB_LIB.T6G(SCH_1):SW_PVDDCR_CPU0_P0_PH6    I73 @T6G_MB_LIB.T6G(SCH_1):PAGE171
     4 PVDDCR_CPU0_P0_PVCC @T6G_MB_LIB.T6G(SCH_1):PVDDCR_CPU0_P0_PVCC    I73 @T6G_MB_LIB.T6G(SCH_1):PAGE171
    36 PVDDCR_CPU0_P0_TEMP0 @T6G_MB_LIB.T6G(SCH_1):PVDDCR_CPU0_P0_TEMP0    I73 @T6G_MB_LIB.T6G(SCH_1):PAGE171
    38 PVDDCR_CPU0_P0_IMON6 @T6G_MB_LIB.T6G(SCH_1):PVDDCR_CPU0_P0_IMON6    I73 @T6G_MB_LIB.T6G(SCH_1):PAGE171
    37 PVDDCR_CPU0_P0_LSET6 @T6G_MB_LIB.T6G(SCH_1):PVDDCR_CPU0_P0_LSET6    I73 @T6G_MB_LIB.T6G(SCH_1):PAGE171
 10_19 SW_PVDDCR_CPU0_P0_SW6 @T6G_MB_LIB.T6G(SCH_1):SW_PVDDCR_CPU0_P0_SW6    I73 @T6G_MB_LIB.T6G(SCH_1):PAGE171
     5    GND @T6G_MB_LIB.T6G(SCH_1):GND    I73 @T6G_MB_LIB.T6G(SCH_1):PAGE171
    30 SW_P12V_AUX_PVDDCR_CPU0_P0_FLT @T6G_MB_LIB.T6G(SCH_1):SW_P12V_AUX_PVDDCR_CPU0_P0_FLT    I73 @T6G_MB_LIB.T6G(SCH_1):PAGE171
     1 PVDDCR_CPU0_P0_VOS6 @T6G_MB_LIB.T6G(SCH_1):PVDDCR_CPU0_P0_VOS6    I73 @T6G_MB_LIB.T6G(SCH_1):PAGE171
    40    GND @T6G_MB_LIB.T6G(SCH_1):GND    I73 @T6G_MB_LIB.T6G(SCH_1):PAGE171
    35 PVDDCR_CPU0_P0_VCC6 @T6G_MB_LIB.T6G(SCH_1):PVDDCR_CPU0_P0_VCC6    I73 @T6G_MB_LIB.T6G(SCH_1):PAGE171
    31 NC_PVDDCR_CPU0_P0_DNC6 @T6G_MB_LIB.T6G(SCH_1):NC_PVDDCR_CPU0_P0_DNC6    I73 @T6G_MB_LIB.T6G(SCH_1):PAGE171
     6 NC_PVDDCR_CPU0_P0_GL1_6 @T6G_MB_LIB.T6G(SCH_1):NC_PVDDCR_CPU0_P0_GL1_6    I73 @T6G_MB_LIB.T6G(SCH_1):PAGE171
    41 NC_PVDDCR_CPU0_P0_GL2_6 @T6G_MB_LIB.T6G(SCH_1):NC_PVDDCR_CPU0_P0_GL2_6    I73 @T6G_MB_LIB.T6G(SCH_1):PAGE171
7_9-20_24    GND @T6G_MB_LIB.T6G(SCH_1):GND    I73 @T6G_MB_LIB.T6G(SCH_1):PAGE171

PU11 ISL99390FRZTR5935-ISL99390FRZ-TR5935,SMLF,IC,AL099A
    34 PVDDCR_CPU1_P0_PWM6 @T6G_MB_LIB.T6G(SCH_1):PVDDCR_CPU1_P0_PWM6    I73 @T6G_MB_LIB.T6G(SCH_1):PAGE178
    39 PVDDCR_CPU1_P0_VCCS @T6G_MB_LIB.T6G(SCH_1):PVDDCR_CPU1_P0_VCCS    I73 @T6G_MB_LIB.T6G(SCH_1):PAGE178
     3 PVDDCR_CPU1_P0_VCC6 @T6G_MB_LIB.T6G(SCH_1):PVDDCR_CPU1_P0_VCC6    I73 @T6G_MB_LIB.T6G(SCH_1):PAGE178
     2    GND @T6G_MB_LIB.T6G(SCH_1):GND    I73 @T6G_MB_LIB.T6G(SCH_1):PAGE178
    33 SW_PVDDCR_CPU1_P0_BOOT6 @T6G_MB_LIB.T6G(SCH_1):SW_PVDDCR_CPU1_P0_BOOT6    I73 @T6G_MB_LIB.T6G(SCH_1):PAGE178
 25_29 SW_P12V_AUX_PVDDCR_CPU1_P0_FLT @T6G_MB_LIB.T6G(SCH_1):SW_P12V_AUX_PVDDCR_CPU1_P0_FLT    I73 @T6G_MB_LIB.T6G(SCH_1):PAGE178
    32 SW_PVDDCR_CPU1_P0_BOOTR6 @T6G_MB_LIB.T6G(SCH_1):SW_PVDDCR_CPU1_P0_BOOTR6    I73 @T6G_MB_LIB.T6G(SCH_1):PAGE178
     4 PVDDCR_CPU1_P0_PVCC @T6G_MB_LIB.T6G(SCH_1):PVDDCR_CPU1_P0_PVCC    I73 @T6G_MB_LIB.T6G(SCH_1):PAGE178
    36 PVDDCR_CPU1_P0_TEMP0 @T6G_MB_LIB.T6G(SCH_1):PVDDCR_CPU1_P0_TEMP0    I73 @T6G_MB_LIB.T6G(SCH_1):PAGE178
    38 PVDDCR_CPU1_P0_IMON6 @T6G_MB_LIB.T6G(SCH_1):PVDDCR_CPU1_P0_IMON6    I73 @T6G_MB_LIB.T6G(SCH_1):PAGE178
    37 PVDDCR_CPU1_P0_LSET6 @T6G_MB_LIB.T6G(SCH_1):PVDDCR_CPU1_P0_LSET6    I73 @T6G_MB_LIB.T6G(SCH_1):PAGE178
 10_19 SW_PVDDCR_CPU1_P0_SW6 @T6G_MB_LIB.T6G(SCH_1):SW_PVDDCR_CPU1_P0_SW6    I73 @T6G_MB_LIB.T6G(SCH_1):PAGE178
     5    GND @T6G_MB_LIB.T6G(SCH_1):GND    I73 @T6G_MB_LIB.T6G(SCH_1):PAGE178
    30 SW_P12V_AUX_PVDDCR_CPU1_P0_FLT @T6G_MB_LIB.T6G(SCH_1):SW_P12V_AUX_PVDDCR_CPU1_P0_FLT    I73 @T6G_MB_LIB.T6G(SCH_1):PAGE178
     1 PVDDCR_CPU1_P0_VOS6 @T6G_MB_LIB.T6G(SCH_1):PVDDCR_CPU1_P0_VOS6    I73 @T6G_MB_LIB.T6G(SCH_1):PAGE178
    40    GND @T6G_MB_LIB.T6G(SCH_1):GND    I73 @T6G_MB_LIB.T6G(SCH_1):PAGE178
    35 PVDDCR_CPU1_P0_VCC6 @T6G_MB_LIB.T6G(SCH_1):PVDDCR_CPU1_P0_VCC6    I73 @T6G_MB_LIB.T6G(SCH_1):PAGE178
    31 NC_PVDDCR_CPU1_P0_DNC6 @T6G_MB_LIB.T6G(SCH_1):NC_PVDDCR_CPU1_P0_DNC6    I73 @T6G_MB_LIB.T6G(SCH_1):PAGE178
     6 NC_PVDDCR_CPU1_P0_GL1_6 @T6G_MB_LIB.T6G(SCH_1):NC_PVDDCR_CPU1_P0_GL1_6    I73 @T6G_MB_LIB.T6G(SCH_1):PAGE178
    41 NC_PVDDCR_CPU1_P0_GL2_6 @T6G_MB_LIB.T6G(SCH_1):NC_PVDDCR_CPU1_P0_GL2_6    I73 @T6G_MB_LIB.T6G(SCH_1):PAGE178
7_9-20_24    GND @T6G_MB_LIB.T6G(SCH_1):GND    I73 @T6G_MB_LIB.T6G(SCH_1):PAGE178

PU12 RAA229620GNPHA0-RAA229620GNP#HA0,SMLF,IC,ARF0TGP40A
    27 PVDDCR_CPU1_P0_IMON1 @T6G_MB_LIB.T6G(SCH_1):PVDDCR_CPU1_P0_IMON1   I128 @T6G_MB_LIB.T6G(SCH_1):PAGE175
    47 PVDDCR_CPU1_P0_VCC @T6G_MB_LIB.T6G(SCH_1):PVDDCR_CPU1_P0_VCC   I128 @T6G_MB_LIB.T6G(SCH_1):PAGE175
    24 SVID_PVDDCR_CPU1_P0_SVTI_R @T6G_MB_LIB.T6G(SCH_1):SVID_PVDDCR_CPU1_P0_SVTI_R   I128 @T6G_MB_LIB.T6G(SCH_1):PAGE175
    14 SMB_CLK_PVDDCR_CPU1_P0_R @T6G_MB_LIB.T6G(SCH_1):SMB_CLK_PVDDCR_CPU1_P0_R   I128 @T6G_MB_LIB.T6G(SCH_1):PAGE175
    22 SVID_PVDDCR_CPU1_P0_SVC_R1 @T6G_MB_LIB.T6G(SCH_1):SVID_PVDDCR_CPU1_P0_SVC_R1   I128 @T6G_MB_LIB.T6G(SCH_1):PAGE175
    32 PVDDCR_CPU1_P0_IMON6 @T6G_MB_LIB.T6G(SCH_1):PVDDCR_CPU1_P0_IMON6   I128 @T6G_MB_LIB.T6G(SCH_1):PAGE175
    23 SVID_PVDDCR_CPU1_P0_SVTO_R @T6G_MB_LIB.T6G(SCH_1):SVID_PVDDCR_CPU1_P0_SVTO_R   I128 @T6G_MB_LIB.T6G(SCH_1):PAGE175
    18 PVDDCR_CPU1_P0_RESET_N_R @T6G_MB_LIB.T6G(SCH_1):PVDDCR_CPU1_P0_RESET_N_R   I128 @T6G_MB_LIB.T6G(SCH_1):PAGE175
    33 NC_PVDDCR_CPU1_P0_IMON7 @T6G_MB_LIB.T6G(SCH_1):NC_PVDDCR_CPU1_P0_IMON7   I128 @T6G_MB_LIB.T6G(SCH_1):PAGE175
    34 NC_PVDDCR_CPU1_P0_IMON8 @T6G_MB_LIB.T6G(SCH_1):NC_PVDDCR_CPU1_P0_IMON8   I128 @T6G_MB_LIB.T6G(SCH_1):PAGE175
    20 PWRGD_PVDDIO_P0_R @T6G_MB_LIB.T6G(SCH_1):PWRGD_PVDDIO_P0_R   I128 @T6G_MB_LIB.T6G(SCH_1):PAGE175
    21 SVID_PVDDCR_CPU1_P0_SVD_R1 @T6G_MB_LIB.T6G(SCH_1):SVID_PVDDCR_CPU1_P0_SVD_R1   I128 @T6G_MB_LIB.T6G(SCH_1):PAGE175
    15 PVDDCR_CPU1_P0_SMB_ALERT_R @T6G_MB_LIB.T6G(SCH_1):PVDDCR_CPU1_P0_SMB_ALERT_R   I128 @T6G_MB_LIB.T6G(SCH_1):PAGE175
    17 PVDDCR_CPU1_P0_EN_R @T6G_MB_LIB.T6G(SCH_1):PVDDCR_CPU1_P0_EN_R   I128 @T6G_MB_LIB.T6G(SCH_1):PAGE175
    26 VSENSE_VSS_SENSE_C_P0 @T6G_MB_LIB.T6G(SCH_1):VSENSE_VSS_SENSE_C_P0   I128 @T6G_MB_LIB.T6G(SCH_1):PAGE175
    13 SMB_DIO_PVDDCR_CPU1_P0_R @T6G_MB_LIB.T6G(SCH_1):SMB_DIO_PVDDCR_CPU1_P0_R   I128 @T6G_MB_LIB.T6G(SCH_1):PAGE175
     5 NC_PVDDCR_CPU1_P0_PWM8 @T6G_MB_LIB.T6G(SCH_1):NC_PVDDCR_CPU1_P0_PWM8   I128 @T6G_MB_LIB.T6G(SCH_1):PAGE175
     6 NC_PVDDCR_CPU1_P0_PWM7 @T6G_MB_LIB.T6G(SCH_1):NC_PVDDCR_CPU1_P0_PWM7   I128 @T6G_MB_LIB.T6G(SCH_1):PAGE175
    25 VSENSE_PVDDCR_CPU1_P0_VSEN0 @T6G_MB_LIB.T6G(SCH_1):VSENSE_PVDDCR_CPU1_P0_VSEN0   I128 @T6G_MB_LIB.T6G(SCH_1):PAGE175
     2 PVDDIO_P0_PWM2 @T6G_MB_LIB.T6G(SCH_1):PVDDIO_P0_PWM2   I128 @T6G_MB_LIB.T6G(SCH_1):PAGE175
    16 PWRGD_PVDDCR_CPU1_P0_R @T6G_MB_LIB.T6G(SCH_1):PWRGD_PVDDCR_CPU1_P0_R   I128 @T6G_MB_LIB.T6G(SCH_1):PAGE175
     7 PVDDCR_CPU1_P0_PWM6 @T6G_MB_LIB.T6G(SCH_1):PVDDCR_CPU1_P0_PWM6   I128 @T6G_MB_LIB.T6G(SCH_1):PAGE175
    48 PVDDCR_CPU1_P0_VCCS @T6G_MB_LIB.T6G(SCH_1):PVDDCR_CPU1_P0_VCCS   I128 @T6G_MB_LIB.T6G(SCH_1):PAGE175
    45 PVDDCR_CPU1_P0_VMON @T6G_MB_LIB.T6G(SCH_1):PVDDCR_CPU1_P0_VMON   I128 @T6G_MB_LIB.T6G(SCH_1):PAGE175
    46 PVDDCR_CPU1_P0_VINSEN @T6G_MB_LIB.T6G(SCH_1):PVDDCR_CPU1_P0_VINSEN   I128 @T6G_MB_LIB.T6G(SCH_1):PAGE175
    44 PVDDCR_CPU1_P0_TEMP0 @T6G_MB_LIB.T6G(SCH_1):PVDDCR_CPU1_P0_TEMP0   I128 @T6G_MB_LIB.T6G(SCH_1):PAGE175
    19 PVDD18_S5_P0 @T6G_MB_LIB.T6G(SCH_1):PVDD18_S5_P0   I128 @T6G_MB_LIB.T6G(SCH_1):PAGE175
    40 VSENSE_PVDDIO_P0_VSEN1 @T6G_MB_LIB.T6G(SCH_1):VSENSE_PVDDIO_P0_VSEN1   I128 @T6G_MB_LIB.T6G(SCH_1):PAGE175
    39 VSENSE_VSS_SENSE_B_P0 @T6G_MB_LIB.T6G(SCH_1):VSENSE_VSS_SENSE_B_P0   I128 @T6G_MB_LIB.T6G(SCH_1):PAGE175
    37 PVDDIO_P0_IMON2 @T6G_MB_LIB.T6G(SCH_1):PVDDIO_P0_IMON2   I128 @T6G_MB_LIB.T6G(SCH_1):PAGE175
    12 PVDDCR_CPU1_P0_PWM1 @T6G_MB_LIB.T6G(SCH_1):PVDDCR_CPU1_P0_PWM1   I128 @T6G_MB_LIB.T6G(SCH_1):PAGE175
     4 PVDDIO_P0_PWM4 @T6G_MB_LIB.T6G(SCH_1):PVDDIO_P0_PWM4   I128 @T6G_MB_LIB.T6G(SCH_1):PAGE175
    35 PVDDIO_P0_IMON4 @T6G_MB_LIB.T6G(SCH_1):PVDDIO_P0_IMON4   I128 @T6G_MB_LIB.T6G(SCH_1):PAGE175
     3 PVDDIO_P0_PWM3 @T6G_MB_LIB.T6G(SCH_1):PVDDIO_P0_PWM3   I128 @T6G_MB_LIB.T6G(SCH_1):PAGE175
    36 PVDDIO_P0_IMON3 @T6G_MB_LIB.T6G(SCH_1):PVDDIO_P0_IMON3   I128 @T6G_MB_LIB.T6G(SCH_1):PAGE175
    41 PVDDCR_CPU1_P0_OCP_N_R @T6G_MB_LIB.T6G(SCH_1):PVDDCR_CPU1_P0_OCP_N_R   I128 @T6G_MB_LIB.T6G(SCH_1):PAGE175
    TH    GND @T6G_MB_LIB.T6G(SCH_1):GND   I128 @T6G_MB_LIB.T6G(SCH_1):PAGE175
    42 PVDDCR_CPU1_P0_EN1_ADDR_CFG @T6G_MB_LIB.T6G(SCH_1):PVDDCR_CPU1_P0_EN1_ADDR_CFG   I128 @T6G_MB_LIB.T6G(SCH_1):PAGE175
    43 PVDDIO_P0_TEMP1 @T6G_MB_LIB.T6G(SCH_1):PVDDIO_P0_TEMP1   I128 @T6G_MB_LIB.T6G(SCH_1):PAGE175
     1 PVDDIO_P0_PWM1 @T6G_MB_LIB.T6G(SCH_1):PVDDIO_P0_PWM1   I128 @T6G_MB_LIB.T6G(SCH_1):PAGE175
    38 PVDDIO_P0_IMON1 @T6G_MB_LIB.T6G(SCH_1):PVDDIO_P0_IMON1   I128 @T6G_MB_LIB.T6G(SCH_1):PAGE175
     8 PVDDCR_CPU1_P0_PWM5 @T6G_MB_LIB.T6G(SCH_1):PVDDCR_CPU1_P0_PWM5   I128 @T6G_MB_LIB.T6G(SCH_1):PAGE175
    31 PVDDCR_CPU1_P0_IMON5 @T6G_MB_LIB.T6G(SCH_1):PVDDCR_CPU1_P0_IMON5   I128 @T6G_MB_LIB.T6G(SCH_1):PAGE175
     9 PVDDCR_CPU1_P0_PWM4 @T6G_MB_LIB.T6G(SCH_1):PVDDCR_CPU1_P0_PWM4   I128 @T6G_MB_LIB.T6G(SCH_1):PAGE175
    30 PVDDCR_CPU1_P0_IMON4 @T6G_MB_LIB.T6G(SCH_1):PVDDCR_CPU1_P0_IMON4   I128 @T6G_MB_LIB.T6G(SCH_1):PAGE175
    10 PVDDCR_CPU1_P0_PWM3 @T6G_MB_LIB.T6G(SCH_1):PVDDCR_CPU1_P0_PWM3   I128 @T6G_MB_LIB.T6G(SCH_1):PAGE175
    29 PVDDCR_CPU1_P0_IMON3 @T6G_MB_LIB.T6G(SCH_1):PVDDCR_CPU1_P0_IMON3   I128 @T6G_MB_LIB.T6G(SCH_1):PAGE175
    11 PVDDCR_CPU1_P0_PWM2 @T6G_MB_LIB.T6G(SCH_1):PVDDCR_CPU1_P0_PWM2   I128 @T6G_MB_LIB.T6G(SCH_1):PAGE175
    28 PVDDCR_CPU1_P0_IMON2 @T6G_MB_LIB.T6G(SCH_1):PVDDCR_CPU1_P0_IMON2   I128 @T6G_MB_LIB.T6G(SCH_1):PAGE175

PU13 ISL99390FRZTR5935-ISL99390FRZ-TR5935,SMLF,IC,AL099A
    34 PVDDCR_CPU1_P0_PWM1 @T6G_MB_LIB.T6G(SCH_1):PVDDCR_CPU1_P0_PWM1    I35 @T6G_MB_LIB.T6G(SCH_1):PAGE176
    39 PVDDCR_CPU1_P0_VCCS @T6G_MB_LIB.T6G(SCH_1):PVDDCR_CPU1_P0_VCCS    I35 @T6G_MB_LIB.T6G(SCH_1):PAGE176
     3 PVDDCR_CPU1_P0_VCC1 @T6G_MB_LIB.T6G(SCH_1):PVDDCR_CPU1_P0_VCC1    I35 @T6G_MB_LIB.T6G(SCH_1):PAGE176
     2    GND @T6G_MB_LIB.T6G(SCH_1):GND    I35 @T6G_MB_LIB.T6G(SCH_1):PAGE176
    33 SW_PVDDCR_CPU1_P0_BOOT1 @T6G_MB_LIB.T6G(SCH_1):SW_PVDDCR_CPU1_P0_BOOT1    I35 @T6G_MB_LIB.T6G(SCH_1):PAGE176
 25_29 SW_P12V_AUX_PVDDCR_CPU1_P0_FLT @T6G_MB_LIB.T6G(SCH_1):SW_P12V_AUX_PVDDCR_CPU1_P0_FLT    I35 @T6G_MB_LIB.T6G(SCH_1):PAGE176
    32 SW_PVDDCR_CPU1_P0_BOOTR1 @T6G_MB_LIB.T6G(SCH_1):SW_PVDDCR_CPU1_P0_BOOTR1    I35 @T6G_MB_LIB.T6G(SCH_1):PAGE176
     4 PVDDCR_CPU1_P0_PVCC @T6G_MB_LIB.T6G(SCH_1):PVDDCR_CPU1_P0_PVCC    I35 @T6G_MB_LIB.T6G(SCH_1):PAGE176
    36 PVDDCR_CPU1_P0_TEMP0 @T6G_MB_LIB.T6G(SCH_1):PVDDCR_CPU1_P0_TEMP0    I35 @T6G_MB_LIB.T6G(SCH_1):PAGE176
    38 PVDDCR_CPU1_P0_IMON1 @T6G_MB_LIB.T6G(SCH_1):PVDDCR_CPU1_P0_IMON1    I35 @T6G_MB_LIB.T6G(SCH_1):PAGE176
    37 PVDDCR_CPU1_P0_LSET1 @T6G_MB_LIB.T6G(SCH_1):PVDDCR_CPU1_P0_LSET1    I35 @T6G_MB_LIB.T6G(SCH_1):PAGE176
 10_19 SW_PVDDCR_CPU1_P0_SW1 @T6G_MB_LIB.T6G(SCH_1):SW_PVDDCR_CPU1_P0_SW1    I35 @T6G_MB_LIB.T6G(SCH_1):PAGE176
     5    GND @T6G_MB_LIB.T6G(SCH_1):GND    I35 @T6G_MB_LIB.T6G(SCH_1):PAGE176
    30 SW_P12V_AUX_PVDDCR_CPU1_P0_FLT @T6G_MB_LIB.T6G(SCH_1):SW_P12V_AUX_PVDDCR_CPU1_P0_FLT    I35 @T6G_MB_LIB.T6G(SCH_1):PAGE176
     1 PVDDCR_CPU1_P0_VOS1 @T6G_MB_LIB.T6G(SCH_1):PVDDCR_CPU1_P0_VOS1    I35 @T6G_MB_LIB.T6G(SCH_1):PAGE176
    40    GND @T6G_MB_LIB.T6G(SCH_1):GND    I35 @T6G_MB_LIB.T6G(SCH_1):PAGE176
    35 PVDDCR_CPU1_P0_VCC1 @T6G_MB_LIB.T6G(SCH_1):PVDDCR_CPU1_P0_VCC1    I35 @T6G_MB_LIB.T6G(SCH_1):PAGE176
    31 NC_PVDDCR_CPU1_P0_DNC1 @T6G_MB_LIB.T6G(SCH_1):NC_PVDDCR_CPU1_P0_DNC1    I35 @T6G_MB_LIB.T6G(SCH_1):PAGE176
     6 NC_PVDDCR_CPU1_P0_GL1_1 @T6G_MB_LIB.T6G(SCH_1):NC_PVDDCR_CPU1_P0_GL1_1    I35 @T6G_MB_LIB.T6G(SCH_1):PAGE176
    41 NC_PVDDCR_CPU1_P0_GL2_1 @T6G_MB_LIB.T6G(SCH_1):NC_PVDDCR_CPU1_P0_GL2_1    I35 @T6G_MB_LIB.T6G(SCH_1):PAGE176
7_9-20_24    GND @T6G_MB_LIB.T6G(SCH_1):GND    I35 @T6G_MB_LIB.T6G(SCH_1):PAGE176

PU14 ISL99390FRZTR5935-ISL99390FRZ-TR5935,SMLF,IC,AL099A
    34 PVDDCR_CPU1_P0_PWM4 @T6G_MB_LIB.T6G(SCH_1):PVDDCR_CPU1_P0_PWM4    I21 @T6G_MB_LIB.T6G(SCH_1):PAGE177
    39 PVDDCR_CPU1_P0_VCCS @T6G_MB_LIB.T6G(SCH_1):PVDDCR_CPU1_P0_VCCS    I21 @T6G_MB_LIB.T6G(SCH_1):PAGE177
     3 PVDDCR_CPU1_P0_VCC4 @T6G_MB_LIB.T6G(SCH_1):PVDDCR_CPU1_P0_VCC4    I21 @T6G_MB_LIB.T6G(SCH_1):PAGE177
     2    GND @T6G_MB_LIB.T6G(SCH_1):GND    I21 @T6G_MB_LIB.T6G(SCH_1):PAGE177
    33 SW_PVDDCR_CPU1_P0_BOOT4 @T6G_MB_LIB.T6G(SCH_1):SW_PVDDCR_CPU1_P0_BOOT4    I21 @T6G_MB_LIB.T6G(SCH_1):PAGE177
 25_29 SW_P12V_AUX_PVDDCR_CPU1_P0_FLT @T6G_MB_LIB.T6G(SCH_1):SW_P12V_AUX_PVDDCR_CPU1_P0_FLT    I21 @T6G_MB_LIB.T6G(SCH_1):PAGE177
    32 SW_PVDDCR_CPU1_P0_BOOTR4 @T6G_MB_LIB.T6G(SCH_1):SW_PVDDCR_CPU1_P0_BOOTR4    I21 @T6G_MB_LIB.T6G(SCH_1):PAGE177
     4 PVDDCR_CPU1_P0_PVCC @T6G_MB_LIB.T6G(SCH_1):PVDDCR_CPU1_P0_PVCC    I21 @T6G_MB_LIB.T6G(SCH_1):PAGE177
    36 PVDDCR_CPU1_P0_TEMP0 @T6G_MB_LIB.T6G(SCH_1):PVDDCR_CPU1_P0_TEMP0    I21 @T6G_MB_LIB.T6G(SCH_1):PAGE177
    38 PVDDCR_CPU1_P0_IMON4 @T6G_MB_LIB.T6G(SCH_1):PVDDCR_CPU1_P0_IMON4    I21 @T6G_MB_LIB.T6G(SCH_1):PAGE177
    37 PVDDCR_CPU1_P0_LSET4 @T6G_MB_LIB.T6G(SCH_1):PVDDCR_CPU1_P0_LSET4    I21 @T6G_MB_LIB.T6G(SCH_1):PAGE177
 10_19 SW_PVDDCR_CPU1_P0_SW4 @T6G_MB_LIB.T6G(SCH_1):SW_PVDDCR_CPU1_P0_SW4    I21 @T6G_MB_LIB.T6G(SCH_1):PAGE177
     5    GND @T6G_MB_LIB.T6G(SCH_1):GND    I21 @T6G_MB_LIB.T6G(SCH_1):PAGE177
    30 SW_P12V_AUX_PVDDCR_CPU1_P0_FLT @T6G_MB_LIB.T6G(SCH_1):SW_P12V_AUX_PVDDCR_CPU1_P0_FLT    I21 @T6G_MB_LIB.T6G(SCH_1):PAGE177
     1 PVDDCR_CPU1_P0_VOS4 @T6G_MB_LIB.T6G(SCH_1):PVDDCR_CPU1_P0_VOS4    I21 @T6G_MB_LIB.T6G(SCH_1):PAGE177
    40    GND @T6G_MB_LIB.T6G(SCH_1):GND    I21 @T6G_MB_LIB.T6G(SCH_1):PAGE177
    35 PVDDCR_CPU1_P0_VCC4 @T6G_MB_LIB.T6G(SCH_1):PVDDCR_CPU1_P0_VCC4    I21 @T6G_MB_LIB.T6G(SCH_1):PAGE177
    31 NC_PVDDCR_CPU1_P0_DNC4 @T6G_MB_LIB.T6G(SCH_1):NC_PVDDCR_CPU1_P0_DNC4    I21 @T6G_MB_LIB.T6G(SCH_1):PAGE177
     6 NC_PVDDCR_CPU1_P0_GL1_4 @T6G_MB_LIB.T6G(SCH_1):NC_PVDDCR_CPU1_P0_GL1_4    I21 @T6G_MB_LIB.T6G(SCH_1):PAGE177
    41 NC_PVDDCR_CPU1_P0_GL2_4 @T6G_MB_LIB.T6G(SCH_1):NC_PVDDCR_CPU1_P0_GL2_4    I21 @T6G_MB_LIB.T6G(SCH_1):PAGE177
7_9-20_24    GND @T6G_MB_LIB.T6G(SCH_1):GND    I21 @T6G_MB_LIB.T6G(SCH_1):PAGE177

PU15 ISL99390FRZTR5935-ISL99390FRZ-TR5935,SMLF,IC,AL099A
    34 PVDDCR_CPU1_P0_PWM3 @T6G_MB_LIB.T6G(SCH_1):PVDDCR_CPU1_P0_PWM3    I23 @T6G_MB_LIB.T6G(SCH_1):PAGE177
    39 PVDDCR_CPU1_P0_VCCS @T6G_MB_LIB.T6G(SCH_1):PVDDCR_CPU1_P0_VCCS    I23 @T6G_MB_LIB.T6G(SCH_1):PAGE177
     3 PVDDCR_CPU1_P0_VCC3 @T6G_MB_LIB.T6G(SCH_1):PVDDCR_CPU1_P0_VCC3    I23 @T6G_MB_LIB.T6G(SCH_1):PAGE177
     2    GND @T6G_MB_LIB.T6G(SCH_1):GND    I23 @T6G_MB_LIB.T6G(SCH_1):PAGE177
    33 SW_PVDDCR_CPU1_P0_BOOT3 @T6G_MB_LIB.T6G(SCH_1):SW_PVDDCR_CPU1_P0_BOOT3    I23 @T6G_MB_LIB.T6G(SCH_1):PAGE177
 25_29 SW_P12V_AUX_PVDDCR_CPU1_P0_FLT @T6G_MB_LIB.T6G(SCH_1):SW_P12V_AUX_PVDDCR_CPU1_P0_FLT    I23 @T6G_MB_LIB.T6G(SCH_1):PAGE177
    32 SW_PVDDCR_CPU1_P0_BOOTR3 @T6G_MB_LIB.T6G(SCH_1):SW_PVDDCR_CPU1_P0_BOOTR3    I23 @T6G_MB_LIB.T6G(SCH_1):PAGE177
     4 PVDDCR_CPU1_P0_PVCC @T6G_MB_LIB.T6G(SCH_1):PVDDCR_CPU1_P0_PVCC    I23 @T6G_MB_LIB.T6G(SCH_1):PAGE177
    36 PVDDCR_CPU1_P0_TEMP0 @T6G_MB_LIB.T6G(SCH_1):PVDDCR_CPU1_P0_TEMP0    I23 @T6G_MB_LIB.T6G(SCH_1):PAGE177
    38 PVDDCR_CPU1_P0_IMON3 @T6G_MB_LIB.T6G(SCH_1):PVDDCR_CPU1_P0_IMON3    I23 @T6G_MB_LIB.T6G(SCH_1):PAGE177
    37 PVDDCR_CPU1_P0_LSET3 @T6G_MB_LIB.T6G(SCH_1):PVDDCR_CPU1_P0_LSET3    I23 @T6G_MB_LIB.T6G(SCH_1):PAGE177
 10_19 SW_PVDDCR_CPU1_P0_SW3 @T6G_MB_LIB.T6G(SCH_1):SW_PVDDCR_CPU1_P0_SW3    I23 @T6G_MB_LIB.T6G(SCH_1):PAGE177
     5    GND @T6G_MB_LIB.T6G(SCH_1):GND    I23 @T6G_MB_LIB.T6G(SCH_1):PAGE177
    30 SW_P12V_AUX_PVDDCR_CPU1_P0_FLT @T6G_MB_LIB.T6G(SCH_1):SW_P12V_AUX_PVDDCR_CPU1_P0_FLT    I23 @T6G_MB_LIB.T6G(SCH_1):PAGE177
     1 PVDDCR_CPU1_P0_VOS3 @T6G_MB_LIB.T6G(SCH_1):PVDDCR_CPU1_P0_VOS3    I23 @T6G_MB_LIB.T6G(SCH_1):PAGE177
    40    GND @T6G_MB_LIB.T6G(SCH_1):GND    I23 @T6G_MB_LIB.T6G(SCH_1):PAGE177
    35 PVDDCR_CPU1_P0_VCC3 @T6G_MB_LIB.T6G(SCH_1):PVDDCR_CPU1_P0_VCC3    I23 @T6G_MB_LIB.T6G(SCH_1):PAGE177
    31 NC_PVDDCR_CPU1_P0_DNC3 @T6G_MB_LIB.T6G(SCH_1):NC_PVDDCR_CPU1_P0_DNC3    I23 @T6G_MB_LIB.T6G(SCH_1):PAGE177
     6 NC_PVDDCR_CPU1_P0_GL1_3 @T6G_MB_LIB.T6G(SCH_1):NC_PVDDCR_CPU1_P0_GL1_3    I23 @T6G_MB_LIB.T6G(SCH_1):PAGE177
    41 NC_PVDDCR_CPU1_P0_GL2_3 @T6G_MB_LIB.T6G(SCH_1):NC_PVDDCR_CPU1_P0_GL2_3    I23 @T6G_MB_LIB.T6G(SCH_1):PAGE177
7_9-20_24    GND @T6G_MB_LIB.T6G(SCH_1):GND    I23 @T6G_MB_LIB.T6G(SCH_1):PAGE177

PU16 ISL99390FRZTR5935-ISL99390FRZ-TR5935,SMLF,IC,AL099A
    34 PVDDCR_CPU1_P0_PWM5 @T6G_MB_LIB.T6G(SCH_1):PVDDCR_CPU1_P0_PWM5    I22 @T6G_MB_LIB.T6G(SCH_1):PAGE178
    39 PVDDCR_CPU1_P0_VCCS @T6G_MB_LIB.T6G(SCH_1):PVDDCR_CPU1_P0_VCCS    I22 @T6G_MB_LIB.T6G(SCH_1):PAGE178
     3 PVDDCR_CPU1_P0_VCC5 @T6G_MB_LIB.T6G(SCH_1):PVDDCR_CPU1_P0_VCC5    I22 @T6G_MB_LIB.T6G(SCH_1):PAGE178
     2    GND @T6G_MB_LIB.T6G(SCH_1):GND    I22 @T6G_MB_LIB.T6G(SCH_1):PAGE178
    33 SW_PVDDCR_CPU1_P0_BOOT5 @T6G_MB_LIB.T6G(SCH_1):SW_PVDDCR_CPU1_P0_BOOT5    I22 @T6G_MB_LIB.T6G(SCH_1):PAGE178
 25_29 SW_P12V_AUX_PVDDCR_CPU1_P0_FLT @T6G_MB_LIB.T6G(SCH_1):SW_P12V_AUX_PVDDCR_CPU1_P0_FLT    I22 @T6G_MB_LIB.T6G(SCH_1):PAGE178
    32 SW_PVDDCR_CPU1_P0_BOOTR5 @T6G_MB_LIB.T6G(SCH_1):SW_PVDDCR_CPU1_P0_BOOTR5    I22 @T6G_MB_LIB.T6G(SCH_1):PAGE178
     4 PVDDCR_CPU1_P0_PVCC @T6G_MB_LIB.T6G(SCH_1):PVDDCR_CPU1_P0_PVCC    I22 @T6G_MB_LIB.T6G(SCH_1):PAGE178
    36 PVDDCR_CPU1_P0_TEMP0 @T6G_MB_LIB.T6G(SCH_1):PVDDCR_CPU1_P0_TEMP0    I22 @T6G_MB_LIB.T6G(SCH_1):PAGE178
    38 PVDDCR_CPU1_P0_IMON5 @T6G_MB_LIB.T6G(SCH_1):PVDDCR_CPU1_P0_IMON5    I22 @T6G_MB_LIB.T6G(SCH_1):PAGE178
    37 PVDDCR_CPU1_P0_LSET5 @T6G_MB_LIB.T6G(SCH_1):PVDDCR_CPU1_P0_LSET5    I22 @T6G_MB_LIB.T6G(SCH_1):PAGE178
 10_19 SW_PVDDCR_CPU1_P0_SW5 @T6G_MB_LIB.T6G(SCH_1):SW_PVDDCR_CPU1_P0_SW5    I22 @T6G_MB_LIB.T6G(SCH_1):PAGE178
     5    GND @T6G_MB_LIB.T6G(SCH_1):GND    I22 @T6G_MB_LIB.T6G(SCH_1):PAGE178
    30 SW_P12V_AUX_PVDDCR_CPU1_P0_FLT @T6G_MB_LIB.T6G(SCH_1):SW_P12V_AUX_PVDDCR_CPU1_P0_FLT    I22 @T6G_MB_LIB.T6G(SCH_1):PAGE178
     1 PVDDCR_CPU1_P0_VOS5 @T6G_MB_LIB.T6G(SCH_1):PVDDCR_CPU1_P0_VOS5    I22 @T6G_MB_LIB.T6G(SCH_1):PAGE178
    40    GND @T6G_MB_LIB.T6G(SCH_1):GND    I22 @T6G_MB_LIB.T6G(SCH_1):PAGE178
    35 PVDDCR_CPU1_P0_VCC5 @T6G_MB_LIB.T6G(SCH_1):PVDDCR_CPU1_P0_VCC5    I22 @T6G_MB_LIB.T6G(SCH_1):PAGE178
    31 NC_PVDDCR_CPU1_P0_DNC5 @T6G_MB_LIB.T6G(SCH_1):NC_PVDDCR_CPU1_P0_DNC5    I22 @T6G_MB_LIB.T6G(SCH_1):PAGE178
     6 NC_PVDDCR_CPU1_P0_GL1_5 @T6G_MB_LIB.T6G(SCH_1):NC_PVDDCR_CPU1_P0_GL1_5    I22 @T6G_MB_LIB.T6G(SCH_1):PAGE178
    41 NC_PVDDCR_CPU1_P0_GL2_5 @T6G_MB_LIB.T6G(SCH_1):NC_PVDDCR_CPU1_P0_GL2_5    I22 @T6G_MB_LIB.T6G(SCH_1):PAGE178
7_9-20_24    GND @T6G_MB_LIB.T6G(SCH_1):GND    I22 @T6G_MB_LIB.T6G(SCH_1):PAGE178

PU17 ISL99390FRZTR5935-ISL99390FRZ-TR5935,SMLF,IC,AL099A
    34 PVDDIO_P0_PWM1 @T6G_MB_LIB.T6G(SCH_1):PVDDIO_P0_PWM1    I84 @T6G_MB_LIB.T6G(SCH_1):PAGE180
    39 PVDDCR_CPU1_P0_VCCS @T6G_MB_LIB.T6G(SCH_1):PVDDCR_CPU1_P0_VCCS    I84 @T6G_MB_LIB.T6G(SCH_1):PAGE180
     3 PVDDIO_P0_VCC1 @T6G_MB_LIB.T6G(SCH_1):PVDDIO_P0_VCC1    I84 @T6G_MB_LIB.T6G(SCH_1):PAGE180
     2    GND @T6G_MB_LIB.T6G(SCH_1):GND    I84 @T6G_MB_LIB.T6G(SCH_1):PAGE180
    33 SW_PVDDIO_P0_BOOT1 @T6G_MB_LIB.T6G(SCH_1):SW_PVDDIO_P0_BOOT1    I84 @T6G_MB_LIB.T6G(SCH_1):PAGE180
 25_29 SW_P12V_AUX_PVDDIO_P0_FLT @T6G_MB_LIB.T6G(SCH_1):SW_P12V_AUX_PVDDIO_P0_FLT    I84 @T6G_MB_LIB.T6G(SCH_1):PAGE180
    32 SW_PVDDIO_P0_BOOTR1 @T6G_MB_LIB.T6G(SCH_1):SW_PVDDIO_P0_BOOTR1    I84 @T6G_MB_LIB.T6G(SCH_1):PAGE180
     4 PVDDCR_CPU1_P0_PVCC @T6G_MB_LIB.T6G(SCH_1):PVDDCR_CPU1_P0_PVCC    I84 @T6G_MB_LIB.T6G(SCH_1):PAGE180
    36 PVDDIO_P0_TEMP1 @T6G_MB_LIB.T6G(SCH_1):PVDDIO_P0_TEMP1    I84 @T6G_MB_LIB.T6G(SCH_1):PAGE180
    38 PVDDIO_P0_IMON1 @T6G_MB_LIB.T6G(SCH_1):PVDDIO_P0_IMON1    I84 @T6G_MB_LIB.T6G(SCH_1):PAGE180
    37 PVDDIO_P0_LSET1 @T6G_MB_LIB.T6G(SCH_1):PVDDIO_P0_LSET1    I84 @T6G_MB_LIB.T6G(SCH_1):PAGE180
 10_19 SW_PVDDIO_P0_SW1 @T6G_MB_LIB.T6G(SCH_1):SW_PVDDIO_P0_SW1    I84 @T6G_MB_LIB.T6G(SCH_1):PAGE180
     5    GND @T6G_MB_LIB.T6G(SCH_1):GND    I84 @T6G_MB_LIB.T6G(SCH_1):PAGE180
    30 SW_P12V_AUX_PVDDIO_P0_FLT @T6G_MB_LIB.T6G(SCH_1):SW_P12V_AUX_PVDDIO_P0_FLT    I84 @T6G_MB_LIB.T6G(SCH_1):PAGE180
     1 PVDDIO_P0_VOS1 @T6G_MB_LIB.T6G(SCH_1):PVDDIO_P0_VOS1    I84 @T6G_MB_LIB.T6G(SCH_1):PAGE180
    40    GND @T6G_MB_LIB.T6G(SCH_1):GND    I84 @T6G_MB_LIB.T6G(SCH_1):PAGE180
    35 PVDDIO_P0_VCC1 @T6G_MB_LIB.T6G(SCH_1):PVDDIO_P0_VCC1    I84 @T6G_MB_LIB.T6G(SCH_1):PAGE180
    31 NC_PVDDIO_P0_DNC1 @T6G_MB_LIB.T6G(SCH_1):NC_PVDDIO_P0_DNC1    I84 @T6G_MB_LIB.T6G(SCH_1):PAGE180
     6 NC_PVDDIO_P0_GL1_1 @T6G_MB_LIB.T6G(SCH_1):NC_PVDDIO_P0_GL1_1    I84 @T6G_MB_LIB.T6G(SCH_1):PAGE180
    41 NC_PVDDIO_P0_GL2_1 @T6G_MB_LIB.T6G(SCH_1):NC_PVDDIO_P0_GL2_1    I84 @T6G_MB_LIB.T6G(SCH_1):PAGE180
7_9-20_24    GND @T6G_MB_LIB.T6G(SCH_1):GND    I84 @T6G_MB_LIB.T6G(SCH_1):PAGE180

PU18 ISL99390FRZTR5935-ISL99390FRZ-TR5935,SMLF,IC,AL099A
    34 PVDDIO_P0_PWM2 @T6G_MB_LIB.T6G(SCH_1):PVDDIO_P0_PWM2    I15 @T6G_MB_LIB.T6G(SCH_1):PAGE180
    39 PVDDCR_CPU1_P0_VCCS @T6G_MB_LIB.T6G(SCH_1):PVDDCR_CPU1_P0_VCCS    I15 @T6G_MB_LIB.T6G(SCH_1):PAGE180
     3 PVDDIO_P0_VCC2 @T6G_MB_LIB.T6G(SCH_1):PVDDIO_P0_VCC2    I15 @T6G_MB_LIB.T6G(SCH_1):PAGE180
     2    GND @T6G_MB_LIB.T6G(SCH_1):GND    I15 @T6G_MB_LIB.T6G(SCH_1):PAGE180
    33 SW_PVDDIO_P0_BOOT2 @T6G_MB_LIB.T6G(SCH_1):SW_PVDDIO_P0_BOOT2    I15 @T6G_MB_LIB.T6G(SCH_1):PAGE180
 25_29 SW_P12V_AUX_PVDDIO_P0_FLT @T6G_MB_LIB.T6G(SCH_1):SW_P12V_AUX_PVDDIO_P0_FLT    I15 @T6G_MB_LIB.T6G(SCH_1):PAGE180
    32 SW_PVDDIO_P0_BOOTR2 @T6G_MB_LIB.T6G(SCH_1):SW_PVDDIO_P0_BOOTR2    I15 @T6G_MB_LIB.T6G(SCH_1):PAGE180
     4 PVDDCR_CPU1_P0_PVCC @T6G_MB_LIB.T6G(SCH_1):PVDDCR_CPU1_P0_PVCC    I15 @T6G_MB_LIB.T6G(SCH_1):PAGE180
    36 PVDDIO_P0_TEMP1 @T6G_MB_LIB.T6G(SCH_1):PVDDIO_P0_TEMP1    I15 @T6G_MB_LIB.T6G(SCH_1):PAGE180
    38 PVDDIO_P0_IMON2 @T6G_MB_LIB.T6G(SCH_1):PVDDIO_P0_IMON2    I15 @T6G_MB_LIB.T6G(SCH_1):PAGE180
    37 PVDDIO_P0_LSET2 @T6G_MB_LIB.T6G(SCH_1):PVDDIO_P0_LSET2    I15 @T6G_MB_LIB.T6G(SCH_1):PAGE180
 10_19 SW_PVDDIO_P0_SW2 @T6G_MB_LIB.T6G(SCH_1):SW_PVDDIO_P0_SW2    I15 @T6G_MB_LIB.T6G(SCH_1):PAGE180
     5    GND @T6G_MB_LIB.T6G(SCH_1):GND    I15 @T6G_MB_LIB.T6G(SCH_1):PAGE180
    30 SW_P12V_AUX_PVDDIO_P0_FLT @T6G_MB_LIB.T6G(SCH_1):SW_P12V_AUX_PVDDIO_P0_FLT    I15 @T6G_MB_LIB.T6G(SCH_1):PAGE180
     1 PVDDIO_P0_VOS2 @T6G_MB_LIB.T6G(SCH_1):PVDDIO_P0_VOS2    I15 @T6G_MB_LIB.T6G(SCH_1):PAGE180
    40    GND @T6G_MB_LIB.T6G(SCH_1):GND    I15 @T6G_MB_LIB.T6G(SCH_1):PAGE180
    35 PVDDIO_P0_VCC2 @T6G_MB_LIB.T6G(SCH_1):PVDDIO_P0_VCC2    I15 @T6G_MB_LIB.T6G(SCH_1):PAGE180
    31 NC_PVDDIO_P0_DNC2 @T6G_MB_LIB.T6G(SCH_1):NC_PVDDIO_P0_DNC2    I15 @T6G_MB_LIB.T6G(SCH_1):PAGE180
     6 NC_PVDDIO_P0_GL1_2 @T6G_MB_LIB.T6G(SCH_1):NC_PVDDIO_P0_GL1_2    I15 @T6G_MB_LIB.T6G(SCH_1):PAGE180
    41 NC_PVDDIO_P0_GL2_2 @T6G_MB_LIB.T6G(SCH_1):NC_PVDDIO_P0_GL2_2    I15 @T6G_MB_LIB.T6G(SCH_1):PAGE180
7_9-20_24    GND @T6G_MB_LIB.T6G(SCH_1):GND    I15 @T6G_MB_LIB.T6G(SCH_1):PAGE180

PU19 ISL99390FRZTR5935-ISL99390FRZ-TR5935,SMLF,IC,AL099A
    34 PVDDIO_P0_PWM3 @T6G_MB_LIB.T6G(SCH_1):PVDDIO_P0_PWM3    I32 @T6G_MB_LIB.T6G(SCH_1):PAGE181
    39 PVDDCR_CPU1_P0_VCCS @T6G_MB_LIB.T6G(SCH_1):PVDDCR_CPU1_P0_VCCS    I32 @T6G_MB_LIB.T6G(SCH_1):PAGE181
     3 PVDDIO_P0_VCC3 @T6G_MB_LIB.T6G(SCH_1):PVDDIO_P0_VCC3    I32 @T6G_MB_LIB.T6G(SCH_1):PAGE181
     2    GND @T6G_MB_LIB.T6G(SCH_1):GND    I32 @T6G_MB_LIB.T6G(SCH_1):PAGE181
    33 SW_PVDDIO_P0_BOOT3 @T6G_MB_LIB.T6G(SCH_1):SW_PVDDIO_P0_BOOT3    I32 @T6G_MB_LIB.T6G(SCH_1):PAGE181
 25_29 SW_P12V_AUX_PVDDIO_P0_FLT @T6G_MB_LIB.T6G(SCH_1):SW_P12V_AUX_PVDDIO_P0_FLT    I32 @T6G_MB_LIB.T6G(SCH_1):PAGE181
    32 SW_PVDDIO_P0_BOOTR3 @T6G_MB_LIB.T6G(SCH_1):SW_PVDDIO_P0_BOOTR3    I32 @T6G_MB_LIB.T6G(SCH_1):PAGE181
     4 PVDDCR_CPU1_P0_PVCC @T6G_MB_LIB.T6G(SCH_1):PVDDCR_CPU1_P0_PVCC    I32 @T6G_MB_LIB.T6G(SCH_1):PAGE181
    36 PVDDIO_P0_TEMP1 @T6G_MB_LIB.T6G(SCH_1):PVDDIO_P0_TEMP1    I32 @T6G_MB_LIB.T6G(SCH_1):PAGE181
    38 PVDDIO_P0_IMON3 @T6G_MB_LIB.T6G(SCH_1):PVDDIO_P0_IMON3    I32 @T6G_MB_LIB.T6G(SCH_1):PAGE181
    37 PVDDIO_P0_LSET3 @T6G_MB_LIB.T6G(SCH_1):PVDDIO_P0_LSET3    I32 @T6G_MB_LIB.T6G(SCH_1):PAGE181
 10_19 SW_PVDDIO_P0_SW3 @T6G_MB_LIB.T6G(SCH_1):SW_PVDDIO_P0_SW3    I32 @T6G_MB_LIB.T6G(SCH_1):PAGE181
     5    GND @T6G_MB_LIB.T6G(SCH_1):GND    I32 @T6G_MB_LIB.T6G(SCH_1):PAGE181
    30 SW_P12V_AUX_PVDDIO_P0_FLT @T6G_MB_LIB.T6G(SCH_1):SW_P12V_AUX_PVDDIO_P0_FLT    I32 @T6G_MB_LIB.T6G(SCH_1):PAGE181
     1 PVDDIO_P0_VOS3 @T6G_MB_LIB.T6G(SCH_1):PVDDIO_P0_VOS3    I32 @T6G_MB_LIB.T6G(SCH_1):PAGE181
    40    GND @T6G_MB_LIB.T6G(SCH_1):GND    I32 @T6G_MB_LIB.T6G(SCH_1):PAGE181
    35 PVDDIO_P0_VCC3 @T6G_MB_LIB.T6G(SCH_1):PVDDIO_P0_VCC3    I32 @T6G_MB_LIB.T6G(SCH_1):PAGE181
    31 NC_PVDDIO_P0_DNC3 @T6G_MB_LIB.T6G(SCH_1):NC_PVDDIO_P0_DNC3    I32 @T6G_MB_LIB.T6G(SCH_1):PAGE181
     6 NC_PVDDIO_P0_GL1_3 @T6G_MB_LIB.T6G(SCH_1):NC_PVDDIO_P0_GL1_3    I32 @T6G_MB_LIB.T6G(SCH_1):PAGE181
    41 NC_PVDDIO_P0_GL2_3 @T6G_MB_LIB.T6G(SCH_1):NC_PVDDIO_P0_GL2_3    I32 @T6G_MB_LIB.T6G(SCH_1):PAGE181
7_9-20_24    GND @T6G_MB_LIB.T6G(SCH_1):GND    I32 @T6G_MB_LIB.T6G(SCH_1):PAGE181

PU20 ISL99390FRZTR5935-ISL99390FRZ-TR5935,SMLF,IC,AL099A
    34 PVDDIO_P0_PWM4 @T6G_MB_LIB.T6G(SCH_1):PVDDIO_P0_PWM4    I73 @T6G_MB_LIB.T6G(SCH_1):PAGE181
    39 PVDDCR_CPU1_P0_VCCS @T6G_MB_LIB.T6G(SCH_1):PVDDCR_CPU1_P0_VCCS    I73 @T6G_MB_LIB.T6G(SCH_1):PAGE181
     3 PVDDIO_P0_VCC4 @T6G_MB_LIB.T6G(SCH_1):PVDDIO_P0_VCC4    I73 @T6G_MB_LIB.T6G(SCH_1):PAGE181
     2    GND @T6G_MB_LIB.T6G(SCH_1):GND    I73 @T6G_MB_LIB.T6G(SCH_1):PAGE181
    33 SW_PVDDIO_P0_BOOT4 @T6G_MB_LIB.T6G(SCH_1):SW_PVDDIO_P0_BOOT4    I73 @T6G_MB_LIB.T6G(SCH_1):PAGE181
 25_29 SW_P12V_AUX_PVDDIO_P0_FLT @T6G_MB_LIB.T6G(SCH_1):SW_P12V_AUX_PVDDIO_P0_FLT    I73 @T6G_MB_LIB.T6G(SCH_1):PAGE181
    32 SW_PVDDIO_P0_BOOTR4 @T6G_MB_LIB.T6G(SCH_1):SW_PVDDIO_P0_BOOTR4    I73 @T6G_MB_LIB.T6G(SCH_1):PAGE181
     4 PVDDCR_CPU1_P0_PVCC @T6G_MB_LIB.T6G(SCH_1):PVDDCR_CPU1_P0_PVCC    I73 @T6G_MB_LIB.T6G(SCH_1):PAGE181
    36 PVDDIO_P0_TEMP1 @T6G_MB_LIB.T6G(SCH_1):PVDDIO_P0_TEMP1    I73 @T6G_MB_LIB.T6G(SCH_1):PAGE181
    38 PVDDIO_P0_IMON4 @T6G_MB_LIB.T6G(SCH_1):PVDDIO_P0_IMON4    I73 @T6G_MB_LIB.T6G(SCH_1):PAGE181
    37 PVDDIO_P0_LSET4 @T6G_MB_LIB.T6G(SCH_1):PVDDIO_P0_LSET4    I73 @T6G_MB_LIB.T6G(SCH_1):PAGE181
 10_19 SW_PVDDIO_P0_SW4 @T6G_MB_LIB.T6G(SCH_1):SW_PVDDIO_P0_SW4    I73 @T6G_MB_LIB.T6G(SCH_1):PAGE181
     5    GND @T6G_MB_LIB.T6G(SCH_1):GND    I73 @T6G_MB_LIB.T6G(SCH_1):PAGE181
    30 SW_P12V_AUX_PVDDIO_P0_FLT @T6G_MB_LIB.T6G(SCH_1):SW_P12V_AUX_PVDDIO_P0_FLT    I73 @T6G_MB_LIB.T6G(SCH_1):PAGE181
     1 PVDDIO_P0_VOS4 @T6G_MB_LIB.T6G(SCH_1):PVDDIO_P0_VOS4    I73 @T6G_MB_LIB.T6G(SCH_1):PAGE181
    40    GND @T6G_MB_LIB.T6G(SCH_1):GND    I73 @T6G_MB_LIB.T6G(SCH_1):PAGE181
    35 PVDDIO_P0_VCC4 @T6G_MB_LIB.T6G(SCH_1):PVDDIO_P0_VCC4    I73 @T6G_MB_LIB.T6G(SCH_1):PAGE181
    31 NC_PVDDIO_P0_DNC4 @T6G_MB_LIB.T6G(SCH_1):NC_PVDDIO_P0_DNC4    I73 @T6G_MB_LIB.T6G(SCH_1):PAGE181
     6 NC_PVDDIO_P0_GL1_4 @T6G_MB_LIB.T6G(SCH_1):NC_PVDDIO_P0_GL1_4    I73 @T6G_MB_LIB.T6G(SCH_1):PAGE181
    41 NC_PVDDIO_P0_GL2_4 @T6G_MB_LIB.T6G(SCH_1):NC_PVDDIO_P0_GL2_4    I73 @T6G_MB_LIB.T6G(SCH_1):PAGE181
7_9-20_24    GND @T6G_MB_LIB.T6G(SCH_1):GND    I73 @T6G_MB_LIB.T6G(SCH_1):PAGE181

PU21 RAA229621GNPHA0-RAA229621GNP#HA0,SMLF,IC,ARF0TGP40A
    23 PVDD11_S3_P0_IMON1 @T6G_MB_LIB.T6G(SCH_1):PVDD11_S3_P0_IMON1    I24 @T6G_MB_LIB.T6G(SCH_1):PAGE182
    39 PVDD11_S3_P0_VCC @T6G_MB_LIB.T6G(SCH_1):PVDD11_S3_P0_VCC    I24 @T6G_MB_LIB.T6G(SCH_1):PAGE182
    20    GND @T6G_MB_LIB.T6G(SCH_1):GND    I24 @T6G_MB_LIB.T6G(SCH_1):PAGE182
    10 PVDD11_S3_P0_PMSCL_R @T6G_MB_LIB.T6G(SCH_1):PVDD11_S3_P0_PMSCL_R    I24 @T6G_MB_LIB.T6G(SCH_1):PAGE182
    18    GND @T6G_MB_LIB.T6G(SCH_1):GND    I24 @T6G_MB_LIB.T6G(SCH_1):PAGE182
    24 PVDD11_S3_P0_IMON2 @T6G_MB_LIB.T6G(SCH_1):PVDD11_S3_P0_IMON2    I24 @T6G_MB_LIB.T6G(SCH_1):PAGE182
    19 NC_PVDD11_S3_P0_SVTO @T6G_MB_LIB.T6G(SCH_1):NC_PVDD11_S3_P0_SVTO    I24 @T6G_MB_LIB.T6G(SCH_1):PAGE182
    14 PVDD11_S3_P0_RESET_N_R @T6G_MB_LIB.T6G(SCH_1):PVDD11_S3_P0_RESET_N_R    I24 @T6G_MB_LIB.T6G(SCH_1):PAGE182
    25 NC_PVDD11_S3_P0_IMON3 @T6G_MB_LIB.T6G(SCH_1):NC_PVDD11_S3_P0_IMON3    I24 @T6G_MB_LIB.T6G(SCH_1):PAGE182
    26 NC_PVDD11_S3_P0_IMON4 @T6G_MB_LIB.T6G(SCH_1):NC_PVDD11_S3_P0_IMON4    I24 @T6G_MB_LIB.T6G(SCH_1):PAGE182
    16 NC_PVDD11_S3_P0_PG1 @T6G_MB_LIB.T6G(SCH_1):NC_PVDD11_S3_P0_PG1    I24 @T6G_MB_LIB.T6G(SCH_1):PAGE182
    17    GND @T6G_MB_LIB.T6G(SCH_1):GND    I24 @T6G_MB_LIB.T6G(SCH_1):PAGE182
    11 PVDD11_S3_P0_PMALERT_R @T6G_MB_LIB.T6G(SCH_1):PVDD11_S3_P0_PMALERT_R    I24 @T6G_MB_LIB.T6G(SCH_1):PAGE182
    13 PVDD11_S3_P0_EN_R @T6G_MB_LIB.T6G(SCH_1):PVDD11_S3_P0_EN_R    I24 @T6G_MB_LIB.T6G(SCH_1):PAGE182
    22 VSENSE_VSS_SENSE_C_P0 @T6G_MB_LIB.T6G(SCH_1):VSENSE_VSS_SENSE_C_P0    I24 @T6G_MB_LIB.T6G(SCH_1):PAGE182
     9 PVDD11_S3_P0_PMSDA_R @T6G_MB_LIB.T6G(SCH_1):PVDD11_S3_P0_PMSDA_R    I24 @T6G_MB_LIB.T6G(SCH_1):PAGE182
     5 NC_PVDD11_S3_P0_PWM4 @T6G_MB_LIB.T6G(SCH_1):NC_PVDD11_S3_P0_PWM4    I24 @T6G_MB_LIB.T6G(SCH_1):PAGE182
     6 NC_PVDD11_S3_P0_PWM3 @T6G_MB_LIB.T6G(SCH_1):NC_PVDD11_S3_P0_PWM3    I24 @T6G_MB_LIB.T6G(SCH_1):PAGE182
    21 VSENSE_PVDD11_S3_P0_R @T6G_MB_LIB.T6G(SCH_1):VSENSE_PVDD11_S3_P0_R    I24 @T6G_MB_LIB.T6G(SCH_1):PAGE182
     2 NC_PVDD11_S3_P0_PWM7 @T6G_MB_LIB.T6G(SCH_1):NC_PVDD11_S3_P0_PWM7    I24 @T6G_MB_LIB.T6G(SCH_1):PAGE182
    12 PWRGD_PVDD11_S3_P0_R @T6G_MB_LIB.T6G(SCH_1):PWRGD_PVDD11_S3_P0_R    I24 @T6G_MB_LIB.T6G(SCH_1):PAGE182
     7 PVDD11_S3_P0_PWM2 @T6G_MB_LIB.T6G(SCH_1):PVDD11_S3_P0_PWM2    I24 @T6G_MB_LIB.T6G(SCH_1):PAGE182
    40 PVDD11_S3_P0_VCCS @T6G_MB_LIB.T6G(SCH_1):PVDD11_S3_P0_VCCS    I24 @T6G_MB_LIB.T6G(SCH_1):PAGE182
    37 PVDD11_S3_P0_VMON @T6G_MB_LIB.T6G(SCH_1):PVDD11_S3_P0_VMON    I24 @T6G_MB_LIB.T6G(SCH_1):PAGE182
    38 PVDD11_S3_P0_VINSEN @T6G_MB_LIB.T6G(SCH_1):PVDD11_S3_P0_VINSEN    I24 @T6G_MB_LIB.T6G(SCH_1):PAGE182
    36 PVDD11_S3_P0_TEMP0 @T6G_MB_LIB.T6G(SCH_1):PVDD11_S3_P0_TEMP0    I24 @T6G_MB_LIB.T6G(SCH_1):PAGE182
    15 PVDD11_S3_P0_VDDIO @T6G_MB_LIB.T6G(SCH_1):PVDD11_S3_P0_VDDIO    I24 @T6G_MB_LIB.T6G(SCH_1):PAGE182
    32    GND @T6G_MB_LIB.T6G(SCH_1):GND    I24 @T6G_MB_LIB.T6G(SCH_1):PAGE182
    31    GND @T6G_MB_LIB.T6G(SCH_1):GND    I24 @T6G_MB_LIB.T6G(SCH_1):PAGE182
    29 NC_PVDD11_S3_P0_IMON7 @T6G_MB_LIB.T6G(SCH_1):NC_PVDD11_S3_P0_IMON7    I24 @T6G_MB_LIB.T6G(SCH_1):PAGE182
     8 PVDD11_S3_P0_PWM1 @T6G_MB_LIB.T6G(SCH_1):PVDD11_S3_P0_PWM1    I24 @T6G_MB_LIB.T6G(SCH_1):PAGE182
     4 NC_PVDD11_S3_P0_PWM5 @T6G_MB_LIB.T6G(SCH_1):NC_PVDD11_S3_P0_PWM5    I24 @T6G_MB_LIB.T6G(SCH_1):PAGE182
    27 NC_PVDD11_S3_P0_IMON5 @T6G_MB_LIB.T6G(SCH_1):NC_PVDD11_S3_P0_IMON5    I24 @T6G_MB_LIB.T6G(SCH_1):PAGE182
     3 NC_PVDD11_S3_P0_PWM6 @T6G_MB_LIB.T6G(SCH_1):NC_PVDD11_S3_P0_PWM6    I24 @T6G_MB_LIB.T6G(SCH_1):PAGE182
    28 NC_PVDD11_S3_P0_IMON6 @T6G_MB_LIB.T6G(SCH_1):NC_PVDD11_S3_P0_IMON6    I24 @T6G_MB_LIB.T6G(SCH_1):PAGE182
    33 PVDD11_S3_P0_OCP_N_R @T6G_MB_LIB.T6G(SCH_1):PVDD11_S3_P0_OCP_N_R    I24 @T6G_MB_LIB.T6G(SCH_1):PAGE182
    TH    GND @T6G_MB_LIB.T6G(SCH_1):GND    I24 @T6G_MB_LIB.T6G(SCH_1):PAGE182
    34 PVDD11_S3_P0_ADDR_CFG @T6G_MB_LIB.T6G(SCH_1):PVDD11_S3_P0_ADDR_CFG    I24 @T6G_MB_LIB.T6G(SCH_1):PAGE182
    35 PVDD11_S3_P0_TEMP1 @T6G_MB_LIB.T6G(SCH_1):PVDD11_S3_P0_TEMP1    I24 @T6G_MB_LIB.T6G(SCH_1):PAGE182
     1 NC_PVDD11_S3_P0_PWM8 @T6G_MB_LIB.T6G(SCH_1):NC_PVDD11_S3_P0_PWM8    I24 @T6G_MB_LIB.T6G(SCH_1):PAGE182
    30 NC_PVDD11_S3_P0_IMON8 @T6G_MB_LIB.T6G(SCH_1):NC_PVDD11_S3_P0_IMON8    I24 @T6G_MB_LIB.T6G(SCH_1):PAGE182

PU22 ISL99390FRZTR5935-ISL99390FRZ-TR5935,SMLF,IC,AL099A
    34 PVDD11_S3_P0_PWM1 @T6G_MB_LIB.T6G(SCH_1):PVDD11_S3_P0_PWM1    I92 @T6G_MB_LIB.T6G(SCH_1):PAGE183
    39 PVDD11_S3_P0_VCCS @T6G_MB_LIB.T6G(SCH_1):PVDD11_S3_P0_VCCS    I92 @T6G_MB_LIB.T6G(SCH_1):PAGE183
     3 PVDD11_S3_P0_VCC1 @T6G_MB_LIB.T6G(SCH_1):PVDD11_S3_P0_VCC1    I92 @T6G_MB_LIB.T6G(SCH_1):PAGE183
     2    GND @T6G_MB_LIB.T6G(SCH_1):GND    I92 @T6G_MB_LIB.T6G(SCH_1):PAGE183
    33 SW_PVDD11_S3_P0_BOOT1 @T6G_MB_LIB.T6G(SCH_1):SW_PVDD11_S3_P0_BOOT1    I92 @T6G_MB_LIB.T6G(SCH_1):PAGE183
 25_29 SW_P12V_AUX_PVDD11_S3_P0_FLT @T6G_MB_LIB.T6G(SCH_1):SW_P12V_AUX_PVDD11_S3_P0_FLT    I92 @T6G_MB_LIB.T6G(SCH_1):PAGE183
    32 SW_PVDD11_S3_P0_PH1 @T6G_MB_LIB.T6G(SCH_1):SW_PVDD11_S3_P0_PH1    I92 @T6G_MB_LIB.T6G(SCH_1):PAGE183
     4 PVDD11_S3_P0_PVCC @T6G_MB_LIB.T6G(SCH_1):PVDD11_S3_P0_PVCC    I92 @T6G_MB_LIB.T6G(SCH_1):PAGE183
    36 PVDD11_S3_P0_TEMP0 @T6G_MB_LIB.T6G(SCH_1):PVDD11_S3_P0_TEMP0    I92 @T6G_MB_LIB.T6G(SCH_1):PAGE183
    38 PVDD11_S3_P0_IMON1 @T6G_MB_LIB.T6G(SCH_1):PVDD11_S3_P0_IMON1    I92 @T6G_MB_LIB.T6G(SCH_1):PAGE183
    37 PVDD11_S3_P0_LSET1 @T6G_MB_LIB.T6G(SCH_1):PVDD11_S3_P0_LSET1    I92 @T6G_MB_LIB.T6G(SCH_1):PAGE183
 10_19 SW_PVDD11_S3_P0_SW1 @T6G_MB_LIB.T6G(SCH_1):SW_PVDD11_S3_P0_SW1    I92 @T6G_MB_LIB.T6G(SCH_1):PAGE183
     5    GND @T6G_MB_LIB.T6G(SCH_1):GND    I92 @T6G_MB_LIB.T6G(SCH_1):PAGE183
    30 SW_P12V_AUX_PVDD11_S3_P0_FLT @T6G_MB_LIB.T6G(SCH_1):SW_P12V_AUX_PVDD11_S3_P0_FLT    I92 @T6G_MB_LIB.T6G(SCH_1):PAGE183
     1 PVDD11_S3_P0_VOS1 @T6G_MB_LIB.T6G(SCH_1):PVDD11_S3_P0_VOS1    I92 @T6G_MB_LIB.T6G(SCH_1):PAGE183
    40    GND @T6G_MB_LIB.T6G(SCH_1):GND    I92 @T6G_MB_LIB.T6G(SCH_1):PAGE183
    35 PVDD11_S3_P0_VCC1 @T6G_MB_LIB.T6G(SCH_1):PVDD11_S3_P0_VCC1    I92 @T6G_MB_LIB.T6G(SCH_1):PAGE183
    31 NC_PVDD11_S3_P0_DNC1 @T6G_MB_LIB.T6G(SCH_1):NC_PVDD11_S3_P0_DNC1    I92 @T6G_MB_LIB.T6G(SCH_1):PAGE183
     6 NC_PVDD11_S3_P0_GL1_1 @T6G_MB_LIB.T6G(SCH_1):NC_PVDD11_S3_P0_GL1_1    I92 @T6G_MB_LIB.T6G(SCH_1):PAGE183
    41 NC_PVDD11_S3_P0_GL2_1 @T6G_MB_LIB.T6G(SCH_1):NC_PVDD11_S3_P0_GL2_1    I92 @T6G_MB_LIB.T6G(SCH_1):PAGE183
7_9-20_24    GND @T6G_MB_LIB.T6G(SCH_1):GND    I92 @T6G_MB_LIB.T6G(SCH_1):PAGE183

PU23 ISL99390FRZTR5935-ISL99390FRZ-TR5935,SMLF,IC,AL099A
    34 PVDD11_S3_P0_PWM2 @T6G_MB_LIB.T6G(SCH_1):PVDD11_S3_P0_PWM2    I13 @T6G_MB_LIB.T6G(SCH_1):PAGE183
    39 PVDD11_S3_P0_VCCS @T6G_MB_LIB.T6G(SCH_1):PVDD11_S3_P0_VCCS    I13 @T6G_MB_LIB.T6G(SCH_1):PAGE183
     3 PVDD11_S3_P0_VCC2 @T6G_MB_LIB.T6G(SCH_1):PVDD11_S3_P0_VCC2    I13 @T6G_MB_LIB.T6G(SCH_1):PAGE183
     2    GND @T6G_MB_LIB.T6G(SCH_1):GND    I13 @T6G_MB_LIB.T6G(SCH_1):PAGE183
    33 SW_PVDD11_S3_P0_BOOT2 @T6G_MB_LIB.T6G(SCH_1):SW_PVDD11_S3_P0_BOOT2    I13 @T6G_MB_LIB.T6G(SCH_1):PAGE183
 25_29 SW_P12V_AUX_PVDD11_S3_P0_FLT @T6G_MB_LIB.T6G(SCH_1):SW_P12V_AUX_PVDD11_S3_P0_FLT    I13 @T6G_MB_LIB.T6G(SCH_1):PAGE183
    32 SW_PVDD11_S3_P0_PH2 @T6G_MB_LIB.T6G(SCH_1):SW_PVDD11_S3_P0_PH2    I13 @T6G_MB_LIB.T6G(SCH_1):PAGE183
     4 PVDD11_S3_P0_PVCC @T6G_MB_LIB.T6G(SCH_1):PVDD11_S3_P0_PVCC    I13 @T6G_MB_LIB.T6G(SCH_1):PAGE183
    36 PVDD11_S3_P0_TEMP0 @T6G_MB_LIB.T6G(SCH_1):PVDD11_S3_P0_TEMP0    I13 @T6G_MB_LIB.T6G(SCH_1):PAGE183
    38 PVDD11_S3_P0_IMON2 @T6G_MB_LIB.T6G(SCH_1):PVDD11_S3_P0_IMON2    I13 @T6G_MB_LIB.T6G(SCH_1):PAGE183
    37 PVDD11_S3_P0_LSET2 @T6G_MB_LIB.T6G(SCH_1):PVDD11_S3_P0_LSET2    I13 @T6G_MB_LIB.T6G(SCH_1):PAGE183
 10_19 SW_PVDD11_S3_P0_SW2 @T6G_MB_LIB.T6G(SCH_1):SW_PVDD11_S3_P0_SW2    I13 @T6G_MB_LIB.T6G(SCH_1):PAGE183
     5    GND @T6G_MB_LIB.T6G(SCH_1):GND    I13 @T6G_MB_LIB.T6G(SCH_1):PAGE183
    30 SW_P12V_AUX_PVDD11_S3_P0_FLT @T6G_MB_LIB.T6G(SCH_1):SW_P12V_AUX_PVDD11_S3_P0_FLT    I13 @T6G_MB_LIB.T6G(SCH_1):PAGE183
     1 PVDD11_S3_P0_VOS2 @T6G_MB_LIB.T6G(SCH_1):PVDD11_S3_P0_VOS2    I13 @T6G_MB_LIB.T6G(SCH_1):PAGE183
    40    GND @T6G_MB_LIB.T6G(SCH_1):GND    I13 @T6G_MB_LIB.T6G(SCH_1):PAGE183
    35 PVDD11_S3_P0_VCC2 @T6G_MB_LIB.T6G(SCH_1):PVDD11_S3_P0_VCC2    I13 @T6G_MB_LIB.T6G(SCH_1):PAGE183
    31 NC_PVDD11_S3_P0_DNC2 @T6G_MB_LIB.T6G(SCH_1):NC_PVDD11_S3_P0_DNC2    I13 @T6G_MB_LIB.T6G(SCH_1):PAGE183
     6 NC_PVDD11_S3_P0_GL1_2 @T6G_MB_LIB.T6G(SCH_1):NC_PVDD11_S3_P0_GL1_2    I13 @T6G_MB_LIB.T6G(SCH_1):PAGE183
    41 NC_PVDD11_S3_P0_GL2_2 @T6G_MB_LIB.T6G(SCH_1):NC_PVDD11_S3_P0_GL2_2    I13 @T6G_MB_LIB.T6G(SCH_1):PAGE183
7_9-20_24    GND @T6G_MB_LIB.T6G(SCH_1):GND    I13 @T6G_MB_LIB.T6G(SCH_1):PAGE183

PU24 ISL99390FRZTR5935-ISL99390FRZ-TR5935,SMLF,IC,AL099A
    34 PVDDCR_CPU0_P1_PWM6 @T6G_MB_LIB.T6G(SCH_1):PVDDCR_CPU0_P1_PWM6    I73 @T6G_MB_LIB.T6G(SCH_1):PAGE188
    39 PVDDCR_CPU0_P1_VCCS @T6G_MB_LIB.T6G(SCH_1):PVDDCR_CPU0_P1_VCCS    I73 @T6G_MB_LIB.T6G(SCH_1):PAGE188
     3 PVDDCR_CPU0_P1_VCC6 @T6G_MB_LIB.T6G(SCH_1):PVDDCR_CPU0_P1_VCC6    I73 @T6G_MB_LIB.T6G(SCH_1):PAGE188
     2    GND @T6G_MB_LIB.T6G(SCH_1):GND    I73 @T6G_MB_LIB.T6G(SCH_1):PAGE188
    33 SW_PVDDCR_CPU0_P1_BOOT6 @T6G_MB_LIB.T6G(SCH_1):SW_PVDDCR_CPU0_P1_BOOT6    I73 @T6G_MB_LIB.T6G(SCH_1):PAGE188
 25_29 SW_P12V_AUX_PVDDCR_CPU0_P1_FLT @T6G_MB_LIB.T6G(SCH_1):SW_P12V_AUX_PVDDCR_CPU0_P1_FLT    I73 @T6G_MB_LIB.T6G(SCH_1):PAGE188
    32 SW_PVDDCR_CPU0_P1_PH6 @T6G_MB_LIB.T6G(SCH_1):SW_PVDDCR_CPU0_P1_PH6    I73 @T6G_MB_LIB.T6G(SCH_1):PAGE188
     4 PVDDCR_CPU0_P1_PVCC @T6G_MB_LIB.T6G(SCH_1):PVDDCR_CPU0_P1_PVCC    I73 @T6G_MB_LIB.T6G(SCH_1):PAGE188
    36 PVDDCR_CPU0_P1_TEMP0 @T6G_MB_LIB.T6G(SCH_1):PVDDCR_CPU0_P1_TEMP0    I73 @T6G_MB_LIB.T6G(SCH_1):PAGE188
    38 PVDDCR_CPU0_P1_IMON6 @T6G_MB_LIB.T6G(SCH_1):PVDDCR_CPU0_P1_IMON6    I73 @T6G_MB_LIB.T6G(SCH_1):PAGE188
    37 PVDDCR_CPU0_P1_LSET6 @T6G_MB_LIB.T6G(SCH_1):PVDDCR_CPU0_P1_LSET6    I73 @T6G_MB_LIB.T6G(SCH_1):PAGE188
 10_19 SW_PVDDCR_CPU0_P1_SW6 @T6G_MB_LIB.T6G(SCH_1):SW_PVDDCR_CPU0_P1_SW6    I73 @T6G_MB_LIB.T6G(SCH_1):PAGE188
     5    GND @T6G_MB_LIB.T6G(SCH_1):GND    I73 @T6G_MB_LIB.T6G(SCH_1):PAGE188
    30 SW_P12V_AUX_PVDDCR_CPU0_P1_FLT @T6G_MB_LIB.T6G(SCH_1):SW_P12V_AUX_PVDDCR_CPU0_P1_FLT    I73 @T6G_MB_LIB.T6G(SCH_1):PAGE188
     1 PVDDCR_CPU0_P1_VOS6 @T6G_MB_LIB.T6G(SCH_1):PVDDCR_CPU0_P1_VOS6    I73 @T6G_MB_LIB.T6G(SCH_1):PAGE188
    40    GND @T6G_MB_LIB.T6G(SCH_1):GND    I73 @T6G_MB_LIB.T6G(SCH_1):PAGE188
    35 PVDDCR_CPU0_P1_VCC6 @T6G_MB_LIB.T6G(SCH_1):PVDDCR_CPU0_P1_VCC6    I73 @T6G_MB_LIB.T6G(SCH_1):PAGE188
    31 NC_PVDDCR_CPU0_P1_DNC6 @T6G_MB_LIB.T6G(SCH_1):NC_PVDDCR_CPU0_P1_DNC6    I73 @T6G_MB_LIB.T6G(SCH_1):PAGE188
     6 NC_PVDDCR_CPU0_P1_GL1_6 @T6G_MB_LIB.T6G(SCH_1):NC_PVDDCR_CPU0_P1_GL1_6    I73 @T6G_MB_LIB.T6G(SCH_1):PAGE188
    41 NC_PVDDCR_CPU0_P1_GL2_6 @T6G_MB_LIB.T6G(SCH_1):NC_PVDDCR_CPU0_P1_GL2_6    I73 @T6G_MB_LIB.T6G(SCH_1):PAGE188
7_9-20_24    GND @T6G_MB_LIB.T6G(SCH_1):GND    I73 @T6G_MB_LIB.T6G(SCH_1):PAGE188

PU25 RAA229620GNPHA0-RAA229620GNP#HA0,SMLF,IC,ARF0TGP40A
    27 PVDDCR_CPU0_P1_IMON1 @T6G_MB_LIB.T6G(SCH_1):PVDDCR_CPU0_P1_IMON1   I133 @T6G_MB_LIB.T6G(SCH_1):PAGE185
    47 PVDDCR_CPU0_P1_VCC @T6G_MB_LIB.T6G(SCH_1):PVDDCR_CPU0_P1_VCC   I133 @T6G_MB_LIB.T6G(SCH_1):PAGE185
    24 SVID_PVDDCR_CPU0_P1_SVTI_R @T6G_MB_LIB.T6G(SCH_1):SVID_PVDDCR_CPU0_P1_SVTI_R   I133 @T6G_MB_LIB.T6G(SCH_1):PAGE185
    14 PVDDCR_CPU0_P1_PMSCL_R @T6G_MB_LIB.T6G(SCH_1):PVDDCR_CPU0_P1_PMSCL_R   I133 @T6G_MB_LIB.T6G(SCH_1):PAGE185
    22 SVID_PVDDCR_CPU0_P1_SVC_R1 @T6G_MB_LIB.T6G(SCH_1):SVID_PVDDCR_CPU0_P1_SVC_R1   I133 @T6G_MB_LIB.T6G(SCH_1):PAGE185
    32 PVDDCR_CPU0_P1_IMON6 @T6G_MB_LIB.T6G(SCH_1):PVDDCR_CPU0_P1_IMON6   I133 @T6G_MB_LIB.T6G(SCH_1):PAGE185
    23 SVID_PVDDCR_CPU0_P1_SVTO_R @T6G_MB_LIB.T6G(SCH_1):SVID_PVDDCR_CPU0_P1_SVTO_R   I133 @T6G_MB_LIB.T6G(SCH_1):PAGE185
    18 PVDDCR_CPU0_P1_RESET_N_R @T6G_MB_LIB.T6G(SCH_1):PVDDCR_CPU0_P1_RESET_N_R   I133 @T6G_MB_LIB.T6G(SCH_1):PAGE185
    33 NC_PVDDCR_CPU0_P1_IMON7 @T6G_MB_LIB.T6G(SCH_1):NC_PVDDCR_CPU0_P1_IMON7   I133 @T6G_MB_LIB.T6G(SCH_1):PAGE185
    34 NC_PVDDCR_CPU0_P1_IMON8 @T6G_MB_LIB.T6G(SCH_1):NC_PVDDCR_CPU0_P1_IMON8   I133 @T6G_MB_LIB.T6G(SCH_1):PAGE185
    20 PWRGD_PVDDCR_SOC_P1_R @T6G_MB_LIB.T6G(SCH_1):PWRGD_PVDDCR_SOC_P1_R   I133 @T6G_MB_LIB.T6G(SCH_1):PAGE185
    21 SVID_PVDDCR_CPU0_P1_SVD_R1 @T6G_MB_LIB.T6G(SCH_1):SVID_PVDDCR_CPU0_P1_SVD_R1   I133 @T6G_MB_LIB.T6G(SCH_1):PAGE185
    15 PVDDCR_CPU0_P1_PMALERT_R @T6G_MB_LIB.T6G(SCH_1):PVDDCR_CPU0_P1_PMALERT_R   I133 @T6G_MB_LIB.T6G(SCH_1):PAGE185
    17 PVDDCR_CPU0_P1_EN_R @T6G_MB_LIB.T6G(SCH_1):PVDDCR_CPU0_P1_EN_R   I133 @T6G_MB_LIB.T6G(SCH_1):PAGE185
    26 VSENSE_VSS_SENSE_A_P1 @T6G_MB_LIB.T6G(SCH_1):VSENSE_VSS_SENSE_A_P1   I133 @T6G_MB_LIB.T6G(SCH_1):PAGE185
    13 PVDDCR_CPU0_P1_PMSDA_R @T6G_MB_LIB.T6G(SCH_1):PVDDCR_CPU0_P1_PMSDA_R   I133 @T6G_MB_LIB.T6G(SCH_1):PAGE185
     5 NC_PVDDCR_CPU0_P1_PWM8 @T6G_MB_LIB.T6G(SCH_1):NC_PVDDCR_CPU0_P1_PWM8   I133 @T6G_MB_LIB.T6G(SCH_1):PAGE185
     6 NC_PVDDCR_CPU0_P1_PWM7 @T6G_MB_LIB.T6G(SCH_1):NC_PVDDCR_CPU0_P1_PWM7   I133 @T6G_MB_LIB.T6G(SCH_1):PAGE185
    25 VSENSE_PVDDCR_CPU0_P1_VSEN0 @T6G_MB_LIB.T6G(SCH_1):VSENSE_PVDDCR_CPU0_P1_VSEN0   I133 @T6G_MB_LIB.T6G(SCH_1):PAGE185
     2 PVDDCR_SOC_P1_PWM2 @T6G_MB_LIB.T6G(SCH_1):PVDDCR_SOC_P1_PWM2   I133 @T6G_MB_LIB.T6G(SCH_1):PAGE185
    16 PWRGD_PVDDCR_CPU0_P1_R @T6G_MB_LIB.T6G(SCH_1):PWRGD_PVDDCR_CPU0_P1_R   I133 @T6G_MB_LIB.T6G(SCH_1):PAGE185
     7 PVDDCR_CPU0_P1_PWM6 @T6G_MB_LIB.T6G(SCH_1):PVDDCR_CPU0_P1_PWM6   I133 @T6G_MB_LIB.T6G(SCH_1):PAGE185
    48 PVDDCR_CPU0_P1_VCCS @T6G_MB_LIB.T6G(SCH_1):PVDDCR_CPU0_P1_VCCS   I133 @T6G_MB_LIB.T6G(SCH_1):PAGE185
    45 PVDDCR_CPU0_P1_VMON @T6G_MB_LIB.T6G(SCH_1):PVDDCR_CPU0_P1_VMON   I133 @T6G_MB_LIB.T6G(SCH_1):PAGE185
    46 PVDDCR_CPU0_P1_VINSEN @T6G_MB_LIB.T6G(SCH_1):PVDDCR_CPU0_P1_VINSEN   I133 @T6G_MB_LIB.T6G(SCH_1):PAGE185
    44 PVDDCR_CPU0_P1_TEMP0 @T6G_MB_LIB.T6G(SCH_1):PVDDCR_CPU0_P1_TEMP0   I133 @T6G_MB_LIB.T6G(SCH_1):PAGE185
    19 PVDD18_S5_P1 @T6G_MB_LIB.T6G(SCH_1):PVDD18_S5_P1   I133 @T6G_MB_LIB.T6G(SCH_1):PAGE185
    40 VSENSE_PVDDCR_SOC_P1_VSEN1 @T6G_MB_LIB.T6G(SCH_1):VSENSE_PVDDCR_SOC_P1_VSEN1   I133 @T6G_MB_LIB.T6G(SCH_1):PAGE185
    39 VSENSE_VSS_SENSE_A_P1 @T6G_MB_LIB.T6G(SCH_1):VSENSE_VSS_SENSE_A_P1   I133 @T6G_MB_LIB.T6G(SCH_1):PAGE185
    37 PVDDCR_SOC_P1_IMON2 @T6G_MB_LIB.T6G(SCH_1):PVDDCR_SOC_P1_IMON2   I133 @T6G_MB_LIB.T6G(SCH_1):PAGE185
    12 PVDDCR_CPU0_P1_PWM1 @T6G_MB_LIB.T6G(SCH_1):PVDDCR_CPU0_P1_PWM1   I133 @T6G_MB_LIB.T6G(SCH_1):PAGE185
     4 NC_PVDDCR_CPU0_P1_PWM9 @T6G_MB_LIB.T6G(SCH_1):NC_PVDDCR_CPU0_P1_PWM9   I133 @T6G_MB_LIB.T6G(SCH_1):PAGE185
    35 NC_PVDDCR_CPU0_P1_IMON9 @T6G_MB_LIB.T6G(SCH_1):NC_PVDDCR_CPU0_P1_IMON9   I133 @T6G_MB_LIB.T6G(SCH_1):PAGE185
     3 PVDDCR_SOC_P1_PWM3 @T6G_MB_LIB.T6G(SCH_1):PVDDCR_SOC_P1_PWM3   I133 @T6G_MB_LIB.T6G(SCH_1):PAGE185
    36 PVDDCR_SOC_P1_IMON3 @T6G_MB_LIB.T6G(SCH_1):PVDDCR_SOC_P1_IMON3   I133 @T6G_MB_LIB.T6G(SCH_1):PAGE185
    41 PVDDCR_CPU0_P1_OCP_N_R @T6G_MB_LIB.T6G(SCH_1):PVDDCR_CPU0_P1_OCP_N_R   I133 @T6G_MB_LIB.T6G(SCH_1):PAGE185
    TH    GND @T6G_MB_LIB.T6G(SCH_1):GND   I133 @T6G_MB_LIB.T6G(SCH_1):PAGE185
    42 PVDDCR_SOC_P1_EN//ADDR_CFG @T6G_MB_LIB.T6G(SCH_1):PVDDCR_SOC_P1_EN//ADDR_CFG   I133 @T6G_MB_LIB.T6G(SCH_1):PAGE185
    43 PVDDCR_SOC_P1_TEMP1 @T6G_MB_LIB.T6G(SCH_1):PVDDCR_SOC_P1_TEMP1   I133 @T6G_MB_LIB.T6G(SCH_1):PAGE185
     1 PVDDCR_SOC_P1_PWM1 @T6G_MB_LIB.T6G(SCH_1):PVDDCR_SOC_P1_PWM1   I133 @T6G_MB_LIB.T6G(SCH_1):PAGE185
    38 PVDDCR_SOC_P1_IMON1 @T6G_MB_LIB.T6G(SCH_1):PVDDCR_SOC_P1_IMON1   I133 @T6G_MB_LIB.T6G(SCH_1):PAGE185
     8 PVDDCR_CPU0_P1_PWM5 @T6G_MB_LIB.T6G(SCH_1):PVDDCR_CPU0_P1_PWM5   I133 @T6G_MB_LIB.T6G(SCH_1):PAGE185
    31 PVDDCR_CPU0_P1_IMON5 @T6G_MB_LIB.T6G(SCH_1):PVDDCR_CPU0_P1_IMON5   I133 @T6G_MB_LIB.T6G(SCH_1):PAGE185
     9 PVDDCR_CPU0_P1_PWM4 @T6G_MB_LIB.T6G(SCH_1):PVDDCR_CPU0_P1_PWM4   I133 @T6G_MB_LIB.T6G(SCH_1):PAGE185
    30 PVDDCR_CPU0_P1_IMON4 @T6G_MB_LIB.T6G(SCH_1):PVDDCR_CPU0_P1_IMON4   I133 @T6G_MB_LIB.T6G(SCH_1):PAGE185
    10 PVDDCR_CPU0_P1_PWM3 @T6G_MB_LIB.T6G(SCH_1):PVDDCR_CPU0_P1_PWM3   I133 @T6G_MB_LIB.T6G(SCH_1):PAGE185
    29 PVDDCR_CPU0_P1_IMON3 @T6G_MB_LIB.T6G(SCH_1):PVDDCR_CPU0_P1_IMON3   I133 @T6G_MB_LIB.T6G(SCH_1):PAGE185
    11 PVDDCR_CPU0_P1_PWM2 @T6G_MB_LIB.T6G(SCH_1):PVDDCR_CPU0_P1_PWM2   I133 @T6G_MB_LIB.T6G(SCH_1):PAGE185
    28 PVDDCR_CPU0_P1_IMON2 @T6G_MB_LIB.T6G(SCH_1):PVDDCR_CPU0_P1_IMON2   I133 @T6G_MB_LIB.T6G(SCH_1):PAGE185

PU26 ISL99390FRZTR5935-ISL99390FRZ-TR5935,SMLF,IC,AL099A
    34 PVDDCR_CPU0_P1_PWM2 @T6G_MB_LIB.T6G(SCH_1):PVDDCR_CPU0_P1_PWM2    I91 @T6G_MB_LIB.T6G(SCH_1):PAGE186
    39 PVDDCR_CPU0_P1_VCCS @T6G_MB_LIB.T6G(SCH_1):PVDDCR_CPU0_P1_VCCS    I91 @T6G_MB_LIB.T6G(SCH_1):PAGE186
     3 PVDDCR_CPU0_P1_VCC2 @T6G_MB_LIB.T6G(SCH_1):PVDDCR_CPU0_P1_VCC2    I91 @T6G_MB_LIB.T6G(SCH_1):PAGE186
     2    GND @T6G_MB_LIB.T6G(SCH_1):GND    I91 @T6G_MB_LIB.T6G(SCH_1):PAGE186
    33 SW_PVDDCR_CPU0_P1_BOOT2 @T6G_MB_LIB.T6G(SCH_1):SW_PVDDCR_CPU0_P1_BOOT2    I91 @T6G_MB_LIB.T6G(SCH_1):PAGE186
 25_29 SW_P12V_AUX_PVDDCR_CPU0_P1_FLT @T6G_MB_LIB.T6G(SCH_1):SW_P12V_AUX_PVDDCR_CPU0_P1_FLT    I91 @T6G_MB_LIB.T6G(SCH_1):PAGE186
    32 SW_PVDDCR_CPU0_P1_PH2 @T6G_MB_LIB.T6G(SCH_1):SW_PVDDCR_CPU0_P1_PH2    I91 @T6G_MB_LIB.T6G(SCH_1):PAGE186
     4 PVDDCR_CPU0_P1_PVCC @T6G_MB_LIB.T6G(SCH_1):PVDDCR_CPU0_P1_PVCC    I91 @T6G_MB_LIB.T6G(SCH_1):PAGE186
    36 PVDDCR_CPU0_P1_TEMP0 @T6G_MB_LIB.T6G(SCH_1):PVDDCR_CPU0_P1_TEMP0    I91 @T6G_MB_LIB.T6G(SCH_1):PAGE186
    38 PVDDCR_CPU0_P1_IMON2 @T6G_MB_LIB.T6G(SCH_1):PVDDCR_CPU0_P1_IMON2    I91 @T6G_MB_LIB.T6G(SCH_1):PAGE186
    37 PVDDCR_CPU0_P1_LSET2 @T6G_MB_LIB.T6G(SCH_1):PVDDCR_CPU0_P1_LSET2    I91 @T6G_MB_LIB.T6G(SCH_1):PAGE186
 10_19 SW_PVDDCR_CPU0_P1_SW2 @T6G_MB_LIB.T6G(SCH_1):SW_PVDDCR_CPU0_P1_SW2    I91 @T6G_MB_LIB.T6G(SCH_1):PAGE186
     5    GND @T6G_MB_LIB.T6G(SCH_1):GND    I91 @T6G_MB_LIB.T6G(SCH_1):PAGE186
    30 SW_P12V_AUX_PVDDCR_CPU0_P1_FLT @T6G_MB_LIB.T6G(SCH_1):SW_P12V_AUX_PVDDCR_CPU0_P1_FLT    I91 @T6G_MB_LIB.T6G(SCH_1):PAGE186
     1 PVDDCR_CPU0_P1_VOS2 @T6G_MB_LIB.T6G(SCH_1):PVDDCR_CPU0_P1_VOS2    I91 @T6G_MB_LIB.T6G(SCH_1):PAGE186
    40    GND @T6G_MB_LIB.T6G(SCH_1):GND    I91 @T6G_MB_LIB.T6G(SCH_1):PAGE186
    35 PVDDCR_CPU0_P1_VCC2 @T6G_MB_LIB.T6G(SCH_1):PVDDCR_CPU0_P1_VCC2    I91 @T6G_MB_LIB.T6G(SCH_1):PAGE186
    31 NC_PVDDCR_CPU0_P1_DNC2 @T6G_MB_LIB.T6G(SCH_1):NC_PVDDCR_CPU0_P1_DNC2    I91 @T6G_MB_LIB.T6G(SCH_1):PAGE186
     6 NC_PVDDCR_CPU0_P1_GL1_2 @T6G_MB_LIB.T6G(SCH_1):NC_PVDDCR_CPU0_P1_GL1_2    I91 @T6G_MB_LIB.T6G(SCH_1):PAGE186
    41 NC_PVDDCR_CPU0_P1_GL2_2 @T6G_MB_LIB.T6G(SCH_1):NC_PVDDCR_CPU0_P1_GL2_2    I91 @T6G_MB_LIB.T6G(SCH_1):PAGE186
7_9-20_24    GND @T6G_MB_LIB.T6G(SCH_1):GND    I91 @T6G_MB_LIB.T6G(SCH_1):PAGE186

PU27 ISL99390FRZTR5935-ISL99390FRZ-TR5935,SMLF,IC,AL099A
    34 PVDDCR_CPU0_P1_PWM3 @T6G_MB_LIB.T6G(SCH_1):PVDDCR_CPU0_P1_PWM3    I39 @T6G_MB_LIB.T6G(SCH_1):PAGE187
    39 PVDDCR_CPU0_P1_VCCS @T6G_MB_LIB.T6G(SCH_1):PVDDCR_CPU0_P1_VCCS    I39 @T6G_MB_LIB.T6G(SCH_1):PAGE187
     3 PVDDCR_CPU0_P1_VCC3 @T6G_MB_LIB.T6G(SCH_1):PVDDCR_CPU0_P1_VCC3    I39 @T6G_MB_LIB.T6G(SCH_1):PAGE187
     2    GND @T6G_MB_LIB.T6G(SCH_1):GND    I39 @T6G_MB_LIB.T6G(SCH_1):PAGE187
    33 SW_PVDDCR_CPU0_P1_BOOT3 @T6G_MB_LIB.T6G(SCH_1):SW_PVDDCR_CPU0_P1_BOOT3    I39 @T6G_MB_LIB.T6G(SCH_1):PAGE187
 25_29 SW_P12V_AUX_PVDDCR_CPU0_P1_FLT @T6G_MB_LIB.T6G(SCH_1):SW_P12V_AUX_PVDDCR_CPU0_P1_FLT    I39 @T6G_MB_LIB.T6G(SCH_1):PAGE187
    32 SW_PVDDCR_CPU0_P1_PH3 @T6G_MB_LIB.T6G(SCH_1):SW_PVDDCR_CPU0_P1_PH3    I39 @T6G_MB_LIB.T6G(SCH_1):PAGE187
     4 PVDDCR_CPU0_P1_PVCC @T6G_MB_LIB.T6G(SCH_1):PVDDCR_CPU0_P1_PVCC    I39 @T6G_MB_LIB.T6G(SCH_1):PAGE187
    36 PVDDCR_CPU0_P1_TEMP0 @T6G_MB_LIB.T6G(SCH_1):PVDDCR_CPU0_P1_TEMP0    I39 @T6G_MB_LIB.T6G(SCH_1):PAGE187
    38 PVDDCR_CPU0_P1_IMON3 @T6G_MB_LIB.T6G(SCH_1):PVDDCR_CPU0_P1_IMON3    I39 @T6G_MB_LIB.T6G(SCH_1):PAGE187
    37 PVDDCR_CPU0_P1_LSET3 @T6G_MB_LIB.T6G(SCH_1):PVDDCR_CPU0_P1_LSET3    I39 @T6G_MB_LIB.T6G(SCH_1):PAGE187
 10_19 SW_PVDDCR_CPU0_P1_SW3 @T6G_MB_LIB.T6G(SCH_1):SW_PVDDCR_CPU0_P1_SW3    I39 @T6G_MB_LIB.T6G(SCH_1):PAGE187
     5    GND @T6G_MB_LIB.T6G(SCH_1):GND    I39 @T6G_MB_LIB.T6G(SCH_1):PAGE187
    30 SW_P12V_AUX_PVDDCR_CPU0_P1_FLT @T6G_MB_LIB.T6G(SCH_1):SW_P12V_AUX_PVDDCR_CPU0_P1_FLT    I39 @T6G_MB_LIB.T6G(SCH_1):PAGE187
     1 PVDDCR_CPU0_P1_VOS3 @T6G_MB_LIB.T6G(SCH_1):PVDDCR_CPU0_P1_VOS3    I39 @T6G_MB_LIB.T6G(SCH_1):PAGE187
    40    GND @T6G_MB_LIB.T6G(SCH_1):GND    I39 @T6G_MB_LIB.T6G(SCH_1):PAGE187
    35 PVDDCR_CPU0_P1_VCC3 @T6G_MB_LIB.T6G(SCH_1):PVDDCR_CPU0_P1_VCC3    I39 @T6G_MB_LIB.T6G(SCH_1):PAGE187
    31 NC_PVDDCR_CPU0_P1_DNC3 @T6G_MB_LIB.T6G(SCH_1):NC_PVDDCR_CPU0_P1_DNC3    I39 @T6G_MB_LIB.T6G(SCH_1):PAGE187
     6 NC_PVDDCR_CPU0_P1_GL1_3 @T6G_MB_LIB.T6G(SCH_1):NC_PVDDCR_CPU0_P1_GL1_3    I39 @T6G_MB_LIB.T6G(SCH_1):PAGE187
    41 NC_PVDDCR_CPU0_P1_GL2_3 @T6G_MB_LIB.T6G(SCH_1):NC_PVDDCR_CPU0_P1_GL2_3    I39 @T6G_MB_LIB.T6G(SCH_1):PAGE187
7_9-20_24    GND @T6G_MB_LIB.T6G(SCH_1):GND    I39 @T6G_MB_LIB.T6G(SCH_1):PAGE187

PU28 ISL99390FRZTR5935-ISL99390FRZ-TR5935,SMLF,IC,AL099A
    34 PVDDCR_CPU0_P1_PWM4 @T6G_MB_LIB.T6G(SCH_1):PVDDCR_CPU0_P1_PWM4     I9 @T6G_MB_LIB.T6G(SCH_1):PAGE187
    39 PVDDCR_CPU0_P1_VCCS @T6G_MB_LIB.T6G(SCH_1):PVDDCR_CPU0_P1_VCCS     I9 @T6G_MB_LIB.T6G(SCH_1):PAGE187
     3 PVDDCR_CPU0_P1_VCC4 @T6G_MB_LIB.T6G(SCH_1):PVDDCR_CPU0_P1_VCC4     I9 @T6G_MB_LIB.T6G(SCH_1):PAGE187
     2    GND @T6G_MB_LIB.T6G(SCH_1):GND     I9 @T6G_MB_LIB.T6G(SCH_1):PAGE187
    33 SW_PVDDCR_CPU0_P1_BOOT4 @T6G_MB_LIB.T6G(SCH_1):SW_PVDDCR_CPU0_P1_BOOT4     I9 @T6G_MB_LIB.T6G(SCH_1):PAGE187
 25_29 SW_P12V_AUX_PVDDCR_CPU0_P1_FLT @T6G_MB_LIB.T6G(SCH_1):SW_P12V_AUX_PVDDCR_CPU0_P1_FLT     I9 @T6G_MB_LIB.T6G(SCH_1):PAGE187
    32 SW_PVDDCR_CPU0_P1_PH4 @T6G_MB_LIB.T6G(SCH_1):SW_PVDDCR_CPU0_P1_PH4     I9 @T6G_MB_LIB.T6G(SCH_1):PAGE187
     4 PVDDCR_CPU0_P1_PVCC @T6G_MB_LIB.T6G(SCH_1):PVDDCR_CPU0_P1_PVCC     I9 @T6G_MB_LIB.T6G(SCH_1):PAGE187
    36 PVDDCR_CPU0_P1_TEMP0 @T6G_MB_LIB.T6G(SCH_1):PVDDCR_CPU0_P1_TEMP0     I9 @T6G_MB_LIB.T6G(SCH_1):PAGE187
    38 PVDDCR_CPU0_P1_IMON4 @T6G_MB_LIB.T6G(SCH_1):PVDDCR_CPU0_P1_IMON4     I9 @T6G_MB_LIB.T6G(SCH_1):PAGE187
    37 PVDDCR_CPU0_P1_LSET4 @T6G_MB_LIB.T6G(SCH_1):PVDDCR_CPU0_P1_LSET4     I9 @T6G_MB_LIB.T6G(SCH_1):PAGE187
 10_19 SW_PVDDCR_CPU0_P1_SW4 @T6G_MB_LIB.T6G(SCH_1):SW_PVDDCR_CPU0_P1_SW4     I9 @T6G_MB_LIB.T6G(SCH_1):PAGE187
     5    GND @T6G_MB_LIB.T6G(SCH_1):GND     I9 @T6G_MB_LIB.T6G(SCH_1):PAGE187
    30 SW_P12V_AUX_PVDDCR_CPU0_P1_FLT @T6G_MB_LIB.T6G(SCH_1):SW_P12V_AUX_PVDDCR_CPU0_P1_FLT     I9 @T6G_MB_LIB.T6G(SCH_1):PAGE187
     1 PVDDCR_CPU0_P1_VOS4 @T6G_MB_LIB.T6G(SCH_1):PVDDCR_CPU0_P1_VOS4     I9 @T6G_MB_LIB.T6G(SCH_1):PAGE187
    40    GND @T6G_MB_LIB.T6G(SCH_1):GND     I9 @T6G_MB_LIB.T6G(SCH_1):PAGE187
    35 PVDDCR_CPU0_P1_VCC4 @T6G_MB_LIB.T6G(SCH_1):PVDDCR_CPU0_P1_VCC4     I9 @T6G_MB_LIB.T6G(SCH_1):PAGE187
    31 NC_PVDDCR_CPU0_P1_DNC4 @T6G_MB_LIB.T6G(SCH_1):NC_PVDDCR_CPU0_P1_DNC4     I9 @T6G_MB_LIB.T6G(SCH_1):PAGE187
     6 NC_PVDDCR_CPU0_P1_GL1_4 @T6G_MB_LIB.T6G(SCH_1):NC_PVDDCR_CPU0_P1_GL1_4     I9 @T6G_MB_LIB.T6G(SCH_1):PAGE187
    41 NC_PVDDCR_CPU0_P1_GL2_4 @T6G_MB_LIB.T6G(SCH_1):NC_PVDDCR_CPU0_P1_GL2_4     I9 @T6G_MB_LIB.T6G(SCH_1):PAGE187
7_9-20_24    GND @T6G_MB_LIB.T6G(SCH_1):GND     I9 @T6G_MB_LIB.T6G(SCH_1):PAGE187

PU29 ISL99390FRZTR5935-ISL99390FRZ-TR5935,SMLF,IC,AL099A
    34 PVDDCR_CPU0_P1_PWM5 @T6G_MB_LIB.T6G(SCH_1):PVDDCR_CPU0_P1_PWM5    I18 @T6G_MB_LIB.T6G(SCH_1):PAGE188
    39 PVDDCR_CPU0_P1_VCCS @T6G_MB_LIB.T6G(SCH_1):PVDDCR_CPU0_P1_VCCS    I18 @T6G_MB_LIB.T6G(SCH_1):PAGE188
     3 PVDDCR_CPU0_P1_VCC5 @T6G_MB_LIB.T6G(SCH_1):PVDDCR_CPU0_P1_VCC5    I18 @T6G_MB_LIB.T6G(SCH_1):PAGE188
     2    GND @T6G_MB_LIB.T6G(SCH_1):GND    I18 @T6G_MB_LIB.T6G(SCH_1):PAGE188
    33 SW_PVDDCR_CPU0_P1_BOOT5 @T6G_MB_LIB.T6G(SCH_1):SW_PVDDCR_CPU0_P1_BOOT5    I18 @T6G_MB_LIB.T6G(SCH_1):PAGE188
 25_29 SW_P12V_AUX_PVDDCR_CPU0_P1_FLT @T6G_MB_LIB.T6G(SCH_1):SW_P12V_AUX_PVDDCR_CPU0_P1_FLT    I18 @T6G_MB_LIB.T6G(SCH_1):PAGE188
    32 SW_PVDDCR_CPU0_P1_PH5 @T6G_MB_LIB.T6G(SCH_1):SW_PVDDCR_CPU0_P1_PH5    I18 @T6G_MB_LIB.T6G(SCH_1):PAGE188
     4 PVDDCR_CPU0_P1_PVCC @T6G_MB_LIB.T6G(SCH_1):PVDDCR_CPU0_P1_PVCC    I18 @T6G_MB_LIB.T6G(SCH_1):PAGE188
    36 PVDDCR_CPU0_P1_TEMP0 @T6G_MB_LIB.T6G(SCH_1):PVDDCR_CPU0_P1_TEMP0    I18 @T6G_MB_LIB.T6G(SCH_1):PAGE188
    38 PVDDCR_CPU0_P1_IMON5 @T6G_MB_LIB.T6G(SCH_1):PVDDCR_CPU0_P1_IMON5    I18 @T6G_MB_LIB.T6G(SCH_1):PAGE188
    37 PVDDCR_CPU0_P1_LSET5 @T6G_MB_LIB.T6G(SCH_1):PVDDCR_CPU0_P1_LSET5    I18 @T6G_MB_LIB.T6G(SCH_1):PAGE188
 10_19 SW_PVDDCR_CPU0_P1_SW5 @T6G_MB_LIB.T6G(SCH_1):SW_PVDDCR_CPU0_P1_SW5    I18 @T6G_MB_LIB.T6G(SCH_1):PAGE188
     5    GND @T6G_MB_LIB.T6G(SCH_1):GND    I18 @T6G_MB_LIB.T6G(SCH_1):PAGE188
    30 SW_P12V_AUX_PVDDCR_CPU0_P1_FLT @T6G_MB_LIB.T6G(SCH_1):SW_P12V_AUX_PVDDCR_CPU0_P1_FLT    I18 @T6G_MB_LIB.T6G(SCH_1):PAGE188
     1 PVDDCR_CPU0_P1_VOS5 @T6G_MB_LIB.T6G(SCH_1):PVDDCR_CPU0_P1_VOS5    I18 @T6G_MB_LIB.T6G(SCH_1):PAGE188
    40    GND @T6G_MB_LIB.T6G(SCH_1):GND    I18 @T6G_MB_LIB.T6G(SCH_1):PAGE188
    35 PVDDCR_CPU0_P1_VCC5 @T6G_MB_LIB.T6G(SCH_1):PVDDCR_CPU0_P1_VCC5    I18 @T6G_MB_LIB.T6G(SCH_1):PAGE188
    31 NC_PVDDCR_CPU0_P1_DNC5 @T6G_MB_LIB.T6G(SCH_1):NC_PVDDCR_CPU0_P1_DNC5    I18 @T6G_MB_LIB.T6G(SCH_1):PAGE188
     6 NC_PVDDCR_CPU0_P1_GL1_5 @T6G_MB_LIB.T6G(SCH_1):NC_PVDDCR_CPU0_P1_GL1_5    I18 @T6G_MB_LIB.T6G(SCH_1):PAGE188
    41 NC_PVDDCR_CPU0_P1_GL2_5 @T6G_MB_LIB.T6G(SCH_1):NC_PVDDCR_CPU0_P1_GL2_5    I18 @T6G_MB_LIB.T6G(SCH_1):PAGE188
7_9-20_24    GND @T6G_MB_LIB.T6G(SCH_1):GND    I18 @T6G_MB_LIB.T6G(SCH_1):PAGE188

PU30 ISL99390FRZTR5935-ISL99390FRZ-TR5935,SMLF,IC,AL099A
    34 PVDDCR_SOC_P1_PWM1 @T6G_MB_LIB.T6G(SCH_1):PVDDCR_SOC_P1_PWM1    I17 @T6G_MB_LIB.T6G(SCH_1):PAGE190
    39 PVDDCR_CPU0_P1_VCCS @T6G_MB_LIB.T6G(SCH_1):PVDDCR_CPU0_P1_VCCS    I17 @T6G_MB_LIB.T6G(SCH_1):PAGE190
     3 PVDDCR_SOC_P1_VCC1 @T6G_MB_LIB.T6G(SCH_1):PVDDCR_SOC_P1_VCC1    I17 @T6G_MB_LIB.T6G(SCH_1):PAGE190
     2    GND @T6G_MB_LIB.T6G(SCH_1):GND    I17 @T6G_MB_LIB.T6G(SCH_1):PAGE190
    33 SW_PVDDCR_SOC_P1_BOOT1 @T6G_MB_LIB.T6G(SCH_1):SW_PVDDCR_SOC_P1_BOOT1    I17 @T6G_MB_LIB.T6G(SCH_1):PAGE190
 25_29 SW_P12V_AUX_PVDDCR_SOC_P1_FLT @T6G_MB_LIB.T6G(SCH_1):SW_P12V_AUX_PVDDCR_SOC_P1_FLT    I17 @T6G_MB_LIB.T6G(SCH_1):PAGE190
    32 SW_PVDDCR_SOC_P1_PH1 @T6G_MB_LIB.T6G(SCH_1):SW_PVDDCR_SOC_P1_PH1    I17 @T6G_MB_LIB.T6G(SCH_1):PAGE190
     4 PVDDCR_CPU0_P1_PVCC @T6G_MB_LIB.T6G(SCH_1):PVDDCR_CPU0_P1_PVCC    I17 @T6G_MB_LIB.T6G(SCH_1):PAGE190
    36 PVDDCR_SOC_P1_TEMP1 @T6G_MB_LIB.T6G(SCH_1):PVDDCR_SOC_P1_TEMP1    I17 @T6G_MB_LIB.T6G(SCH_1):PAGE190
    38 PVDDCR_SOC_P1_IMON1 @T6G_MB_LIB.T6G(SCH_1):PVDDCR_SOC_P1_IMON1    I17 @T6G_MB_LIB.T6G(SCH_1):PAGE190
    37 PVDDCR_SOC_P1_LSET1 @T6G_MB_LIB.T6G(SCH_1):PVDDCR_SOC_P1_LSET1    I17 @T6G_MB_LIB.T6G(SCH_1):PAGE190
 10_19 SW_PVDDCR_SOC_P1_SW1 @T6G_MB_LIB.T6G(SCH_1):SW_PVDDCR_SOC_P1_SW1    I17 @T6G_MB_LIB.T6G(SCH_1):PAGE190
     5    GND @T6G_MB_LIB.T6G(SCH_1):GND    I17 @T6G_MB_LIB.T6G(SCH_1):PAGE190
    30 SW_P12V_AUX_PVDDCR_SOC_P1_FLT @T6G_MB_LIB.T6G(SCH_1):SW_P12V_AUX_PVDDCR_SOC_P1_FLT    I17 @T6G_MB_LIB.T6G(SCH_1):PAGE190
     1 PVDDCR_SOC_P1_VOS1 @T6G_MB_LIB.T6G(SCH_1):PVDDCR_SOC_P1_VOS1    I17 @T6G_MB_LIB.T6G(SCH_1):PAGE190
    40    GND @T6G_MB_LIB.T6G(SCH_1):GND    I17 @T6G_MB_LIB.T6G(SCH_1):PAGE190
    35 PVDDCR_SOC_P1_VCC1 @T6G_MB_LIB.T6G(SCH_1):PVDDCR_SOC_P1_VCC1    I17 @T6G_MB_LIB.T6G(SCH_1):PAGE190
    31 NC_PVDDCR_SOC_P1_DNC1 @T6G_MB_LIB.T6G(SCH_1):NC_PVDDCR_SOC_P1_DNC1    I17 @T6G_MB_LIB.T6G(SCH_1):PAGE190
     6 NC_PVDDCR_SOC_P1_GL1_1 @T6G_MB_LIB.T6G(SCH_1):NC_PVDDCR_SOC_P1_GL1_1    I17 @T6G_MB_LIB.T6G(SCH_1):PAGE190
    41 NC_PVDDCR_SOC_P1_GL2_1 @T6G_MB_LIB.T6G(SCH_1):NC_PVDDCR_SOC_P1_GL2_1    I17 @T6G_MB_LIB.T6G(SCH_1):PAGE190
7_9-20_24    GND @T6G_MB_LIB.T6G(SCH_1):GND    I17 @T6G_MB_LIB.T6G(SCH_1):PAGE190

PU31 ISL99390FRZTR5935-ISL99390FRZ-TR5935,SMLF,IC,AL099A
    34 PVDDCR_SOC_P1_PWM2 @T6G_MB_LIB.T6G(SCH_1):PVDDCR_SOC_P1_PWM2    I86 @T6G_MB_LIB.T6G(SCH_1):PAGE190
    39 PVDDCR_CPU0_P1_VCCS @T6G_MB_LIB.T6G(SCH_1):PVDDCR_CPU0_P1_VCCS    I86 @T6G_MB_LIB.T6G(SCH_1):PAGE190
     3 PVDDCR_SOC_P1_VCC2 @T6G_MB_LIB.T6G(SCH_1):PVDDCR_SOC_P1_VCC2    I86 @T6G_MB_LIB.T6G(SCH_1):PAGE190
     2    GND @T6G_MB_LIB.T6G(SCH_1):GND    I86 @T6G_MB_LIB.T6G(SCH_1):PAGE190
    33 SW_PVDDCR_SOC_P1_BOOT2 @T6G_MB_LIB.T6G(SCH_1):SW_PVDDCR_SOC_P1_BOOT2    I86 @T6G_MB_LIB.T6G(SCH_1):PAGE190
 25_29 SW_P12V_AUX_PVDDCR_SOC_P1_FLT @T6G_MB_LIB.T6G(SCH_1):SW_P12V_AUX_PVDDCR_SOC_P1_FLT    I86 @T6G_MB_LIB.T6G(SCH_1):PAGE190
    32 SW_PVDDCR_SOC_P1_PH2 @T6G_MB_LIB.T6G(SCH_1):SW_PVDDCR_SOC_P1_PH2    I86 @T6G_MB_LIB.T6G(SCH_1):PAGE190
     4 PVDDCR_CPU0_P1_PVCC @T6G_MB_LIB.T6G(SCH_1):PVDDCR_CPU0_P1_PVCC    I86 @T6G_MB_LIB.T6G(SCH_1):PAGE190
    36 PVDDCR_SOC_P1_TEMP1 @T6G_MB_LIB.T6G(SCH_1):PVDDCR_SOC_P1_TEMP1    I86 @T6G_MB_LIB.T6G(SCH_1):PAGE190
    38 PVDDCR_SOC_P1_IMON2 @T6G_MB_LIB.T6G(SCH_1):PVDDCR_SOC_P1_IMON2    I86 @T6G_MB_LIB.T6G(SCH_1):PAGE190
    37 PVDDCR_SOC_P1_LSET2 @T6G_MB_LIB.T6G(SCH_1):PVDDCR_SOC_P1_LSET2    I86 @T6G_MB_LIB.T6G(SCH_1):PAGE190
 10_19 SW_PVDDCR_SOC_P1_SW2 @T6G_MB_LIB.T6G(SCH_1):SW_PVDDCR_SOC_P1_SW2    I86 @T6G_MB_LIB.T6G(SCH_1):PAGE190
     5    GND @T6G_MB_LIB.T6G(SCH_1):GND    I86 @T6G_MB_LIB.T6G(SCH_1):PAGE190
    30 SW_P12V_AUX_PVDDCR_SOC_P1_FLT @T6G_MB_LIB.T6G(SCH_1):SW_P12V_AUX_PVDDCR_SOC_P1_FLT    I86 @T6G_MB_LIB.T6G(SCH_1):PAGE190
     1 PVDDCR_SOC_P1_VOS2 @T6G_MB_LIB.T6G(SCH_1):PVDDCR_SOC_P1_VOS2    I86 @T6G_MB_LIB.T6G(SCH_1):PAGE190
    40    GND @T6G_MB_LIB.T6G(SCH_1):GND    I86 @T6G_MB_LIB.T6G(SCH_1):PAGE190
    35 PVDDCR_SOC_P1_VCC2 @T6G_MB_LIB.T6G(SCH_1):PVDDCR_SOC_P1_VCC2    I86 @T6G_MB_LIB.T6G(SCH_1):PAGE190
    31 NC_PVDDCR_SOC_P1_DNC2 @T6G_MB_LIB.T6G(SCH_1):NC_PVDDCR_SOC_P1_DNC2    I86 @T6G_MB_LIB.T6G(SCH_1):PAGE190
     6 NC_PVDDCR_SOC_P1_GL1_2 @T6G_MB_LIB.T6G(SCH_1):NC_PVDDCR_SOC_P1_GL1_2    I86 @T6G_MB_LIB.T6G(SCH_1):PAGE190
    41 NC_PVDDCR_SOC_P1_GL2_2 @T6G_MB_LIB.T6G(SCH_1):NC_PVDDCR_SOC_P1_GL2_2    I86 @T6G_MB_LIB.T6G(SCH_1):PAGE190
7_9-20_24    GND @T6G_MB_LIB.T6G(SCH_1):GND    I86 @T6G_MB_LIB.T6G(SCH_1):PAGE190

PU32 ISL99390FRZTR5935-ISL99390FRZ-TR5935,SMLF,IC,AL099A
    34 PVDDCR_SOC_P1_PWM3 @T6G_MB_LIB.T6G(SCH_1):PVDDCR_SOC_P1_PWM3    I38 @T6G_MB_LIB.T6G(SCH_1):PAGE191
    39 PVDDCR_CPU0_P1_VCCS @T6G_MB_LIB.T6G(SCH_1):PVDDCR_CPU0_P1_VCCS    I38 @T6G_MB_LIB.T6G(SCH_1):PAGE191
     3 PVDDCR_SOC_P1_VCC3 @T6G_MB_LIB.T6G(SCH_1):PVDDCR_SOC_P1_VCC3    I38 @T6G_MB_LIB.T6G(SCH_1):PAGE191
     2    GND @T6G_MB_LIB.T6G(SCH_1):GND    I38 @T6G_MB_LIB.T6G(SCH_1):PAGE191
    33 SW_PVDDCR_SOC_P1_BOOT3 @T6G_MB_LIB.T6G(SCH_1):SW_PVDDCR_SOC_P1_BOOT3    I38 @T6G_MB_LIB.T6G(SCH_1):PAGE191
 25_29 SW_P12V_AUX_PVDDCR_SOC_P1_FLT @T6G_MB_LIB.T6G(SCH_1):SW_P12V_AUX_PVDDCR_SOC_P1_FLT    I38 @T6G_MB_LIB.T6G(SCH_1):PAGE191
    32 SW_PVDDCR_SOC_P1_PH3 @T6G_MB_LIB.T6G(SCH_1):SW_PVDDCR_SOC_P1_PH3    I38 @T6G_MB_LIB.T6G(SCH_1):PAGE191
     4 PVDDCR_CPU0_P1_PVCC @T6G_MB_LIB.T6G(SCH_1):PVDDCR_CPU0_P1_PVCC    I38 @T6G_MB_LIB.T6G(SCH_1):PAGE191
    36 PVDDCR_SOC_P1_TEMP1 @T6G_MB_LIB.T6G(SCH_1):PVDDCR_SOC_P1_TEMP1    I38 @T6G_MB_LIB.T6G(SCH_1):PAGE191
    38 PVDDCR_SOC_P1_IMON3 @T6G_MB_LIB.T6G(SCH_1):PVDDCR_SOC_P1_IMON3    I38 @T6G_MB_LIB.T6G(SCH_1):PAGE191
    37 PVDDCR_SOC_P1_LSET3 @T6G_MB_LIB.T6G(SCH_1):PVDDCR_SOC_P1_LSET3    I38 @T6G_MB_LIB.T6G(SCH_1):PAGE191
 10_19 SW_PVDDCR_SOC_P1_SW3 @T6G_MB_LIB.T6G(SCH_1):SW_PVDDCR_SOC_P1_SW3    I38 @T6G_MB_LIB.T6G(SCH_1):PAGE191
     5    GND @T6G_MB_LIB.T6G(SCH_1):GND    I38 @T6G_MB_LIB.T6G(SCH_1):PAGE191
    30 SW_P12V_AUX_PVDDCR_SOC_P1_FLT @T6G_MB_LIB.T6G(SCH_1):SW_P12V_AUX_PVDDCR_SOC_P1_FLT    I38 @T6G_MB_LIB.T6G(SCH_1):PAGE191
     1 PVDDCR_SOC_P1_VOS3 @T6G_MB_LIB.T6G(SCH_1):PVDDCR_SOC_P1_VOS3    I38 @T6G_MB_LIB.T6G(SCH_1):PAGE191
    40    GND @T6G_MB_LIB.T6G(SCH_1):GND    I38 @T6G_MB_LIB.T6G(SCH_1):PAGE191
    35 PVDDCR_SOC_P1_VCC3 @T6G_MB_LIB.T6G(SCH_1):PVDDCR_SOC_P1_VCC3    I38 @T6G_MB_LIB.T6G(SCH_1):PAGE191
    31 NC_PVDDCR_SOC_P1_DNC3 @T6G_MB_LIB.T6G(SCH_1):NC_PVDDCR_SOC_P1_DNC3    I38 @T6G_MB_LIB.T6G(SCH_1):PAGE191
     6 NC_PVDDCR_SOC_P1_GL1_3 @T6G_MB_LIB.T6G(SCH_1):NC_PVDDCR_SOC_P1_GL1_3    I38 @T6G_MB_LIB.T6G(SCH_1):PAGE191
    41 NC_PVDDCR_SOC_P1_GL2_3 @T6G_MB_LIB.T6G(SCH_1):NC_PVDDCR_SOC_P1_GL2_3    I38 @T6G_MB_LIB.T6G(SCH_1):PAGE191
7_9-20_24    GND @T6G_MB_LIB.T6G(SCH_1):GND    I38 @T6G_MB_LIB.T6G(SCH_1):PAGE191

PU33 ISL99390FRZTR5935-ISL99390FRZ-TR5935,SMLF,IC,AL099A
    34 PVDDCR_CPU1_P1_PWM6 @T6G_MB_LIB.T6G(SCH_1):PVDDCR_CPU1_P1_PWM6    I19 @T6G_MB_LIB.T6G(SCH_1):PAGE195
    39 PVDDCR_CPU1_P1_VCCS @T6G_MB_LIB.T6G(SCH_1):PVDDCR_CPU1_P1_VCCS    I19 @T6G_MB_LIB.T6G(SCH_1):PAGE195
     3 PVDDCR_CPU1_P1_VCC6 @T6G_MB_LIB.T6G(SCH_1):PVDDCR_CPU1_P1_VCC6    I19 @T6G_MB_LIB.T6G(SCH_1):PAGE195
     2    GND @T6G_MB_LIB.T6G(SCH_1):GND    I19 @T6G_MB_LIB.T6G(SCH_1):PAGE195
    33 SW_PVDDCR_CPU1_P1_BOOT6 @T6G_MB_LIB.T6G(SCH_1):SW_PVDDCR_CPU1_P1_BOOT6    I19 @T6G_MB_LIB.T6G(SCH_1):PAGE195
 25_29 SW_P12V_AUX_PVDDCR_CPU1_P1_FLT @T6G_MB_LIB.T6G(SCH_1):SW_P12V_AUX_PVDDCR_CPU1_P1_FLT    I19 @T6G_MB_LIB.T6G(SCH_1):PAGE195
    32 SW_PVDDCR_CPU1_P1_BOOTR6 @T6G_MB_LIB.T6G(SCH_1):SW_PVDDCR_CPU1_P1_BOOTR6    I19 @T6G_MB_LIB.T6G(SCH_1):PAGE195
     4 PVDDCR_CPU1_P1_PVCC @T6G_MB_LIB.T6G(SCH_1):PVDDCR_CPU1_P1_PVCC    I19 @T6G_MB_LIB.T6G(SCH_1):PAGE195
    36 PVDDCR_CPU1_P1_TEMP0 @T6G_MB_LIB.T6G(SCH_1):PVDDCR_CPU1_P1_TEMP0    I19 @T6G_MB_LIB.T6G(SCH_1):PAGE195
    38 PVDDCR_CPU1_P1_IMON6 @T6G_MB_LIB.T6G(SCH_1):PVDDCR_CPU1_P1_IMON6    I19 @T6G_MB_LIB.T6G(SCH_1):PAGE195
    37 PVDDCR_CPU1_P1_LSET6 @T6G_MB_LIB.T6G(SCH_1):PVDDCR_CPU1_P1_LSET6    I19 @T6G_MB_LIB.T6G(SCH_1):PAGE195
 10_19 SW_PVDDCR_CPU1_P1_SW6 @T6G_MB_LIB.T6G(SCH_1):SW_PVDDCR_CPU1_P1_SW6    I19 @T6G_MB_LIB.T6G(SCH_1):PAGE195
     5    GND @T6G_MB_LIB.T6G(SCH_1):GND    I19 @T6G_MB_LIB.T6G(SCH_1):PAGE195
    30 SW_P12V_AUX_PVDDCR_CPU1_P1_FLT @T6G_MB_LIB.T6G(SCH_1):SW_P12V_AUX_PVDDCR_CPU1_P1_FLT    I19 @T6G_MB_LIB.T6G(SCH_1):PAGE195
     1 PVDDCR_CPU1_P1_VOS6 @T6G_MB_LIB.T6G(SCH_1):PVDDCR_CPU1_P1_VOS6    I19 @T6G_MB_LIB.T6G(SCH_1):PAGE195
    40    GND @T6G_MB_LIB.T6G(SCH_1):GND    I19 @T6G_MB_LIB.T6G(SCH_1):PAGE195
    35 PVDDCR_CPU1_P1_VCC6 @T6G_MB_LIB.T6G(SCH_1):PVDDCR_CPU1_P1_VCC6    I19 @T6G_MB_LIB.T6G(SCH_1):PAGE195
    31 NC_PVDDCR_CPU1_P1_DNC6 @T6G_MB_LIB.T6G(SCH_1):NC_PVDDCR_CPU1_P1_DNC6    I19 @T6G_MB_LIB.T6G(SCH_1):PAGE195
     6 NC_PVDDCR_CPU1_P1_GL1_6 @T6G_MB_LIB.T6G(SCH_1):NC_PVDDCR_CPU1_P1_GL1_6    I19 @T6G_MB_LIB.T6G(SCH_1):PAGE195
    41 NC_PVDDCR_CPU1_P1_GL2_6 @T6G_MB_LIB.T6G(SCH_1):NC_PVDDCR_CPU1_P1_GL2_6    I19 @T6G_MB_LIB.T6G(SCH_1):PAGE195
7_9-20_24    GND @T6G_MB_LIB.T6G(SCH_1):GND    I19 @T6G_MB_LIB.T6G(SCH_1):PAGE195

PU34 RAA229620GNPHA0-RAA229620GNP#HA0,SMLF,IC,ARF0TGP40A
    27 PVDDCR_CPU1_P1_IMON1 @T6G_MB_LIB.T6G(SCH_1):PVDDCR_CPU1_P1_IMON1   I128 @T6G_MB_LIB.T6G(SCH_1):PAGE192
    47 PVDDCR_CPU1_P1_VCC @T6G_MB_LIB.T6G(SCH_1):PVDDCR_CPU1_P1_VCC   I128 @T6G_MB_LIB.T6G(SCH_1):PAGE192
    24 SVID_PVDDCR_CPU1_P1_SVTI_R @T6G_MB_LIB.T6G(SCH_1):SVID_PVDDCR_CPU1_P1_SVTI_R   I128 @T6G_MB_LIB.T6G(SCH_1):PAGE192
    14 SMB_CLK_PVDDCR_CPU1_P1_R @T6G_MB_LIB.T6G(SCH_1):SMB_CLK_PVDDCR_CPU1_P1_R   I128 @T6G_MB_LIB.T6G(SCH_1):PAGE192
    22 SVID_PVDDCR_CPU1_P1_SVC_R1 @T6G_MB_LIB.T6G(SCH_1):SVID_PVDDCR_CPU1_P1_SVC_R1   I128 @T6G_MB_LIB.T6G(SCH_1):PAGE192
    32 PVDDCR_CPU1_P1_IMON6 @T6G_MB_LIB.T6G(SCH_1):PVDDCR_CPU1_P1_IMON6   I128 @T6G_MB_LIB.T6G(SCH_1):PAGE192
    23 SVID_PVDDCR_CPU1_P1_SVTO_R @T6G_MB_LIB.T6G(SCH_1):SVID_PVDDCR_CPU1_P1_SVTO_R   I128 @T6G_MB_LIB.T6G(SCH_1):PAGE192
    18 PVDDCR_CPU1_P1_RESET_N_R @T6G_MB_LIB.T6G(SCH_1):PVDDCR_CPU1_P1_RESET_N_R   I128 @T6G_MB_LIB.T6G(SCH_1):PAGE192
    33 NC_PVDDCR_CPU1_P1_IMON7 @T6G_MB_LIB.T6G(SCH_1):NC_PVDDCR_CPU1_P1_IMON7   I128 @T6G_MB_LIB.T6G(SCH_1):PAGE192
    34 NC_PVDDCR_CPU1_P1_IMON8 @T6G_MB_LIB.T6G(SCH_1):NC_PVDDCR_CPU1_P1_IMON8   I128 @T6G_MB_LIB.T6G(SCH_1):PAGE192
    20 PWRGD_PVDDIO_P1_R @T6G_MB_LIB.T6G(SCH_1):PWRGD_PVDDIO_P1_R   I128 @T6G_MB_LIB.T6G(SCH_1):PAGE192
    21 SVID_PVDDCR_CPU1_P1_SVD_R1 @T6G_MB_LIB.T6G(SCH_1):SVID_PVDDCR_CPU1_P1_SVD_R1   I128 @T6G_MB_LIB.T6G(SCH_1):PAGE192
    15 PVDDCR_CPU1_P1_SMB_ALERT_R @T6G_MB_LIB.T6G(SCH_1):PVDDCR_CPU1_P1_SMB_ALERT_R   I128 @T6G_MB_LIB.T6G(SCH_1):PAGE192
    17 PVDDCR_CPU1_P1_EN_R @T6G_MB_LIB.T6G(SCH_1):PVDDCR_CPU1_P1_EN_R   I128 @T6G_MB_LIB.T6G(SCH_1):PAGE192
    26 VSENSE_VSS_SENSE_C_P1 @T6G_MB_LIB.T6G(SCH_1):VSENSE_VSS_SENSE_C_P1   I128 @T6G_MB_LIB.T6G(SCH_1):PAGE192
    13 SMB_DIO_PVDDCR_CPU1_P1_R @T6G_MB_LIB.T6G(SCH_1):SMB_DIO_PVDDCR_CPU1_P1_R   I128 @T6G_MB_LIB.T6G(SCH_1):PAGE192
     5 NC_PVDDCR_CPU1_P1_PWM8 @T6G_MB_LIB.T6G(SCH_1):NC_PVDDCR_CPU1_P1_PWM8   I128 @T6G_MB_LIB.T6G(SCH_1):PAGE192
     6 NC_PVDDCR_CPU1_P1_PWM7 @T6G_MB_LIB.T6G(SCH_1):NC_PVDDCR_CPU1_P1_PWM7   I128 @T6G_MB_LIB.T6G(SCH_1):PAGE192
    25 VSENSE_PVDDCR_CPU1_P1_VSEN0 @T6G_MB_LIB.T6G(SCH_1):VSENSE_PVDDCR_CPU1_P1_VSEN0   I128 @T6G_MB_LIB.T6G(SCH_1):PAGE192
     2 PVDDIO_P1_PWM2 @T6G_MB_LIB.T6G(SCH_1):PVDDIO_P1_PWM2   I128 @T6G_MB_LIB.T6G(SCH_1):PAGE192
    16 PWRGD_PVDDCR_CPU1_P1_R @T6G_MB_LIB.T6G(SCH_1):PWRGD_PVDDCR_CPU1_P1_R   I128 @T6G_MB_LIB.T6G(SCH_1):PAGE192
     7 PVDDCR_CPU1_P1_PWM6 @T6G_MB_LIB.T6G(SCH_1):PVDDCR_CPU1_P1_PWM6   I128 @T6G_MB_LIB.T6G(SCH_1):PAGE192
    48 PVDDCR_CPU1_P1_VCCS @T6G_MB_LIB.T6G(SCH_1):PVDDCR_CPU1_P1_VCCS   I128 @T6G_MB_LIB.T6G(SCH_1):PAGE192
    45 PVDDCR_CPU1_P1_VMON @T6G_MB_LIB.T6G(SCH_1):PVDDCR_CPU1_P1_VMON   I128 @T6G_MB_LIB.T6G(SCH_1):PAGE192
    46 PVDDCR_CPU1_P1_VINSEN @T6G_MB_LIB.T6G(SCH_1):PVDDCR_CPU1_P1_VINSEN   I128 @T6G_MB_LIB.T6G(SCH_1):PAGE192
    44 PVDDCR_CPU1_P1_TEMP0 @T6G_MB_LIB.T6G(SCH_1):PVDDCR_CPU1_P1_TEMP0   I128 @T6G_MB_LIB.T6G(SCH_1):PAGE192
    19 PVDD18_S5_P1 @T6G_MB_LIB.T6G(SCH_1):PVDD18_S5_P1   I128 @T6G_MB_LIB.T6G(SCH_1):PAGE192
    40 VSENSE_PVDDIO_P1_VSEN1 @T6G_MB_LIB.T6G(SCH_1):VSENSE_PVDDIO_P1_VSEN1   I128 @T6G_MB_LIB.T6G(SCH_1):PAGE192
    39 VSENSE_VSS_SENSE_B_P1 @T6G_MB_LIB.T6G(SCH_1):VSENSE_VSS_SENSE_B_P1   I128 @T6G_MB_LIB.T6G(SCH_1):PAGE192
    37 PVDDIO_P1_IMON2 @T6G_MB_LIB.T6G(SCH_1):PVDDIO_P1_IMON2   I128 @T6G_MB_LIB.T6G(SCH_1):PAGE192
    12 PVDDCR_CPU1_P1_PWM1 @T6G_MB_LIB.T6G(SCH_1):PVDDCR_CPU1_P1_PWM1   I128 @T6G_MB_LIB.T6G(SCH_1):PAGE192
     4 PVDDIO_P1_PWM4 @T6G_MB_LIB.T6G(SCH_1):PVDDIO_P1_PWM4   I128 @T6G_MB_LIB.T6G(SCH_1):PAGE192
    35 PVDDIO_P1_IMON4 @T6G_MB_LIB.T6G(SCH_1):PVDDIO_P1_IMON4   I128 @T6G_MB_LIB.T6G(SCH_1):PAGE192
     3 PVDDIO_P1_PWM3 @T6G_MB_LIB.T6G(SCH_1):PVDDIO_P1_PWM3   I128 @T6G_MB_LIB.T6G(SCH_1):PAGE192
    36 PVDDIO_P1_IMON3 @T6G_MB_LIB.T6G(SCH_1):PVDDIO_P1_IMON3   I128 @T6G_MB_LIB.T6G(SCH_1):PAGE192
    41 PVDDCR_CPU1_P1_OCP_N_R @T6G_MB_LIB.T6G(SCH_1):PVDDCR_CPU1_P1_OCP_N_R   I128 @T6G_MB_LIB.T6G(SCH_1):PAGE192
    TH    GND @T6G_MB_LIB.T6G(SCH_1):GND   I128 @T6G_MB_LIB.T6G(SCH_1):PAGE192
    42 PVDDCR_CPU1_P1_EN1_ADDR_CFG @T6G_MB_LIB.T6G(SCH_1):PVDDCR_CPU1_P1_EN1_ADDR_CFG   I128 @T6G_MB_LIB.T6G(SCH_1):PAGE192
    43 PVDDIO_P1_TEMP1 @T6G_MB_LIB.T6G(SCH_1):PVDDIO_P1_TEMP1   I128 @T6G_MB_LIB.T6G(SCH_1):PAGE192
     1 PVDDIO_P1_PWM1 @T6G_MB_LIB.T6G(SCH_1):PVDDIO_P1_PWM1   I128 @T6G_MB_LIB.T6G(SCH_1):PAGE192
    38 PVDDIO_P1_IMON1 @T6G_MB_LIB.T6G(SCH_1):PVDDIO_P1_IMON1   I128 @T6G_MB_LIB.T6G(SCH_1):PAGE192
     8 PVDDCR_CPU1_P1_PWM5 @T6G_MB_LIB.T6G(SCH_1):PVDDCR_CPU1_P1_PWM5   I128 @T6G_MB_LIB.T6G(SCH_1):PAGE192
    31 PVDDCR_CPU1_P1_IMON5 @T6G_MB_LIB.T6G(SCH_1):PVDDCR_CPU1_P1_IMON5   I128 @T6G_MB_LIB.T6G(SCH_1):PAGE192
     9 PVDDCR_CPU1_P1_PWM4 @T6G_MB_LIB.T6G(SCH_1):PVDDCR_CPU1_P1_PWM4   I128 @T6G_MB_LIB.T6G(SCH_1):PAGE192
    30 PVDDCR_CPU1_P1_IMON4 @T6G_MB_LIB.T6G(SCH_1):PVDDCR_CPU1_P1_IMON4   I128 @T6G_MB_LIB.T6G(SCH_1):PAGE192
    10 PVDDCR_CPU1_P1_PWM3 @T6G_MB_LIB.T6G(SCH_1):PVDDCR_CPU1_P1_PWM3   I128 @T6G_MB_LIB.T6G(SCH_1):PAGE192
    29 PVDDCR_CPU1_P1_IMON3 @T6G_MB_LIB.T6G(SCH_1):PVDDCR_CPU1_P1_IMON3   I128 @T6G_MB_LIB.T6G(SCH_1):PAGE192
    11 PVDDCR_CPU1_P1_PWM2 @T6G_MB_LIB.T6G(SCH_1):PVDDCR_CPU1_P1_PWM2   I128 @T6G_MB_LIB.T6G(SCH_1):PAGE192
    28 PVDDCR_CPU1_P1_IMON2 @T6G_MB_LIB.T6G(SCH_1):PVDDCR_CPU1_P1_IMON2   I128 @T6G_MB_LIB.T6G(SCH_1):PAGE192

PU35 ISL99390FRZTR5935-ISL99390FRZ-TR5935,SMLF,IC,AL099A
    34 PVDDCR_CPU1_P1_PWM1 @T6G_MB_LIB.T6G(SCH_1):PVDDCR_CPU1_P1_PWM1    I91 @T6G_MB_LIB.T6G(SCH_1):PAGE193
    39 PVDDCR_CPU1_P1_VCCS @T6G_MB_LIB.T6G(SCH_1):PVDDCR_CPU1_P1_VCCS    I91 @T6G_MB_LIB.T6G(SCH_1):PAGE193
     3 PVDDCR_CPU1_P1_VCC1 @T6G_MB_LIB.T6G(SCH_1):PVDDCR_CPU1_P1_VCC1    I91 @T6G_MB_LIB.T6G(SCH_1):PAGE193
     2    GND @T6G_MB_LIB.T6G(SCH_1):GND    I91 @T6G_MB_LIB.T6G(SCH_1):PAGE193
    33 SW_PVDDCR_CPU1_P1_BOOT1 @T6G_MB_LIB.T6G(SCH_1):SW_PVDDCR_CPU1_P1_BOOT1    I91 @T6G_MB_LIB.T6G(SCH_1):PAGE193
 25_29 SW_P12V_AUX_PVDDCR_CPU1_P1_FLT @T6G_MB_LIB.T6G(SCH_1):SW_P12V_AUX_PVDDCR_CPU1_P1_FLT    I91 @T6G_MB_LIB.T6G(SCH_1):PAGE193
    32 SW_PVDDCR_CPU1_P1_BOOTR1 @T6G_MB_LIB.T6G(SCH_1):SW_PVDDCR_CPU1_P1_BOOTR1    I91 @T6G_MB_LIB.T6G(SCH_1):PAGE193
     4 PVDDCR_CPU1_P1_PVCC @T6G_MB_LIB.T6G(SCH_1):PVDDCR_CPU1_P1_PVCC    I91 @T6G_MB_LIB.T6G(SCH_1):PAGE193
    36 PVDDCR_CPU1_P1_TEMP0 @T6G_MB_LIB.T6G(SCH_1):PVDDCR_CPU1_P1_TEMP0    I91 @T6G_MB_LIB.T6G(SCH_1):PAGE193
    38 PVDDCR_CPU1_P1_IMON1 @T6G_MB_LIB.T6G(SCH_1):PVDDCR_CPU1_P1_IMON1    I91 @T6G_MB_LIB.T6G(SCH_1):PAGE193
    37 PVDDCR_CPU1_P1_LSET1 @T6G_MB_LIB.T6G(SCH_1):PVDDCR_CPU1_P1_LSET1    I91 @T6G_MB_LIB.T6G(SCH_1):PAGE193
 10_19 SW_PVDDCR_CPU1_P1_SW1 @T6G_MB_LIB.T6G(SCH_1):SW_PVDDCR_CPU1_P1_SW1    I91 @T6G_MB_LIB.T6G(SCH_1):PAGE193
     5    GND @T6G_MB_LIB.T6G(SCH_1):GND    I91 @T6G_MB_LIB.T6G(SCH_1):PAGE193
    30 SW_P12V_AUX_PVDDCR_CPU1_P1_FLT @T6G_MB_LIB.T6G(SCH_1):SW_P12V_AUX_PVDDCR_CPU1_P1_FLT    I91 @T6G_MB_LIB.T6G(SCH_1):PAGE193
     1 PVDDCR_CPU1_P1_VOS1 @T6G_MB_LIB.T6G(SCH_1):PVDDCR_CPU1_P1_VOS1    I91 @T6G_MB_LIB.T6G(SCH_1):PAGE193
    40    GND @T6G_MB_LIB.T6G(SCH_1):GND    I91 @T6G_MB_LIB.T6G(SCH_1):PAGE193
    35 PVDDCR_CPU1_P1_VCC1 @T6G_MB_LIB.T6G(SCH_1):PVDDCR_CPU1_P1_VCC1    I91 @T6G_MB_LIB.T6G(SCH_1):PAGE193
    31 NC_PVDDCR_CPU1_P1_DNC1 @T6G_MB_LIB.T6G(SCH_1):NC_PVDDCR_CPU1_P1_DNC1    I91 @T6G_MB_LIB.T6G(SCH_1):PAGE193
     6 NC_PVDDCR_CPU1_P1_GL1_1 @T6G_MB_LIB.T6G(SCH_1):NC_PVDDCR_CPU1_P1_GL1_1    I91 @T6G_MB_LIB.T6G(SCH_1):PAGE193
    41 NC_PVDDCR_CPU1_P1_GL2_1 @T6G_MB_LIB.T6G(SCH_1):NC_PVDDCR_CPU1_P1_GL2_1    I91 @T6G_MB_LIB.T6G(SCH_1):PAGE193
7_9-20_24    GND @T6G_MB_LIB.T6G(SCH_1):GND    I91 @T6G_MB_LIB.T6G(SCH_1):PAGE193

PU36 ISL99390FRZTR5935-ISL99390FRZ-TR5935,SMLF,IC,AL099A
    34 PVDDCR_CPU1_P1_PWM4 @T6G_MB_LIB.T6G(SCH_1):PVDDCR_CPU1_P1_PWM4    I21 @T6G_MB_LIB.T6G(SCH_1):PAGE194
    39 PVDDCR_CPU1_P1_VCCS @T6G_MB_LIB.T6G(SCH_1):PVDDCR_CPU1_P1_VCCS    I21 @T6G_MB_LIB.T6G(SCH_1):PAGE194
     3 PVDDCR_CPU1_P1_VCC4 @T6G_MB_LIB.T6G(SCH_1):PVDDCR_CPU1_P1_VCC4    I21 @T6G_MB_LIB.T6G(SCH_1):PAGE194
     2    GND @T6G_MB_LIB.T6G(SCH_1):GND    I21 @T6G_MB_LIB.T6G(SCH_1):PAGE194
    33 SW_PVDDCR_CPU1_P1_BOOT4 @T6G_MB_LIB.T6G(SCH_1):SW_PVDDCR_CPU1_P1_BOOT4    I21 @T6G_MB_LIB.T6G(SCH_1):PAGE194
 25_29 SW_P12V_AUX_PVDDCR_CPU1_P1_FLT @T6G_MB_LIB.T6G(SCH_1):SW_P12V_AUX_PVDDCR_CPU1_P1_FLT    I21 @T6G_MB_LIB.T6G(SCH_1):PAGE194
    32 SW_PVDDCR_CPU1_P1_BOOTR4 @T6G_MB_LIB.T6G(SCH_1):SW_PVDDCR_CPU1_P1_BOOTR4    I21 @T6G_MB_LIB.T6G(SCH_1):PAGE194
     4 PVDDCR_CPU1_P1_PVCC @T6G_MB_LIB.T6G(SCH_1):PVDDCR_CPU1_P1_PVCC    I21 @T6G_MB_LIB.T6G(SCH_1):PAGE194
    36 PVDDCR_CPU1_P1_TEMP0 @T6G_MB_LIB.T6G(SCH_1):PVDDCR_CPU1_P1_TEMP0    I21 @T6G_MB_LIB.T6G(SCH_1):PAGE194
    38 PVDDCR_CPU1_P1_IMON4 @T6G_MB_LIB.T6G(SCH_1):PVDDCR_CPU1_P1_IMON4    I21 @T6G_MB_LIB.T6G(SCH_1):PAGE194
    37 PVDDCR_CPU1_P1_LSET4 @T6G_MB_LIB.T6G(SCH_1):PVDDCR_CPU1_P1_LSET4    I21 @T6G_MB_LIB.T6G(SCH_1):PAGE194
 10_19 SW_PVDDCR_CPU1_P1_SW4 @T6G_MB_LIB.T6G(SCH_1):SW_PVDDCR_CPU1_P1_SW4    I21 @T6G_MB_LIB.T6G(SCH_1):PAGE194
     5    GND @T6G_MB_LIB.T6G(SCH_1):GND    I21 @T6G_MB_LIB.T6G(SCH_1):PAGE194
    30 SW_P12V_AUX_PVDDCR_CPU1_P1_FLT @T6G_MB_LIB.T6G(SCH_1):SW_P12V_AUX_PVDDCR_CPU1_P1_FLT    I21 @T6G_MB_LIB.T6G(SCH_1):PAGE194
     1 PVDDCR_CPU1_P1_VOS4 @T6G_MB_LIB.T6G(SCH_1):PVDDCR_CPU1_P1_VOS4    I21 @T6G_MB_LIB.T6G(SCH_1):PAGE194
    40    GND @T6G_MB_LIB.T6G(SCH_1):GND    I21 @T6G_MB_LIB.T6G(SCH_1):PAGE194
    35 PVDDCR_CPU1_P1_VCC4 @T6G_MB_LIB.T6G(SCH_1):PVDDCR_CPU1_P1_VCC4    I21 @T6G_MB_LIB.T6G(SCH_1):PAGE194
    31 NC_PVDDCR_CPU1_P1_DNC4 @T6G_MB_LIB.T6G(SCH_1):NC_PVDDCR_CPU1_P1_DNC4    I21 @T6G_MB_LIB.T6G(SCH_1):PAGE194
     6 NC_PVDDCR_CPU1_P1_GL1_4 @T6G_MB_LIB.T6G(SCH_1):NC_PVDDCR_CPU1_P1_GL1_4    I21 @T6G_MB_LIB.T6G(SCH_1):PAGE194
    41 NC_PVDDCR_CPU1_P1_GL2_4 @T6G_MB_LIB.T6G(SCH_1):NC_PVDDCR_CPU1_P1_GL2_4    I21 @T6G_MB_LIB.T6G(SCH_1):PAGE194
7_9-20_24    GND @T6G_MB_LIB.T6G(SCH_1):GND    I21 @T6G_MB_LIB.T6G(SCH_1):PAGE194

PU37 ISL99390FRZTR5935-ISL99390FRZ-TR5935,SMLF,IC,AL099A
    34 PVDDCR_CPU1_P1_PWM3 @T6G_MB_LIB.T6G(SCH_1):PVDDCR_CPU1_P1_PWM3    I72 @T6G_MB_LIB.T6G(SCH_1):PAGE194
    39 PVDDCR_CPU1_P1_VCCS @T6G_MB_LIB.T6G(SCH_1):PVDDCR_CPU1_P1_VCCS    I72 @T6G_MB_LIB.T6G(SCH_1):PAGE194
     3 PVDDCR_CPU1_P1_VCC3 @T6G_MB_LIB.T6G(SCH_1):PVDDCR_CPU1_P1_VCC3    I72 @T6G_MB_LIB.T6G(SCH_1):PAGE194
     2    GND @T6G_MB_LIB.T6G(SCH_1):GND    I72 @T6G_MB_LIB.T6G(SCH_1):PAGE194
    33 SW_PVDDCR_CPU1_P1_BOOT3 @T6G_MB_LIB.T6G(SCH_1):SW_PVDDCR_CPU1_P1_BOOT3    I72 @T6G_MB_LIB.T6G(SCH_1):PAGE194
 25_29 SW_P12V_AUX_PVDDCR_CPU1_P1_FLT @T6G_MB_LIB.T6G(SCH_1):SW_P12V_AUX_PVDDCR_CPU1_P1_FLT    I72 @T6G_MB_LIB.T6G(SCH_1):PAGE194
    32 SW_PVDDCR_CPU1_P1_BOOTR3 @T6G_MB_LIB.T6G(SCH_1):SW_PVDDCR_CPU1_P1_BOOTR3    I72 @T6G_MB_LIB.T6G(SCH_1):PAGE194
     4 PVDDCR_CPU1_P1_PVCC @T6G_MB_LIB.T6G(SCH_1):PVDDCR_CPU1_P1_PVCC    I72 @T6G_MB_LIB.T6G(SCH_1):PAGE194
    36 PVDDCR_CPU1_P1_TEMP0 @T6G_MB_LIB.T6G(SCH_1):PVDDCR_CPU1_P1_TEMP0    I72 @T6G_MB_LIB.T6G(SCH_1):PAGE194
    38 PVDDCR_CPU1_P1_IMON3 @T6G_MB_LIB.T6G(SCH_1):PVDDCR_CPU1_P1_IMON3    I72 @T6G_MB_LIB.T6G(SCH_1):PAGE194
    37 PVDDCR_CPU1_P1_LSET3 @T6G_MB_LIB.T6G(SCH_1):PVDDCR_CPU1_P1_LSET3    I72 @T6G_MB_LIB.T6G(SCH_1):PAGE194
 10_19 SW_PVDDCR_CPU1_P1_SW3 @T6G_MB_LIB.T6G(SCH_1):SW_PVDDCR_CPU1_P1_SW3    I72 @T6G_MB_LIB.T6G(SCH_1):PAGE194
     5    GND @T6G_MB_LIB.T6G(SCH_1):GND    I72 @T6G_MB_LIB.T6G(SCH_1):PAGE194
    30 SW_P12V_AUX_PVDDCR_CPU1_P1_FLT @T6G_MB_LIB.T6G(SCH_1):SW_P12V_AUX_PVDDCR_CPU1_P1_FLT    I72 @T6G_MB_LIB.T6G(SCH_1):PAGE194
     1 PVDDCR_CPU1_P1_VOS3 @T6G_MB_LIB.T6G(SCH_1):PVDDCR_CPU1_P1_VOS3    I72 @T6G_MB_LIB.T6G(SCH_1):PAGE194
    40    GND @T6G_MB_LIB.T6G(SCH_1):GND    I72 @T6G_MB_LIB.T6G(SCH_1):PAGE194
    35 PVDDCR_CPU1_P1_VCC3 @T6G_MB_LIB.T6G(SCH_1):PVDDCR_CPU1_P1_VCC3    I72 @T6G_MB_LIB.T6G(SCH_1):PAGE194
    31 NC_PVDDCR_CPU1_P1_DNC3 @T6G_MB_LIB.T6G(SCH_1):NC_PVDDCR_CPU1_P1_DNC3    I72 @T6G_MB_LIB.T6G(SCH_1):PAGE194
     6 NC_PVDDCR_CPU1_P1_GL1_3 @T6G_MB_LIB.T6G(SCH_1):NC_PVDDCR_CPU1_P1_GL1_3    I72 @T6G_MB_LIB.T6G(SCH_1):PAGE194
    41 NC_PVDDCR_CPU1_P1_GL2_3 @T6G_MB_LIB.T6G(SCH_1):NC_PVDDCR_CPU1_P1_GL2_3    I72 @T6G_MB_LIB.T6G(SCH_1):PAGE194
7_9-20_24    GND @T6G_MB_LIB.T6G(SCH_1):GND    I72 @T6G_MB_LIB.T6G(SCH_1):PAGE194

PU38 ISL99390FRZTR5935-ISL99390FRZ-TR5935,SMLF,IC,AL099A
    34 PVDDCR_CPU1_P1_PWM5 @T6G_MB_LIB.T6G(SCH_1):PVDDCR_CPU1_P1_PWM5    I73 @T6G_MB_LIB.T6G(SCH_1):PAGE195
    39 PVDDCR_CPU1_P1_VCCS @T6G_MB_LIB.T6G(SCH_1):PVDDCR_CPU1_P1_VCCS    I73 @T6G_MB_LIB.T6G(SCH_1):PAGE195
     3 PVDDCR_CPU1_P1_VCC5 @T6G_MB_LIB.T6G(SCH_1):PVDDCR_CPU1_P1_VCC5    I73 @T6G_MB_LIB.T6G(SCH_1):PAGE195
     2    GND @T6G_MB_LIB.T6G(SCH_1):GND    I73 @T6G_MB_LIB.T6G(SCH_1):PAGE195
    33 SW_PVDDCR_CPU1_P1_BOOT5 @T6G_MB_LIB.T6G(SCH_1):SW_PVDDCR_CPU1_P1_BOOT5    I73 @T6G_MB_LIB.T6G(SCH_1):PAGE195
 25_29 SW_P12V_AUX_PVDDCR_CPU1_P1_FLT @T6G_MB_LIB.T6G(SCH_1):SW_P12V_AUX_PVDDCR_CPU1_P1_FLT    I73 @T6G_MB_LIB.T6G(SCH_1):PAGE195
    32 SW_PVDDCR_CPU1_P1_BOOTR5 @T6G_MB_LIB.T6G(SCH_1):SW_PVDDCR_CPU1_P1_BOOTR5    I73 @T6G_MB_LIB.T6G(SCH_1):PAGE195
     4 PVDDCR_CPU1_P1_PVCC @T6G_MB_LIB.T6G(SCH_1):PVDDCR_CPU1_P1_PVCC    I73 @T6G_MB_LIB.T6G(SCH_1):PAGE195
    36 PVDDCR_CPU1_P1_TEMP0 @T6G_MB_LIB.T6G(SCH_1):PVDDCR_CPU1_P1_TEMP0    I73 @T6G_MB_LIB.T6G(SCH_1):PAGE195
    38 PVDDCR_CPU1_P1_IMON5 @T6G_MB_LIB.T6G(SCH_1):PVDDCR_CPU1_P1_IMON5    I73 @T6G_MB_LIB.T6G(SCH_1):PAGE195
    37 PVDDCR_CPU1_P1_LSET5 @T6G_MB_LIB.T6G(SCH_1):PVDDCR_CPU1_P1_LSET5    I73 @T6G_MB_LIB.T6G(SCH_1):PAGE195
 10_19 SW_PVDDCR_CPU1_P1_SW5 @T6G_MB_LIB.T6G(SCH_1):SW_PVDDCR_CPU1_P1_SW5    I73 @T6G_MB_LIB.T6G(SCH_1):PAGE195
     5    GND @T6G_MB_LIB.T6G(SCH_1):GND    I73 @T6G_MB_LIB.T6G(SCH_1):PAGE195
    30 SW_P12V_AUX_PVDDCR_CPU1_P1_FLT @T6G_MB_LIB.T6G(SCH_1):SW_P12V_AUX_PVDDCR_CPU1_P1_FLT    I73 @T6G_MB_LIB.T6G(SCH_1):PAGE195
     1 PVDDCR_CPU1_P1_VOS5 @T6G_MB_LIB.T6G(SCH_1):PVDDCR_CPU1_P1_VOS5    I73 @T6G_MB_LIB.T6G(SCH_1):PAGE195
    40    GND @T6G_MB_LIB.T6G(SCH_1):GND    I73 @T6G_MB_LIB.T6G(SCH_1):PAGE195
    35 PVDDCR_CPU1_P1_VCC5 @T6G_MB_LIB.T6G(SCH_1):PVDDCR_CPU1_P1_VCC5    I73 @T6G_MB_LIB.T6G(SCH_1):PAGE195
    31 NC_PVDDCR_CPU1_P1_DNC5 @T6G_MB_LIB.T6G(SCH_1):NC_PVDDCR_CPU1_P1_DNC5    I73 @T6G_MB_LIB.T6G(SCH_1):PAGE195
     6 NC_PVDDCR_CPU1_P1_GL1_5 @T6G_MB_LIB.T6G(SCH_1):NC_PVDDCR_CPU1_P1_GL1_5    I73 @T6G_MB_LIB.T6G(SCH_1):PAGE195
    41 NC_PVDDCR_CPU1_P1_GL2_5 @T6G_MB_LIB.T6G(SCH_1):NC_PVDDCR_CPU1_P1_GL2_5    I73 @T6G_MB_LIB.T6G(SCH_1):PAGE195
7_9-20_24    GND @T6G_MB_LIB.T6G(SCH_1):GND    I73 @T6G_MB_LIB.T6G(SCH_1):PAGE195

PU39 ISL99390FRZTR5935-ISL99390FRZ-TR5935,SMLF,IC,AL099A
    34 PVDDIO_P1_PWM1 @T6G_MB_LIB.T6G(SCH_1):PVDDIO_P1_PWM1    I39 @T6G_MB_LIB.T6G(SCH_1):PAGE197
    39 PVDDCR_CPU1_P1_VCCS @T6G_MB_LIB.T6G(SCH_1):PVDDCR_CPU1_P1_VCCS    I39 @T6G_MB_LIB.T6G(SCH_1):PAGE197
     3 PVDDIO_P1_VCC1 @T6G_MB_LIB.T6G(SCH_1):PVDDIO_P1_VCC1    I39 @T6G_MB_LIB.T6G(SCH_1):PAGE197
     2    GND @T6G_MB_LIB.T6G(SCH_1):GND    I39 @T6G_MB_LIB.T6G(SCH_1):PAGE197
    33 SW_PVDDIO_P1_BOOT1 @T6G_MB_LIB.T6G(SCH_1):SW_PVDDIO_P1_BOOT1    I39 @T6G_MB_LIB.T6G(SCH_1):PAGE197
 25_29 SW_P12V_AUX_PVDDIO_P1_FLT @T6G_MB_LIB.T6G(SCH_1):SW_P12V_AUX_PVDDIO_P1_FLT    I39 @T6G_MB_LIB.T6G(SCH_1):PAGE197
    32 SW_PVDDIO_P1_BOOTR1 @T6G_MB_LIB.T6G(SCH_1):SW_PVDDIO_P1_BOOTR1    I39 @T6G_MB_LIB.T6G(SCH_1):PAGE197
     4 PVDDCR_CPU1_P1_PVCC @T6G_MB_LIB.T6G(SCH_1):PVDDCR_CPU1_P1_PVCC    I39 @T6G_MB_LIB.T6G(SCH_1):PAGE197
    36 PVDDIO_P1_TEMP1 @T6G_MB_LIB.T6G(SCH_1):PVDDIO_P1_TEMP1    I39 @T6G_MB_LIB.T6G(SCH_1):PAGE197
    38 PVDDIO_P1_IMON1 @T6G_MB_LIB.T6G(SCH_1):PVDDIO_P1_IMON1    I39 @T6G_MB_LIB.T6G(SCH_1):PAGE197
    37 PVDDIO_P1_LSET1 @T6G_MB_LIB.T6G(SCH_1):PVDDIO_P1_LSET1    I39 @T6G_MB_LIB.T6G(SCH_1):PAGE197
 10_19 SW_PVDDIO_P1_SW1 @T6G_MB_LIB.T6G(SCH_1):SW_PVDDIO_P1_SW1    I39 @T6G_MB_LIB.T6G(SCH_1):PAGE197
     5    GND @T6G_MB_LIB.T6G(SCH_1):GND    I39 @T6G_MB_LIB.T6G(SCH_1):PAGE197
    30 SW_P12V_AUX_PVDDIO_P1_FLT @T6G_MB_LIB.T6G(SCH_1):SW_P12V_AUX_PVDDIO_P1_FLT    I39 @T6G_MB_LIB.T6G(SCH_1):PAGE197
     1 PVDDIO_P1_VOS1 @T6G_MB_LIB.T6G(SCH_1):PVDDIO_P1_VOS1    I39 @T6G_MB_LIB.T6G(SCH_1):PAGE197
    40    GND @T6G_MB_LIB.T6G(SCH_1):GND    I39 @T6G_MB_LIB.T6G(SCH_1):PAGE197
    35 PVDDIO_P1_VCC1 @T6G_MB_LIB.T6G(SCH_1):PVDDIO_P1_VCC1    I39 @T6G_MB_LIB.T6G(SCH_1):PAGE197
    31 NC_PVDDIO_P1_DNC1 @T6G_MB_LIB.T6G(SCH_1):NC_PVDDIO_P1_DNC1    I39 @T6G_MB_LIB.T6G(SCH_1):PAGE197
     6 NC_PVDDIO_P1_GL1_1 @T6G_MB_LIB.T6G(SCH_1):NC_PVDDIO_P1_GL1_1    I39 @T6G_MB_LIB.T6G(SCH_1):PAGE197
    41 NC_PVDDIO_P1_GL2_1 @T6G_MB_LIB.T6G(SCH_1):NC_PVDDIO_P1_GL2_1    I39 @T6G_MB_LIB.T6G(SCH_1):PAGE197
7_9-20_24    GND @T6G_MB_LIB.T6G(SCH_1):GND    I39 @T6G_MB_LIB.T6G(SCH_1):PAGE197

PU40 ISL99390FRZTR5935-ISL99390FRZ-TR5935,SMLF,IC,AL099A
    34 PVDDIO_P1_PWM2 @T6G_MB_LIB.T6G(SCH_1):PVDDIO_P1_PWM2    I84 @T6G_MB_LIB.T6G(SCH_1):PAGE197
    39 PVDDCR_CPU1_P1_VCCS @T6G_MB_LIB.T6G(SCH_1):PVDDCR_CPU1_P1_VCCS    I84 @T6G_MB_LIB.T6G(SCH_1):PAGE197
     3 PVDDIO_P1_VCC2 @T6G_MB_LIB.T6G(SCH_1):PVDDIO_P1_VCC2    I84 @T6G_MB_LIB.T6G(SCH_1):PAGE197
     2    GND @T6G_MB_LIB.T6G(SCH_1):GND    I84 @T6G_MB_LIB.T6G(SCH_1):PAGE197
    33 SW_PVDDIO_P1_BOOT2 @T6G_MB_LIB.T6G(SCH_1):SW_PVDDIO_P1_BOOT2    I84 @T6G_MB_LIB.T6G(SCH_1):PAGE197
 25_29 SW_P12V_AUX_PVDDIO_P1_FLT @T6G_MB_LIB.T6G(SCH_1):SW_P12V_AUX_PVDDIO_P1_FLT    I84 @T6G_MB_LIB.T6G(SCH_1):PAGE197
    32 SW_PVDDIO_P1_BOOTR2 @T6G_MB_LIB.T6G(SCH_1):SW_PVDDIO_P1_BOOTR2    I84 @T6G_MB_LIB.T6G(SCH_1):PAGE197
     4 PVDDCR_CPU1_P1_PVCC @T6G_MB_LIB.T6G(SCH_1):PVDDCR_CPU1_P1_PVCC    I84 @T6G_MB_LIB.T6G(SCH_1):PAGE197
    36 PVDDIO_P1_TEMP1 @T6G_MB_LIB.T6G(SCH_1):PVDDIO_P1_TEMP1    I84 @T6G_MB_LIB.T6G(SCH_1):PAGE197
    38 PVDDIO_P1_IMON2 @T6G_MB_LIB.T6G(SCH_1):PVDDIO_P1_IMON2    I84 @T6G_MB_LIB.T6G(SCH_1):PAGE197
    37 PVDDIO_P1_LSET2 @T6G_MB_LIB.T6G(SCH_1):PVDDIO_P1_LSET2    I84 @T6G_MB_LIB.T6G(SCH_1):PAGE197
 10_19 SW_PVDDIO_P1_SW2 @T6G_MB_LIB.T6G(SCH_1):SW_PVDDIO_P1_SW2    I84 @T6G_MB_LIB.T6G(SCH_1):PAGE197
     5    GND @T6G_MB_LIB.T6G(SCH_1):GND    I84 @T6G_MB_LIB.T6G(SCH_1):PAGE197
    30 SW_P12V_AUX_PVDDIO_P1_FLT @T6G_MB_LIB.T6G(SCH_1):SW_P12V_AUX_PVDDIO_P1_FLT    I84 @T6G_MB_LIB.T6G(SCH_1):PAGE197
     1 PVDDIO_P1_VOS2 @T6G_MB_LIB.T6G(SCH_1):PVDDIO_P1_VOS2    I84 @T6G_MB_LIB.T6G(SCH_1):PAGE197
    40    GND @T6G_MB_LIB.T6G(SCH_1):GND    I84 @T6G_MB_LIB.T6G(SCH_1):PAGE197
    35 PVDDIO_P1_VCC2 @T6G_MB_LIB.T6G(SCH_1):PVDDIO_P1_VCC2    I84 @T6G_MB_LIB.T6G(SCH_1):PAGE197
    31 NC_PVDDIO_P1_DNC2 @T6G_MB_LIB.T6G(SCH_1):NC_PVDDIO_P1_DNC2    I84 @T6G_MB_LIB.T6G(SCH_1):PAGE197
     6 NC_PVDDIO_P1_GL1_2 @T6G_MB_LIB.T6G(SCH_1):NC_PVDDIO_P1_GL1_2    I84 @T6G_MB_LIB.T6G(SCH_1):PAGE197
    41 NC_PVDDIO_P1_GL2_2 @T6G_MB_LIB.T6G(SCH_1):NC_PVDDIO_P1_GL2_2    I84 @T6G_MB_LIB.T6G(SCH_1):PAGE197
7_9-20_24    GND @T6G_MB_LIB.T6G(SCH_1):GND    I84 @T6G_MB_LIB.T6G(SCH_1):PAGE197

PU42 RAA229620GNPHA0-RAA229620GNP#HA0,SMLF,IC,ARF0TGP40A
    27 PVDDCR_CPU0_P0_IMON1 @T6G_MB_LIB.T6G(SCH_1):PVDDCR_CPU0_P0_IMON1   I135 @T6G_MB_LIB.T6G(SCH_1):PAGE168
    47 PVDDCR_CPU0_P0_VCC @T6G_MB_LIB.T6G(SCH_1):PVDDCR_CPU0_P0_VCC   I135 @T6G_MB_LIB.T6G(SCH_1):PAGE168
    24 SVID_PVDDCR_CPU0_P0_SVTI_R @T6G_MB_LIB.T6G(SCH_1):SVID_PVDDCR_CPU0_P0_SVTI_R   I135 @T6G_MB_LIB.T6G(SCH_1):PAGE168
    14 PVDDCR_CPU0_P0_PMSCL_R @T6G_MB_LIB.T6G(SCH_1):PVDDCR_CPU0_P0_PMSCL_R   I135 @T6G_MB_LIB.T6G(SCH_1):PAGE168
    22 SVID_PVDDCR_CPU0_P0_SVC_R1 @T6G_MB_LIB.T6G(SCH_1):SVID_PVDDCR_CPU0_P0_SVC_R1   I135 @T6G_MB_LIB.T6G(SCH_1):PAGE168
    32 PVDDCR_CPU0_P0_IMON6 @T6G_MB_LIB.T6G(SCH_1):PVDDCR_CPU0_P0_IMON6   I135 @T6G_MB_LIB.T6G(SCH_1):PAGE168
    23 SVID_PVDDCR_CPU0_P0_SVTO_R @T6G_MB_LIB.T6G(SCH_1):SVID_PVDDCR_CPU0_P0_SVTO_R   I135 @T6G_MB_LIB.T6G(SCH_1):PAGE168
    18 PVDDCR_CPU0_P0_RESET_N_R @T6G_MB_LIB.T6G(SCH_1):PVDDCR_CPU0_P0_RESET_N_R   I135 @T6G_MB_LIB.T6G(SCH_1):PAGE168
    33 NC_PVDDCR_CPU0_P0_IMON7 @T6G_MB_LIB.T6G(SCH_1):NC_PVDDCR_CPU0_P0_IMON7   I135 @T6G_MB_LIB.T6G(SCH_1):PAGE168
    34 NC_PVDDCR_CPU0_P0_IMON8 @T6G_MB_LIB.T6G(SCH_1):NC_PVDDCR_CPU0_P0_IMON8   I135 @T6G_MB_LIB.T6G(SCH_1):PAGE168
    20 PWRGD_PVDDCR_SOC_P0_R @T6G_MB_LIB.T6G(SCH_1):PWRGD_PVDDCR_SOC_P0_R   I135 @T6G_MB_LIB.T6G(SCH_1):PAGE168
    21 SVID_PVDDCR_CPU0_P0_SVD_R1 @T6G_MB_LIB.T6G(SCH_1):SVID_PVDDCR_CPU0_P0_SVD_R1   I135 @T6G_MB_LIB.T6G(SCH_1):PAGE168
    15 PVDDCR_CPU0_P0_PMALERT_R @T6G_MB_LIB.T6G(SCH_1):PVDDCR_CPU0_P0_PMALERT_R   I135 @T6G_MB_LIB.T6G(SCH_1):PAGE168
    17 PVDDCR_CPU0_P0_EN_R @T6G_MB_LIB.T6G(SCH_1):PVDDCR_CPU0_P0_EN_R   I135 @T6G_MB_LIB.T6G(SCH_1):PAGE168
    26 VSENSE_VSS_SENSE_A_P0 @T6G_MB_LIB.T6G(SCH_1):VSENSE_VSS_SENSE_A_P0   I135 @T6G_MB_LIB.T6G(SCH_1):PAGE168
    13 PVDDCR_CPU0_P0_PMSDA_R @T6G_MB_LIB.T6G(SCH_1):PVDDCR_CPU0_P0_PMSDA_R   I135 @T6G_MB_LIB.T6G(SCH_1):PAGE168
     5 NC_PVDDCR_CPU0_P0_PWM8 @T6G_MB_LIB.T6G(SCH_1):NC_PVDDCR_CPU0_P0_PWM8   I135 @T6G_MB_LIB.T6G(SCH_1):PAGE168
     6 NC_PVDDCR_CPU0_P0_PWM7 @T6G_MB_LIB.T6G(SCH_1):NC_PVDDCR_CPU0_P0_PWM7   I135 @T6G_MB_LIB.T6G(SCH_1):PAGE168
    25 VSENSE_PVDDCR_CPU0_P0_VSEN0 @T6G_MB_LIB.T6G(SCH_1):VSENSE_PVDDCR_CPU0_P0_VSEN0   I135 @T6G_MB_LIB.T6G(SCH_1):PAGE168
     2 PVDDCR_SOC_P0_PWM2 @T6G_MB_LIB.T6G(SCH_1):PVDDCR_SOC_P0_PWM2   I135 @T6G_MB_LIB.T6G(SCH_1):PAGE168
    16 PWRGD_PVDDCR_CPU0_P0_R @T6G_MB_LIB.T6G(SCH_1):PWRGD_PVDDCR_CPU0_P0_R   I135 @T6G_MB_LIB.T6G(SCH_1):PAGE168
     7 PVDDCR_CPU0_P0_PWM6 @T6G_MB_LIB.T6G(SCH_1):PVDDCR_CPU0_P0_PWM6   I135 @T6G_MB_LIB.T6G(SCH_1):PAGE168
    48 PVDDCR_CPU0_P0_VCCS @T6G_MB_LIB.T6G(SCH_1):PVDDCR_CPU0_P0_VCCS   I135 @T6G_MB_LIB.T6G(SCH_1):PAGE168
    45 PVDDCR_CPU0_P0_VMON @T6G_MB_LIB.T6G(SCH_1):PVDDCR_CPU0_P0_VMON   I135 @T6G_MB_LIB.T6G(SCH_1):PAGE168
    46 PVDDCR_CPU0_P0_VINSEN @T6G_MB_LIB.T6G(SCH_1):PVDDCR_CPU0_P0_VINSEN   I135 @T6G_MB_LIB.T6G(SCH_1):PAGE168
    44 PVDDCR_CPU0_P0_TEMP0 @T6G_MB_LIB.T6G(SCH_1):PVDDCR_CPU0_P0_TEMP0   I135 @T6G_MB_LIB.T6G(SCH_1):PAGE168
    19 PVDD18_S5_P0 @T6G_MB_LIB.T6G(SCH_1):PVDD18_S5_P0   I135 @T6G_MB_LIB.T6G(SCH_1):PAGE168
    40 VSENSE_PVDDCR_SOC_P0_VSEN1 @T6G_MB_LIB.T6G(SCH_1):VSENSE_PVDDCR_SOC_P0_VSEN1   I135 @T6G_MB_LIB.T6G(SCH_1):PAGE168
    39 VSENSE_VSS_SENSE_A_P0 @T6G_MB_LIB.T6G(SCH_1):VSENSE_VSS_SENSE_A_P0   I135 @T6G_MB_LIB.T6G(SCH_1):PAGE168
    37 PVDDCR_SOC_P0_IMON2 @T6G_MB_LIB.T6G(SCH_1):PVDDCR_SOC_P0_IMON2   I135 @T6G_MB_LIB.T6G(SCH_1):PAGE168
    12 PVDDCR_CPU0_P0_PWM1 @T6G_MB_LIB.T6G(SCH_1):PVDDCR_CPU0_P0_PWM1   I135 @T6G_MB_LIB.T6G(SCH_1):PAGE168
     4 NC_PVDDCR_CPU0_P0_PWM9 @T6G_MB_LIB.T6G(SCH_1):NC_PVDDCR_CPU0_P0_PWM9   I135 @T6G_MB_LIB.T6G(SCH_1):PAGE168
    35 NC_PVDDCR_CPU0_P0_IMON9 @T6G_MB_LIB.T6G(SCH_1):NC_PVDDCR_CPU0_P0_IMON9   I135 @T6G_MB_LIB.T6G(SCH_1):PAGE168
     3 PVDDCR_SOC_P0_PWM3 @T6G_MB_LIB.T6G(SCH_1):PVDDCR_SOC_P0_PWM3   I135 @T6G_MB_LIB.T6G(SCH_1):PAGE168
    36 PVDDCR_SOC_P0_IMON3 @T6G_MB_LIB.T6G(SCH_1):PVDDCR_SOC_P0_IMON3   I135 @T6G_MB_LIB.T6G(SCH_1):PAGE168
    41 PVDDCR_CPU0_P0_OCP_N_R @T6G_MB_LIB.T6G(SCH_1):PVDDCR_CPU0_P0_OCP_N_R   I135 @T6G_MB_LIB.T6G(SCH_1):PAGE168
    TH    GND @T6G_MB_LIB.T6G(SCH_1):GND   I135 @T6G_MB_LIB.T6G(SCH_1):PAGE168
    42 PVDDCR_SOC_P0_EN//ADDR_CFG @T6G_MB_LIB.T6G(SCH_1):PVDDCR_SOC_P0_EN//ADDR_CFG   I135 @T6G_MB_LIB.T6G(SCH_1):PAGE168
    43 PVDDCR_SOC_P0_TEMP1 @T6G_MB_LIB.T6G(SCH_1):PVDDCR_SOC_P0_TEMP1   I135 @T6G_MB_LIB.T6G(SCH_1):PAGE168
     1 PVDDCR_SOC_P0_PWM1 @T6G_MB_LIB.T6G(SCH_1):PVDDCR_SOC_P0_PWM1   I135 @T6G_MB_LIB.T6G(SCH_1):PAGE168
    38 PVDDCR_SOC_P0_IMON1 @T6G_MB_LIB.T6G(SCH_1):PVDDCR_SOC_P0_IMON1   I135 @T6G_MB_LIB.T6G(SCH_1):PAGE168
     8 PVDDCR_CPU0_P0_PWM5 @T6G_MB_LIB.T6G(SCH_1):PVDDCR_CPU0_P0_PWM5   I135 @T6G_MB_LIB.T6G(SCH_1):PAGE168
    31 PVDDCR_CPU0_P0_IMON5 @T6G_MB_LIB.T6G(SCH_1):PVDDCR_CPU0_P0_IMON5   I135 @T6G_MB_LIB.T6G(SCH_1):PAGE168
     9 PVDDCR_CPU0_P0_PWM4 @T6G_MB_LIB.T6G(SCH_1):PVDDCR_CPU0_P0_PWM4   I135 @T6G_MB_LIB.T6G(SCH_1):PAGE168
    30 PVDDCR_CPU0_P0_IMON4 @T6G_MB_LIB.T6G(SCH_1):PVDDCR_CPU0_P0_IMON4   I135 @T6G_MB_LIB.T6G(SCH_1):PAGE168
    10 PVDDCR_CPU0_P0_PWM3 @T6G_MB_LIB.T6G(SCH_1):PVDDCR_CPU0_P0_PWM3   I135 @T6G_MB_LIB.T6G(SCH_1):PAGE168
    29 PVDDCR_CPU0_P0_IMON3 @T6G_MB_LIB.T6G(SCH_1):PVDDCR_CPU0_P0_IMON3   I135 @T6G_MB_LIB.T6G(SCH_1):PAGE168
    11 PVDDCR_CPU0_P0_PWM2 @T6G_MB_LIB.T6G(SCH_1):PVDDCR_CPU0_P0_PWM2   I135 @T6G_MB_LIB.T6G(SCH_1):PAGE168
    28 PVDDCR_CPU0_P0_IMON2 @T6G_MB_LIB.T6G(SCH_1):PVDDCR_CPU0_P0_IMON2   I135 @T6G_MB_LIB.T6G(SCH_1):PAGE168

PU43 ISL99390FRZTR5935-ISL99390FRZ-TR5935,SMLF,IC,AL099A
    34 PVDDCR_CPU0_P0_PWM2 @T6G_MB_LIB.T6G(SCH_1):PVDDCR_CPU0_P0_PWM2    I16 @T6G_MB_LIB.T6G(SCH_1):PAGE169
    39 PVDDCR_CPU0_P0_VCCS @T6G_MB_LIB.T6G(SCH_1):PVDDCR_CPU0_P0_VCCS    I16 @T6G_MB_LIB.T6G(SCH_1):PAGE169
     3 PVDDCR_CPU0_P0_VCC2 @T6G_MB_LIB.T6G(SCH_1):PVDDCR_CPU0_P0_VCC2    I16 @T6G_MB_LIB.T6G(SCH_1):PAGE169
     2    GND @T6G_MB_LIB.T6G(SCH_1):GND    I16 @T6G_MB_LIB.T6G(SCH_1):PAGE169
    33 SW_PVDDCR_CPU0_P0_BOOT2 @T6G_MB_LIB.T6G(SCH_1):SW_PVDDCR_CPU0_P0_BOOT2    I16 @T6G_MB_LIB.T6G(SCH_1):PAGE169
 25_29 SW_P12V_AUX_PVDDCR_CPU0_P0_FLT @T6G_MB_LIB.T6G(SCH_1):SW_P12V_AUX_PVDDCR_CPU0_P0_FLT    I16 @T6G_MB_LIB.T6G(SCH_1):PAGE169
    32 SW_PVDDCR_CPU0_P0_PH2 @T6G_MB_LIB.T6G(SCH_1):SW_PVDDCR_CPU0_P0_PH2    I16 @T6G_MB_LIB.T6G(SCH_1):PAGE169
     4 PVDDCR_CPU0_P0_PVCC @T6G_MB_LIB.T6G(SCH_1):PVDDCR_CPU0_P0_PVCC    I16 @T6G_MB_LIB.T6G(SCH_1):PAGE169
    36 PVDDCR_CPU0_P0_TEMP0 @T6G_MB_LIB.T6G(SCH_1):PVDDCR_CPU0_P0_TEMP0    I16 @T6G_MB_LIB.T6G(SCH_1):PAGE169
    38 PVDDCR_CPU0_P0_IMON2 @T6G_MB_LIB.T6G(SCH_1):PVDDCR_CPU0_P0_IMON2    I16 @T6G_MB_LIB.T6G(SCH_1):PAGE169
    37 PVDDCR_CPU0_P0_LSET2 @T6G_MB_LIB.T6G(SCH_1):PVDDCR_CPU0_P0_LSET2    I16 @T6G_MB_LIB.T6G(SCH_1):PAGE169
 10_19 SW_PVDDCR_CPU0_P0_SW2 @T6G_MB_LIB.T6G(SCH_1):SW_PVDDCR_CPU0_P0_SW2    I16 @T6G_MB_LIB.T6G(SCH_1):PAGE169
     5    GND @T6G_MB_LIB.T6G(SCH_1):GND    I16 @T6G_MB_LIB.T6G(SCH_1):PAGE169
    30 SW_P12V_AUX_PVDDCR_CPU0_P0_FLT @T6G_MB_LIB.T6G(SCH_1):SW_P12V_AUX_PVDDCR_CPU0_P0_FLT    I16 @T6G_MB_LIB.T6G(SCH_1):PAGE169
     1 PVDDCR_CPU0_P0_VOS2 @T6G_MB_LIB.T6G(SCH_1):PVDDCR_CPU0_P0_VOS2    I16 @T6G_MB_LIB.T6G(SCH_1):PAGE169
    40    GND @T6G_MB_LIB.T6G(SCH_1):GND    I16 @T6G_MB_LIB.T6G(SCH_1):PAGE169
    35 PVDDCR_CPU0_P0_VCC2 @T6G_MB_LIB.T6G(SCH_1):PVDDCR_CPU0_P0_VCC2    I16 @T6G_MB_LIB.T6G(SCH_1):PAGE169
    31 NC_PVDDCR_CPU0_P0_DNC2 @T6G_MB_LIB.T6G(SCH_1):NC_PVDDCR_CPU0_P0_DNC2    I16 @T6G_MB_LIB.T6G(SCH_1):PAGE169
     6 NC_PVDDCR_CPU0_P0_GL1_2 @T6G_MB_LIB.T6G(SCH_1):NC_PVDDCR_CPU0_P0_GL1_2    I16 @T6G_MB_LIB.T6G(SCH_1):PAGE169
    41 NC_PVDDCR_CPU0_P0_GL2_2 @T6G_MB_LIB.T6G(SCH_1):NC_PVDDCR_CPU0_P0_GL2_2    I16 @T6G_MB_LIB.T6G(SCH_1):PAGE169
7_9-20_24    GND @T6G_MB_LIB.T6G(SCH_1):GND    I16 @T6G_MB_LIB.T6G(SCH_1):PAGE169

PU44 ISL99390FRZTR5935-ISL99390FRZ-TR5935,SMLF,IC,AL099A
    34 PVDD11_S3_P1_PWM1 @T6G_MB_LIB.T6G(SCH_1):PVDD11_S3_P1_PWM1    I22 @T6G_MB_LIB.T6G(SCH_1):PAGE200
    39 PVDD11_S3_P1_VCCS @T6G_MB_LIB.T6G(SCH_1):PVDD11_S3_P1_VCCS    I22 @T6G_MB_LIB.T6G(SCH_1):PAGE200
     3 PVDD11_S3_P1_VCC1 @T6G_MB_LIB.T6G(SCH_1):PVDD11_S3_P1_VCC1    I22 @T6G_MB_LIB.T6G(SCH_1):PAGE200
     2    GND @T6G_MB_LIB.T6G(SCH_1):GND    I22 @T6G_MB_LIB.T6G(SCH_1):PAGE200
    33 SW_PVDD11_S3_P1_BOOT1 @T6G_MB_LIB.T6G(SCH_1):SW_PVDD11_S3_P1_BOOT1    I22 @T6G_MB_LIB.T6G(SCH_1):PAGE200
 25_29 SW_P12V_AUX_PVDD11_S3_P1_FLT @T6G_MB_LIB.T6G(SCH_1):SW_P12V_AUX_PVDD11_S3_P1_FLT    I22 @T6G_MB_LIB.T6G(SCH_1):PAGE200
    32 SW_PVDD11_S3_P1_PH1 @T6G_MB_LIB.T6G(SCH_1):SW_PVDD11_S3_P1_PH1    I22 @T6G_MB_LIB.T6G(SCH_1):PAGE200
     4 PVDD11_S3_P1_PVCC @T6G_MB_LIB.T6G(SCH_1):PVDD11_S3_P1_PVCC    I22 @T6G_MB_LIB.T6G(SCH_1):PAGE200
    36 PVDD11_S3_P1_TEMP0 @T6G_MB_LIB.T6G(SCH_1):PVDD11_S3_P1_TEMP0    I22 @T6G_MB_LIB.T6G(SCH_1):PAGE200
    38 PVDD11_S3_P1_IMON1 @T6G_MB_LIB.T6G(SCH_1):PVDD11_S3_P1_IMON1    I22 @T6G_MB_LIB.T6G(SCH_1):PAGE200
    37 PVDD11_S3_P1_LSET1 @T6G_MB_LIB.T6G(SCH_1):PVDD11_S3_P1_LSET1    I22 @T6G_MB_LIB.T6G(SCH_1):PAGE200
 10_19 SW_PVDD11_S3_P1_SW1 @T6G_MB_LIB.T6G(SCH_1):SW_PVDD11_S3_P1_SW1    I22 @T6G_MB_LIB.T6G(SCH_1):PAGE200
     5    GND @T6G_MB_LIB.T6G(SCH_1):GND    I22 @T6G_MB_LIB.T6G(SCH_1):PAGE200
    30 SW_P12V_AUX_PVDD11_S3_P1_FLT @T6G_MB_LIB.T6G(SCH_1):SW_P12V_AUX_PVDD11_S3_P1_FLT    I22 @T6G_MB_LIB.T6G(SCH_1):PAGE200
     1 PVDD11_S3_P1_VOS1 @T6G_MB_LIB.T6G(SCH_1):PVDD11_S3_P1_VOS1    I22 @T6G_MB_LIB.T6G(SCH_1):PAGE200
    40    GND @T6G_MB_LIB.T6G(SCH_1):GND    I22 @T6G_MB_LIB.T6G(SCH_1):PAGE200
    35 PVDD11_S3_P1_VCC1 @T6G_MB_LIB.T6G(SCH_1):PVDD11_S3_P1_VCC1    I22 @T6G_MB_LIB.T6G(SCH_1):PAGE200
    31 NC_PVDD11_S3_P1_DNC1 @T6G_MB_LIB.T6G(SCH_1):NC_PVDD11_S3_P1_DNC1    I22 @T6G_MB_LIB.T6G(SCH_1):PAGE200
     6 NC_PVDD11_S3_P1_GL1_1 @T6G_MB_LIB.T6G(SCH_1):NC_PVDD11_S3_P1_GL1_1    I22 @T6G_MB_LIB.T6G(SCH_1):PAGE200
    41 NC_PVDD11_S3_P1_GL2_1 @T6G_MB_LIB.T6G(SCH_1):NC_PVDD11_S3_P1_GL2_1    I22 @T6G_MB_LIB.T6G(SCH_1):PAGE200
7_9-20_24    GND @T6G_MB_LIB.T6G(SCH_1):GND    I22 @T6G_MB_LIB.T6G(SCH_1):PAGE200

PU45 ISL99390FRZTR5935-ISL99390FRZ-TR5935,SMLF,IC,AL099A
    34 PVDD11_S3_P1_PWM2 @T6G_MB_LIB.T6G(SCH_1):PVDD11_S3_P1_PWM2    I92 @T6G_MB_LIB.T6G(SCH_1):PAGE200
    39 PVDD11_S3_P1_VCCS @T6G_MB_LIB.T6G(SCH_1):PVDD11_S3_P1_VCCS    I92 @T6G_MB_LIB.T6G(SCH_1):PAGE200
     3 PVDD11_S3_P1_VCC2 @T6G_MB_LIB.T6G(SCH_1):PVDD11_S3_P1_VCC2    I92 @T6G_MB_LIB.T6G(SCH_1):PAGE200
     2    GND @T6G_MB_LIB.T6G(SCH_1):GND    I92 @T6G_MB_LIB.T6G(SCH_1):PAGE200
    33 SW_PVDD11_S3_P1_BOOT2 @T6G_MB_LIB.T6G(SCH_1):SW_PVDD11_S3_P1_BOOT2    I92 @T6G_MB_LIB.T6G(SCH_1):PAGE200
 25_29 SW_P12V_AUX_PVDD11_S3_P1_FLT @T6G_MB_LIB.T6G(SCH_1):SW_P12V_AUX_PVDD11_S3_P1_FLT    I92 @T6G_MB_LIB.T6G(SCH_1):PAGE200
    32 SW_PVDD11_S3_P1_PH2 @T6G_MB_LIB.T6G(SCH_1):SW_PVDD11_S3_P1_PH2    I92 @T6G_MB_LIB.T6G(SCH_1):PAGE200
     4 PVDD11_S3_P1_PVCC @T6G_MB_LIB.T6G(SCH_1):PVDD11_S3_P1_PVCC    I92 @T6G_MB_LIB.T6G(SCH_1):PAGE200
    36 PVDD11_S3_P1_TEMP0 @T6G_MB_LIB.T6G(SCH_1):PVDD11_S3_P1_TEMP0    I92 @T6G_MB_LIB.T6G(SCH_1):PAGE200
    38 PVDD11_S3_P1_IMON2 @T6G_MB_LIB.T6G(SCH_1):PVDD11_S3_P1_IMON2    I92 @T6G_MB_LIB.T6G(SCH_1):PAGE200
    37 PVDD11_S3_P1_LSET2 @T6G_MB_LIB.T6G(SCH_1):PVDD11_S3_P1_LSET2    I92 @T6G_MB_LIB.T6G(SCH_1):PAGE200
 10_19 SW_PVDD11_S3_P1_SW2 @T6G_MB_LIB.T6G(SCH_1):SW_PVDD11_S3_P1_SW2    I92 @T6G_MB_LIB.T6G(SCH_1):PAGE200
     5    GND @T6G_MB_LIB.T6G(SCH_1):GND    I92 @T6G_MB_LIB.T6G(SCH_1):PAGE200
    30 SW_P12V_AUX_PVDD11_S3_P1_FLT @T6G_MB_LIB.T6G(SCH_1):SW_P12V_AUX_PVDD11_S3_P1_FLT    I92 @T6G_MB_LIB.T6G(SCH_1):PAGE200
     1 PVDD11_S3_P1_VOS2 @T6G_MB_LIB.T6G(SCH_1):PVDD11_S3_P1_VOS2    I92 @T6G_MB_LIB.T6G(SCH_1):PAGE200
    40    GND @T6G_MB_LIB.T6G(SCH_1):GND    I92 @T6G_MB_LIB.T6G(SCH_1):PAGE200
    35 PVDD11_S3_P1_VCC2 @T6G_MB_LIB.T6G(SCH_1):PVDD11_S3_P1_VCC2    I92 @T6G_MB_LIB.T6G(SCH_1):PAGE200
    31 NC_PVDD11_S3_P1_DNC2 @T6G_MB_LIB.T6G(SCH_1):NC_PVDD11_S3_P1_DNC2    I92 @T6G_MB_LIB.T6G(SCH_1):PAGE200
     6 NC_PVDD11_S3_P1_GL1_2 @T6G_MB_LIB.T6G(SCH_1):NC_PVDD11_S3_P1_GL1_2    I92 @T6G_MB_LIB.T6G(SCH_1):PAGE200
    41 NC_PVDD11_S3_P1_GL2_2 @T6G_MB_LIB.T6G(SCH_1):NC_PVDD11_S3_P1_GL2_2    I92 @T6G_MB_LIB.T6G(SCH_1):PAGE200
7_9-20_24    GND @T6G_MB_LIB.T6G(SCH_1):GND    I92 @T6G_MB_LIB.T6G(SCH_1):PAGE200

PU46 ISL99390FRZTR5935-ISL99390FRZ-TR5935,SMLF,IC,AL099A
    34 PVDDCR_CPU0_P0_PWM3 @T6G_MB_LIB.T6G(SCH_1):PVDDCR_CPU0_P0_PWM3    I38 @T6G_MB_LIB.T6G(SCH_1):PAGE170
    39 PVDDCR_CPU0_P0_VCCS @T6G_MB_LIB.T6G(SCH_1):PVDDCR_CPU0_P0_VCCS    I38 @T6G_MB_LIB.T6G(SCH_1):PAGE170
     3 PVDDCR_CPU0_P0_VCC3 @T6G_MB_LIB.T6G(SCH_1):PVDDCR_CPU0_P0_VCC3    I38 @T6G_MB_LIB.T6G(SCH_1):PAGE170
     2    GND @T6G_MB_LIB.T6G(SCH_1):GND    I38 @T6G_MB_LIB.T6G(SCH_1):PAGE170
    33 SW_PVDDCR_CPU0_P0_BOOT3 @T6G_MB_LIB.T6G(SCH_1):SW_PVDDCR_CPU0_P0_BOOT3    I38 @T6G_MB_LIB.T6G(SCH_1):PAGE170
 25_29 SW_P12V_AUX_PVDDCR_CPU0_P0_FLT @T6G_MB_LIB.T6G(SCH_1):SW_P12V_AUX_PVDDCR_CPU0_P0_FLT    I38 @T6G_MB_LIB.T6G(SCH_1):PAGE170
    32 SW_PVDDCR_CPU0_P0_PH3 @T6G_MB_LIB.T6G(SCH_1):SW_PVDDCR_CPU0_P0_PH3    I38 @T6G_MB_LIB.T6G(SCH_1):PAGE170
     4 PVDDCR_CPU0_P0_PVCC @T6G_MB_LIB.T6G(SCH_1):PVDDCR_CPU0_P0_PVCC    I38 @T6G_MB_LIB.T6G(SCH_1):PAGE170
    36 PVDDCR_CPU0_P0_TEMP0 @T6G_MB_LIB.T6G(SCH_1):PVDDCR_CPU0_P0_TEMP0    I38 @T6G_MB_LIB.T6G(SCH_1):PAGE170
    38 PVDDCR_CPU0_P0_IMON3 @T6G_MB_LIB.T6G(SCH_1):PVDDCR_CPU0_P0_IMON3    I38 @T6G_MB_LIB.T6G(SCH_1):PAGE170
    37 PVDDCR_CPU0_P0_LSET3 @T6G_MB_LIB.T6G(SCH_1):PVDDCR_CPU0_P0_LSET3    I38 @T6G_MB_LIB.T6G(SCH_1):PAGE170
 10_19 SW_PVDDCR_CPU0_P0_SW3 @T6G_MB_LIB.T6G(SCH_1):SW_PVDDCR_CPU0_P0_SW3    I38 @T6G_MB_LIB.T6G(SCH_1):PAGE170
     5    GND @T6G_MB_LIB.T6G(SCH_1):GND    I38 @T6G_MB_LIB.T6G(SCH_1):PAGE170
    30 SW_P12V_AUX_PVDDCR_CPU0_P0_FLT @T6G_MB_LIB.T6G(SCH_1):SW_P12V_AUX_PVDDCR_CPU0_P0_FLT    I38 @T6G_MB_LIB.T6G(SCH_1):PAGE170
     1 PVDDCR_CPU0_P0_VOS3 @T6G_MB_LIB.T6G(SCH_1):PVDDCR_CPU0_P0_VOS3    I38 @T6G_MB_LIB.T6G(SCH_1):PAGE170
    40    GND @T6G_MB_LIB.T6G(SCH_1):GND    I38 @T6G_MB_LIB.T6G(SCH_1):PAGE170
    35 PVDDCR_CPU0_P0_VCC3 @T6G_MB_LIB.T6G(SCH_1):PVDDCR_CPU0_P0_VCC3    I38 @T6G_MB_LIB.T6G(SCH_1):PAGE170
    31 NC_PVDDCR_CPU0_P0_DNC3 @T6G_MB_LIB.T6G(SCH_1):NC_PVDDCR_CPU0_P0_DNC3    I38 @T6G_MB_LIB.T6G(SCH_1):PAGE170
     6 NC_PVDDCR_CPU0_P0_GL1_3 @T6G_MB_LIB.T6G(SCH_1):NC_PVDDCR_CPU0_P0_GL1_3    I38 @T6G_MB_LIB.T6G(SCH_1):PAGE170
    41 NC_PVDDCR_CPU0_P0_GL2_3 @T6G_MB_LIB.T6G(SCH_1):NC_PVDDCR_CPU0_P0_GL2_3    I38 @T6G_MB_LIB.T6G(SCH_1):PAGE170
7_9-20_24    GND @T6G_MB_LIB.T6G(SCH_1):GND    I38 @T6G_MB_LIB.T6G(SCH_1):PAGE170

PU47 ISL99390FRZTR5935-ISL99390FRZ-TR5935,SMLF,IC,AL099A
    34 PVDDCR_CPU0_P0_PWM4 @T6G_MB_LIB.T6G(SCH_1):PVDDCR_CPU0_P0_PWM4     I9 @T6G_MB_LIB.T6G(SCH_1):PAGE170
    39 PVDDCR_CPU0_P0_VCCS @T6G_MB_LIB.T6G(SCH_1):PVDDCR_CPU0_P0_VCCS     I9 @T6G_MB_LIB.T6G(SCH_1):PAGE170
     3 PVDDCR_CPU0_P0_VCC4 @T6G_MB_LIB.T6G(SCH_1):PVDDCR_CPU0_P0_VCC4     I9 @T6G_MB_LIB.T6G(SCH_1):PAGE170
     2    GND @T6G_MB_LIB.T6G(SCH_1):GND     I9 @T6G_MB_LIB.T6G(SCH_1):PAGE170
    33 SW_PVDDCR_CPU0_P0_BOOT4 @T6G_MB_LIB.T6G(SCH_1):SW_PVDDCR_CPU0_P0_BOOT4     I9 @T6G_MB_LIB.T6G(SCH_1):PAGE170
 25_29 SW_P12V_AUX_PVDDCR_CPU0_P0_FLT @T6G_MB_LIB.T6G(SCH_1):SW_P12V_AUX_PVDDCR_CPU0_P0_FLT     I9 @T6G_MB_LIB.T6G(SCH_1):PAGE170
    32 SW_PVDDCR_CPU0_P0_PH4 @T6G_MB_LIB.T6G(SCH_1):SW_PVDDCR_CPU0_P0_PH4     I9 @T6G_MB_LIB.T6G(SCH_1):PAGE170
     4 PVDDCR_CPU0_P0_PVCC @T6G_MB_LIB.T6G(SCH_1):PVDDCR_CPU0_P0_PVCC     I9 @T6G_MB_LIB.T6G(SCH_1):PAGE170
    36 PVDDCR_CPU0_P0_TEMP0 @T6G_MB_LIB.T6G(SCH_1):PVDDCR_CPU0_P0_TEMP0     I9 @T6G_MB_LIB.T6G(SCH_1):PAGE170
    38 PVDDCR_CPU0_P0_IMON4 @T6G_MB_LIB.T6G(SCH_1):PVDDCR_CPU0_P0_IMON4     I9 @T6G_MB_LIB.T6G(SCH_1):PAGE170
    37 PVDDCR_CPU0_P0_LSET4 @T6G_MB_LIB.T6G(SCH_1):PVDDCR_CPU0_P0_LSET4     I9 @T6G_MB_LIB.T6G(SCH_1):PAGE170
 10_19 SW_PVDDCR_CPU0_P0_SW4 @T6G_MB_LIB.T6G(SCH_1):SW_PVDDCR_CPU0_P0_SW4     I9 @T6G_MB_LIB.T6G(SCH_1):PAGE170
     5    GND @T6G_MB_LIB.T6G(SCH_1):GND     I9 @T6G_MB_LIB.T6G(SCH_1):PAGE170
    30 SW_P12V_AUX_PVDDCR_CPU0_P0_FLT @T6G_MB_LIB.T6G(SCH_1):SW_P12V_AUX_PVDDCR_CPU0_P0_FLT     I9 @T6G_MB_LIB.T6G(SCH_1):PAGE170
     1 PVDDCR_CPU0_P0_VOS4 @T6G_MB_LIB.T6G(SCH_1):PVDDCR_CPU0_P0_VOS4     I9 @T6G_MB_LIB.T6G(SCH_1):PAGE170
    40    GND @T6G_MB_LIB.T6G(SCH_1):GND     I9 @T6G_MB_LIB.T6G(SCH_1):PAGE170
    35 PVDDCR_CPU0_P0_VCC4 @T6G_MB_LIB.T6G(SCH_1):PVDDCR_CPU0_P0_VCC4     I9 @T6G_MB_LIB.T6G(SCH_1):PAGE170
    31 NC_PVDDCR_CPU0_P0_DNC4 @T6G_MB_LIB.T6G(SCH_1):NC_PVDDCR_CPU0_P0_DNC4     I9 @T6G_MB_LIB.T6G(SCH_1):PAGE170
     6 NC_PVDDCR_CPU0_P0_GL1_4 @T6G_MB_LIB.T6G(SCH_1):NC_PVDDCR_CPU0_P0_GL1_4     I9 @T6G_MB_LIB.T6G(SCH_1):PAGE170
    41 NC_PVDDCR_CPU0_P0_GL2_4 @T6G_MB_LIB.T6G(SCH_1):NC_PVDDCR_CPU0_P0_GL2_4     I9 @T6G_MB_LIB.T6G(SCH_1):PAGE170
7_9-20_24    GND @T6G_MB_LIB.T6G(SCH_1):GND     I9 @T6G_MB_LIB.T6G(SCH_1):PAGE170

PU48 ISL99390FRZTR5935-ISL99390FRZ-TR5935,SMLF,IC,AL099A
    34 PVDDCR_CPU0_P0_PWM5 @T6G_MB_LIB.T6G(SCH_1):PVDDCR_CPU0_P0_PWM5    I18 @T6G_MB_LIB.T6G(SCH_1):PAGE171
    39 PVDDCR_CPU0_P0_VCCS @T6G_MB_LIB.T6G(SCH_1):PVDDCR_CPU0_P0_VCCS    I18 @T6G_MB_LIB.T6G(SCH_1):PAGE171
     3 PVDDCR_CPU0_P0_VCC5 @T6G_MB_LIB.T6G(SCH_1):PVDDCR_CPU0_P0_VCC5    I18 @T6G_MB_LIB.T6G(SCH_1):PAGE171
     2    GND @T6G_MB_LIB.T6G(SCH_1):GND    I18 @T6G_MB_LIB.T6G(SCH_1):PAGE171
    33 SW_PVDDCR_CPU0_P0_BOOT5 @T6G_MB_LIB.T6G(SCH_1):SW_PVDDCR_CPU0_P0_BOOT5    I18 @T6G_MB_LIB.T6G(SCH_1):PAGE171
 25_29 SW_P12V_AUX_PVDDCR_CPU0_P0_FLT @T6G_MB_LIB.T6G(SCH_1):SW_P12V_AUX_PVDDCR_CPU0_P0_FLT    I18 @T6G_MB_LIB.T6G(SCH_1):PAGE171
    32 SW_PVDDCR_CPU0_P0_PH5 @T6G_MB_LIB.T6G(SCH_1):SW_PVDDCR_CPU0_P0_PH5    I18 @T6G_MB_LIB.T6G(SCH_1):PAGE171
     4 PVDDCR_CPU0_P0_PVCC @T6G_MB_LIB.T6G(SCH_1):PVDDCR_CPU0_P0_PVCC    I18 @T6G_MB_LIB.T6G(SCH_1):PAGE171
    36 PVDDCR_CPU0_P0_TEMP0 @T6G_MB_LIB.T6G(SCH_1):PVDDCR_CPU0_P0_TEMP0    I18 @T6G_MB_LIB.T6G(SCH_1):PAGE171
    38 PVDDCR_CPU0_P0_IMON5 @T6G_MB_LIB.T6G(SCH_1):PVDDCR_CPU0_P0_IMON5    I18 @T6G_MB_LIB.T6G(SCH_1):PAGE171
    37 PVDDCR_CPU0_P0_LSET5 @T6G_MB_LIB.T6G(SCH_1):PVDDCR_CPU0_P0_LSET5    I18 @T6G_MB_LIB.T6G(SCH_1):PAGE171
 10_19 SW_PVDDCR_CPU0_P0_SW5 @T6G_MB_LIB.T6G(SCH_1):SW_PVDDCR_CPU0_P0_SW5    I18 @T6G_MB_LIB.T6G(SCH_1):PAGE171
     5    GND @T6G_MB_LIB.T6G(SCH_1):GND    I18 @T6G_MB_LIB.T6G(SCH_1):PAGE171
    30 SW_P12V_AUX_PVDDCR_CPU0_P0_FLT @T6G_MB_LIB.T6G(SCH_1):SW_P12V_AUX_PVDDCR_CPU0_P0_FLT    I18 @T6G_MB_LIB.T6G(SCH_1):PAGE171
     1 PVDDCR_CPU0_P0_VOS5 @T6G_MB_LIB.T6G(SCH_1):PVDDCR_CPU0_P0_VOS5    I18 @T6G_MB_LIB.T6G(SCH_1):PAGE171
    40    GND @T6G_MB_LIB.T6G(SCH_1):GND    I18 @T6G_MB_LIB.T6G(SCH_1):PAGE171
    35 PVDDCR_CPU0_P0_VCC5 @T6G_MB_LIB.T6G(SCH_1):PVDDCR_CPU0_P0_VCC5    I18 @T6G_MB_LIB.T6G(SCH_1):PAGE171
    31 NC_PVDDCR_CPU0_P0_DNC5 @T6G_MB_LIB.T6G(SCH_1):NC_PVDDCR_CPU0_P0_DNC5    I18 @T6G_MB_LIB.T6G(SCH_1):PAGE171
     6 NC_PVDDCR_CPU0_P0_GL1_5 @T6G_MB_LIB.T6G(SCH_1):NC_PVDDCR_CPU0_P0_GL1_5    I18 @T6G_MB_LIB.T6G(SCH_1):PAGE171
    41 NC_PVDDCR_CPU0_P0_GL2_5 @T6G_MB_LIB.T6G(SCH_1):NC_PVDDCR_CPU0_P0_GL2_5    I18 @T6G_MB_LIB.T6G(SCH_1):PAGE171
7_9-20_24    GND @T6G_MB_LIB.T6G(SCH_1):GND    I18 @T6G_MB_LIB.T6G(SCH_1):PAGE171

PU49 ISL99390FRZTR5935-ISL99390FRZ-TR5935,SMLF,IC,AL099A
    34 PVDDCR_SOC_P0_PWM1 @T6G_MB_LIB.T6G(SCH_1):PVDDCR_SOC_P0_PWM1    I41 @T6G_MB_LIB.T6G(SCH_1):PAGE173
    39 PVDDCR_CPU0_P0_VCCS @T6G_MB_LIB.T6G(SCH_1):PVDDCR_CPU0_P0_VCCS    I41 @T6G_MB_LIB.T6G(SCH_1):PAGE173
     3 PVDDCR_SOC_P0_VCC1 @T6G_MB_LIB.T6G(SCH_1):PVDDCR_SOC_P0_VCC1    I41 @T6G_MB_LIB.T6G(SCH_1):PAGE173
     2    GND @T6G_MB_LIB.T6G(SCH_1):GND    I41 @T6G_MB_LIB.T6G(SCH_1):PAGE173
    33 SW_PVDDCR_SOC_P0_BOOT1 @T6G_MB_LIB.T6G(SCH_1):SW_PVDDCR_SOC_P0_BOOT1    I41 @T6G_MB_LIB.T6G(SCH_1):PAGE173
 25_29 SW_P12V_AUX_PVDDCR_SOC_P0_FLT @T6G_MB_LIB.T6G(SCH_1):SW_P12V_AUX_PVDDCR_SOC_P0_FLT    I41 @T6G_MB_LIB.T6G(SCH_1):PAGE173
    32 SW_PVDDCR_SOC_P0_PH1 @T6G_MB_LIB.T6G(SCH_1):SW_PVDDCR_SOC_P0_PH1    I41 @T6G_MB_LIB.T6G(SCH_1):PAGE173
     4 PVDDCR_CPU0_P0_PVCC @T6G_MB_LIB.T6G(SCH_1):PVDDCR_CPU0_P0_PVCC    I41 @T6G_MB_LIB.T6G(SCH_1):PAGE173
    36 PVDDCR_SOC_P0_TEMP1 @T6G_MB_LIB.T6G(SCH_1):PVDDCR_SOC_P0_TEMP1    I41 @T6G_MB_LIB.T6G(SCH_1):PAGE173
    38 PVDDCR_SOC_P0_IMON1 @T6G_MB_LIB.T6G(SCH_1):PVDDCR_SOC_P0_IMON1    I41 @T6G_MB_LIB.T6G(SCH_1):PAGE173
    37 PVDDCR_SOC_P0_LSET1 @T6G_MB_LIB.T6G(SCH_1):PVDDCR_SOC_P0_LSET1    I41 @T6G_MB_LIB.T6G(SCH_1):PAGE173
 10_19 SW_PVDDCR_SOC_P0_SW1 @T6G_MB_LIB.T6G(SCH_1):SW_PVDDCR_SOC_P0_SW1    I41 @T6G_MB_LIB.T6G(SCH_1):PAGE173
     5    GND @T6G_MB_LIB.T6G(SCH_1):GND    I41 @T6G_MB_LIB.T6G(SCH_1):PAGE173
    30 SW_P12V_AUX_PVDDCR_SOC_P0_FLT @T6G_MB_LIB.T6G(SCH_1):SW_P12V_AUX_PVDDCR_SOC_P0_FLT    I41 @T6G_MB_LIB.T6G(SCH_1):PAGE173
     1 PVDDCR_SOC_P0_VOS1 @T6G_MB_LIB.T6G(SCH_1):PVDDCR_SOC_P0_VOS1    I41 @T6G_MB_LIB.T6G(SCH_1):PAGE173
    40    GND @T6G_MB_LIB.T6G(SCH_1):GND    I41 @T6G_MB_LIB.T6G(SCH_1):PAGE173
    35 PVDDCR_SOC_P0_VCC1 @T6G_MB_LIB.T6G(SCH_1):PVDDCR_SOC_P0_VCC1    I41 @T6G_MB_LIB.T6G(SCH_1):PAGE173
    31 NC_PVDDCR_SOC_P0_DNC1 @T6G_MB_LIB.T6G(SCH_1):NC_PVDDCR_SOC_P0_DNC1    I41 @T6G_MB_LIB.T6G(SCH_1):PAGE173
     6 NC_PVDDCR_SOC_P0_GL1_1 @T6G_MB_LIB.T6G(SCH_1):NC_PVDDCR_SOC_P0_GL1_1    I41 @T6G_MB_LIB.T6G(SCH_1):PAGE173
    41 NC_PVDDCR_SOC_P0_GL2_1 @T6G_MB_LIB.T6G(SCH_1):NC_PVDDCR_SOC_P0_GL2_1    I41 @T6G_MB_LIB.T6G(SCH_1):PAGE173
7_9-20_24    GND @T6G_MB_LIB.T6G(SCH_1):GND    I41 @T6G_MB_LIB.T6G(SCH_1):PAGE173

PU50 ISL99390FRZTR5935-ISL99390FRZ-TR5935,SMLF,IC,AL099A
    34 PVDDCR_SOC_P0_PWM2 @T6G_MB_LIB.T6G(SCH_1):PVDDCR_SOC_P0_PWM2    I86 @T6G_MB_LIB.T6G(SCH_1):PAGE173
    39 PVDDCR_CPU0_P0_VCCS @T6G_MB_LIB.T6G(SCH_1):PVDDCR_CPU0_P0_VCCS    I86 @T6G_MB_LIB.T6G(SCH_1):PAGE173
     3 PVDDCR_SOC_P0_VCC2 @T6G_MB_LIB.T6G(SCH_1):PVDDCR_SOC_P0_VCC2    I86 @T6G_MB_LIB.T6G(SCH_1):PAGE173
     2    GND @T6G_MB_LIB.T6G(SCH_1):GND    I86 @T6G_MB_LIB.T6G(SCH_1):PAGE173
    33 SW_PVDDCR_SOC_P0_BOOT2 @T6G_MB_LIB.T6G(SCH_1):SW_PVDDCR_SOC_P0_BOOT2    I86 @T6G_MB_LIB.T6G(SCH_1):PAGE173
 25_29 SW_P12V_AUX_PVDDCR_SOC_P0_FLT @T6G_MB_LIB.T6G(SCH_1):SW_P12V_AUX_PVDDCR_SOC_P0_FLT    I86 @T6G_MB_LIB.T6G(SCH_1):PAGE173
    32 SW_PVDDCR_SOC_P0_PH2 @T6G_MB_LIB.T6G(SCH_1):SW_PVDDCR_SOC_P0_PH2    I86 @T6G_MB_LIB.T6G(SCH_1):PAGE173
     4 PVDDCR_CPU0_P0_PVCC @T6G_MB_LIB.T6G(SCH_1):PVDDCR_CPU0_P0_PVCC    I86 @T6G_MB_LIB.T6G(SCH_1):PAGE173
    36 PVDDCR_SOC_P0_TEMP1 @T6G_MB_LIB.T6G(SCH_1):PVDDCR_SOC_P0_TEMP1    I86 @T6G_MB_LIB.T6G(SCH_1):PAGE173
    38 PVDDCR_SOC_P0_IMON2 @T6G_MB_LIB.T6G(SCH_1):PVDDCR_SOC_P0_IMON2    I86 @T6G_MB_LIB.T6G(SCH_1):PAGE173
    37 PVDDCR_SOC_P0_LSET2 @T6G_MB_LIB.T6G(SCH_1):PVDDCR_SOC_P0_LSET2    I86 @T6G_MB_LIB.T6G(SCH_1):PAGE173
 10_19 SW_PVDDCR_SOC_P0_SW2 @T6G_MB_LIB.T6G(SCH_1):SW_PVDDCR_SOC_P0_SW2    I86 @T6G_MB_LIB.T6G(SCH_1):PAGE173
     5    GND @T6G_MB_LIB.T6G(SCH_1):GND    I86 @T6G_MB_LIB.T6G(SCH_1):PAGE173
    30 SW_P12V_AUX_PVDDCR_SOC_P0_FLT @T6G_MB_LIB.T6G(SCH_1):SW_P12V_AUX_PVDDCR_SOC_P0_FLT    I86 @T6G_MB_LIB.T6G(SCH_1):PAGE173
     1 PVDDCR_SOC_P0_VOS2 @T6G_MB_LIB.T6G(SCH_1):PVDDCR_SOC_P0_VOS2    I86 @T6G_MB_LIB.T6G(SCH_1):PAGE173
    40    GND @T6G_MB_LIB.T6G(SCH_1):GND    I86 @T6G_MB_LIB.T6G(SCH_1):PAGE173
    35 PVDDCR_SOC_P0_VCC2 @T6G_MB_LIB.T6G(SCH_1):PVDDCR_SOC_P0_VCC2    I86 @T6G_MB_LIB.T6G(SCH_1):PAGE173
    31 NC_PVDDCR_SOC_P0_DNC2 @T6G_MB_LIB.T6G(SCH_1):NC_PVDDCR_SOC_P0_DNC2    I86 @T6G_MB_LIB.T6G(SCH_1):PAGE173
     6 NC_PVDDCR_SOC_P0_GL1_2 @T6G_MB_LIB.T6G(SCH_1):NC_PVDDCR_SOC_P0_GL1_2    I86 @T6G_MB_LIB.T6G(SCH_1):PAGE173
    41 NC_PVDDCR_SOC_P0_GL2_2 @T6G_MB_LIB.T6G(SCH_1):NC_PVDDCR_SOC_P0_GL2_2    I86 @T6G_MB_LIB.T6G(SCH_1):PAGE173
7_9-20_24    GND @T6G_MB_LIB.T6G(SCH_1):GND    I86 @T6G_MB_LIB.T6G(SCH_1):PAGE173

PU51 ISL99390FRZTR5935-ISL99390FRZ-TR5935,SMLF,IC,AL099A
    34 PVDDCR_SOC_P0_PWM3 @T6G_MB_LIB.T6G(SCH_1):PVDDCR_SOC_P0_PWM3    I38 @T6G_MB_LIB.T6G(SCH_1):PAGE174
    39 PVDDCR_CPU0_P0_VCCS @T6G_MB_LIB.T6G(SCH_1):PVDDCR_CPU0_P0_VCCS    I38 @T6G_MB_LIB.T6G(SCH_1):PAGE174
     3 PVDDCR_SOC_P0_VCC3 @T6G_MB_LIB.T6G(SCH_1):PVDDCR_SOC_P0_VCC3    I38 @T6G_MB_LIB.T6G(SCH_1):PAGE174
     2    GND @T6G_MB_LIB.T6G(SCH_1):GND    I38 @T6G_MB_LIB.T6G(SCH_1):PAGE174
    33 SW_PVDDCR_SOC_P0_BOOT3 @T6G_MB_LIB.T6G(SCH_1):SW_PVDDCR_SOC_P0_BOOT3    I38 @T6G_MB_LIB.T6G(SCH_1):PAGE174
 25_29 SW_P12V_AUX_PVDDCR_SOC_P0_FLT @T6G_MB_LIB.T6G(SCH_1):SW_P12V_AUX_PVDDCR_SOC_P0_FLT    I38 @T6G_MB_LIB.T6G(SCH_1):PAGE174
    32 SW_PVDDCR_SOC_P0_PH3 @T6G_MB_LIB.T6G(SCH_1):SW_PVDDCR_SOC_P0_PH3    I38 @T6G_MB_LIB.T6G(SCH_1):PAGE174
     4 PVDDCR_CPU0_P0_PVCC @T6G_MB_LIB.T6G(SCH_1):PVDDCR_CPU0_P0_PVCC    I38 @T6G_MB_LIB.T6G(SCH_1):PAGE174
    36 PVDDCR_SOC_P0_TEMP1 @T6G_MB_LIB.T6G(SCH_1):PVDDCR_SOC_P0_TEMP1    I38 @T6G_MB_LIB.T6G(SCH_1):PAGE174
    38 PVDDCR_SOC_P0_IMON3 @T6G_MB_LIB.T6G(SCH_1):PVDDCR_SOC_P0_IMON3    I38 @T6G_MB_LIB.T6G(SCH_1):PAGE174
    37 PVDDCR_SOC_P0_LSET3 @T6G_MB_LIB.T6G(SCH_1):PVDDCR_SOC_P0_LSET3    I38 @T6G_MB_LIB.T6G(SCH_1):PAGE174
 10_19 SW_PVDDCR_SOC_P0_SW3 @T6G_MB_LIB.T6G(SCH_1):SW_PVDDCR_SOC_P0_SW3    I38 @T6G_MB_LIB.T6G(SCH_1):PAGE174
     5    GND @T6G_MB_LIB.T6G(SCH_1):GND    I38 @T6G_MB_LIB.T6G(SCH_1):PAGE174
    30 SW_P12V_AUX_PVDDCR_SOC_P0_FLT @T6G_MB_LIB.T6G(SCH_1):SW_P12V_AUX_PVDDCR_SOC_P0_FLT    I38 @T6G_MB_LIB.T6G(SCH_1):PAGE174
     1 PVDDCR_SOC_P0_VOS3 @T6G_MB_LIB.T6G(SCH_1):PVDDCR_SOC_P0_VOS3    I38 @T6G_MB_LIB.T6G(SCH_1):PAGE174
    40    GND @T6G_MB_LIB.T6G(SCH_1):GND    I38 @T6G_MB_LIB.T6G(SCH_1):PAGE174
    35 PVDDCR_SOC_P0_VCC3 @T6G_MB_LIB.T6G(SCH_1):PVDDCR_SOC_P0_VCC3    I38 @T6G_MB_LIB.T6G(SCH_1):PAGE174
    31 NC_PVDDCR_SOC_P0_DNC3 @T6G_MB_LIB.T6G(SCH_1):NC_PVDDCR_SOC_P0_DNC3    I38 @T6G_MB_LIB.T6G(SCH_1):PAGE174
     6 NC_PVDDCR_SOC_P0_GL1_3 @T6G_MB_LIB.T6G(SCH_1):NC_PVDDCR_SOC_P0_GL1_3    I38 @T6G_MB_LIB.T6G(SCH_1):PAGE174
    41 NC_PVDDCR_SOC_P0_GL2_3 @T6G_MB_LIB.T6G(SCH_1):NC_PVDDCR_SOC_P0_GL2_3    I38 @T6G_MB_LIB.T6G(SCH_1):PAGE174
7_9-20_24    GND @T6G_MB_LIB.T6G(SCH_1):GND    I38 @T6G_MB_LIB.T6G(SCH_1):PAGE174

PU52 ISL99390FRZTR5935-ISL99390FRZ-TR5935,SMLF,IC,AL099A
    34 PVDDIO_P1_PWM3 @T6G_MB_LIB.T6G(SCH_1):PVDDIO_P1_PWM3    I73 @T6G_MB_LIB.T6G(SCH_1):PAGE198
    39 PVDDCR_CPU1_P1_VCCS @T6G_MB_LIB.T6G(SCH_1):PVDDCR_CPU1_P1_VCCS    I73 @T6G_MB_LIB.T6G(SCH_1):PAGE198
     3 PVDDIO_P1_VCC3 @T6G_MB_LIB.T6G(SCH_1):PVDDIO_P1_VCC3    I73 @T6G_MB_LIB.T6G(SCH_1):PAGE198
     2    GND @T6G_MB_LIB.T6G(SCH_1):GND    I73 @T6G_MB_LIB.T6G(SCH_1):PAGE198
    33 SW_PVDDIO_P1_BOOT3 @T6G_MB_LIB.T6G(SCH_1):SW_PVDDIO_P1_BOOT3    I73 @T6G_MB_LIB.T6G(SCH_1):PAGE198
 25_29 SW_P12V_AUX_PVDDIO_P1_FLT @T6G_MB_LIB.T6G(SCH_1):SW_P12V_AUX_PVDDIO_P1_FLT    I73 @T6G_MB_LIB.T6G(SCH_1):PAGE198
    32 SW_PVDDIO_P1_BOOTR3 @T6G_MB_LIB.T6G(SCH_1):SW_PVDDIO_P1_BOOTR3    I73 @T6G_MB_LIB.T6G(SCH_1):PAGE198
     4 PVDDCR_CPU1_P1_PVCC @T6G_MB_LIB.T6G(SCH_1):PVDDCR_CPU1_P1_PVCC    I73 @T6G_MB_LIB.T6G(SCH_1):PAGE198
    36 PVDDIO_P1_TEMP1 @T6G_MB_LIB.T6G(SCH_1):PVDDIO_P1_TEMP1    I73 @T6G_MB_LIB.T6G(SCH_1):PAGE198
    38 PVDDIO_P1_IMON3 @T6G_MB_LIB.T6G(SCH_1):PVDDIO_P1_IMON3    I73 @T6G_MB_LIB.T6G(SCH_1):PAGE198
    37 PVDDIO_P1_LSET3 @T6G_MB_LIB.T6G(SCH_1):PVDDIO_P1_LSET3    I73 @T6G_MB_LIB.T6G(SCH_1):PAGE198
 10_19 SW_PVDDIO_P1_SW3 @T6G_MB_LIB.T6G(SCH_1):SW_PVDDIO_P1_SW3    I73 @T6G_MB_LIB.T6G(SCH_1):PAGE198
     5    GND @T6G_MB_LIB.T6G(SCH_1):GND    I73 @T6G_MB_LIB.T6G(SCH_1):PAGE198
    30 SW_P12V_AUX_PVDDIO_P1_FLT @T6G_MB_LIB.T6G(SCH_1):SW_P12V_AUX_PVDDIO_P1_FLT    I73 @T6G_MB_LIB.T6G(SCH_1):PAGE198
     1 PVDDIO_P1_VOS3 @T6G_MB_LIB.T6G(SCH_1):PVDDIO_P1_VOS3    I73 @T6G_MB_LIB.T6G(SCH_1):PAGE198
    40    GND @T6G_MB_LIB.T6G(SCH_1):GND    I73 @T6G_MB_LIB.T6G(SCH_1):PAGE198
    35 PVDDIO_P1_VCC3 @T6G_MB_LIB.T6G(SCH_1):PVDDIO_P1_VCC3    I73 @T6G_MB_LIB.T6G(SCH_1):PAGE198
    31 NC_PVDDIO_P1_DNC3 @T6G_MB_LIB.T6G(SCH_1):NC_PVDDIO_P1_DNC3    I73 @T6G_MB_LIB.T6G(SCH_1):PAGE198
     6 NC_PVDDIO_P1_GL1_3 @T6G_MB_LIB.T6G(SCH_1):NC_PVDDIO_P1_GL1_3    I73 @T6G_MB_LIB.T6G(SCH_1):PAGE198
    41 NC_PVDDIO_P1_GL2_3 @T6G_MB_LIB.T6G(SCH_1):NC_PVDDIO_P1_GL2_3    I73 @T6G_MB_LIB.T6G(SCH_1):PAGE198
7_9-20_24    GND @T6G_MB_LIB.T6G(SCH_1):GND    I73 @T6G_MB_LIB.T6G(SCH_1):PAGE198

PU53 ISL99390FRZTR5935-ISL99390FRZ-TR5935,SMLF,IC,AL099A
    34 PVDDIO_P1_PWM4 @T6G_MB_LIB.T6G(SCH_1):PVDDIO_P1_PWM4    I15 @T6G_MB_LIB.T6G(SCH_1):PAGE198
    39 PVDDCR_CPU1_P1_VCCS @T6G_MB_LIB.T6G(SCH_1):PVDDCR_CPU1_P1_VCCS    I15 @T6G_MB_LIB.T6G(SCH_1):PAGE198
     3 PVDDIO_P1_VCC4 @T6G_MB_LIB.T6G(SCH_1):PVDDIO_P1_VCC4    I15 @T6G_MB_LIB.T6G(SCH_1):PAGE198
     2    GND @T6G_MB_LIB.T6G(SCH_1):GND    I15 @T6G_MB_LIB.T6G(SCH_1):PAGE198
    33 SW_PVDDIO_P1_BOOT4 @T6G_MB_LIB.T6G(SCH_1):SW_PVDDIO_P1_BOOT4    I15 @T6G_MB_LIB.T6G(SCH_1):PAGE198
 25_29 SW_P12V_AUX_PVDDIO_P1_FLT @T6G_MB_LIB.T6G(SCH_1):SW_P12V_AUX_PVDDIO_P1_FLT    I15 @T6G_MB_LIB.T6G(SCH_1):PAGE198
    32 SW_PVDDIO_P1_BOOTR4 @T6G_MB_LIB.T6G(SCH_1):SW_PVDDIO_P1_BOOTR4    I15 @T6G_MB_LIB.T6G(SCH_1):PAGE198
     4 PVDDCR_CPU1_P1_PVCC @T6G_MB_LIB.T6G(SCH_1):PVDDCR_CPU1_P1_PVCC    I15 @T6G_MB_LIB.T6G(SCH_1):PAGE198
    36 PVDDIO_P1_TEMP1 @T6G_MB_LIB.T6G(SCH_1):PVDDIO_P1_TEMP1    I15 @T6G_MB_LIB.T6G(SCH_1):PAGE198
    38 PVDDIO_P1_IMON4 @T6G_MB_LIB.T6G(SCH_1):PVDDIO_P1_IMON4    I15 @T6G_MB_LIB.T6G(SCH_1):PAGE198
    37 PVDDIO_P1_LSET4 @T6G_MB_LIB.T6G(SCH_1):PVDDIO_P1_LSET4    I15 @T6G_MB_LIB.T6G(SCH_1):PAGE198
 10_19 SW_PVDDIO_P1_SW4 @T6G_MB_LIB.T6G(SCH_1):SW_PVDDIO_P1_SW4    I15 @T6G_MB_LIB.T6G(SCH_1):PAGE198
     5    GND @T6G_MB_LIB.T6G(SCH_1):GND    I15 @T6G_MB_LIB.T6G(SCH_1):PAGE198
    30 SW_P12V_AUX_PVDDIO_P1_FLT @T6G_MB_LIB.T6G(SCH_1):SW_P12V_AUX_PVDDIO_P1_FLT    I15 @T6G_MB_LIB.T6G(SCH_1):PAGE198
     1 PVDDIO_P1_VOS4 @T6G_MB_LIB.T6G(SCH_1):PVDDIO_P1_VOS4    I15 @T6G_MB_LIB.T6G(SCH_1):PAGE198
    40    GND @T6G_MB_LIB.T6G(SCH_1):GND    I15 @T6G_MB_LIB.T6G(SCH_1):PAGE198
    35 PVDDIO_P1_VCC4 @T6G_MB_LIB.T6G(SCH_1):PVDDIO_P1_VCC4    I15 @T6G_MB_LIB.T6G(SCH_1):PAGE198
    31 NC_PVDDIO_P1_DNC4 @T6G_MB_LIB.T6G(SCH_1):NC_PVDDIO_P1_DNC4    I15 @T6G_MB_LIB.T6G(SCH_1):PAGE198
     6 NC_PVDDIO_P1_GL1_4 @T6G_MB_LIB.T6G(SCH_1):NC_PVDDIO_P1_GL1_4    I15 @T6G_MB_LIB.T6G(SCH_1):PAGE198
    41 NC_PVDDIO_P1_GL2_4 @T6G_MB_LIB.T6G(SCH_1):NC_PVDDIO_P1_GL2_4    I15 @T6G_MB_LIB.T6G(SCH_1):PAGE198
7_9-20_24    GND @T6G_MB_LIB.T6G(SCH_1):GND    I15 @T6G_MB_LIB.T6G(SCH_1):PAGE198

PU54 RAA229621GNPHA0-RAA229621GNP#HA0,SMLF,IC,ARF0TGP40A
    23 PVDD11_S3_P1_IMON1 @T6G_MB_LIB.T6G(SCH_1):PVDD11_S3_P1_IMON1    I86 @T6G_MB_LIB.T6G(SCH_1):PAGE199
    39 PVDD11_S3_P1_VCC @T6G_MB_LIB.T6G(SCH_1):PVDD11_S3_P1_VCC    I86 @T6G_MB_LIB.T6G(SCH_1):PAGE199
    20    GND @T6G_MB_LIB.T6G(SCH_1):GND    I86 @T6G_MB_LIB.T6G(SCH_1):PAGE199
    10 PVDD11_S3_P1_PMSCL_R @T6G_MB_LIB.T6G(SCH_1):PVDD11_S3_P1_PMSCL_R    I86 @T6G_MB_LIB.T6G(SCH_1):PAGE199
    18    GND @T6G_MB_LIB.T6G(SCH_1):GND    I86 @T6G_MB_LIB.T6G(SCH_1):PAGE199
    24 PVDD11_S3_P1_IMON2 @T6G_MB_LIB.T6G(SCH_1):PVDD11_S3_P1_IMON2    I86 @T6G_MB_LIB.T6G(SCH_1):PAGE199
    19 NC_PVDD11_S3_P1_SVTO @T6G_MB_LIB.T6G(SCH_1):NC_PVDD11_S3_P1_SVTO    I86 @T6G_MB_LIB.T6G(SCH_1):PAGE199
    14 PVDD11_S3_P1_RESET_N_R @T6G_MB_LIB.T6G(SCH_1):PVDD11_S3_P1_RESET_N_R    I86 @T6G_MB_LIB.T6G(SCH_1):PAGE199
    25 NC_PVDD11_S3_P1_IMON3 @T6G_MB_LIB.T6G(SCH_1):NC_PVDD11_S3_P1_IMON3    I86 @T6G_MB_LIB.T6G(SCH_1):PAGE199
    26 NC_PVDD11_S3_P1_IMON4 @T6G_MB_LIB.T6G(SCH_1):NC_PVDD11_S3_P1_IMON4    I86 @T6G_MB_LIB.T6G(SCH_1):PAGE199
    16 NC_PVDD11_S3_P1_PG1 @T6G_MB_LIB.T6G(SCH_1):NC_PVDD11_S3_P1_PG1    I86 @T6G_MB_LIB.T6G(SCH_1):PAGE199
    17    GND @T6G_MB_LIB.T6G(SCH_1):GND    I86 @T6G_MB_LIB.T6G(SCH_1):PAGE199
    11 PVDD11_S3_P1_PMALERT_R @T6G_MB_LIB.T6G(SCH_1):PVDD11_S3_P1_PMALERT_R    I86 @T6G_MB_LIB.T6G(SCH_1):PAGE199
    13 PVDD11_S3_P1_EN_R @T6G_MB_LIB.T6G(SCH_1):PVDD11_S3_P1_EN_R    I86 @T6G_MB_LIB.T6G(SCH_1):PAGE199
    22 VSENSE_VSS_SENSE_C_P1 @T6G_MB_LIB.T6G(SCH_1):VSENSE_VSS_SENSE_C_P1    I86 @T6G_MB_LIB.T6G(SCH_1):PAGE199
     9 PVDD11_S3_P1_PMSDA_R @T6G_MB_LIB.T6G(SCH_1):PVDD11_S3_P1_PMSDA_R    I86 @T6G_MB_LIB.T6G(SCH_1):PAGE199
     5 NC_PVDD11_S3_P1_PWM4 @T6G_MB_LIB.T6G(SCH_1):NC_PVDD11_S3_P1_PWM4    I86 @T6G_MB_LIB.T6G(SCH_1):PAGE199
     6 NC_PVDD11_S3_P1_PWM3 @T6G_MB_LIB.T6G(SCH_1):NC_PVDD11_S3_P1_PWM3    I86 @T6G_MB_LIB.T6G(SCH_1):PAGE199
    21 VSENSE_PVDD11_S3_P1_R @T6G_MB_LIB.T6G(SCH_1):VSENSE_PVDD11_S3_P1_R    I86 @T6G_MB_LIB.T6G(SCH_1):PAGE199
     2 NC_PVDD11_S3_P1_PWM7 @T6G_MB_LIB.T6G(SCH_1):NC_PVDD11_S3_P1_PWM7    I86 @T6G_MB_LIB.T6G(SCH_1):PAGE199
    12 PWRGD_PVDD11_S3_P1_R @T6G_MB_LIB.T6G(SCH_1):PWRGD_PVDD11_S3_P1_R    I86 @T6G_MB_LIB.T6G(SCH_1):PAGE199
     7 PVDD11_S3_P1_PWM2 @T6G_MB_LIB.T6G(SCH_1):PVDD11_S3_P1_PWM2    I86 @T6G_MB_LIB.T6G(SCH_1):PAGE199
    40 PVDD11_S3_P1_VCCS @T6G_MB_LIB.T6G(SCH_1):PVDD11_S3_P1_VCCS    I86 @T6G_MB_LIB.T6G(SCH_1):PAGE199
    37 PVDD11_S3_P1_VMON @T6G_MB_LIB.T6G(SCH_1):PVDD11_S3_P1_VMON    I86 @T6G_MB_LIB.T6G(SCH_1):PAGE199
    38 PVDD11_S3_P1_VINSEN @T6G_MB_LIB.T6G(SCH_1):PVDD11_S3_P1_VINSEN    I86 @T6G_MB_LIB.T6G(SCH_1):PAGE199
    36 PVDD11_S3_P1_TEMP0 @T6G_MB_LIB.T6G(SCH_1):PVDD11_S3_P1_TEMP0    I86 @T6G_MB_LIB.T6G(SCH_1):PAGE199
    15 PVDD11_S3_P1_VDDIO @T6G_MB_LIB.T6G(SCH_1):PVDD11_S3_P1_VDDIO    I86 @T6G_MB_LIB.T6G(SCH_1):PAGE199
    32    GND @T6G_MB_LIB.T6G(SCH_1):GND    I86 @T6G_MB_LIB.T6G(SCH_1):PAGE199
    31    GND @T6G_MB_LIB.T6G(SCH_1):GND    I86 @T6G_MB_LIB.T6G(SCH_1):PAGE199
    29 NC_PVDD11_S3_P1_IMON7 @T6G_MB_LIB.T6G(SCH_1):NC_PVDD11_S3_P1_IMON7    I86 @T6G_MB_LIB.T6G(SCH_1):PAGE199
     8 PVDD11_S3_P1_PWM1 @T6G_MB_LIB.T6G(SCH_1):PVDD11_S3_P1_PWM1    I86 @T6G_MB_LIB.T6G(SCH_1):PAGE199
     4 NC_PVDD11_S3_P1_PWM5 @T6G_MB_LIB.T6G(SCH_1):NC_PVDD11_S3_P1_PWM5    I86 @T6G_MB_LIB.T6G(SCH_1):PAGE199
    27 NC_PVDD11_S3_P1_IMON5 @T6G_MB_LIB.T6G(SCH_1):NC_PVDD11_S3_P1_IMON5    I86 @T6G_MB_LIB.T6G(SCH_1):PAGE199
     3 NC_PVDD11_S3_P1_PWM6 @T6G_MB_LIB.T6G(SCH_1):NC_PVDD11_S3_P1_PWM6    I86 @T6G_MB_LIB.T6G(SCH_1):PAGE199
    28 NC_PVDD11_S3_P1_IMON6 @T6G_MB_LIB.T6G(SCH_1):NC_PVDD11_S3_P1_IMON6    I86 @T6G_MB_LIB.T6G(SCH_1):PAGE199
    33 PVDD11_S3_P1_OCP_N_R @T6G_MB_LIB.T6G(SCH_1):PVDD11_S3_P1_OCP_N_R    I86 @T6G_MB_LIB.T6G(SCH_1):PAGE199
    TH    GND @T6G_MB_LIB.T6G(SCH_1):GND    I86 @T6G_MB_LIB.T6G(SCH_1):PAGE199
    34 PVDD11_S3_P1_ADDR_CFG @T6G_MB_LIB.T6G(SCH_1):PVDD11_S3_P1_ADDR_CFG    I86 @T6G_MB_LIB.T6G(SCH_1):PAGE199
    35 PVDD11_S3_P1_TEMP1 @T6G_MB_LIB.T6G(SCH_1):PVDD11_S3_P1_TEMP1    I86 @T6G_MB_LIB.T6G(SCH_1):PAGE199
     1 NC_PVDD11_S3_P1_PWM8 @T6G_MB_LIB.T6G(SCH_1):NC_PVDD11_S3_P1_PWM8    I86 @T6G_MB_LIB.T6G(SCH_1):PAGE199
    30 NC_PVDD11_S3_P1_IMON8 @T6G_MB_LIB.T6G(SCH_1):NC_PVDD11_S3_P1_IMON8    I86 @T6G_MB_LIB.T6G(SCH_1):PAGE199

PU55 MPQ8633AGLEC807Z-MPQ8633AGLE-C807-Z,SMLF,IC,AL0086A
    10 SW_P12V_AUX_PVDD_33_S5_FLT @T6G_MB_LIB.T6G(SCH_1):SW_P12V_AUX_PVDD_33_S5_FLT    I41 @T6G_MB_LIB.T6G(SCH_1):PAGE167
     9 PWRGD_PVDD33_S5 @T6G_MB_LIB.T6G(SCH_1):PWRGD_PVDD33_S5    I41 @T6G_MB_LIB.T6G(SCH_1):PAGE167
 11_18    GND @T6G_MB_LIB.T6G(SCH_1):GND    I41 @T6G_MB_LIB.T6G(SCH_1):PAGE167
     8 PVDD33_S5_EN @T6G_MB_LIB.T6G(SCH_1):PVDD33_S5_EN    I41 @T6G_MB_LIB.T6G(SCH_1):PAGE167
     1 SW_PVDD_33_S5_BST @T6G_MB_LIB.T6G(SCH_1):SW_PVDD_33_S5_BST    I41 @T6G_MB_LIB.T6G(SCH_1):PAGE167
     7 PVDD_33_S5_FB @T6G_MB_LIB.T6G(SCH_1):PVDD_33_S5_FB    I41 @T6G_MB_LIB.T6G(SCH_1):PAGE167
     2    GND @T6G_MB_LIB.T6G(SCH_1):GND    I41 @T6G_MB_LIB.T6G(SCH_1):PAGE167
    19 PVDD_33_S5_VCC @T6G_MB_LIB.T6G(SCH_1):PVDD_33_S5_VCC    I41 @T6G_MB_LIB.T6G(SCH_1):PAGE167
     6    GND @T6G_MB_LIB.T6G(SCH_1):GND    I41 @T6G_MB_LIB.T6G(SCH_1):PAGE167
    20 SW_PVDD_33_S5_SW @T6G_MB_LIB.T6G(SCH_1):SW_PVDD_33_S5_SW    I41 @T6G_MB_LIB.T6G(SCH_1):PAGE167
     5 PVDD_33_S5_REF @T6G_MB_LIB.T6G(SCH_1):PVDD_33_S5_REF    I41 @T6G_MB_LIB.T6G(SCH_1):PAGE167
     4 PVDD_33_S5_MODE @T6G_MB_LIB.T6G(SCH_1):PVDD_33_S5_MODE    I41 @T6G_MB_LIB.T6G(SCH_1):PAGE167
     3 PVDD_33_S5_CS @T6G_MB_LIB.T6G(SCH_1):PVDD_33_S5_CS    I41 @T6G_MB_LIB.T6G(SCH_1):PAGE167
    21 SW_P12V_AUX_PVDD_33_S5_FLT @T6G_MB_LIB.T6G(SCH_1):SW_P12V_AUX_PVDD_33_S5_FLT    I41 @T6G_MB_LIB.T6G(SCH_1):PAGE167

PU57 MPQ8633BGLEC838Z-MPQ8633BGLE-C838-Z,SMLF,IC,AL0086A
    10 SW_P12V_AUX_PVDD18_S5_P0_FLT @T6G_MB_LIB.T6G(SCH_1):SW_P12V_AUX_PVDD18_S5_P0_FLT    I18 @T6G_MB_LIB.T6G(SCH_1):PAGE184
     9 PWRGD_PVDD18_S5_P0 @T6G_MB_LIB.T6G(SCH_1):PWRGD_PVDD18_S5_P0    I18 @T6G_MB_LIB.T6G(SCH_1):PAGE184
 11_18    GND @T6G_MB_LIB.T6G(SCH_1):GND    I18 @T6G_MB_LIB.T6G(SCH_1):PAGE184
     8 PVDD18_S5_P0_EN @T6G_MB_LIB.T6G(SCH_1):PVDD18_S5_P0_EN    I18 @T6G_MB_LIB.T6G(SCH_1):PAGE184
     1 SW_PVDD18_S5_P0_BST @T6G_MB_LIB.T6G(SCH_1):SW_PVDD18_S5_P0_BST    I18 @T6G_MB_LIB.T6G(SCH_1):PAGE184
     7 PVDD18_S5_P0_FB @T6G_MB_LIB.T6G(SCH_1):PVDD18_S5_P0_FB    I18 @T6G_MB_LIB.T6G(SCH_1):PAGE184
     2    GND @T6G_MB_LIB.T6G(SCH_1):GND    I18 @T6G_MB_LIB.T6G(SCH_1):PAGE184
    19 PVDD18_S5_P0_VCC @T6G_MB_LIB.T6G(SCH_1):PVDD18_S5_P0_VCC    I18 @T6G_MB_LIB.T6G(SCH_1):PAGE184
     6 PVDD18_S5_P0_RGND @T6G_MB_LIB.T6G(SCH_1):PVDD18_S5_P0_RGND    I18 @T6G_MB_LIB.T6G(SCH_1):PAGE184
    20 SW_PVDD18_S5_P0_SW @T6G_MB_LIB.T6G(SCH_1):SW_PVDD18_S5_P0_SW    I18 @T6G_MB_LIB.T6G(SCH_1):PAGE184
     5 PVDD18_S5_P0_REF @T6G_MB_LIB.T6G(SCH_1):PVDD18_S5_P0_REF    I18 @T6G_MB_LIB.T6G(SCH_1):PAGE184
     4 PVDD18_S5_P0_MODE @T6G_MB_LIB.T6G(SCH_1):PVDD18_S5_P0_MODE    I18 @T6G_MB_LIB.T6G(SCH_1):PAGE184
     3 PVDD18_S5_P0_CS @T6G_MB_LIB.T6G(SCH_1):PVDD18_S5_P0_CS    I18 @T6G_MB_LIB.T6G(SCH_1):PAGE184
    21 SW_P12V_AUX_PVDD18_S5_P0_FLT @T6G_MB_LIB.T6G(SCH_1):SW_P12V_AUX_PVDD18_S5_P0_FLT    I18 @T6G_MB_LIB.T6G(SCH_1):PAGE184

PU200 MAX15090BEWIT-MAX15090BEWI+T,SMLF,IC,AL015080B00
    A2 P3V3_OCP_VCC_2 @T6G_MB_LIB.T6G(SCH_1):P3V3_OCP_VCC_2    I89 @T6G_MB_LIB.T6G(SCH_1):PAGE343
    A3 P3V3_AUX @T6G_MB_LIB.T6G(SCH_1):P3V3_AUX    I89 @T6G_MB_LIB.T6G(SCH_1):PAGE343
    A5 P3V3_AUX @T6G_MB_LIB.T6G(SCH_1):P3V3_AUX    I89 @T6G_MB_LIB.T6G(SCH_1):PAGE343
    B3 P3V3_AUX @T6G_MB_LIB.T6G(SCH_1):P3V3_AUX    I89 @T6G_MB_LIB.T6G(SCH_1):PAGE343
    B5 P3V3_AUX @T6G_MB_LIB.T6G(SCH_1):P3V3_AUX    I89 @T6G_MB_LIB.T6G(SCH_1):PAGE343
    C3 P3V3_AUX @T6G_MB_LIB.T6G(SCH_1):P3V3_AUX    I89 @T6G_MB_LIB.T6G(SCH_1):PAGE343
    C5 P3V3_AUX @T6G_MB_LIB.T6G(SCH_1):P3V3_AUX    I89 @T6G_MB_LIB.T6G(SCH_1):PAGE343
    D5 P3V3_AUX @T6G_MB_LIB.T6G(SCH_1):P3V3_AUX    I89 @T6G_MB_LIB.T6G(SCH_1):PAGE343
    B1 P3V3_OCP_CB_2 @T6G_MB_LIB.T6G(SCH_1):P3V3_OCP_CB_2    I89 @T6G_MB_LIB.T6G(SCH_1):PAGE343
    B7    GND @T6G_MB_LIB.T6G(SCH_1):GND    I89 @T6G_MB_LIB.T6G(SCH_1):PAGE343
    D1 P3V3_OCP_REG_2 @T6G_MB_LIB.T6G(SCH_1):P3V3_OCP_REG_2    I89 @T6G_MB_LIB.T6G(SCH_1):PAGE343
    D2 P3V3_OCP_UV_2 @T6G_MB_LIB.T6G(SCH_1):P3V3_OCP_UV_2    I89 @T6G_MB_LIB.T6G(SCH_1):PAGE343
    D3 P3V3_OCP_OV_2 @T6G_MB_LIB.T6G(SCH_1):P3V3_OCP_OV_2    I89 @T6G_MB_LIB.T6G(SCH_1):PAGE343
    A1 P3V3_OCP_SENSE_2 @T6G_MB_LIB.T6G(SCH_1):P3V3_OCP_SENSE_2    I89 @T6G_MB_LIB.T6G(SCH_1):PAGE343
    A4 P3V3_OCP_V3_2_R @T6G_MB_LIB.T6G(SCH_1):P3V3_OCP_V3_2_R    I89 @T6G_MB_LIB.T6G(SCH_1):PAGE343
    B4 P3V3_OCP_V3_2_R @T6G_MB_LIB.T6G(SCH_1):P3V3_OCP_V3_2_R    I89 @T6G_MB_LIB.T6G(SCH_1):PAGE343
    B6 P3V3_OCP_V3_2_R @T6G_MB_LIB.T6G(SCH_1):P3V3_OCP_V3_2_R    I89 @T6G_MB_LIB.T6G(SCH_1):PAGE343
    C4 P3V3_OCP_V3_2_R @T6G_MB_LIB.T6G(SCH_1):P3V3_OCP_V3_2_R    I89 @T6G_MB_LIB.T6G(SCH_1):PAGE343
    C6 P3V3_OCP_V3_2_R @T6G_MB_LIB.T6G(SCH_1):P3V3_OCP_V3_2_R    I89 @T6G_MB_LIB.T6G(SCH_1):PAGE343
    D4 P3V3_OCP_V3_2_R @T6G_MB_LIB.T6G(SCH_1):P3V3_OCP_V3_2_R    I89 @T6G_MB_LIB.T6G(SCH_1):PAGE343
    D6 P3V3_OCP_V3_2_R @T6G_MB_LIB.T6G(SCH_1):P3V3_OCP_V3_2_R    I89 @T6G_MB_LIB.T6G(SCH_1):PAGE343
    A6 P3V3_OCP_GATE_2 @T6G_MB_LIB.T6G(SCH_1):P3V3_OCP_GATE_2    I89 @T6G_MB_LIB.T6G(SCH_1):PAGE343
    A7    GND @T6G_MB_LIB.T6G(SCH_1):GND    I89 @T6G_MB_LIB.T6G(SCH_1):PAGE343
    B2    GND @T6G_MB_LIB.T6G(SCH_1):GND    I89 @T6G_MB_LIB.T6G(SCH_1):PAGE343
    C1    GND @T6G_MB_LIB.T6G(SCH_1):GND    I89 @T6G_MB_LIB.T6G(SCH_1):PAGE343
    C2    GND @T6G_MB_LIB.T6G(SCH_1):GND    I89 @T6G_MB_LIB.T6G(SCH_1):PAGE343
    C7 P3V3_OCP_FAULT_2 @T6G_MB_LIB.T6G(SCH_1):P3V3_OCP_FAULT_2    I89 @T6G_MB_LIB.T6G(SCH_1):PAGE343
    D7 P3V3_OCP_PWRGD_2 @T6G_MB_LIB.T6G(SCH_1):P3V3_OCP_PWRGD_2    I89 @T6G_MB_LIB.T6G(SCH_1):PAGE343

PU201 MAX15090BEWIT-MAX15090BEWI+T,SMLF,IC,AL015080B00
    A2 P12V_OCP_VCC_2 @T6G_MB_LIB.T6G(SCH_1):P12V_OCP_VCC_2    I67 @T6G_MB_LIB.T6G(SCH_1):PAGE343
    A3 P12V_AUX @T6G_MB_LIB.T6G(SCH_1):P12V_AUX    I67 @T6G_MB_LIB.T6G(SCH_1):PAGE343
    A5 P12V_AUX @T6G_MB_LIB.T6G(SCH_1):P12V_AUX    I67 @T6G_MB_LIB.T6G(SCH_1):PAGE343
    B3 P12V_AUX @T6G_MB_LIB.T6G(SCH_1):P12V_AUX    I67 @T6G_MB_LIB.T6G(SCH_1):PAGE343
    B5 P12V_AUX @T6G_MB_LIB.T6G(SCH_1):P12V_AUX    I67 @T6G_MB_LIB.T6G(SCH_1):PAGE343
    C3 P12V_AUX @T6G_MB_LIB.T6G(SCH_1):P12V_AUX    I67 @T6G_MB_LIB.T6G(SCH_1):PAGE343
    C5 P12V_AUX @T6G_MB_LIB.T6G(SCH_1):P12V_AUX    I67 @T6G_MB_LIB.T6G(SCH_1):PAGE343
    D5 P12V_AUX @T6G_MB_LIB.T6G(SCH_1):P12V_AUX    I67 @T6G_MB_LIB.T6G(SCH_1):PAGE343
    B1 P12V_OCP_CB_2 @T6G_MB_LIB.T6G(SCH_1):P12V_OCP_CB_2    I67 @T6G_MB_LIB.T6G(SCH_1):PAGE343
    B7    GND @T6G_MB_LIB.T6G(SCH_1):GND    I67 @T6G_MB_LIB.T6G(SCH_1):PAGE343
    D1 P12V_OCP_REG_2 @T6G_MB_LIB.T6G(SCH_1):P12V_OCP_REG_2    I67 @T6G_MB_LIB.T6G(SCH_1):PAGE343
    D2 P12V_OCP_UV_2 @T6G_MB_LIB.T6G(SCH_1):P12V_OCP_UV_2    I67 @T6G_MB_LIB.T6G(SCH_1):PAGE343
    D3 P12V_OCP_OV_2 @T6G_MB_LIB.T6G(SCH_1):P12V_OCP_OV_2    I67 @T6G_MB_LIB.T6G(SCH_1):PAGE343
    A1 P12V_OCP_SENSE_2 @T6G_MB_LIB.T6G(SCH_1):P12V_OCP_SENSE_2    I67 @T6G_MB_LIB.T6G(SCH_1):PAGE343
    A4 P12V_OCP_V3_2 @T6G_MB_LIB.T6G(SCH_1):P12V_OCP_V3_2    I67 @T6G_MB_LIB.T6G(SCH_1):PAGE343
    B4 P12V_OCP_V3_2 @T6G_MB_LIB.T6G(SCH_1):P12V_OCP_V3_2    I67 @T6G_MB_LIB.T6G(SCH_1):PAGE343
    B6 P12V_OCP_V3_2 @T6G_MB_LIB.T6G(SCH_1):P12V_OCP_V3_2    I67 @T6G_MB_LIB.T6G(SCH_1):PAGE343
    C4 P12V_OCP_V3_2 @T6G_MB_LIB.T6G(SCH_1):P12V_OCP_V3_2    I67 @T6G_MB_LIB.T6G(SCH_1):PAGE343
    C6 P12V_OCP_V3_2 @T6G_MB_LIB.T6G(SCH_1):P12V_OCP_V3_2    I67 @T6G_MB_LIB.T6G(SCH_1):PAGE343
    D4 P12V_OCP_V3_2 @T6G_MB_LIB.T6G(SCH_1):P12V_OCP_V3_2    I67 @T6G_MB_LIB.T6G(SCH_1):PAGE343
    D6 P12V_OCP_V3_2 @T6G_MB_LIB.T6G(SCH_1):P12V_OCP_V3_2    I67 @T6G_MB_LIB.T6G(SCH_1):PAGE343
    A6 P12V_OCP_GATE_2 @T6G_MB_LIB.T6G(SCH_1):P12V_OCP_GATE_2    I67 @T6G_MB_LIB.T6G(SCH_1):PAGE343
    A7    GND @T6G_MB_LIB.T6G(SCH_1):GND    I67 @T6G_MB_LIB.T6G(SCH_1):PAGE343
    B2    GND @T6G_MB_LIB.T6G(SCH_1):GND    I67 @T6G_MB_LIB.T6G(SCH_1):PAGE343
    C1    GND @T6G_MB_LIB.T6G(SCH_1):GND    I67 @T6G_MB_LIB.T6G(SCH_1):PAGE343
    C2    GND @T6G_MB_LIB.T6G(SCH_1):GND    I67 @T6G_MB_LIB.T6G(SCH_1):PAGE343
    C7 P12V_OCP_FAULT_2 @T6G_MB_LIB.T6G(SCH_1):P12V_OCP_FAULT_2    I67 @T6G_MB_LIB.T6G(SCH_1):PAGE343
    D7 P12V_OCP_PWRGD_2 @T6G_MB_LIB.T6G(SCH_1):P12V_OCP_PWRGD_2    I67 @T6G_MB_LIB.T6G(SCH_1):PAGE343

PU202 MAX15090BEWIT-MAX15090BEWI+T,SMLF,IC,AL015080B00
    A2 P3V3_OCP_VCC_1 @T6G_MB_LIB.T6G(SCH_1):P3V3_OCP_VCC_1   I113 @T6G_MB_LIB.T6G(SCH_1):PAGE338
    A3 P3V3_AUX @T6G_MB_LIB.T6G(SCH_1):P3V3_AUX   I113 @T6G_MB_LIB.T6G(SCH_1):PAGE338
    A5 P3V3_AUX @T6G_MB_LIB.T6G(SCH_1):P3V3_AUX   I113 @T6G_MB_LIB.T6G(SCH_1):PAGE338
    B3 P3V3_AUX @T6G_MB_LIB.T6G(SCH_1):P3V3_AUX   I113 @T6G_MB_LIB.T6G(SCH_1):PAGE338
    B5 P3V3_AUX @T6G_MB_LIB.T6G(SCH_1):P3V3_AUX   I113 @T6G_MB_LIB.T6G(SCH_1):PAGE338
    C3 P3V3_AUX @T6G_MB_LIB.T6G(SCH_1):P3V3_AUX   I113 @T6G_MB_LIB.T6G(SCH_1):PAGE338
    C5 P3V3_AUX @T6G_MB_LIB.T6G(SCH_1):P3V3_AUX   I113 @T6G_MB_LIB.T6G(SCH_1):PAGE338
    D5 P3V3_AUX @T6G_MB_LIB.T6G(SCH_1):P3V3_AUX   I113 @T6G_MB_LIB.T6G(SCH_1):PAGE338
    B1 P3V3_OCP_CB_1 @T6G_MB_LIB.T6G(SCH_1):P3V3_OCP_CB_1   I113 @T6G_MB_LIB.T6G(SCH_1):PAGE338
    B7    GND @T6G_MB_LIB.T6G(SCH_1):GND   I113 @T6G_MB_LIB.T6G(SCH_1):PAGE338
    D1 P3V3_OCP_REG_1 @T6G_MB_LIB.T6G(SCH_1):P3V3_OCP_REG_1   I113 @T6G_MB_LIB.T6G(SCH_1):PAGE338
    D2 P3V3_OCP_UV_1 @T6G_MB_LIB.T6G(SCH_1):P3V3_OCP_UV_1   I113 @T6G_MB_LIB.T6G(SCH_1):PAGE338
    D3 P3V3_OCP_OV_1 @T6G_MB_LIB.T6G(SCH_1):P3V3_OCP_OV_1   I113 @T6G_MB_LIB.T6G(SCH_1):PAGE338
    A1 P3V3_OCP_SENSE_1 @T6G_MB_LIB.T6G(SCH_1):P3V3_OCP_SENSE_1   I113 @T6G_MB_LIB.T6G(SCH_1):PAGE338
    A4 P3V3_OCP_SFF_R @T6G_MB_LIB.T6G(SCH_1):P3V3_OCP_SFF_R   I113 @T6G_MB_LIB.T6G(SCH_1):PAGE338
    B4 P3V3_OCP_SFF_R @T6G_MB_LIB.T6G(SCH_1):P3V3_OCP_SFF_R   I113 @T6G_MB_LIB.T6G(SCH_1):PAGE338
    B6 P3V3_OCP_SFF_R @T6G_MB_LIB.T6G(SCH_1):P3V3_OCP_SFF_R   I113 @T6G_MB_LIB.T6G(SCH_1):PAGE338
    C4 P3V3_OCP_SFF_R @T6G_MB_LIB.T6G(SCH_1):P3V3_OCP_SFF_R   I113 @T6G_MB_LIB.T6G(SCH_1):PAGE338
    C6 P3V3_OCP_SFF_R @T6G_MB_LIB.T6G(SCH_1):P3V3_OCP_SFF_R   I113 @T6G_MB_LIB.T6G(SCH_1):PAGE338
    D4 P3V3_OCP_SFF_R @T6G_MB_LIB.T6G(SCH_1):P3V3_OCP_SFF_R   I113 @T6G_MB_LIB.T6G(SCH_1):PAGE338
    D6 P3V3_OCP_SFF_R @T6G_MB_LIB.T6G(SCH_1):P3V3_OCP_SFF_R   I113 @T6G_MB_LIB.T6G(SCH_1):PAGE338
    A6 P3V3_OCP_GATE_PU202_1 @T6G_MB_LIB.T6G(SCH_1):P3V3_OCP_GATE_PU202_1   I113 @T6G_MB_LIB.T6G(SCH_1):PAGE338
    A7    GND @T6G_MB_LIB.T6G(SCH_1):GND   I113 @T6G_MB_LIB.T6G(SCH_1):PAGE338
    B2    GND @T6G_MB_LIB.T6G(SCH_1):GND   I113 @T6G_MB_LIB.T6G(SCH_1):PAGE338
    C1    GND @T6G_MB_LIB.T6G(SCH_1):GND   I113 @T6G_MB_LIB.T6G(SCH_1):PAGE338
    C2    GND @T6G_MB_LIB.T6G(SCH_1):GND   I113 @T6G_MB_LIB.T6G(SCH_1):PAGE338
    C7 P3V3_OCP_FAULT_1 @T6G_MB_LIB.T6G(SCH_1):P3V3_OCP_FAULT_1   I113 @T6G_MB_LIB.T6G(SCH_1):PAGE338
    D7 P3V3_OCP_PWRGD_1 @T6G_MB_LIB.T6G(SCH_1):P3V3_OCP_PWRGD_1   I113 @T6G_MB_LIB.T6G(SCH_1):PAGE338

PU203 MAX15090BEWIT-MAX15090BEWI+T,SMLF,IC,AL015080B00
    A2 P12V_OCP_VCC_1 @T6G_MB_LIB.T6G(SCH_1):P12V_OCP_VCC_1    I50 @T6G_MB_LIB.T6G(SCH_1):PAGE338
    A3 P12V_AUX @T6G_MB_LIB.T6G(SCH_1):P12V_AUX    I50 @T6G_MB_LIB.T6G(SCH_1):PAGE338
    A5 P12V_AUX @T6G_MB_LIB.T6G(SCH_1):P12V_AUX    I50 @T6G_MB_LIB.T6G(SCH_1):PAGE338
    B3 P12V_AUX @T6G_MB_LIB.T6G(SCH_1):P12V_AUX    I50 @T6G_MB_LIB.T6G(SCH_1):PAGE338
    B5 P12V_AUX @T6G_MB_LIB.T6G(SCH_1):P12V_AUX    I50 @T6G_MB_LIB.T6G(SCH_1):PAGE338
    C3 P12V_AUX @T6G_MB_LIB.T6G(SCH_1):P12V_AUX    I50 @T6G_MB_LIB.T6G(SCH_1):PAGE338
    C5 P12V_AUX @T6G_MB_LIB.T6G(SCH_1):P12V_AUX    I50 @T6G_MB_LIB.T6G(SCH_1):PAGE338
    D5 P12V_AUX @T6G_MB_LIB.T6G(SCH_1):P12V_AUX    I50 @T6G_MB_LIB.T6G(SCH_1):PAGE338
    B1 P12V_OCP_CB_1 @T6G_MB_LIB.T6G(SCH_1):P12V_OCP_CB_1    I50 @T6G_MB_LIB.T6G(SCH_1):PAGE338
    B7    GND @T6G_MB_LIB.T6G(SCH_1):GND    I50 @T6G_MB_LIB.T6G(SCH_1):PAGE338
    D1 P12V_OCP_REG_1 @T6G_MB_LIB.T6G(SCH_1):P12V_OCP_REG_1    I50 @T6G_MB_LIB.T6G(SCH_1):PAGE338
    D2 P12V_OCP_UV_1 @T6G_MB_LIB.T6G(SCH_1):P12V_OCP_UV_1    I50 @T6G_MB_LIB.T6G(SCH_1):PAGE338
    D3 P12V_OCP_OV_1 @T6G_MB_LIB.T6G(SCH_1):P12V_OCP_OV_1    I50 @T6G_MB_LIB.T6G(SCH_1):PAGE338
    A1 P12V_OCP_SENSE_1 @T6G_MB_LIB.T6G(SCH_1):P12V_OCP_SENSE_1    I50 @T6G_MB_LIB.T6G(SCH_1):PAGE338
    A4 P12V_OCP_SFF @T6G_MB_LIB.T6G(SCH_1):P12V_OCP_SFF    I50 @T6G_MB_LIB.T6G(SCH_1):PAGE338
    B4 P12V_OCP_SFF @T6G_MB_LIB.T6G(SCH_1):P12V_OCP_SFF    I50 @T6G_MB_LIB.T6G(SCH_1):PAGE338
    B6 P12V_OCP_SFF @T6G_MB_LIB.T6G(SCH_1):P12V_OCP_SFF    I50 @T6G_MB_LIB.T6G(SCH_1):PAGE338
    C4 P12V_OCP_SFF @T6G_MB_LIB.T6G(SCH_1):P12V_OCP_SFF    I50 @T6G_MB_LIB.T6G(SCH_1):PAGE338
    C6 P12V_OCP_SFF @T6G_MB_LIB.T6G(SCH_1):P12V_OCP_SFF    I50 @T6G_MB_LIB.T6G(SCH_1):PAGE338
    D4 P12V_OCP_SFF @T6G_MB_LIB.T6G(SCH_1):P12V_OCP_SFF    I50 @T6G_MB_LIB.T6G(SCH_1):PAGE338
    D6 P12V_OCP_SFF @T6G_MB_LIB.T6G(SCH_1):P12V_OCP_SFF    I50 @T6G_MB_LIB.T6G(SCH_1):PAGE338
    A6 P12V_OCP_GATE_1 @T6G_MB_LIB.T6G(SCH_1):P12V_OCP_GATE_1    I50 @T6G_MB_LIB.T6G(SCH_1):PAGE338
    A7    GND @T6G_MB_LIB.T6G(SCH_1):GND    I50 @T6G_MB_LIB.T6G(SCH_1):PAGE338
    B2    GND @T6G_MB_LIB.T6G(SCH_1):GND    I50 @T6G_MB_LIB.T6G(SCH_1):PAGE338
    C1    GND @T6G_MB_LIB.T6G(SCH_1):GND    I50 @T6G_MB_LIB.T6G(SCH_1):PAGE338
    C2    GND @T6G_MB_LIB.T6G(SCH_1):GND    I50 @T6G_MB_LIB.T6G(SCH_1):PAGE338
    C7 P12V_OCP_FAULT_1 @T6G_MB_LIB.T6G(SCH_1):P12V_OCP_FAULT_1    I50 @T6G_MB_LIB.T6G(SCH_1):PAGE338
    D7 P12V_OCP_PWRGD_1 @T6G_MB_LIB.T6G(SCH_1):P12V_OCP_PWRGD_1    I50 @T6G_MB_LIB.T6G(SCH_1):PAGE338

PU204 RS31312R-RS31312R,SMLF,IC,AL031312000
    20 P12V_OCP_SFF @T6G_MB_LIB.T6G(SCH_1):P12V_OCP_SFF   I137 @T6G_MB_LIB.T6G(SCH_1):PAGE339
 21_22 P12V_AUX @T6G_MB_LIB.T6G(SCH_1):P12V_AUX   I137 @T6G_MB_LIB.T6G(SCH_1):PAGE339
    19 P12V_OCP_SFF @T6G_MB_LIB.T6G(SCH_1):P12V_OCP_SFF   I137 @T6G_MB_LIB.T6G(SCH_1):PAGE339
    18 P12V_OCP_SFF @T6G_MB_LIB.T6G(SCH_1):P12V_OCP_SFF   I137 @T6G_MB_LIB.T6G(SCH_1):PAGE339
    17 P12V_OCP_SFF @T6G_MB_LIB.T6G(SCH_1):P12V_OCP_SFF   I137 @T6G_MB_LIB.T6G(SCH_1):PAGE339
    16 P12V_OCP_SFF @T6G_MB_LIB.T6G(SCH_1):P12V_OCP_SFF   I137 @T6G_MB_LIB.T6G(SCH_1):PAGE339
    15 P12V_OCP_SFF @T6G_MB_LIB.T6G(SCH_1):P12V_OCP_SFF   I137 @T6G_MB_LIB.T6G(SCH_1):PAGE339
    14 P12V_OCP_SFF @T6G_MB_LIB.T6G(SCH_1):P12V_OCP_SFF   I137 @T6G_MB_LIB.T6G(SCH_1):PAGE339
    12 P12V_OCP_AVIN_PD_1 @T6G_MB_LIB.T6G(SCH_1):P12V_OCP_AVIN_PD_1   I137 @T6G_MB_LIB.T6G(SCH_1):PAGE339
    13 P12V_OCP_SFF @T6G_MB_LIB.T6G(SCH_1):P12V_OCP_SFF   I137 @T6G_MB_LIB.T6G(SCH_1):PAGE339
    11 P12V_OCP_OV_FB_1 @T6G_MB_LIB.T6G(SCH_1):P12V_OCP_OV_FB_1   I137 @T6G_MB_LIB.T6G(SCH_1):PAGE339
    10 HP_LVC3_OCP_V3_1_P12V_PWRGD @T6G_MB_LIB.T6G(SCH_1):HP_LVC3_OCP_V3_1_P12V_PWRGD   I137 @T6G_MB_LIB.T6G(SCH_1):PAGE339
     9 P12V_OCP_FLTB_1 @T6G_MB_LIB.T6G(SCH_1):P12V_OCP_FLTB_1   I137 @T6G_MB_LIB.T6G(SCH_1):PAGE339
     8 P12V_OCP_IMON_1 @T6G_MB_LIB.T6G(SCH_1):P12V_OCP_IMON_1   I137 @T6G_MB_LIB.T6G(SCH_1):PAGE339
    23 P12V_AUX @T6G_MB_LIB.T6G(SCH_1):P12V_AUX   I137 @T6G_MB_LIB.T6G(SCH_1):PAGE339
    24 P12V_AUX @T6G_MB_LIB.T6G(SCH_1):P12V_AUX   I137 @T6G_MB_LIB.T6G(SCH_1):PAGE339
    25 P12V_AUX @T6G_MB_LIB.T6G(SCH_1):P12V_AUX   I137 @T6G_MB_LIB.T6G(SCH_1):PAGE339
    26 P12V_AUX @T6G_MB_LIB.T6G(SCH_1):P12V_AUX   I137 @T6G_MB_LIB.T6G(SCH_1):PAGE339
     1 P12V_OCP_EN_1_R2 @T6G_MB_LIB.T6G(SCH_1):P12V_OCP_EN_1_R2   I137 @T6G_MB_LIB.T6G(SCH_1):PAGE339
     2    GND @T6G_MB_LIB.T6G(SCH_1):GND   I137 @T6G_MB_LIB.T6G(SCH_1):PAGE339
     3    GND @T6G_MB_LIB.T6G(SCH_1):GND   I137 @T6G_MB_LIB.T6G(SCH_1):PAGE339
     4 P12V_OCP_TIMER_1 @T6G_MB_LIB.T6G(SCH_1):P12V_OCP_TIMER_1   I137 @T6G_MB_LIB.T6G(SCH_1):PAGE339
     5 P12V_OCP_ISET_1 @T6G_MB_LIB.T6G(SCH_1):P12V_OCP_ISET_1   I137 @T6G_MB_LIB.T6G(SCH_1):PAGE339
     6 P12V_OCP_SS_1 @T6G_MB_LIB.T6G(SCH_1):P12V_OCP_SS_1   I137 @T6G_MB_LIB.T6G(SCH_1):PAGE339
     7    GND @T6G_MB_LIB.T6G(SCH_1):GND   I137 @T6G_MB_LIB.T6G(SCH_1):PAGE339

PU205 MP5016GQHLZ-MP5016GQH-L-Z,SMLF,IC,AL005016007
     9 P3V3_OCP_EN_1_R2 @T6G_MB_LIB.T6G(SCH_1):P3V3_OCP_EN_1_R2   I113 @T6G_MB_LIB.T6G(SCH_1):PAGE339
     5 P3V3_OCP_MODE_1 @T6G_MB_LIB.T6G(SCH_1):P3V3_OCP_MODE_1   I113 @T6G_MB_LIB.T6G(SCH_1):PAGE339
     4 P3V3_OCP_ILIMIT_1 @T6G_MB_LIB.T6G(SCH_1):P3V3_OCP_ILIMIT_1   I113 @T6G_MB_LIB.T6G(SCH_1):PAGE339
     3    GND @T6G_MB_LIB.T6G(SCH_1):GND   I113 @T6G_MB_LIB.T6G(SCH_1):PAGE339
   1_2 P3V3_AUX @T6G_MB_LIB.T6G(SCH_1):P3V3_AUX   I113 @T6G_MB_LIB.T6G(SCH_1):PAGE339
    10 P3V3_OCP_DVDT_1 @T6G_MB_LIB.T6G(SCH_1):P3V3_OCP_DVDT_1   I113 @T6G_MB_LIB.T6G(SCH_1):PAGE339
     8 P3V3_OCP_GATE_1 @T6G_MB_LIB.T6G(SCH_1):P3V3_OCP_GATE_1   I113 @T6G_MB_LIB.T6G(SCH_1):PAGE339
   6_7 P3V3_OCP_SFF_R @T6G_MB_LIB.T6G(SCH_1):P3V3_OCP_SFF_R   I113 @T6G_MB_LIB.T6G(SCH_1):PAGE339

PU206 RS31312R-RS31312R,SMLF,IC,AL031312000
    20 P12V_OCP_V3_2 @T6G_MB_LIB.T6G(SCH_1):P12V_OCP_V3_2    I82 @T6G_MB_LIB.T6G(SCH_1):PAGE344
 21_22 P12V_AUX @T6G_MB_LIB.T6G(SCH_1):P12V_AUX    I82 @T6G_MB_LIB.T6G(SCH_1):PAGE344
    19 P12V_OCP_V3_2 @T6G_MB_LIB.T6G(SCH_1):P12V_OCP_V3_2    I82 @T6G_MB_LIB.T6G(SCH_1):PAGE344
    18 P12V_OCP_V3_2 @T6G_MB_LIB.T6G(SCH_1):P12V_OCP_V3_2    I82 @T6G_MB_LIB.T6G(SCH_1):PAGE344
    17 P12V_OCP_V3_2 @T6G_MB_LIB.T6G(SCH_1):P12V_OCP_V3_2    I82 @T6G_MB_LIB.T6G(SCH_1):PAGE344
    16 P12V_OCP_V3_2 @T6G_MB_LIB.T6G(SCH_1):P12V_OCP_V3_2    I82 @T6G_MB_LIB.T6G(SCH_1):PAGE344
    15 P12V_OCP_V3_2 @T6G_MB_LIB.T6G(SCH_1):P12V_OCP_V3_2    I82 @T6G_MB_LIB.T6G(SCH_1):PAGE344
    14 P12V_OCP_V3_2 @T6G_MB_LIB.T6G(SCH_1):P12V_OCP_V3_2    I82 @T6G_MB_LIB.T6G(SCH_1):PAGE344
    12 P12V_OCP_AVIN_PD_2 @T6G_MB_LIB.T6G(SCH_1):P12V_OCP_AVIN_PD_2    I82 @T6G_MB_LIB.T6G(SCH_1):PAGE344
    13 P12V_OCP_V3_2 @T6G_MB_LIB.T6G(SCH_1):P12V_OCP_V3_2    I82 @T6G_MB_LIB.T6G(SCH_1):PAGE344
    11 P12V_OCP_OV_FB_2 @T6G_MB_LIB.T6G(SCH_1):P12V_OCP_OV_FB_2    I82 @T6G_MB_LIB.T6G(SCH_1):PAGE344
    10 HP_LVC3_OCP_V3_2_P12V_PWRGD @T6G_MB_LIB.T6G(SCH_1):HP_LVC3_OCP_V3_2_P12V_PWRGD    I82 @T6G_MB_LIB.T6G(SCH_1):PAGE344
     9 P12V_OCP_FLTB_2 @T6G_MB_LIB.T6G(SCH_1):P12V_OCP_FLTB_2    I82 @T6G_MB_LIB.T6G(SCH_1):PAGE344
     8 P12V_OCP_IMON_2 @T6G_MB_LIB.T6G(SCH_1):P12V_OCP_IMON_2    I82 @T6G_MB_LIB.T6G(SCH_1):PAGE344
    23 P12V_AUX @T6G_MB_LIB.T6G(SCH_1):P12V_AUX    I82 @T6G_MB_LIB.T6G(SCH_1):PAGE344
    24 P12V_AUX @T6G_MB_LIB.T6G(SCH_1):P12V_AUX    I82 @T6G_MB_LIB.T6G(SCH_1):PAGE344
    25 P12V_AUX @T6G_MB_LIB.T6G(SCH_1):P12V_AUX    I82 @T6G_MB_LIB.T6G(SCH_1):PAGE344
    26 P12V_AUX @T6G_MB_LIB.T6G(SCH_1):P12V_AUX    I82 @T6G_MB_LIB.T6G(SCH_1):PAGE344
     1 P12V_OCP_V3_2_EN_2_R3 @T6G_MB_LIB.T6G(SCH_1):P12V_OCP_V3_2_EN_2_R3    I82 @T6G_MB_LIB.T6G(SCH_1):PAGE344
     2    GND @T6G_MB_LIB.T6G(SCH_1):GND    I82 @T6G_MB_LIB.T6G(SCH_1):PAGE344
     3    GND @T6G_MB_LIB.T6G(SCH_1):GND    I82 @T6G_MB_LIB.T6G(SCH_1):PAGE344
     4 P12V_OCP_TIMER_2 @T6G_MB_LIB.T6G(SCH_1):P12V_OCP_TIMER_2    I82 @T6G_MB_LIB.T6G(SCH_1):PAGE344
     5 P12V_OCP_ISET_2 @T6G_MB_LIB.T6G(SCH_1):P12V_OCP_ISET_2    I82 @T6G_MB_LIB.T6G(SCH_1):PAGE344
     6 P12V_OCP_SS_2 @T6G_MB_LIB.T6G(SCH_1):P12V_OCP_SS_2    I82 @T6G_MB_LIB.T6G(SCH_1):PAGE344
     7    GND @T6G_MB_LIB.T6G(SCH_1):GND    I82 @T6G_MB_LIB.T6G(SCH_1):PAGE344

PU207 MP5016GQHLZ-MP5016GQH-L-Z,SMLF,IC,AL005016007
     9 P3V3_OCP_EN_2 @T6G_MB_LIB.T6G(SCH_1):P3V3_OCP_EN_2    I51 @T6G_MB_LIB.T6G(SCH_1):PAGE344
     5 P3V3_OCP_MODE_2 @T6G_MB_LIB.T6G(SCH_1):P3V3_OCP_MODE_2    I51 @T6G_MB_LIB.T6G(SCH_1):PAGE344
     4 P3V3_OCP_ILIMIT_2 @T6G_MB_LIB.T6G(SCH_1):P3V3_OCP_ILIMIT_2    I51 @T6G_MB_LIB.T6G(SCH_1):PAGE344
     3    GND @T6G_MB_LIB.T6G(SCH_1):GND    I51 @T6G_MB_LIB.T6G(SCH_1):PAGE344
   1_2 P3V3_AUX @T6G_MB_LIB.T6G(SCH_1):P3V3_AUX    I51 @T6G_MB_LIB.T6G(SCH_1):PAGE344
    10 P3V3_OCP_DVDT_2 @T6G_MB_LIB.T6G(SCH_1):P3V3_OCP_DVDT_2    I51 @T6G_MB_LIB.T6G(SCH_1):PAGE344
     8 P3V3_OCP_GATE_PU207_2 @T6G_MB_LIB.T6G(SCH_1):P3V3_OCP_GATE_PU207_2    I51 @T6G_MB_LIB.T6G(SCH_1):PAGE344
   6_7 P3V3_OCP_V3_2_R @T6G_MB_LIB.T6G(SCH_1):P3V3_OCP_V3_2_R    I51 @T6G_MB_LIB.T6G(SCH_1):PAGE344

PU287 MP5991GLUZ-MP5991GLU-Z,SMLF,IC,AL005991A00
     9 P12V_PSU @T6G_MB_LIB.T6G(SCH_1):P12V_PSU    I35 @T6G_MB_LIB.T6G(SCH_1):PAGE301
    10 P12V_PSU @T6G_MB_LIB.T6G(SCH_1):P12V_PSU    I35 @T6G_MB_LIB.T6G(SCH_1):PAGE301
    11 P12V_PSU @T6G_MB_LIB.T6G(SCH_1):P12V_PSU    I35 @T6G_MB_LIB.T6G(SCH_1):PAGE301
    12 P12V_PSU @T6G_MB_LIB.T6G(SCH_1):P12V_PSU    I35 @T6G_MB_LIB.T6G(SCH_1):PAGE301
    13 P12V_PSU @T6G_MB_LIB.T6G(SCH_1):P12V_PSU    I35 @T6G_MB_LIB.T6G(SCH_1):PAGE301
     4 HSC_ON @T6G_MB_LIB.T6G(SCH_1):HSC_ON    I35 @T6G_MB_LIB.T6G(SCH_1):PAGE301
    24 HSC_OCREF @T6G_MB_LIB.T6G(SCH_1):HSC_OCREF    I35 @T6G_MB_LIB.T6G(SCH_1):PAGE301
    23 HSC_CS_1 @T6G_MB_LIB.T6G(SCH_1):HSC_CS_1    I35 @T6G_MB_LIB.T6G(SCH_1):PAGE301
    22 HSC_IMON @T6G_MB_LIB.T6G(SCH_1):HSC_IMON    I35 @T6G_MB_LIB.T6G(SCH_1):PAGE301
    21 HSC_VDD_R_1 @T6G_MB_LIB.T6G(SCH_1):HSC_VDD_R_1    I35 @T6G_MB_LIB.T6G(SCH_1):PAGE301
    20 AGND_HSC @T6G_MB_LIB.T6G(SCH_1):AGND_HSC    I35 @T6G_MB_LIB.T6G(SCH_1):PAGE301
    19 HSC_SS @T6G_MB_LIB.T6G(SCH_1):HSC_SS    I35 @T6G_MB_LIB.T6G(SCH_1):PAGE301
     5 HSC_FAULT @T6G_MB_LIB.T6G(SCH_1):HSC_FAULT    I35 @T6G_MB_LIB.T6G(SCH_1):PAGE301
    18 HSC_VTEMP @T6G_MB_LIB.T6G(SCH_1):HSC_VTEMP    I35 @T6G_MB_LIB.T6G(SCH_1):PAGE301
     1 P12V_AUX @T6G_MB_LIB.T6G(SCH_1):P12V_AUX    I35 @T6G_MB_LIB.T6G(SCH_1):PAGE301
     2 P12V_AUX @T6G_MB_LIB.T6G(SCH_1):P12V_AUX    I35 @T6G_MB_LIB.T6G(SCH_1):PAGE301
    25 P12V_AUX @T6G_MB_LIB.T6G(SCH_1):P12V_AUX    I35 @T6G_MB_LIB.T6G(SCH_1):PAGE301
    26 P12V_AUX @T6G_MB_LIB.T6G(SCH_1):P12V_AUX    I35 @T6G_MB_LIB.T6G(SCH_1):PAGE301
     3 HSC_D_OC_1 @T6G_MB_LIB.T6G(SCH_1):HSC_D_OC_1    I35 @T6G_MB_LIB.T6G(SCH_1):PAGE301
    14 P12V_PSU @T6G_MB_LIB.T6G(SCH_1):P12V_PSU    I35 @T6G_MB_LIB.T6G(SCH_1):PAGE301
    15 P12V_PSU @T6G_MB_LIB.T6G(SCH_1):P12V_PSU    I35 @T6G_MB_LIB.T6G(SCH_1):PAGE301
    16 P12V_PSU @T6G_MB_LIB.T6G(SCH_1):P12V_PSU    I35 @T6G_MB_LIB.T6G(SCH_1):PAGE301
    33 P12V_PSU @T6G_MB_LIB.T6G(SCH_1):P12V_PSU    I35 @T6G_MB_LIB.T6G(SCH_1):PAGE301
    27 P12V_AUX @T6G_MB_LIB.T6G(SCH_1):P12V_AUX    I35 @T6G_MB_LIB.T6G(SCH_1):PAGE301
    28 P12V_AUX @T6G_MB_LIB.T6G(SCH_1):P12V_AUX    I35 @T6G_MB_LIB.T6G(SCH_1):PAGE301
    29 P12V_AUX @T6G_MB_LIB.T6G(SCH_1):P12V_AUX    I35 @T6G_MB_LIB.T6G(SCH_1):PAGE301
    30 P12V_AUX @T6G_MB_LIB.T6G(SCH_1):P12V_AUX    I35 @T6G_MB_LIB.T6G(SCH_1):PAGE301
    31 P12V_AUX @T6G_MB_LIB.T6G(SCH_1):P12V_AUX    I35 @T6G_MB_LIB.T6G(SCH_1):PAGE301
    32 P12V_AUX @T6G_MB_LIB.T6G(SCH_1):P12V_AUX    I35 @T6G_MB_LIB.T6G(SCH_1):PAGE301
     8 HSC_MODE_1 @T6G_MB_LIB.T6G(SCH_1):HSC_MODE_1    I35 @T6G_MB_LIB.T6G(SCH_1):PAGE301
    17 HSC_SCREF_1 @T6G_MB_LIB.T6G(SCH_1):HSC_SCREF_1    I35 @T6G_MB_LIB.T6G(SCH_1):PAGE301
     6 HSC_FLT_TYPE_1 @T6G_MB_LIB.T6G(SCH_1):HSC_FLT_TYPE_1    I35 @T6G_MB_LIB.T6G(SCH_1):PAGE301
     7 HSC_NC1_1 @T6G_MB_LIB.T6G(SCH_1):HSC_NC1_1    I35 @T6G_MB_LIB.T6G(SCH_1):PAGE301

PU288 MP5991GLUZ-MP5991GLU-Z,SMLF,IC,AL005991A00
     9 P12V_PSU @T6G_MB_LIB.T6G(SCH_1):P12V_PSU    I16 @T6G_MB_LIB.T6G(SCH_1):PAGE301
    10 P12V_PSU @T6G_MB_LIB.T6G(SCH_1):P12V_PSU    I16 @T6G_MB_LIB.T6G(SCH_1):PAGE301
    11 P12V_PSU @T6G_MB_LIB.T6G(SCH_1):P12V_PSU    I16 @T6G_MB_LIB.T6G(SCH_1):PAGE301
    12 P12V_PSU @T6G_MB_LIB.T6G(SCH_1):P12V_PSU    I16 @T6G_MB_LIB.T6G(SCH_1):PAGE301
    13 P12V_PSU @T6G_MB_LIB.T6G(SCH_1):P12V_PSU    I16 @T6G_MB_LIB.T6G(SCH_1):PAGE301
     4 HSC_ON @T6G_MB_LIB.T6G(SCH_1):HSC_ON    I16 @T6G_MB_LIB.T6G(SCH_1):PAGE301
    24 HSC_OCREF @T6G_MB_LIB.T6G(SCH_1):HSC_OCREF    I16 @T6G_MB_LIB.T6G(SCH_1):PAGE301
    23 HSC_CS_2 @T6G_MB_LIB.T6G(SCH_1):HSC_CS_2    I16 @T6G_MB_LIB.T6G(SCH_1):PAGE301
    22 HSC_IMON @T6G_MB_LIB.T6G(SCH_1):HSC_IMON    I16 @T6G_MB_LIB.T6G(SCH_1):PAGE301
    21 HSC_VDD_R_2 @T6G_MB_LIB.T6G(SCH_1):HSC_VDD_R_2    I16 @T6G_MB_LIB.T6G(SCH_1):PAGE301
    20 AGND_HSC @T6G_MB_LIB.T6G(SCH_1):AGND_HSC    I16 @T6G_MB_LIB.T6G(SCH_1):PAGE301
    19 HSC_SS @T6G_MB_LIB.T6G(SCH_1):HSC_SS    I16 @T6G_MB_LIB.T6G(SCH_1):PAGE301
     5 HSC_FAULT @T6G_MB_LIB.T6G(SCH_1):HSC_FAULT    I16 @T6G_MB_LIB.T6G(SCH_1):PAGE301
    18 HSC_VTEMP @T6G_MB_LIB.T6G(SCH_1):HSC_VTEMP    I16 @T6G_MB_LIB.T6G(SCH_1):PAGE301
     1 P12V_AUX @T6G_MB_LIB.T6G(SCH_1):P12V_AUX    I16 @T6G_MB_LIB.T6G(SCH_1):PAGE301
     2 P12V_AUX @T6G_MB_LIB.T6G(SCH_1):P12V_AUX    I16 @T6G_MB_LIB.T6G(SCH_1):PAGE301
    25 P12V_AUX @T6G_MB_LIB.T6G(SCH_1):P12V_AUX    I16 @T6G_MB_LIB.T6G(SCH_1):PAGE301
    26 P12V_AUX @T6G_MB_LIB.T6G(SCH_1):P12V_AUX    I16 @T6G_MB_LIB.T6G(SCH_1):PAGE301
     3 HSC_D_OC_2 @T6G_MB_LIB.T6G(SCH_1):HSC_D_OC_2    I16 @T6G_MB_LIB.T6G(SCH_1):PAGE301
    14 P12V_PSU @T6G_MB_LIB.T6G(SCH_1):P12V_PSU    I16 @T6G_MB_LIB.T6G(SCH_1):PAGE301
    15 P12V_PSU @T6G_MB_LIB.T6G(SCH_1):P12V_PSU    I16 @T6G_MB_LIB.T6G(SCH_1):PAGE301
    16 P12V_PSU @T6G_MB_LIB.T6G(SCH_1):P12V_PSU    I16 @T6G_MB_LIB.T6G(SCH_1):PAGE301
    33 P12V_PSU @T6G_MB_LIB.T6G(SCH_1):P12V_PSU    I16 @T6G_MB_LIB.T6G(SCH_1):PAGE301
    27 P12V_AUX @T6G_MB_LIB.T6G(SCH_1):P12V_AUX    I16 @T6G_MB_LIB.T6G(SCH_1):PAGE301
    28 P12V_AUX @T6G_MB_LIB.T6G(SCH_1):P12V_AUX    I16 @T6G_MB_LIB.T6G(SCH_1):PAGE301
    29 P12V_AUX @T6G_MB_LIB.T6G(SCH_1):P12V_AUX    I16 @T6G_MB_LIB.T6G(SCH_1):PAGE301
    30 P12V_AUX @T6G_MB_LIB.T6G(SCH_1):P12V_AUX    I16 @T6G_MB_LIB.T6G(SCH_1):PAGE301
    31 P12V_AUX @T6G_MB_LIB.T6G(SCH_1):P12V_AUX    I16 @T6G_MB_LIB.T6G(SCH_1):PAGE301
    32 P12V_AUX @T6G_MB_LIB.T6G(SCH_1):P12V_AUX    I16 @T6G_MB_LIB.T6G(SCH_1):PAGE301
     8 HSC_MODE_2 @T6G_MB_LIB.T6G(SCH_1):HSC_MODE_2    I16 @T6G_MB_LIB.T6G(SCH_1):PAGE301
    17 HSC_SCREF_2 @T6G_MB_LIB.T6G(SCH_1):HSC_SCREF_2    I16 @T6G_MB_LIB.T6G(SCH_1):PAGE301
     6 HSC_FLT_TYPE_2 @T6G_MB_LIB.T6G(SCH_1):HSC_FLT_TYPE_2    I16 @T6G_MB_LIB.T6G(SCH_1):PAGE301
     7 HSC_NC1_2 @T6G_MB_LIB.T6G(SCH_1):HSC_NC1_2    I16 @T6G_MB_LIB.T6G(SCH_1):PAGE301

PU289 MP5990GMA1111Z-MP5990GMA-1111-Z,SMLF,IC,AR0F0TP4023
    29 P12V_AUX @T6G_MB_LIB.T6G(SCH_1):P12V_AUX    I58 @T6G_MB_LIB.T6G(SCH_1):PAGE267
    28 P12V_AUX @T6G_MB_LIB.T6G(SCH_1):P12V_AUX    I58 @T6G_MB_LIB.T6G(SCH_1):PAGE267
    27 P12V_AUX @T6G_MB_LIB.T6G(SCH_1):P12V_AUX    I58 @T6G_MB_LIB.T6G(SCH_1):PAGE267
     2 P12V_PSU @T6G_MB_LIB.T6G(SCH_1):P12V_PSU    I58 @T6G_MB_LIB.T6G(SCH_1):PAGE267
    26 HSC_EN_R @T6G_MB_LIB.T6G(SCH_1):HSC_EN_R    I58 @T6G_MB_LIB.T6G(SCH_1):PAGE267
     3 P12V_PSU @T6G_MB_LIB.T6G(SCH_1):P12V_PSU    I58 @T6G_MB_LIB.T6G(SCH_1):PAGE267
     4 P12V_PSU @T6G_MB_LIB.T6G(SCH_1):P12V_PSU    I58 @T6G_MB_LIB.T6G(SCH_1):PAGE267
    18 AGND_HSC @T6G_MB_LIB.T6G(SCH_1):AGND_HSC    I58 @T6G_MB_LIB.T6G(SCH_1):PAGE267
    12 SMB_SML1_PMBUS_HSC_R_SDA @T6G_MB_LIB.T6G(SCH_1):SMB_SML1_PMBUS_HSC_R_SDA    I58 @T6G_MB_LIB.T6G(SCH_1):PAGE267
    14 HSC_VIN_UVW_N @T6G_MB_LIB.T6G(SCH_1):HSC_VIN_UVW_N    I58 @T6G_MB_LIB.T6G(SCH_1):PAGE267
    11 SMB_SML1_PMBUS_HSC_L_SCL @T6G_MB_LIB.T6G(SCH_1):SMB_SML1_PMBUS_HSC_L_SCL    I58 @T6G_MB_LIB.T6G(SCH_1):PAGE267
    37 HSC_D_OC_R @T6G_MB_LIB.T6G(SCH_1):HSC_D_OC_R    I58 @T6G_MB_LIB.T6G(SCH_1):PAGE267
    31 P12V_AUX @T6G_MB_LIB.T6G(SCH_1):P12V_AUX    I58 @T6G_MB_LIB.T6G(SCH_1):PAGE267
    35 P12V_AUX @T6G_MB_LIB.T6G(SCH_1):P12V_AUX    I58 @T6G_MB_LIB.T6G(SCH_1):PAGE267
    10 IRQ_SML1_PMBUS_ALERT @T6G_MB_LIB.T6G(SCH_1):IRQ_SML1_PMBUS_ALERT    I58 @T6G_MB_LIB.T6G(SCH_1):PAGE267
    39 HSC_FAULT @T6G_MB_LIB.T6G(SCH_1):HSC_FAULT    I58 @T6G_MB_LIB.T6G(SCH_1):PAGE267
     7 P12V_PSU @T6G_MB_LIB.T6G(SCH_1):P12V_PSU    I58 @T6G_MB_LIB.T6G(SCH_1):PAGE267
    33 P12V_AUX @T6G_MB_LIB.T6G(SCH_1):P12V_AUX    I58 @T6G_MB_LIB.T6G(SCH_1):PAGE267
    41 HSC_MODE @T6G_MB_LIB.T6G(SCH_1):HSC_MODE    I58 @T6G_MB_LIB.T6G(SCH_1):PAGE267
     8 P12V_PSU @T6G_MB_LIB.T6G(SCH_1):P12V_PSU    I58 @T6G_MB_LIB.T6G(SCH_1):PAGE267
    13 MB0_P12V_STBY_PWRGD @T6G_MB_LIB.T6G(SCH_1):MB0_P12V_STBY_PWRGD    I58 @T6G_MB_LIB.T6G(SCH_1):PAGE267
    34 P12V_AUX @T6G_MB_LIB.T6G(SCH_1):P12V_AUX    I58 @T6G_MB_LIB.T6G(SCH_1):PAGE267
    38 HSC_ON_R @T6G_MB_LIB.T6G(SCH_1):HSC_ON_R    I58 @T6G_MB_LIB.T6G(SCH_1):PAGE267
     5 P12V_PSU @T6G_MB_LIB.T6G(SCH_1):P12V_PSU    I58 @T6G_MB_LIB.T6G(SCH_1):PAGE267
     6 P12V_PSU @T6G_MB_LIB.T6G(SCH_1):P12V_PSU    I58 @T6G_MB_LIB.T6G(SCH_1):PAGE267
    15 HSC_VTEMP @T6G_MB_LIB.T6G(SCH_1):HSC_VTEMP    I58 @T6G_MB_LIB.T6G(SCH_1):PAGE267
    22 HSC_OCREF @T6G_MB_LIB.T6G(SCH_1):HSC_OCREF    I58 @T6G_MB_LIB.T6G(SCH_1):PAGE267
    25 HSC_SCREF @T6G_MB_LIB.T6G(SCH_1):HSC_SCREF    I58 @T6G_MB_LIB.T6G(SCH_1):PAGE267
    16 HSC_SS @T6G_MB_LIB.T6G(SCH_1):HSC_SS    I58 @T6G_MB_LIB.T6G(SCH_1):PAGE267
    32 P12V_AUX @T6G_MB_LIB.T6G(SCH_1):P12V_AUX    I58 @T6G_MB_LIB.T6G(SCH_1):PAGE267
    21 HSC_IMON @T6G_MB_LIB.T6G(SCH_1):HSC_IMON    I58 @T6G_MB_LIB.T6G(SCH_1):PAGE267
    20 HSC_CS @T6G_MB_LIB.T6G(SCH_1):HSC_CS    I58 @T6G_MB_LIB.T6G(SCH_1):PAGE267
    42 P12V_PSU @T6G_MB_LIB.T6G(SCH_1):P12V_PSU    I58 @T6G_MB_LIB.T6G(SCH_1):PAGE267
    36 P12V_AUX @T6G_MB_LIB.T6G(SCH_1):P12V_AUX    I58 @T6G_MB_LIB.T6G(SCH_1):PAGE267
    24 HSC_VOSEN @T6G_MB_LIB.T6G(SCH_1):HSC_VOSEN    I58 @T6G_MB_LIB.T6G(SCH_1):PAGE267
    30 P12V_AUX @T6G_MB_LIB.T6G(SCH_1):P12V_AUX    I58 @T6G_MB_LIB.T6G(SCH_1):PAGE267
     1 P12V_PSU @T6G_MB_LIB.T6G(SCH_1):P12V_PSU    I58 @T6G_MB_LIB.T6G(SCH_1):PAGE267
    44 AGND_HSC @T6G_MB_LIB.T6G(SCH_1):AGND_HSC    I58 @T6G_MB_LIB.T6G(SCH_1):PAGE267
    40 HSC_FLT_TYPE @T6G_MB_LIB.T6G(SCH_1):HSC_FLT_TYPE    I58 @T6G_MB_LIB.T6G(SCH_1):PAGE267
    43 P12V_PSU @T6G_MB_LIB.T6G(SCH_1):P12V_PSU    I58 @T6G_MB_LIB.T6G(SCH_1):PAGE267
     9 HSC_VSENSE @T6G_MB_LIB.T6G(SCH_1):HSC_VSENSE    I58 @T6G_MB_LIB.T6G(SCH_1):PAGE267
    17 HSC_VDD_R @T6G_MB_LIB.T6G(SCH_1):HSC_VDD_R    I58 @T6G_MB_LIB.T6G(SCH_1):PAGE267
    45 HSC_VDD_R @T6G_MB_LIB.T6G(SCH_1):HSC_VDD_R    I58 @T6G_MB_LIB.T6G(SCH_1):PAGE267
    19 HSC_VDD18 @T6G_MB_LIB.T6G(SCH_1):HSC_VDD18    I58 @T6G_MB_LIB.T6G(SCH_1):PAGE267
    23 HSC_ADDR @T6G_MB_LIB.T6G(SCH_1):HSC_ADDR    I58 @T6G_MB_LIB.T6G(SCH_1):PAGE267

PU292 RS31312R-RS31312R,SMLF,IC,AL031312000
    20 P12V_E1S_0 @T6G_MB_LIB.T6G(SCH_1):P12V_E1S_0    I76 @T6G_MB_LIB.T6G(SCH_1):PAGE323
 21_22 P12V_AUX @T6G_MB_LIB.T6G(SCH_1):P12V_AUX    I76 @T6G_MB_LIB.T6G(SCH_1):PAGE323
    19 P12V_E1S_0 @T6G_MB_LIB.T6G(SCH_1):P12V_E1S_0    I76 @T6G_MB_LIB.T6G(SCH_1):PAGE323
    18 P12V_E1S_0 @T6G_MB_LIB.T6G(SCH_1):P12V_E1S_0    I76 @T6G_MB_LIB.T6G(SCH_1):PAGE323
    17 P12V_E1S_0 @T6G_MB_LIB.T6G(SCH_1):P12V_E1S_0    I76 @T6G_MB_LIB.T6G(SCH_1):PAGE323
    16 P12V_E1S_0 @T6G_MB_LIB.T6G(SCH_1):P12V_E1S_0    I76 @T6G_MB_LIB.T6G(SCH_1):PAGE323
    15 P12V_E1S_0 @T6G_MB_LIB.T6G(SCH_1):P12V_E1S_0    I76 @T6G_MB_LIB.T6G(SCH_1):PAGE323
    14 P12V_E1S_0 @T6G_MB_LIB.T6G(SCH_1):P12V_E1S_0    I76 @T6G_MB_LIB.T6G(SCH_1):PAGE323
    12 P12V_E1S_AVIN_PD_0 @T6G_MB_LIB.T6G(SCH_1):P12V_E1S_AVIN_PD_0    I76 @T6G_MB_LIB.T6G(SCH_1):PAGE323
    13 P12V_E1S_0 @T6G_MB_LIB.T6G(SCH_1):P12V_E1S_0    I76 @T6G_MB_LIB.T6G(SCH_1):PAGE323
    11 P12V_E1S_OV_FB_0 @T6G_MB_LIB.T6G(SCH_1):P12V_E1S_OV_FB_0    I76 @T6G_MB_LIB.T6G(SCH_1):PAGE323
    10 HP_LVC3_E1S_0_HSC_PWRGD @T6G_MB_LIB.T6G(SCH_1):HP_LVC3_E1S_0_HSC_PWRGD    I76 @T6G_MB_LIB.T6G(SCH_1):PAGE323
     9 P12V_E1S_FLTB_0 @T6G_MB_LIB.T6G(SCH_1):P12V_E1S_FLTB_0    I76 @T6G_MB_LIB.T6G(SCH_1):PAGE323
     8 P12V_E1S_IMON_0 @T6G_MB_LIB.T6G(SCH_1):P12V_E1S_IMON_0    I76 @T6G_MB_LIB.T6G(SCH_1):PAGE323
    23 P12V_AUX @T6G_MB_LIB.T6G(SCH_1):P12V_AUX    I76 @T6G_MB_LIB.T6G(SCH_1):PAGE323
    24 P12V_AUX @T6G_MB_LIB.T6G(SCH_1):P12V_AUX    I76 @T6G_MB_LIB.T6G(SCH_1):PAGE323
    25 P12V_AUX @T6G_MB_LIB.T6G(SCH_1):P12V_AUX    I76 @T6G_MB_LIB.T6G(SCH_1):PAGE323
    26 P12V_AUX @T6G_MB_LIB.T6G(SCH_1):P12V_AUX    I76 @T6G_MB_LIB.T6G(SCH_1):PAGE323
     1 P12V_E1S_EN_0_R2 @T6G_MB_LIB.T6G(SCH_1):P12V_E1S_EN_0_R2    I76 @T6G_MB_LIB.T6G(SCH_1):PAGE323
     2    GND @T6G_MB_LIB.T6G(SCH_1):GND    I76 @T6G_MB_LIB.T6G(SCH_1):PAGE323
     3    GND @T6G_MB_LIB.T6G(SCH_1):GND    I76 @T6G_MB_LIB.T6G(SCH_1):PAGE323
     4 P12V_E1S_TIMER_0 @T6G_MB_LIB.T6G(SCH_1):P12V_E1S_TIMER_0    I76 @T6G_MB_LIB.T6G(SCH_1):PAGE323
     5 P12V_E1S_ISET_0 @T6G_MB_LIB.T6G(SCH_1):P12V_E1S_ISET_0    I76 @T6G_MB_LIB.T6G(SCH_1):PAGE323
     6 P12V_E1S_SS_0 @T6G_MB_LIB.T6G(SCH_1):P12V_E1S_SS_0    I76 @T6G_MB_LIB.T6G(SCH_1):PAGE323
     7    GND @T6G_MB_LIB.T6G(SCH_1):GND    I76 @T6G_MB_LIB.T6G(SCH_1):PAGE323

PU293 MP5016GQHLZ-MP5016GQH-L-Z,SMLF,IC,AL005016007
     9 P3V3_E1S_EN_0_R2 @T6G_MB_LIB.T6G(SCH_1):P3V3_E1S_EN_0_R2    I31 @T6G_MB_LIB.T6G(SCH_1):PAGE323
     5 P3V3_E1S_MODE_0 @T6G_MB_LIB.T6G(SCH_1):P3V3_E1S_MODE_0    I31 @T6G_MB_LIB.T6G(SCH_1):PAGE323
     4 P3V3_E1S_ILIMIT_0 @T6G_MB_LIB.T6G(SCH_1):P3V3_E1S_ILIMIT_0    I31 @T6G_MB_LIB.T6G(SCH_1):PAGE323
     3    GND @T6G_MB_LIB.T6G(SCH_1):GND    I31 @T6G_MB_LIB.T6G(SCH_1):PAGE323
   1_2 P3V3_AUX @T6G_MB_LIB.T6G(SCH_1):P3V3_AUX    I31 @T6G_MB_LIB.T6G(SCH_1):PAGE323
    10 P3V3_E1S_DVDT_0 @T6G_MB_LIB.T6G(SCH_1):P3V3_E1S_DVDT_0    I31 @T6G_MB_LIB.T6G(SCH_1):PAGE323
     8 P3V3_E1S_GATE_0_PU293 @T6G_MB_LIB.T6G(SCH_1):P3V3_E1S_GATE_0_PU293    I31 @T6G_MB_LIB.T6G(SCH_1):PAGE323
   6_7 P3V3_E1S_0_R @T6G_MB_LIB.T6G(SCH_1):P3V3_E1S_0_R    I31 @T6G_MB_LIB.T6G(SCH_1):PAGE323

PU294 MAX15090BEWIT-MAX15090BEWI+T,SMLF,IC,AL015080B00
    A2 P12V_E1S_VCC_0 @T6G_MB_LIB.T6G(SCH_1):P12V_E1S_VCC_0    I66 @T6G_MB_LIB.T6G(SCH_1):PAGE324
    A3 P12V_AUX @T6G_MB_LIB.T6G(SCH_1):P12V_AUX    I66 @T6G_MB_LIB.T6G(SCH_1):PAGE324
    A5 P12V_AUX @T6G_MB_LIB.T6G(SCH_1):P12V_AUX    I66 @T6G_MB_LIB.T6G(SCH_1):PAGE324
    B3 P12V_AUX @T6G_MB_LIB.T6G(SCH_1):P12V_AUX    I66 @T6G_MB_LIB.T6G(SCH_1):PAGE324
    B5 P12V_AUX @T6G_MB_LIB.T6G(SCH_1):P12V_AUX    I66 @T6G_MB_LIB.T6G(SCH_1):PAGE324
    C3 P12V_AUX @T6G_MB_LIB.T6G(SCH_1):P12V_AUX    I66 @T6G_MB_LIB.T6G(SCH_1):PAGE324
    C5 P12V_AUX @T6G_MB_LIB.T6G(SCH_1):P12V_AUX    I66 @T6G_MB_LIB.T6G(SCH_1):PAGE324
    D5 P12V_AUX @T6G_MB_LIB.T6G(SCH_1):P12V_AUX    I66 @T6G_MB_LIB.T6G(SCH_1):PAGE324
    B1 P12V_E1S_CB_0 @T6G_MB_LIB.T6G(SCH_1):P12V_E1S_CB_0    I66 @T6G_MB_LIB.T6G(SCH_1):PAGE324
    B7    GND @T6G_MB_LIB.T6G(SCH_1):GND    I66 @T6G_MB_LIB.T6G(SCH_1):PAGE324
    D1 P12V_E1S_REG_0 @T6G_MB_LIB.T6G(SCH_1):P12V_E1S_REG_0    I66 @T6G_MB_LIB.T6G(SCH_1):PAGE324
    D2 P12V_E1S_UV_0 @T6G_MB_LIB.T6G(SCH_1):P12V_E1S_UV_0    I66 @T6G_MB_LIB.T6G(SCH_1):PAGE324
    D3 P12V_E1S_OV_0 @T6G_MB_LIB.T6G(SCH_1):P12V_E1S_OV_0    I66 @T6G_MB_LIB.T6G(SCH_1):PAGE324
    A1 P12V_E1S_SENSE_0 @T6G_MB_LIB.T6G(SCH_1):P12V_E1S_SENSE_0    I66 @T6G_MB_LIB.T6G(SCH_1):PAGE324
    A4 P12V_E1S_0 @T6G_MB_LIB.T6G(SCH_1):P12V_E1S_0    I66 @T6G_MB_LIB.T6G(SCH_1):PAGE324
    B4 P12V_E1S_0 @T6G_MB_LIB.T6G(SCH_1):P12V_E1S_0    I66 @T6G_MB_LIB.T6G(SCH_1):PAGE324
    B6 P12V_E1S_0 @T6G_MB_LIB.T6G(SCH_1):P12V_E1S_0    I66 @T6G_MB_LIB.T6G(SCH_1):PAGE324
    C4 P12V_E1S_0 @T6G_MB_LIB.T6G(SCH_1):P12V_E1S_0    I66 @T6G_MB_LIB.T6G(SCH_1):PAGE324
    C6 P12V_E1S_0 @T6G_MB_LIB.T6G(SCH_1):P12V_E1S_0    I66 @T6G_MB_LIB.T6G(SCH_1):PAGE324
    D4 P12V_E1S_0 @T6G_MB_LIB.T6G(SCH_1):P12V_E1S_0    I66 @T6G_MB_LIB.T6G(SCH_1):PAGE324
    D6 P12V_E1S_0 @T6G_MB_LIB.T6G(SCH_1):P12V_E1S_0    I66 @T6G_MB_LIB.T6G(SCH_1):PAGE324
    A6 P12V_E1S_GATE_0 @T6G_MB_LIB.T6G(SCH_1):P12V_E1S_GATE_0    I66 @T6G_MB_LIB.T6G(SCH_1):PAGE324
    A7    GND @T6G_MB_LIB.T6G(SCH_1):GND    I66 @T6G_MB_LIB.T6G(SCH_1):PAGE324
    B2    GND @T6G_MB_LIB.T6G(SCH_1):GND    I66 @T6G_MB_LIB.T6G(SCH_1):PAGE324
    C1    GND @T6G_MB_LIB.T6G(SCH_1):GND    I66 @T6G_MB_LIB.T6G(SCH_1):PAGE324
    C2    GND @T6G_MB_LIB.T6G(SCH_1):GND    I66 @T6G_MB_LIB.T6G(SCH_1):PAGE324
    C7 P12V_E1S_FAULT_0 @T6G_MB_LIB.T6G(SCH_1):P12V_E1S_FAULT_0    I66 @T6G_MB_LIB.T6G(SCH_1):PAGE324
    D7 P12V_E1S_PWRGD_0 @T6G_MB_LIB.T6G(SCH_1):P12V_E1S_PWRGD_0    I66 @T6G_MB_LIB.T6G(SCH_1):PAGE324

PU295 MAX15090BEWIT-MAX15090BEWI+T,SMLF,IC,AL015080B00
    A2 P3V3_E1S_VCC_0 @T6G_MB_LIB.T6G(SCH_1):P3V3_E1S_VCC_0    I88 @T6G_MB_LIB.T6G(SCH_1):PAGE324
    A3 P3V3_AUX @T6G_MB_LIB.T6G(SCH_1):P3V3_AUX    I88 @T6G_MB_LIB.T6G(SCH_1):PAGE324
    A5 P3V3_AUX @T6G_MB_LIB.T6G(SCH_1):P3V3_AUX    I88 @T6G_MB_LIB.T6G(SCH_1):PAGE324
    B3 P3V3_AUX @T6G_MB_LIB.T6G(SCH_1):P3V3_AUX    I88 @T6G_MB_LIB.T6G(SCH_1):PAGE324
    B5 P3V3_AUX @T6G_MB_LIB.T6G(SCH_1):P3V3_AUX    I88 @T6G_MB_LIB.T6G(SCH_1):PAGE324
    C3 P3V3_AUX @T6G_MB_LIB.T6G(SCH_1):P3V3_AUX    I88 @T6G_MB_LIB.T6G(SCH_1):PAGE324
    C5 P3V3_AUX @T6G_MB_LIB.T6G(SCH_1):P3V3_AUX    I88 @T6G_MB_LIB.T6G(SCH_1):PAGE324
    D5 P3V3_AUX @T6G_MB_LIB.T6G(SCH_1):P3V3_AUX    I88 @T6G_MB_LIB.T6G(SCH_1):PAGE324
    B1 P3V3_E1S_CB_0 @T6G_MB_LIB.T6G(SCH_1):P3V3_E1S_CB_0    I88 @T6G_MB_LIB.T6G(SCH_1):PAGE324
    B7    GND @T6G_MB_LIB.T6G(SCH_1):GND    I88 @T6G_MB_LIB.T6G(SCH_1):PAGE324
    D1 P3V3_E1S_REG_0 @T6G_MB_LIB.T6G(SCH_1):P3V3_E1S_REG_0    I88 @T6G_MB_LIB.T6G(SCH_1):PAGE324
    D2 P3V3_E1S_UV_0 @T6G_MB_LIB.T6G(SCH_1):P3V3_E1S_UV_0    I88 @T6G_MB_LIB.T6G(SCH_1):PAGE324
    D3 P3V3_E1S_OV_0 @T6G_MB_LIB.T6G(SCH_1):P3V3_E1S_OV_0    I88 @T6G_MB_LIB.T6G(SCH_1):PAGE324
    A1 P3V3_E1S_SENSE_0 @T6G_MB_LIB.T6G(SCH_1):P3V3_E1S_SENSE_0    I88 @T6G_MB_LIB.T6G(SCH_1):PAGE324
    A4 P3V3_E1S_0_R @T6G_MB_LIB.T6G(SCH_1):P3V3_E1S_0_R    I88 @T6G_MB_LIB.T6G(SCH_1):PAGE324
    B4 P3V3_E1S_0_R @T6G_MB_LIB.T6G(SCH_1):P3V3_E1S_0_R    I88 @T6G_MB_LIB.T6G(SCH_1):PAGE324
    B6 P3V3_E1S_0_R @T6G_MB_LIB.T6G(SCH_1):P3V3_E1S_0_R    I88 @T6G_MB_LIB.T6G(SCH_1):PAGE324
    C4 P3V3_E1S_0_R @T6G_MB_LIB.T6G(SCH_1):P3V3_E1S_0_R    I88 @T6G_MB_LIB.T6G(SCH_1):PAGE324
    C6 P3V3_E1S_0_R @T6G_MB_LIB.T6G(SCH_1):P3V3_E1S_0_R    I88 @T6G_MB_LIB.T6G(SCH_1):PAGE324
    D4 P3V3_E1S_0_R @T6G_MB_LIB.T6G(SCH_1):P3V3_E1S_0_R    I88 @T6G_MB_LIB.T6G(SCH_1):PAGE324
    D6 P3V3_E1S_0_R @T6G_MB_LIB.T6G(SCH_1):P3V3_E1S_0_R    I88 @T6G_MB_LIB.T6G(SCH_1):PAGE324
    A6 P3V3_E1S_GATE_0 @T6G_MB_LIB.T6G(SCH_1):P3V3_E1S_GATE_0    I88 @T6G_MB_LIB.T6G(SCH_1):PAGE324
    A7    GND @T6G_MB_LIB.T6G(SCH_1):GND    I88 @T6G_MB_LIB.T6G(SCH_1):PAGE324
    B2    GND @T6G_MB_LIB.T6G(SCH_1):GND    I88 @T6G_MB_LIB.T6G(SCH_1):PAGE324
    C1    GND @T6G_MB_LIB.T6G(SCH_1):GND    I88 @T6G_MB_LIB.T6G(SCH_1):PAGE324
    C2    GND @T6G_MB_LIB.T6G(SCH_1):GND    I88 @T6G_MB_LIB.T6G(SCH_1):PAGE324
    C7 P3V3_E1S_FAULT_0 @T6G_MB_LIB.T6G(SCH_1):P3V3_E1S_FAULT_0    I88 @T6G_MB_LIB.T6G(SCH_1):PAGE324
    D7 P3V3_E1S_PWRGD_0 @T6G_MB_LIB.T6G(SCH_1):P3V3_E1S_PWRGD_0    I88 @T6G_MB_LIB.T6G(SCH_1):PAGE324

PU296 MP5991GLUZ-MP5991GLU-Z,SMLF,IC,AL005991A00
     9 P12V_PSU @T6G_MB_LIB.T6G(SCH_1):P12V_PSU    I35 @T6G_MB_LIB.T6G(SCH_1):PAGE325
    10 P12V_PSU @T6G_MB_LIB.T6G(SCH_1):P12V_PSU    I35 @T6G_MB_LIB.T6G(SCH_1):PAGE325
    11 P12V_PSU @T6G_MB_LIB.T6G(SCH_1):P12V_PSU    I35 @T6G_MB_LIB.T6G(SCH_1):PAGE325
    12 P12V_PSU @T6G_MB_LIB.T6G(SCH_1):P12V_PSU    I35 @T6G_MB_LIB.T6G(SCH_1):PAGE325
    13 P12V_PSU @T6G_MB_LIB.T6G(SCH_1):P12V_PSU    I35 @T6G_MB_LIB.T6G(SCH_1):PAGE325
     4 HSC_ON @T6G_MB_LIB.T6G(SCH_1):HSC_ON    I35 @T6G_MB_LIB.T6G(SCH_1):PAGE325
    24 HSC_OCREF @T6G_MB_LIB.T6G(SCH_1):HSC_OCREF    I35 @T6G_MB_LIB.T6G(SCH_1):PAGE325
    23 HSC_CS_3 @T6G_MB_LIB.T6G(SCH_1):HSC_CS_3    I35 @T6G_MB_LIB.T6G(SCH_1):PAGE325
    22 HSC_IMON @T6G_MB_LIB.T6G(SCH_1):HSC_IMON    I35 @T6G_MB_LIB.T6G(SCH_1):PAGE325
    21 HSC_VDD_R_3 @T6G_MB_LIB.T6G(SCH_1):HSC_VDD_R_3    I35 @T6G_MB_LIB.T6G(SCH_1):PAGE325
    20 AGND_HSC @T6G_MB_LIB.T6G(SCH_1):AGND_HSC    I35 @T6G_MB_LIB.T6G(SCH_1):PAGE325
    19 HSC_SS @T6G_MB_LIB.T6G(SCH_1):HSC_SS    I35 @T6G_MB_LIB.T6G(SCH_1):PAGE325
     5 HSC_FAULT @T6G_MB_LIB.T6G(SCH_1):HSC_FAULT    I35 @T6G_MB_LIB.T6G(SCH_1):PAGE325
    18 HSC_VTEMP @T6G_MB_LIB.T6G(SCH_1):HSC_VTEMP    I35 @T6G_MB_LIB.T6G(SCH_1):PAGE325
     1 P12V_AUX @T6G_MB_LIB.T6G(SCH_1):P12V_AUX    I35 @T6G_MB_LIB.T6G(SCH_1):PAGE325
     2 P12V_AUX @T6G_MB_LIB.T6G(SCH_1):P12V_AUX    I35 @T6G_MB_LIB.T6G(SCH_1):PAGE325
    25 P12V_AUX @T6G_MB_LIB.T6G(SCH_1):P12V_AUX    I35 @T6G_MB_LIB.T6G(SCH_1):PAGE325
    26 P12V_AUX @T6G_MB_LIB.T6G(SCH_1):P12V_AUX    I35 @T6G_MB_LIB.T6G(SCH_1):PAGE325
     3 HSC_D_OC_3 @T6G_MB_LIB.T6G(SCH_1):HSC_D_OC_3    I35 @T6G_MB_LIB.T6G(SCH_1):PAGE325
    14 P12V_PSU @T6G_MB_LIB.T6G(SCH_1):P12V_PSU    I35 @T6G_MB_LIB.T6G(SCH_1):PAGE325
    15 P12V_PSU @T6G_MB_LIB.T6G(SCH_1):P12V_PSU    I35 @T6G_MB_LIB.T6G(SCH_1):PAGE325
    16 P12V_PSU @T6G_MB_LIB.T6G(SCH_1):P12V_PSU    I35 @T6G_MB_LIB.T6G(SCH_1):PAGE325
    33 P12V_PSU @T6G_MB_LIB.T6G(SCH_1):P12V_PSU    I35 @T6G_MB_LIB.T6G(SCH_1):PAGE325
    27 P12V_AUX @T6G_MB_LIB.T6G(SCH_1):P12V_AUX    I35 @T6G_MB_LIB.T6G(SCH_1):PAGE325
    28 P12V_AUX @T6G_MB_LIB.T6G(SCH_1):P12V_AUX    I35 @T6G_MB_LIB.T6G(SCH_1):PAGE325
    29 P12V_AUX @T6G_MB_LIB.T6G(SCH_1):P12V_AUX    I35 @T6G_MB_LIB.T6G(SCH_1):PAGE325
    30 P12V_AUX @T6G_MB_LIB.T6G(SCH_1):P12V_AUX    I35 @T6G_MB_LIB.T6G(SCH_1):PAGE325
    31 P12V_AUX @T6G_MB_LIB.T6G(SCH_1):P12V_AUX    I35 @T6G_MB_LIB.T6G(SCH_1):PAGE325
    32 P12V_AUX @T6G_MB_LIB.T6G(SCH_1):P12V_AUX    I35 @T6G_MB_LIB.T6G(SCH_1):PAGE325
     8 HSC_MODE_3 @T6G_MB_LIB.T6G(SCH_1):HSC_MODE_3    I35 @T6G_MB_LIB.T6G(SCH_1):PAGE325
    17 HSC_SCREF_3 @T6G_MB_LIB.T6G(SCH_1):HSC_SCREF_3    I35 @T6G_MB_LIB.T6G(SCH_1):PAGE325
     6 HSC_FLT_TYPE_3 @T6G_MB_LIB.T6G(SCH_1):HSC_FLT_TYPE_3    I35 @T6G_MB_LIB.T6G(SCH_1):PAGE325
     7 HSC_NC1_3 @T6G_MB_LIB.T6G(SCH_1):HSC_NC1_3    I35 @T6G_MB_LIB.T6G(SCH_1):PAGE325

PU297 MP5991GLUZ-MP5991GLU-Z,SMLF,IC,AL005991A00
     9 P12V_PSU @T6G_MB_LIB.T6G(SCH_1):P12V_PSU    I17 @T6G_MB_LIB.T6G(SCH_1):PAGE325
    10 P12V_PSU @T6G_MB_LIB.T6G(SCH_1):P12V_PSU    I17 @T6G_MB_LIB.T6G(SCH_1):PAGE325
    11 P12V_PSU @T6G_MB_LIB.T6G(SCH_1):P12V_PSU    I17 @T6G_MB_LIB.T6G(SCH_1):PAGE325
    12 P12V_PSU @T6G_MB_LIB.T6G(SCH_1):P12V_PSU    I17 @T6G_MB_LIB.T6G(SCH_1):PAGE325
    13 P12V_PSU @T6G_MB_LIB.T6G(SCH_1):P12V_PSU    I17 @T6G_MB_LIB.T6G(SCH_1):PAGE325
     4 HSC_ON @T6G_MB_LIB.T6G(SCH_1):HSC_ON    I17 @T6G_MB_LIB.T6G(SCH_1):PAGE325
    24 HSC_OCREF @T6G_MB_LIB.T6G(SCH_1):HSC_OCREF    I17 @T6G_MB_LIB.T6G(SCH_1):PAGE325
    23 HSC_CS_4 @T6G_MB_LIB.T6G(SCH_1):HSC_CS_4    I17 @T6G_MB_LIB.T6G(SCH_1):PAGE325
    22 HSC_IMON @T6G_MB_LIB.T6G(SCH_1):HSC_IMON    I17 @T6G_MB_LIB.T6G(SCH_1):PAGE325
    21 HSC_VDD_R_4 @T6G_MB_LIB.T6G(SCH_1):HSC_VDD_R_4    I17 @T6G_MB_LIB.T6G(SCH_1):PAGE325
    20 AGND_HSC @T6G_MB_LIB.T6G(SCH_1):AGND_HSC    I17 @T6G_MB_LIB.T6G(SCH_1):PAGE325
    19 HSC_SS @T6G_MB_LIB.T6G(SCH_1):HSC_SS    I17 @T6G_MB_LIB.T6G(SCH_1):PAGE325
     5 HSC_FAULT @T6G_MB_LIB.T6G(SCH_1):HSC_FAULT    I17 @T6G_MB_LIB.T6G(SCH_1):PAGE325
    18 HSC_VTEMP @T6G_MB_LIB.T6G(SCH_1):HSC_VTEMP    I17 @T6G_MB_LIB.T6G(SCH_1):PAGE325
     1 P12V_AUX @T6G_MB_LIB.T6G(SCH_1):P12V_AUX    I17 @T6G_MB_LIB.T6G(SCH_1):PAGE325
     2 P12V_AUX @T6G_MB_LIB.T6G(SCH_1):P12V_AUX    I17 @T6G_MB_LIB.T6G(SCH_1):PAGE325
    25 P12V_AUX @T6G_MB_LIB.T6G(SCH_1):P12V_AUX    I17 @T6G_MB_LIB.T6G(SCH_1):PAGE325
    26 P12V_AUX @T6G_MB_LIB.T6G(SCH_1):P12V_AUX    I17 @T6G_MB_LIB.T6G(SCH_1):PAGE325
     3 HSC_D_OC_4 @T6G_MB_LIB.T6G(SCH_1):HSC_D_OC_4    I17 @T6G_MB_LIB.T6G(SCH_1):PAGE325
    14 P12V_PSU @T6G_MB_LIB.T6G(SCH_1):P12V_PSU    I17 @T6G_MB_LIB.T6G(SCH_1):PAGE325
    15 P12V_PSU @T6G_MB_LIB.T6G(SCH_1):P12V_PSU    I17 @T6G_MB_LIB.T6G(SCH_1):PAGE325
    16 P12V_PSU @T6G_MB_LIB.T6G(SCH_1):P12V_PSU    I17 @T6G_MB_LIB.T6G(SCH_1):PAGE325
    33 P12V_PSU @T6G_MB_LIB.T6G(SCH_1):P12V_PSU    I17 @T6G_MB_LIB.T6G(SCH_1):PAGE325
    27 P12V_AUX @T6G_MB_LIB.T6G(SCH_1):P12V_AUX    I17 @T6G_MB_LIB.T6G(SCH_1):PAGE325
    28 P12V_AUX @T6G_MB_LIB.T6G(SCH_1):P12V_AUX    I17 @T6G_MB_LIB.T6G(SCH_1):PAGE325
    29 P12V_AUX @T6G_MB_LIB.T6G(SCH_1):P12V_AUX    I17 @T6G_MB_LIB.T6G(SCH_1):PAGE325
    30 P12V_AUX @T6G_MB_LIB.T6G(SCH_1):P12V_AUX    I17 @T6G_MB_LIB.T6G(SCH_1):PAGE325
    31 P12V_AUX @T6G_MB_LIB.T6G(SCH_1):P12V_AUX    I17 @T6G_MB_LIB.T6G(SCH_1):PAGE325
    32 P12V_AUX @T6G_MB_LIB.T6G(SCH_1):P12V_AUX    I17 @T6G_MB_LIB.T6G(SCH_1):PAGE325
     8 HSC_MODE_4 @T6G_MB_LIB.T6G(SCH_1):HSC_MODE_4    I17 @T6G_MB_LIB.T6G(SCH_1):PAGE325
    17 HSC_SCREF_4 @T6G_MB_LIB.T6G(SCH_1):HSC_SCREF_4    I17 @T6G_MB_LIB.T6G(SCH_1):PAGE325
     6 HSC_FLT_TYPE_4 @T6G_MB_LIB.T6G(SCH_1):HSC_FLT_TYPE_4    I17 @T6G_MB_LIB.T6G(SCH_1):PAGE325
     7 HSC_NC1_4 @T6G_MB_LIB.T6G(SCH_1):HSC_NC1_4    I17 @T6G_MB_LIB.T6G(SCH_1):PAGE325

PU299 RS31312R-RS31312R,SMLF,IC,AL031312000
    20 P12V_SCM_R @T6G_MB_LIB.T6G(SCH_1):P12V_SCM_R    I95 @T6G_MB_LIB.T6G(SCH_1):PAGE350
 21_22 P12V_AUX @T6G_MB_LIB.T6G(SCH_1):P12V_AUX    I95 @T6G_MB_LIB.T6G(SCH_1):PAGE350
    19 P12V_SCM_R @T6G_MB_LIB.T6G(SCH_1):P12V_SCM_R    I95 @T6G_MB_LIB.T6G(SCH_1):PAGE350
    18 P12V_SCM_R @T6G_MB_LIB.T6G(SCH_1):P12V_SCM_R    I95 @T6G_MB_LIB.T6G(SCH_1):PAGE350
    17 P12V_SCM_R @T6G_MB_LIB.T6G(SCH_1):P12V_SCM_R    I95 @T6G_MB_LIB.T6G(SCH_1):PAGE350
    16 P12V_SCM_R @T6G_MB_LIB.T6G(SCH_1):P12V_SCM_R    I95 @T6G_MB_LIB.T6G(SCH_1):PAGE350
    15 P12V_SCM_R @T6G_MB_LIB.T6G(SCH_1):P12V_SCM_R    I95 @T6G_MB_LIB.T6G(SCH_1):PAGE350
    14 P12V_SCM_R @T6G_MB_LIB.T6G(SCH_1):P12V_SCM_R    I95 @T6G_MB_LIB.T6G(SCH_1):PAGE350
    12 P12V_SCM_AVIN_PD @T6G_MB_LIB.T6G(SCH_1):P12V_SCM_AVIN_PD    I95 @T6G_MB_LIB.T6G(SCH_1):PAGE350
    13 P12V_SCM_R @T6G_MB_LIB.T6G(SCH_1):P12V_SCM_R    I95 @T6G_MB_LIB.T6G(SCH_1):PAGE350
    11 P12V_SCM_OV_FB @T6G_MB_LIB.T6G(SCH_1):P12V_SCM_OV_FB    I95 @T6G_MB_LIB.T6G(SCH_1):PAGE350
    10 HP_LVC3_SCM_HSC_PWRGD_R @T6G_MB_LIB.T6G(SCH_1):HP_LVC3_SCM_HSC_PWRGD_R    I95 @T6G_MB_LIB.T6G(SCH_1):PAGE350
     9 P12V_SCM_FLTB_N @T6G_MB_LIB.T6G(SCH_1):P12V_SCM_FLTB_N    I95 @T6G_MB_LIB.T6G(SCH_1):PAGE350
     8 P12V_SCM_IMON @T6G_MB_LIB.T6G(SCH_1):P12V_SCM_IMON    I95 @T6G_MB_LIB.T6G(SCH_1):PAGE350
    23 P12V_AUX @T6G_MB_LIB.T6G(SCH_1):P12V_AUX    I95 @T6G_MB_LIB.T6G(SCH_1):PAGE350
    24 P12V_AUX @T6G_MB_LIB.T6G(SCH_1):P12V_AUX    I95 @T6G_MB_LIB.T6G(SCH_1):PAGE350
    25 P12V_AUX @T6G_MB_LIB.T6G(SCH_1):P12V_AUX    I95 @T6G_MB_LIB.T6G(SCH_1):PAGE350
    26 P12V_AUX @T6G_MB_LIB.T6G(SCH_1):P12V_AUX    I95 @T6G_MB_LIB.T6G(SCH_1):PAGE350
     1 P12V_SCM_EN_R2 @T6G_MB_LIB.T6G(SCH_1):P12V_SCM_EN_R2    I95 @T6G_MB_LIB.T6G(SCH_1):PAGE350
     2    GND @T6G_MB_LIB.T6G(SCH_1):GND    I95 @T6G_MB_LIB.T6G(SCH_1):PAGE350
     3    GND @T6G_MB_LIB.T6G(SCH_1):GND    I95 @T6G_MB_LIB.T6G(SCH_1):PAGE350
     4 P12V_SCM_TIMER @T6G_MB_LIB.T6G(SCH_1):P12V_SCM_TIMER    I95 @T6G_MB_LIB.T6G(SCH_1):PAGE350
     5 P12V_SCM_ISET @T6G_MB_LIB.T6G(SCH_1):P12V_SCM_ISET    I95 @T6G_MB_LIB.T6G(SCH_1):PAGE350
     6 P12V_SCM_SS @T6G_MB_LIB.T6G(SCH_1):P12V_SCM_SS    I95 @T6G_MB_LIB.T6G(SCH_1):PAGE350
     7    GND @T6G_MB_LIB.T6G(SCH_1):GND    I95 @T6G_MB_LIB.T6G(SCH_1):PAGE350

PU300 MAX15090BEWIT-MAX15090BEWI+T,SMLF,IC,AL015080B00
    A2 P12V_SCM_VCC @T6G_MB_LIB.T6G(SCH_1):P12V_SCM_VCC    I86 @T6G_MB_LIB.T6G(SCH_1):PAGE350
    A3 P12V_AUX @T6G_MB_LIB.T6G(SCH_1):P12V_AUX    I86 @T6G_MB_LIB.T6G(SCH_1):PAGE350
    A5 P12V_AUX @T6G_MB_LIB.T6G(SCH_1):P12V_AUX    I86 @T6G_MB_LIB.T6G(SCH_1):PAGE350
    B3 P12V_AUX @T6G_MB_LIB.T6G(SCH_1):P12V_AUX    I86 @T6G_MB_LIB.T6G(SCH_1):PAGE350
    B5 P12V_AUX @T6G_MB_LIB.T6G(SCH_1):P12V_AUX    I86 @T6G_MB_LIB.T6G(SCH_1):PAGE350
    C3 P12V_AUX @T6G_MB_LIB.T6G(SCH_1):P12V_AUX    I86 @T6G_MB_LIB.T6G(SCH_1):PAGE350
    C5 P12V_AUX @T6G_MB_LIB.T6G(SCH_1):P12V_AUX    I86 @T6G_MB_LIB.T6G(SCH_1):PAGE350
    D5 P12V_AUX @T6G_MB_LIB.T6G(SCH_1):P12V_AUX    I86 @T6G_MB_LIB.T6G(SCH_1):PAGE350
    B1 P12V_SCM_CB @T6G_MB_LIB.T6G(SCH_1):P12V_SCM_CB    I86 @T6G_MB_LIB.T6G(SCH_1):PAGE350
    B7    GND @T6G_MB_LIB.T6G(SCH_1):GND    I86 @T6G_MB_LIB.T6G(SCH_1):PAGE350
    D1 P12V_SCM_REG @T6G_MB_LIB.T6G(SCH_1):P12V_SCM_REG    I86 @T6G_MB_LIB.T6G(SCH_1):PAGE350
    D2 P12V_SCM_UV @T6G_MB_LIB.T6G(SCH_1):P12V_SCM_UV    I86 @T6G_MB_LIB.T6G(SCH_1):PAGE350
    D3 P12V_SCM_OV @T6G_MB_LIB.T6G(SCH_1):P12V_SCM_OV    I86 @T6G_MB_LIB.T6G(SCH_1):PAGE350
    A1 P12V_SCM_SENSE @T6G_MB_LIB.T6G(SCH_1):P12V_SCM_SENSE    I86 @T6G_MB_LIB.T6G(SCH_1):PAGE350
    A4 P12V_SCM_R @T6G_MB_LIB.T6G(SCH_1):P12V_SCM_R    I86 @T6G_MB_LIB.T6G(SCH_1):PAGE350
    B4 P12V_SCM_R @T6G_MB_LIB.T6G(SCH_1):P12V_SCM_R    I86 @T6G_MB_LIB.T6G(SCH_1):PAGE350
    B6 P12V_SCM_R @T6G_MB_LIB.T6G(SCH_1):P12V_SCM_R    I86 @T6G_MB_LIB.T6G(SCH_1):PAGE350
    C4 P12V_SCM_R @T6G_MB_LIB.T6G(SCH_1):P12V_SCM_R    I86 @T6G_MB_LIB.T6G(SCH_1):PAGE350
    C6 P12V_SCM_R @T6G_MB_LIB.T6G(SCH_1):P12V_SCM_R    I86 @T6G_MB_LIB.T6G(SCH_1):PAGE350
    D4 P12V_SCM_R @T6G_MB_LIB.T6G(SCH_1):P12V_SCM_R    I86 @T6G_MB_LIB.T6G(SCH_1):PAGE350
    D6 P12V_SCM_R @T6G_MB_LIB.T6G(SCH_1):P12V_SCM_R    I86 @T6G_MB_LIB.T6G(SCH_1):PAGE350
    A6 P12V_SCM_GATE @T6G_MB_LIB.T6G(SCH_1):P12V_SCM_GATE    I86 @T6G_MB_LIB.T6G(SCH_1):PAGE350
    A7    GND @T6G_MB_LIB.T6G(SCH_1):GND    I86 @T6G_MB_LIB.T6G(SCH_1):PAGE350
    B2    GND @T6G_MB_LIB.T6G(SCH_1):GND    I86 @T6G_MB_LIB.T6G(SCH_1):PAGE350
    C1    GND @T6G_MB_LIB.T6G(SCH_1):GND    I86 @T6G_MB_LIB.T6G(SCH_1):PAGE350
    C2    GND @T6G_MB_LIB.T6G(SCH_1):GND    I86 @T6G_MB_LIB.T6G(SCH_1):PAGE350
    C7 P12V_SCM_FAULT_N @T6G_MB_LIB.T6G(SCH_1):P12V_SCM_FAULT_N    I86 @T6G_MB_LIB.T6G(SCH_1):PAGE350
    D7 P12V_SCM_PWRGD @T6G_MB_LIB.T6G(SCH_1):P12V_SCM_PWRGD    I86 @T6G_MB_LIB.T6G(SCH_1):PAGE350

PU6000 MPQ8626GDZ-MPQ8626GD-Z,SMLF,IC,AL008626000
     3 SW_P12V_AUX_P1V8_AUX_FLT @T6G_MB_LIB.T6G(SCH_1):SW_P12V_AUX_P1V8_AUX_FLT    I18 @T6G_MB_LIB.T6G(SCH_1):PAGE315
     9 PWRGD_P1V8_AUX @T6G_MB_LIB.T6G(SCH_1):PWRGD_P1V8_AUX    I18 @T6G_MB_LIB.T6G(SCH_1):PAGE315
    14    GND @T6G_MB_LIB.T6G(SCH_1):GND    I18 @T6G_MB_LIB.T6G(SCH_1):PAGE315
     5 P1V8_AUX_ENABLE @T6G_MB_LIB.T6G(SCH_1):P1V8_AUX_ENABLE    I18 @T6G_MB_LIB.T6G(SCH_1):PAGE315
    10 SW_P1V8_AUX_BT @T6G_MB_LIB.T6G(SCH_1):SW_P1V8_AUX_BT    I18 @T6G_MB_LIB.T6G(SCH_1):PAGE315
     6 P1V8_AUX_FB @T6G_MB_LIB.T6G(SCH_1):P1V8_AUX_FB    I18 @T6G_MB_LIB.T6G(SCH_1):PAGE315
     7    GND @T6G_MB_LIB.T6G(SCH_1):GND    I18 @T6G_MB_LIB.T6G(SCH_1):PAGE315
    13 P1V8_AUX_VCC @T6G_MB_LIB.T6G(SCH_1):P1V8_AUX_VCC    I18 @T6G_MB_LIB.T6G(SCH_1):PAGE315
     1    GND @T6G_MB_LIB.T6G(SCH_1):GND    I18 @T6G_MB_LIB.T6G(SCH_1):PAGE315
    11 SW_P1V8_AUX_PH @T6G_MB_LIB.T6G(SCH_1):SW_P1V8_AUX_PH    I18 @T6G_MB_LIB.T6G(SCH_1):PAGE315
     8 P1V8_AUX_REF @T6G_MB_LIB.T6G(SCH_1):P1V8_AUX_REF    I18 @T6G_MB_LIB.T6G(SCH_1):PAGE315
    12 P1V8_AUX_MODE @T6G_MB_LIB.T6G(SCH_1):P1V8_AUX_MODE    I18 @T6G_MB_LIB.T6G(SCH_1):PAGE315
     4 P1V8_AUX_CS @T6G_MB_LIB.T6G(SCH_1):P1V8_AUX_CS    I18 @T6G_MB_LIB.T6G(SCH_1):PAGE315
     2 SW_P1V8_AUX_PH @T6G_MB_LIB.T6G(SCH_1):SW_P1V8_AUX_PH    I18 @T6G_MB_LIB.T6G(SCH_1):PAGE315

PU6001 MPQ8626GDZ-MPQ8626GD-Z,SMLF,IC,AL008626000
     3 SW_P12V_AUX_P1V2_AUX_FLT @T6G_MB_LIB.T6G(SCH_1):SW_P12V_AUX_P1V2_AUX_FLT    I16 @T6G_MB_LIB.T6G(SCH_1):PAGE380
     9 PWRGD_P1V2_AUX @T6G_MB_LIB.T6G(SCH_1):PWRGD_P1V2_AUX    I16 @T6G_MB_LIB.T6G(SCH_1):PAGE380
    14    GND @T6G_MB_LIB.T6G(SCH_1):GND    I16 @T6G_MB_LIB.T6G(SCH_1):PAGE380
     5 P1V2_AUX_ENABLE @T6G_MB_LIB.T6G(SCH_1):P1V2_AUX_ENABLE    I16 @T6G_MB_LIB.T6G(SCH_1):PAGE380
    10 SW_P1V2_AUX_BT @T6G_MB_LIB.T6G(SCH_1):SW_P1V2_AUX_BT    I16 @T6G_MB_LIB.T6G(SCH_1):PAGE380
     6 P1V2_AUX_FB @T6G_MB_LIB.T6G(SCH_1):P1V2_AUX_FB    I16 @T6G_MB_LIB.T6G(SCH_1):PAGE380
     7    GND @T6G_MB_LIB.T6G(SCH_1):GND    I16 @T6G_MB_LIB.T6G(SCH_1):PAGE380
    13 P1V2_AUX_VCC @T6G_MB_LIB.T6G(SCH_1):P1V2_AUX_VCC    I16 @T6G_MB_LIB.T6G(SCH_1):PAGE380
     1    GND @T6G_MB_LIB.T6G(SCH_1):GND    I16 @T6G_MB_LIB.T6G(SCH_1):PAGE380
    11 SW_P1V2_AUX_PH @T6G_MB_LIB.T6G(SCH_1):SW_P1V2_AUX_PH    I16 @T6G_MB_LIB.T6G(SCH_1):PAGE380
     8 P1V2_AUX_REF @T6G_MB_LIB.T6G(SCH_1):P1V2_AUX_REF    I16 @T6G_MB_LIB.T6G(SCH_1):PAGE380
    12 P1V2_AUX_MODE @T6G_MB_LIB.T6G(SCH_1):P1V2_AUX_MODE    I16 @T6G_MB_LIB.T6G(SCH_1):PAGE380
     4 P1V2_AUX_CS @T6G_MB_LIB.T6G(SCH_1):P1V2_AUX_CS    I16 @T6G_MB_LIB.T6G(SCH_1):PAGE380
     2 SW_P1V2_AUX_PH @T6G_MB_LIB.T6G(SCH_1):SW_P1V2_AUX_PH    I16 @T6G_MB_LIB.T6G(SCH_1):PAGE380

PU6500 MPQ8633BGLEC838Z-MPQ8633BGLE-C838-Z,SMLF,IC,AL0086A
    10 SW_P12V_AUX_P1V8_RETIMER_CPU0_FLT @T6G_MB_LIB.T6G(SCH_1):SW_P12V_AUX_P1V8_RETIMER_CPU0_FLT    I51 @T6G_MB_LIB.T6G(SCH_1):PAGE469
     9 PWRGD_P1V8_RETIMER_CPU0 @T6G_MB_LIB.T6G(SCH_1):PWRGD_P1V8_RETIMER_CPU0    I51 @T6G_MB_LIB.T6G(SCH_1):PAGE469
 11_18    GND @T6G_MB_LIB.T6G(SCH_1):GND    I51 @T6G_MB_LIB.T6G(SCH_1):PAGE469
     8 P1V8_RETIMER_CPU0_EN @T6G_MB_LIB.T6G(SCH_1):P1V8_RETIMER_CPU0_EN    I51 @T6G_MB_LIB.T6G(SCH_1):PAGE469
     1 SW_P1V8_RETIMER_CPU0_BST @T6G_MB_LIB.T6G(SCH_1):SW_P1V8_RETIMER_CPU0_BST    I51 @T6G_MB_LIB.T6G(SCH_1):PAGE469
     7 P1V8_RETIMER_CPU0_FB @T6G_MB_LIB.T6G(SCH_1):P1V8_RETIMER_CPU0_FB    I51 @T6G_MB_LIB.T6G(SCH_1):PAGE469
     2    GND @T6G_MB_LIB.T6G(SCH_1):GND    I51 @T6G_MB_LIB.T6G(SCH_1):PAGE469
    19 P1V8_RETIMER_CPU0_VCC @T6G_MB_LIB.T6G(SCH_1):P1V8_RETIMER_CPU0_VCC    I51 @T6G_MB_LIB.T6G(SCH_1):PAGE469
     6    GND @T6G_MB_LIB.T6G(SCH_1):GND    I51 @T6G_MB_LIB.T6G(SCH_1):PAGE469
    20 SW_P1V8_RETIMER_CPU0_SW @T6G_MB_LIB.T6G(SCH_1):SW_P1V8_RETIMER_CPU0_SW    I51 @T6G_MB_LIB.T6G(SCH_1):PAGE469
     5 P1V8_RETIMER_CPU0_REF @T6G_MB_LIB.T6G(SCH_1):P1V8_RETIMER_CPU0_REF    I51 @T6G_MB_LIB.T6G(SCH_1):PAGE469
     4 P1V8_RETIMER_CPU0_MODE @T6G_MB_LIB.T6G(SCH_1):P1V8_RETIMER_CPU0_MODE    I51 @T6G_MB_LIB.T6G(SCH_1):PAGE469
     3 P1V8_RETIMER_CPU0_CS @T6G_MB_LIB.T6G(SCH_1):P1V8_RETIMER_CPU0_CS    I51 @T6G_MB_LIB.T6G(SCH_1):PAGE469
    21 SW_P12V_AUX_P1V8_RETIMER_CPU0_FLT @T6G_MB_LIB.T6G(SCH_1):SW_P12V_AUX_P1V8_RETIMER_CPU0_FLT    I51 @T6G_MB_LIB.T6G(SCH_1):PAGE469

PU6501 MPQ8633BGLEC838Z-MPQ8633BGLE-C838-Z,SMLF,IC,AL0086A
    10 SW_P12V_AUX_P1V8_RETIMER_CPU1_FLT @T6G_MB_LIB.T6G(SCH_1):SW_P12V_AUX_P1V8_RETIMER_CPU1_FLT    I51 @T6G_MB_LIB.T6G(SCH_1):PAGE470
     9 PWRGD_P1V8_RETIMER_CPU1 @T6G_MB_LIB.T6G(SCH_1):PWRGD_P1V8_RETIMER_CPU1    I51 @T6G_MB_LIB.T6G(SCH_1):PAGE470
 11_18    GND @T6G_MB_LIB.T6G(SCH_1):GND    I51 @T6G_MB_LIB.T6G(SCH_1):PAGE470
     8 P1V8_RETIMER_CPU1_EN @T6G_MB_LIB.T6G(SCH_1):P1V8_RETIMER_CPU1_EN    I51 @T6G_MB_LIB.T6G(SCH_1):PAGE470
     1 SW_P1V8_RETIMER_CPU1_BST @T6G_MB_LIB.T6G(SCH_1):SW_P1V8_RETIMER_CPU1_BST    I51 @T6G_MB_LIB.T6G(SCH_1):PAGE470
     7 P1V8_RETIMER_CPU1_FB @T6G_MB_LIB.T6G(SCH_1):P1V8_RETIMER_CPU1_FB    I51 @T6G_MB_LIB.T6G(SCH_1):PAGE470
     2    GND @T6G_MB_LIB.T6G(SCH_1):GND    I51 @T6G_MB_LIB.T6G(SCH_1):PAGE470
    19 P1V8_RETIMER_CPU1_VCC @T6G_MB_LIB.T6G(SCH_1):P1V8_RETIMER_CPU1_VCC    I51 @T6G_MB_LIB.T6G(SCH_1):PAGE470
     6    GND @T6G_MB_LIB.T6G(SCH_1):GND    I51 @T6G_MB_LIB.T6G(SCH_1):PAGE470
    20 SW_P1V8_RETIMER_CPU1_SW @T6G_MB_LIB.T6G(SCH_1):SW_P1V8_RETIMER_CPU1_SW    I51 @T6G_MB_LIB.T6G(SCH_1):PAGE470
     5 P1V8_RETIMER_CPU1_REF @T6G_MB_LIB.T6G(SCH_1):P1V8_RETIMER_CPU1_REF    I51 @T6G_MB_LIB.T6G(SCH_1):PAGE470
     4 P1V8_RETIMER_CPU1_MODE @T6G_MB_LIB.T6G(SCH_1):P1V8_RETIMER_CPU1_MODE    I51 @T6G_MB_LIB.T6G(SCH_1):PAGE470
     3 P1V8_RETIMER_CPU1_CS @T6G_MB_LIB.T6G(SCH_1):P1V8_RETIMER_CPU1_CS    I51 @T6G_MB_LIB.T6G(SCH_1):PAGE470
    21 SW_P12V_AUX_P1V8_RETIMER_CPU1_FLT @T6G_MB_LIB.T6G(SCH_1):SW_P12V_AUX_P1V8_RETIMER_CPU1_FLT    I51 @T6G_MB_LIB.T6G(SCH_1):PAGE470

PU6502 ISL69260IRAZT-ISL69260IRAZ-T,SMLF,IC,AL069260000
    23 P0V9_RETIMER_CPU0_IMON1 @T6G_MB_LIB.T6G(SCH_1):P0V9_RETIMER_CPU0_IMON1    I42 @T6G_MB_LIB.T6G(SCH_1):PAGE475
    39 P0V9_RETIMER_CPU0_VCC @T6G_MB_LIB.T6G(SCH_1):P0V9_RETIMER_CPU0_VCC    I42 @T6G_MB_LIB.T6G(SCH_1):PAGE475
    20 P0V9_RETIMER_CPU0_EN1_R @T6G_MB_LIB.T6G(SCH_1):P0V9_RETIMER_CPU0_EN1_R    I42 @T6G_MB_LIB.T6G(SCH_1):PAGE475
    10 P0V9_RETIMER_CPU0_PMSCL_R @T6G_MB_LIB.T6G(SCH_1):P0V9_RETIMER_CPU0_PMSCL_R    I42 @T6G_MB_LIB.T6G(SCH_1):PAGE475
    18 P0V9_RETIMER_CPU0_SVID_SDA @T6G_MB_LIB.T6G(SCH_1):P0V9_RETIMER_CPU0_SVID_SDA    I42 @T6G_MB_LIB.T6G(SCH_1):PAGE475
    24 P0V9_RETIMER_CPU0_IMON2 @T6G_MB_LIB.T6G(SCH_1):P0V9_RETIMER_CPU0_IMON2    I42 @T6G_MB_LIB.T6G(SCH_1):PAGE475
    19 TP_P0V9_RETIMER_CPU0_SVID_ALERT_N @T6G_MB_LIB.T6G(SCH_1):TP_P0V9_RETIMER_CPU0_SVID_ALERT_N    I42 @T6G_MB_LIB.T6G(SCH_1):PAGE475
    14 P0V9_RETIMER_CPU0_VRHOT @T6G_MB_LIB.T6G(SCH_1):P0V9_RETIMER_CPU0_VRHOT    I42 @T6G_MB_LIB.T6G(SCH_1):PAGE475
    25 NC_P0V9_RETIMER_CPU0_IMON3 @T6G_MB_LIB.T6G(SCH_1):NC_P0V9_RETIMER_CPU0_IMON3    I42 @T6G_MB_LIB.T6G(SCH_1):PAGE475
    26 NC_P0V9_RETIMER_CPU0_IMON4 @T6G_MB_LIB.T6G(SCH_1):NC_P0V9_RETIMER_CPU0_IMON4    I42 @T6G_MB_LIB.T6G(SCH_1):PAGE475
    16 NC_P0V9_RETIMER_CPU0_PG1 @T6G_MB_LIB.T6G(SCH_1):NC_P0V9_RETIMER_CPU0_PG1    I42 @T6G_MB_LIB.T6G(SCH_1):PAGE475
    17 P0V9_RETIMER_CPU0_SVID_CLK @T6G_MB_LIB.T6G(SCH_1):P0V9_RETIMER_CPU0_SVID_CLK    I42 @T6G_MB_LIB.T6G(SCH_1):PAGE475
    11 TP_P0V9_RETIMER_CPU0_PMALERT @T6G_MB_LIB.T6G(SCH_1):TP_P0V9_RETIMER_CPU0_PMALERT    I42 @T6G_MB_LIB.T6G(SCH_1):PAGE475
    13 P0V9_RETIMER_CPU0_EN0_R @T6G_MB_LIB.T6G(SCH_1):P0V9_RETIMER_CPU0_EN0_R    I42 @T6G_MB_LIB.T6G(SCH_1):PAGE475
    22 P0V9_RETIMER_CPU0_SENSE_SH_N @T6G_MB_LIB.T6G(SCH_1):P0V9_RETIMER_CPU0_SENSE_SH_N    I42 @T6G_MB_LIB.T6G(SCH_1):PAGE475
     9 P0V9_RETIMER_CPU0_PMSDA_R @T6G_MB_LIB.T6G(SCH_1):P0V9_RETIMER_CPU0_PMSDA_R    I42 @T6G_MB_LIB.T6G(SCH_1):PAGE475
     5 NC_P0V9_RETIMER_CPU0_PWM4 @T6G_MB_LIB.T6G(SCH_1):NC_P0V9_RETIMER_CPU0_PWM4    I42 @T6G_MB_LIB.T6G(SCH_1):PAGE475
     6 NC_P0V9_RETIMER_CPU0_PWM3 @T6G_MB_LIB.T6G(SCH_1):NC_P0V9_RETIMER_CPU0_PWM3    I42 @T6G_MB_LIB.T6G(SCH_1):PAGE475
    21 P0V9_RETIMER_CPU0_SENSE_R_P @T6G_MB_LIB.T6G(SCH_1):P0V9_RETIMER_CPU0_SENSE_R_P    I42 @T6G_MB_LIB.T6G(SCH_1):PAGE475
     2 NC_P0V9_RETIMER_CPU0_PWM7 @T6G_MB_LIB.T6G(SCH_1):NC_P0V9_RETIMER_CPU0_PWM7    I42 @T6G_MB_LIB.T6G(SCH_1):PAGE475
    12 PWRGD_P0V9_RETIMER_CPU0_R @T6G_MB_LIB.T6G(SCH_1):PWRGD_P0V9_RETIMER_CPU0_R    I42 @T6G_MB_LIB.T6G(SCH_1):PAGE475
     7 P0V9_RETIMER_CPU0_PWM2 @T6G_MB_LIB.T6G(SCH_1):P0V9_RETIMER_CPU0_PWM2    I42 @T6G_MB_LIB.T6G(SCH_1):PAGE475
    40 PV09_RETIMER_CPU0_VCCS @T6G_MB_LIB.T6G(SCH_1):PV09_RETIMER_CPU0_VCCS    I42 @T6G_MB_LIB.T6G(SCH_1):PAGE475
    37 P0V9_RETIMER_CPU0_VMON @T6G_MB_LIB.T6G(SCH_1):P0V9_RETIMER_CPU0_VMON    I42 @T6G_MB_LIB.T6G(SCH_1):PAGE475
    38 P0V9_RETIMER_CPU0_VINSEN @T6G_MB_LIB.T6G(SCH_1):P0V9_RETIMER_CPU0_VINSEN    I42 @T6G_MB_LIB.T6G(SCH_1):PAGE475
    36 P0V9_RETIMER_CPU0_TEMP1_R @T6G_MB_LIB.T6G(SCH_1):P0V9_RETIMER_CPU0_TEMP1_R    I42 @T6G_MB_LIB.T6G(SCH_1):PAGE475
    15 P0V9_RETIMER_CPU0_INALERT @T6G_MB_LIB.T6G(SCH_1):P0V9_RETIMER_CPU0_INALERT    I42 @T6G_MB_LIB.T6G(SCH_1):PAGE475
    32    GND @T6G_MB_LIB.T6G(SCH_1):GND    I42 @T6G_MB_LIB.T6G(SCH_1):PAGE475
    31    GND @T6G_MB_LIB.T6G(SCH_1):GND    I42 @T6G_MB_LIB.T6G(SCH_1):PAGE475
    29 NC_P0V9_RETIMER_CPU0_IMON7 @T6G_MB_LIB.T6G(SCH_1):NC_P0V9_RETIMER_CPU0_IMON7    I42 @T6G_MB_LIB.T6G(SCH_1):PAGE475
     8 P0V9_RETIMER_CPU0_PWM1 @T6G_MB_LIB.T6G(SCH_1):P0V9_RETIMER_CPU0_PWM1    I42 @T6G_MB_LIB.T6G(SCH_1):PAGE475
     4 NC_P0V9_RETIMER_CPU0_PWM5 @T6G_MB_LIB.T6G(SCH_1):NC_P0V9_RETIMER_CPU0_PWM5    I42 @T6G_MB_LIB.T6G(SCH_1):PAGE475
    27 NC_P0V9_RETIMER_CPU0_IMON5 @T6G_MB_LIB.T6G(SCH_1):NC_P0V9_RETIMER_CPU0_IMON5    I42 @T6G_MB_LIB.T6G(SCH_1):PAGE475
     3 NC_P0V9_RETIMER_CPU0_PWM6 @T6G_MB_LIB.T6G(SCH_1):NC_P0V9_RETIMER_CPU0_PWM6    I42 @T6G_MB_LIB.T6G(SCH_1):PAGE475
    28 NC_P0V9_RETIMER_CPU0_IMON6 @T6G_MB_LIB.T6G(SCH_1):NC_P0V9_RETIMER_CPU0_IMON6    I42 @T6G_MB_LIB.T6G(SCH_1):PAGE475
    33 P0V9_RETIMER_CPU0_CFP @T6G_MB_LIB.T6G(SCH_1):P0V9_RETIMER_CPU0_CFP    I42 @T6G_MB_LIB.T6G(SCH_1):PAGE475
    TH    GND @T6G_MB_LIB.T6G(SCH_1):GND    I42 @T6G_MB_LIB.T6G(SCH_1):PAGE475
    34 P0V9_RETIMER_CPU0_ADDR @T6G_MB_LIB.T6G(SCH_1):P0V9_RETIMER_CPU0_ADDR    I42 @T6G_MB_LIB.T6G(SCH_1):PAGE475
    35 P0V9_RETIMER_CPU0_TEMP0 @T6G_MB_LIB.T6G(SCH_1):P0V9_RETIMER_CPU0_TEMP0    I42 @T6G_MB_LIB.T6G(SCH_1):PAGE475
     1 NC_P0V9_RETIMER_CPU0_PWM8 @T6G_MB_LIB.T6G(SCH_1):NC_P0V9_RETIMER_CPU0_PWM8    I42 @T6G_MB_LIB.T6G(SCH_1):PAGE475
    30 NC_P0V9_RETIMER_CPU0_IMON8 @T6G_MB_LIB.T6G(SCH_1):NC_P0V9_RETIMER_CPU0_IMON8    I42 @T6G_MB_LIB.T6G(SCH_1):PAGE475

PU6503 ISL99390FRZTR5935-ISL99390FRZ-TR5935,SMLF,IC,AL099A
    34 P0V9_RETIMER_CPU0_PWM1 @T6G_MB_LIB.T6G(SCH_1):P0V9_RETIMER_CPU0_PWM1    I53 @T6G_MB_LIB.T6G(SCH_1):PAGE476
    39 PV09_RETIMER_CPU0_VCCS @T6G_MB_LIB.T6G(SCH_1):PV09_RETIMER_CPU0_VCCS    I53 @T6G_MB_LIB.T6G(SCH_1):PAGE476
     3 P0V9_RETIMER_CPU0_VCC1 @T6G_MB_LIB.T6G(SCH_1):P0V9_RETIMER_CPU0_VCC1    I53 @T6G_MB_LIB.T6G(SCH_1):PAGE476
     2    GND @T6G_MB_LIB.T6G(SCH_1):GND    I53 @T6G_MB_LIB.T6G(SCH_1):PAGE476
    33 SW_P0V9_RETIMER_CPU0_BOOT1 @T6G_MB_LIB.T6G(SCH_1):SW_P0V9_RETIMER_CPU0_BOOT1    I53 @T6G_MB_LIB.T6G(SCH_1):PAGE476
 25_29 SW_P12V_AUX_P0V9_RETIMER_CPU0_FLT @T6G_MB_LIB.T6G(SCH_1):SW_P12V_AUX_P0V9_RETIMER_CPU0_FLT    I53 @T6G_MB_LIB.T6G(SCH_1):PAGE476
    32 SW_P0V9_RETIMER_CPU0_PH1 @T6G_MB_LIB.T6G(SCH_1):SW_P0V9_RETIMER_CPU0_PH1    I53 @T6G_MB_LIB.T6G(SCH_1):PAGE476
     4 P0V9_RETIMER_CPU0_PVCC @T6G_MB_LIB.T6G(SCH_1):P0V9_RETIMER_CPU0_PVCC    I53 @T6G_MB_LIB.T6G(SCH_1):PAGE476
    36 P0V9_RETIMER_CPU0_TEMP0 @T6G_MB_LIB.T6G(SCH_1):P0V9_RETIMER_CPU0_TEMP0    I53 @T6G_MB_LIB.T6G(SCH_1):PAGE476
    38 P0V9_RETIMER_CPU0_IMON1 @T6G_MB_LIB.T6G(SCH_1):P0V9_RETIMER_CPU0_IMON1    I53 @T6G_MB_LIB.T6G(SCH_1):PAGE476
    37 P0V9_RETIMER_CPU0_LSET1 @T6G_MB_LIB.T6G(SCH_1):P0V9_RETIMER_CPU0_LSET1    I53 @T6G_MB_LIB.T6G(SCH_1):PAGE476
 10_19 SW_P0V9_RETIMER_CPU0_SW1 @T6G_MB_LIB.T6G(SCH_1):SW_P0V9_RETIMER_CPU0_SW1    I53 @T6G_MB_LIB.T6G(SCH_1):PAGE476
     5    GND @T6G_MB_LIB.T6G(SCH_1):GND    I53 @T6G_MB_LIB.T6G(SCH_1):PAGE476
    30 SW_P12V_AUX_P0V9_RETIMER_CPU0_FLT @T6G_MB_LIB.T6G(SCH_1):SW_P12V_AUX_P0V9_RETIMER_CPU0_FLT    I53 @T6G_MB_LIB.T6G(SCH_1):PAGE476
     1 P0V9_RETIMER_CPU0_VOS1 @T6G_MB_LIB.T6G(SCH_1):P0V9_RETIMER_CPU0_VOS1    I53 @T6G_MB_LIB.T6G(SCH_1):PAGE476
    40    GND @T6G_MB_LIB.T6G(SCH_1):GND    I53 @T6G_MB_LIB.T6G(SCH_1):PAGE476
    35 P0V9_RETIMER_CPU0_VCC1 @T6G_MB_LIB.T6G(SCH_1):P0V9_RETIMER_CPU0_VCC1    I53 @T6G_MB_LIB.T6G(SCH_1):PAGE476
    31 NC_PV09_RETIMER_CPU0_DNC1 @T6G_MB_LIB.T6G(SCH_1):NC_PV09_RETIMER_CPU0_DNC1    I53 @T6G_MB_LIB.T6G(SCH_1):PAGE476
     6 NC_PV09_RETIMER_CPU0_GL1_1 @T6G_MB_LIB.T6G(SCH_1):NC_PV09_RETIMER_CPU0_GL1_1    I53 @T6G_MB_LIB.T6G(SCH_1):PAGE476
    41 NC_PV09_RETIMER_CPU0_GL2_1 @T6G_MB_LIB.T6G(SCH_1):NC_PV09_RETIMER_CPU0_GL2_1    I53 @T6G_MB_LIB.T6G(SCH_1):PAGE476
7_9-20_24    GND @T6G_MB_LIB.T6G(SCH_1):GND    I53 @T6G_MB_LIB.T6G(SCH_1):PAGE476

PU6504 ISL99390FRZTR5935-ISL99390FRZ-TR5935,SMLF,IC,AL099A
    34 P0V9_RETIMER_CPU0_PWM2 @T6G_MB_LIB.T6G(SCH_1):P0V9_RETIMER_CPU0_PWM2   I270 @T6G_MB_LIB.T6G(SCH_1):PAGE476
    39 PV09_RETIMER_CPU0_VCCS @T6G_MB_LIB.T6G(SCH_1):PV09_RETIMER_CPU0_VCCS   I270 @T6G_MB_LIB.T6G(SCH_1):PAGE476
     3 P0V9_RETIMER_CPU0_VCC2 @T6G_MB_LIB.T6G(SCH_1):P0V9_RETIMER_CPU0_VCC2   I270 @T6G_MB_LIB.T6G(SCH_1):PAGE476
     2    GND @T6G_MB_LIB.T6G(SCH_1):GND   I270 @T6G_MB_LIB.T6G(SCH_1):PAGE476
    33 SW_P0V9_RETIMER_CPU0_BOOT2 @T6G_MB_LIB.T6G(SCH_1):SW_P0V9_RETIMER_CPU0_BOOT2   I270 @T6G_MB_LIB.T6G(SCH_1):PAGE476
 25_29 SW_P12V_AUX_P0V9_RETIMER_CPU0_FLT @T6G_MB_LIB.T6G(SCH_1):SW_P12V_AUX_P0V9_RETIMER_CPU0_FLT   I270 @T6G_MB_LIB.T6G(SCH_1):PAGE476
    32 SW_P0V9_RETIMER_CPU0_PH2 @T6G_MB_LIB.T6G(SCH_1):SW_P0V9_RETIMER_CPU0_PH2   I270 @T6G_MB_LIB.T6G(SCH_1):PAGE476
     4 P0V9_RETIMER_CPU0_PVCC @T6G_MB_LIB.T6G(SCH_1):P0V9_RETIMER_CPU0_PVCC   I270 @T6G_MB_LIB.T6G(SCH_1):PAGE476
    36 P0V9_RETIMER_CPU0_TEMP0 @T6G_MB_LIB.T6G(SCH_1):P0V9_RETIMER_CPU0_TEMP0   I270 @T6G_MB_LIB.T6G(SCH_1):PAGE476
    38 P0V9_RETIMER_CPU0_IMON2 @T6G_MB_LIB.T6G(SCH_1):P0V9_RETIMER_CPU0_IMON2   I270 @T6G_MB_LIB.T6G(SCH_1):PAGE476
    37 P0V9_RETIMER_CPU0_LSET2 @T6G_MB_LIB.T6G(SCH_1):P0V9_RETIMER_CPU0_LSET2   I270 @T6G_MB_LIB.T6G(SCH_1):PAGE476
 10_19 SW_P0V9_RETIMER_CPU0_SW2 @T6G_MB_LIB.T6G(SCH_1):SW_P0V9_RETIMER_CPU0_SW2   I270 @T6G_MB_LIB.T6G(SCH_1):PAGE476
     5    GND @T6G_MB_LIB.T6G(SCH_1):GND   I270 @T6G_MB_LIB.T6G(SCH_1):PAGE476
    30 SW_P12V_AUX_P0V9_RETIMER_CPU0_FLT @T6G_MB_LIB.T6G(SCH_1):SW_P12V_AUX_P0V9_RETIMER_CPU0_FLT   I270 @T6G_MB_LIB.T6G(SCH_1):PAGE476
     1 P0V9_RETIMER_CPU0_VOS2 @T6G_MB_LIB.T6G(SCH_1):P0V9_RETIMER_CPU0_VOS2   I270 @T6G_MB_LIB.T6G(SCH_1):PAGE476
    40    GND @T6G_MB_LIB.T6G(SCH_1):GND   I270 @T6G_MB_LIB.T6G(SCH_1):PAGE476
    35 P0V9_RETIMER_CPU0_VCC2 @T6G_MB_LIB.T6G(SCH_1):P0V9_RETIMER_CPU0_VCC2   I270 @T6G_MB_LIB.T6G(SCH_1):PAGE476
    31 NC_PV09_RETIMER_CPU0_DNC2 @T6G_MB_LIB.T6G(SCH_1):NC_PV09_RETIMER_CPU0_DNC2   I270 @T6G_MB_LIB.T6G(SCH_1):PAGE476
     6 NC_PV09_RETIMER_CPU0_GL1_2 @T6G_MB_LIB.T6G(SCH_1):NC_PV09_RETIMER_CPU0_GL1_2   I270 @T6G_MB_LIB.T6G(SCH_1):PAGE476
    41 NC_PV09_RETIMER_CPU0_GL2_2 @T6G_MB_LIB.T6G(SCH_1):NC_PV09_RETIMER_CPU0_GL2_2   I270 @T6G_MB_LIB.T6G(SCH_1):PAGE476
7_9-20_24    GND @T6G_MB_LIB.T6G(SCH_1):GND   I270 @T6G_MB_LIB.T6G(SCH_1):PAGE476

PU6510 ISL69260IRAZT-ISL69260IRAZ-T,SMLF,IC,AL069260000
    23 P0V9_RETIMER_CPU1_IMON1 @T6G_MB_LIB.T6G(SCH_1):P0V9_RETIMER_CPU1_IMON1    I88 @T6G_MB_LIB.T6G(SCH_1):PAGE477
    39 P0V9_RETIMER_CPU1_VCC @T6G_MB_LIB.T6G(SCH_1):P0V9_RETIMER_CPU1_VCC    I88 @T6G_MB_LIB.T6G(SCH_1):PAGE477
    20 P0V9_RETIMER_CPU1_EN1_R @T6G_MB_LIB.T6G(SCH_1):P0V9_RETIMER_CPU1_EN1_R    I88 @T6G_MB_LIB.T6G(SCH_1):PAGE477
    10 P0V9_RETIMER_CPU1_PMSCL_R @T6G_MB_LIB.T6G(SCH_1):P0V9_RETIMER_CPU1_PMSCL_R    I88 @T6G_MB_LIB.T6G(SCH_1):PAGE477
    18 P0V9_RETIMER_CPU1_SVID_SDA @T6G_MB_LIB.T6G(SCH_1):P0V9_RETIMER_CPU1_SVID_SDA    I88 @T6G_MB_LIB.T6G(SCH_1):PAGE477
    24 P0V9_RETIMER_CPU1_IMON2 @T6G_MB_LIB.T6G(SCH_1):P0V9_RETIMER_CPU1_IMON2    I88 @T6G_MB_LIB.T6G(SCH_1):PAGE477
    19 TP_P0V9_RETIMER_CPU1_SVID_ALERT_N @T6G_MB_LIB.T6G(SCH_1):TP_P0V9_RETIMER_CPU1_SVID_ALERT_N    I88 @T6G_MB_LIB.T6G(SCH_1):PAGE477
    14 P0V9_RETIMER_CPU1_VRHOT @T6G_MB_LIB.T6G(SCH_1):P0V9_RETIMER_CPU1_VRHOT    I88 @T6G_MB_LIB.T6G(SCH_1):PAGE477
    25 NC_P0V9_RETIMER_CPU1_IMON3 @T6G_MB_LIB.T6G(SCH_1):NC_P0V9_RETIMER_CPU1_IMON3    I88 @T6G_MB_LIB.T6G(SCH_1):PAGE477
    26 NC_P0V9_RETIMER_CPU1_IMON4 @T6G_MB_LIB.T6G(SCH_1):NC_P0V9_RETIMER_CPU1_IMON4    I88 @T6G_MB_LIB.T6G(SCH_1):PAGE477
    16 NC_P0V9_RETIMER_CPU1_PG1 @T6G_MB_LIB.T6G(SCH_1):NC_P0V9_RETIMER_CPU1_PG1    I88 @T6G_MB_LIB.T6G(SCH_1):PAGE477
    17 P0V9_RETIMER_CPU1_SVID_CLK @T6G_MB_LIB.T6G(SCH_1):P0V9_RETIMER_CPU1_SVID_CLK    I88 @T6G_MB_LIB.T6G(SCH_1):PAGE477
    11 TP_P0V9_RETIMER_CPU1_PMALERT @T6G_MB_LIB.T6G(SCH_1):TP_P0V9_RETIMER_CPU1_PMALERT    I88 @T6G_MB_LIB.T6G(SCH_1):PAGE477
    13 P0V9_RETIMER_CPU1_EN0_R @T6G_MB_LIB.T6G(SCH_1):P0V9_RETIMER_CPU1_EN0_R    I88 @T6G_MB_LIB.T6G(SCH_1):PAGE477
    22 P0V9_RETIMER_CPU1_SENSE_SH_N @T6G_MB_LIB.T6G(SCH_1):P0V9_RETIMER_CPU1_SENSE_SH_N    I88 @T6G_MB_LIB.T6G(SCH_1):PAGE477
     9 P0V9_RETIMER_CPU1_PMSDA_R @T6G_MB_LIB.T6G(SCH_1):P0V9_RETIMER_CPU1_PMSDA_R    I88 @T6G_MB_LIB.T6G(SCH_1):PAGE477
     5 NC_P0V9_RETIMER_CPU1_PWM4 @T6G_MB_LIB.T6G(SCH_1):NC_P0V9_RETIMER_CPU1_PWM4    I88 @T6G_MB_LIB.T6G(SCH_1):PAGE477
     6 NC_P0V9_RETIMER_CPU1_PWM3 @T6G_MB_LIB.T6G(SCH_1):NC_P0V9_RETIMER_CPU1_PWM3    I88 @T6G_MB_LIB.T6G(SCH_1):PAGE477
    21 P0V9_RETIMER_CPU1_SENSE_R_P @T6G_MB_LIB.T6G(SCH_1):P0V9_RETIMER_CPU1_SENSE_R_P    I88 @T6G_MB_LIB.T6G(SCH_1):PAGE477
     2 NC_P0V9_RETIMER_CPU1_PWM7 @T6G_MB_LIB.T6G(SCH_1):NC_P0V9_RETIMER_CPU1_PWM7    I88 @T6G_MB_LIB.T6G(SCH_1):PAGE477
    12 PWRGD_P0V9_RETIMER_CPU1_R @T6G_MB_LIB.T6G(SCH_1):PWRGD_P0V9_RETIMER_CPU1_R    I88 @T6G_MB_LIB.T6G(SCH_1):PAGE477
     7 P0V9_RETIMER_CPU1_PWM2 @T6G_MB_LIB.T6G(SCH_1):P0V9_RETIMER_CPU1_PWM2    I88 @T6G_MB_LIB.T6G(SCH_1):PAGE477
    40 PV09_RETIMER_CPU1_VCCS @T6G_MB_LIB.T6G(SCH_1):PV09_RETIMER_CPU1_VCCS    I88 @T6G_MB_LIB.T6G(SCH_1):PAGE477
    37 P0V9_RETIMER_CPU1_VMON @T6G_MB_LIB.T6G(SCH_1):P0V9_RETIMER_CPU1_VMON    I88 @T6G_MB_LIB.T6G(SCH_1):PAGE477
    38 P0V9_RETIMER_CPU1_VINSEN @T6G_MB_LIB.T6G(SCH_1):P0V9_RETIMER_CPU1_VINSEN    I88 @T6G_MB_LIB.T6G(SCH_1):PAGE477
    36 P0V9_RETIMER_CPU1_TEMP1_R @T6G_MB_LIB.T6G(SCH_1):P0V9_RETIMER_CPU1_TEMP1_R    I88 @T6G_MB_LIB.T6G(SCH_1):PAGE477
    15 P0V9_RETIMER_CPU1_INALERT @T6G_MB_LIB.T6G(SCH_1):P0V9_RETIMER_CPU1_INALERT    I88 @T6G_MB_LIB.T6G(SCH_1):PAGE477
    32    GND @T6G_MB_LIB.T6G(SCH_1):GND    I88 @T6G_MB_LIB.T6G(SCH_1):PAGE477
    31    GND @T6G_MB_LIB.T6G(SCH_1):GND    I88 @T6G_MB_LIB.T6G(SCH_1):PAGE477
    29 NC_P0V9_RETIMER_CPU1_IMON7 @T6G_MB_LIB.T6G(SCH_1):NC_P0V9_RETIMER_CPU1_IMON7    I88 @T6G_MB_LIB.T6G(SCH_1):PAGE477
     8 P0V9_RETIMER_CPU1_PWM1 @T6G_MB_LIB.T6G(SCH_1):P0V9_RETIMER_CPU1_PWM1    I88 @T6G_MB_LIB.T6G(SCH_1):PAGE477
     4 NC_P0V9_RETIMER_CPU1_PWM5 @T6G_MB_LIB.T6G(SCH_1):NC_P0V9_RETIMER_CPU1_PWM5    I88 @T6G_MB_LIB.T6G(SCH_1):PAGE477
    27 NC_P0V9_RETIMER_CPU1_IMON5 @T6G_MB_LIB.T6G(SCH_1):NC_P0V9_RETIMER_CPU1_IMON5    I88 @T6G_MB_LIB.T6G(SCH_1):PAGE477
     3 NC_P0V9_RETIMER_CPU1_PWM6 @T6G_MB_LIB.T6G(SCH_1):NC_P0V9_RETIMER_CPU1_PWM6    I88 @T6G_MB_LIB.T6G(SCH_1):PAGE477
    28 NC_P0V9_RETIMER_CPU1_IMON6 @T6G_MB_LIB.T6G(SCH_1):NC_P0V9_RETIMER_CPU1_IMON6    I88 @T6G_MB_LIB.T6G(SCH_1):PAGE477
    33 P0V9_RETIMER_CPU1_CFP @T6G_MB_LIB.T6G(SCH_1):P0V9_RETIMER_CPU1_CFP    I88 @T6G_MB_LIB.T6G(SCH_1):PAGE477
    TH    GND @T6G_MB_LIB.T6G(SCH_1):GND    I88 @T6G_MB_LIB.T6G(SCH_1):PAGE477
    34 P0V9_RETIMER_CPU1_ADDR @T6G_MB_LIB.T6G(SCH_1):P0V9_RETIMER_CPU1_ADDR    I88 @T6G_MB_LIB.T6G(SCH_1):PAGE477
    35 P0V9_RETIMER_CPU1_TEMP0 @T6G_MB_LIB.T6G(SCH_1):P0V9_RETIMER_CPU1_TEMP0    I88 @T6G_MB_LIB.T6G(SCH_1):PAGE477
     1 NC_P0V9_RETIMER_CPU1_PWM8 @T6G_MB_LIB.T6G(SCH_1):NC_P0V9_RETIMER_CPU1_PWM8    I88 @T6G_MB_LIB.T6G(SCH_1):PAGE477
    30 NC_P0V9_RETIMER_CPU1_IMON8 @T6G_MB_LIB.T6G(SCH_1):NC_P0V9_RETIMER_CPU1_IMON8    I88 @T6G_MB_LIB.T6G(SCH_1):PAGE477

PU6511 ISL99390FRZTR5935-ISL99390FRZ-TR5935,SMLF,IC,AL099A
    34 P0V9_RETIMER_CPU1_PWM1 @T6G_MB_LIB.T6G(SCH_1):P0V9_RETIMER_CPU1_PWM1    I51 @T6G_MB_LIB.T6G(SCH_1):PAGE478
    39 PV09_RETIMER_CPU1_VCCS @T6G_MB_LIB.T6G(SCH_1):PV09_RETIMER_CPU1_VCCS    I51 @T6G_MB_LIB.T6G(SCH_1):PAGE478
     3 P0V9_RETIMER_CPU1_VCC1 @T6G_MB_LIB.T6G(SCH_1):P0V9_RETIMER_CPU1_VCC1    I51 @T6G_MB_LIB.T6G(SCH_1):PAGE478
     2    GND @T6G_MB_LIB.T6G(SCH_1):GND    I51 @T6G_MB_LIB.T6G(SCH_1):PAGE478
    33 SW_P0V9_RETIMER_CPU1_BOOT1 @T6G_MB_LIB.T6G(SCH_1):SW_P0V9_RETIMER_CPU1_BOOT1    I51 @T6G_MB_LIB.T6G(SCH_1):PAGE478
 25_29 SW_P12V_AUX_P0V9_RETIMER_CPU1_FLT @T6G_MB_LIB.T6G(SCH_1):SW_P12V_AUX_P0V9_RETIMER_CPU1_FLT    I51 @T6G_MB_LIB.T6G(SCH_1):PAGE478
    32 SW_P0V9_RETIMER_CPU1_PH1 @T6G_MB_LIB.T6G(SCH_1):SW_P0V9_RETIMER_CPU1_PH1    I51 @T6G_MB_LIB.T6G(SCH_1):PAGE478
     4 P0V9_RETIMER_CPU1_PVCC @T6G_MB_LIB.T6G(SCH_1):P0V9_RETIMER_CPU1_PVCC    I51 @T6G_MB_LIB.T6G(SCH_1):PAGE478
    36 P0V9_RETIMER_CPU1_TEMP0 @T6G_MB_LIB.T6G(SCH_1):P0V9_RETIMER_CPU1_TEMP0    I51 @T6G_MB_LIB.T6G(SCH_1):PAGE478
    38 P0V9_RETIMER_CPU1_IMON1 @T6G_MB_LIB.T6G(SCH_1):P0V9_RETIMER_CPU1_IMON1    I51 @T6G_MB_LIB.T6G(SCH_1):PAGE478
    37 P0V9_RETIMER_CPU1_LSET1 @T6G_MB_LIB.T6G(SCH_1):P0V9_RETIMER_CPU1_LSET1    I51 @T6G_MB_LIB.T6G(SCH_1):PAGE478
 10_19 SW_P0V9_RETIMER_CPU1_SW1 @T6G_MB_LIB.T6G(SCH_1):SW_P0V9_RETIMER_CPU1_SW1    I51 @T6G_MB_LIB.T6G(SCH_1):PAGE478
     5    GND @T6G_MB_LIB.T6G(SCH_1):GND    I51 @T6G_MB_LIB.T6G(SCH_1):PAGE478
    30 SW_P12V_AUX_P0V9_RETIMER_CPU1_FLT @T6G_MB_LIB.T6G(SCH_1):SW_P12V_AUX_P0V9_RETIMER_CPU1_FLT    I51 @T6G_MB_LIB.T6G(SCH_1):PAGE478
     1 P0V9_RETIMER_CPU1_VOS1 @T6G_MB_LIB.T6G(SCH_1):P0V9_RETIMER_CPU1_VOS1    I51 @T6G_MB_LIB.T6G(SCH_1):PAGE478
    40    GND @T6G_MB_LIB.T6G(SCH_1):GND    I51 @T6G_MB_LIB.T6G(SCH_1):PAGE478
    35 P0V9_RETIMER_CPU1_VCC1 @T6G_MB_LIB.T6G(SCH_1):P0V9_RETIMER_CPU1_VCC1    I51 @T6G_MB_LIB.T6G(SCH_1):PAGE478
    31 NC_PV09_RETIMER_CPU1_DNC1 @T6G_MB_LIB.T6G(SCH_1):NC_PV09_RETIMER_CPU1_DNC1    I51 @T6G_MB_LIB.T6G(SCH_1):PAGE478
     6 NC_PV09_RETIMER_CPU1_GL1_1 @T6G_MB_LIB.T6G(SCH_1):NC_PV09_RETIMER_CPU1_GL1_1    I51 @T6G_MB_LIB.T6G(SCH_1):PAGE478
    41 NC_PV09_RETIMER_CPU1_GL2_1 @T6G_MB_LIB.T6G(SCH_1):NC_PV09_RETIMER_CPU1_GL2_1    I51 @T6G_MB_LIB.T6G(SCH_1):PAGE478
7_9-20_24    GND @T6G_MB_LIB.T6G(SCH_1):GND    I51 @T6G_MB_LIB.T6G(SCH_1):PAGE478

PU6512 ISL99390FRZTR5935-ISL99390FRZ-TR5935,SMLF,IC,AL099A
    34 P0V9_RETIMER_CPU1_PWM2 @T6G_MB_LIB.T6G(SCH_1):P0V9_RETIMER_CPU1_PWM2    I12 @T6G_MB_LIB.T6G(SCH_1):PAGE478
    39 PV09_RETIMER_CPU1_VCCS @T6G_MB_LIB.T6G(SCH_1):PV09_RETIMER_CPU1_VCCS    I12 @T6G_MB_LIB.T6G(SCH_1):PAGE478
     3 P0V9_RETIMER_CPU1_VCC2 @T6G_MB_LIB.T6G(SCH_1):P0V9_RETIMER_CPU1_VCC2    I12 @T6G_MB_LIB.T6G(SCH_1):PAGE478
     2    GND @T6G_MB_LIB.T6G(SCH_1):GND    I12 @T6G_MB_LIB.T6G(SCH_1):PAGE478
    33 SW_P0V9_RETIMER_CPU1_BOOT2 @T6G_MB_LIB.T6G(SCH_1):SW_P0V9_RETIMER_CPU1_BOOT2    I12 @T6G_MB_LIB.T6G(SCH_1):PAGE478
 25_29 SW_P12V_AUX_P0V9_RETIMER_CPU1_FLT @T6G_MB_LIB.T6G(SCH_1):SW_P12V_AUX_P0V9_RETIMER_CPU1_FLT    I12 @T6G_MB_LIB.T6G(SCH_1):PAGE478
    32 SW_P0V9_RETIMER_CPU1_PH2 @T6G_MB_LIB.T6G(SCH_1):SW_P0V9_RETIMER_CPU1_PH2    I12 @T6G_MB_LIB.T6G(SCH_1):PAGE478
     4 P0V9_RETIMER_CPU1_PVCC @T6G_MB_LIB.T6G(SCH_1):P0V9_RETIMER_CPU1_PVCC    I12 @T6G_MB_LIB.T6G(SCH_1):PAGE478
    36 P0V9_RETIMER_CPU1_TEMP0 @T6G_MB_LIB.T6G(SCH_1):P0V9_RETIMER_CPU1_TEMP0    I12 @T6G_MB_LIB.T6G(SCH_1):PAGE478
    38 P0V9_RETIMER_CPU1_IMON2 @T6G_MB_LIB.T6G(SCH_1):P0V9_RETIMER_CPU1_IMON2    I12 @T6G_MB_LIB.T6G(SCH_1):PAGE478
    37 P0V9_RETIMER_CPU1_LSET2 @T6G_MB_LIB.T6G(SCH_1):P0V9_RETIMER_CPU1_LSET2    I12 @T6G_MB_LIB.T6G(SCH_1):PAGE478
 10_19 SW_P0V9_RETIMER_CPU1_SW2 @T6G_MB_LIB.T6G(SCH_1):SW_P0V9_RETIMER_CPU1_SW2    I12 @T6G_MB_LIB.T6G(SCH_1):PAGE478
     5    GND @T6G_MB_LIB.T6G(SCH_1):GND    I12 @T6G_MB_LIB.T6G(SCH_1):PAGE478
    30 SW_P12V_AUX_P0V9_RETIMER_CPU1_FLT @T6G_MB_LIB.T6G(SCH_1):SW_P12V_AUX_P0V9_RETIMER_CPU1_FLT    I12 @T6G_MB_LIB.T6G(SCH_1):PAGE478
     1 P0V9_RETIMER_CPU1_VOS2 @T6G_MB_LIB.T6G(SCH_1):P0V9_RETIMER_CPU1_VOS2    I12 @T6G_MB_LIB.T6G(SCH_1):PAGE478
    40    GND @T6G_MB_LIB.T6G(SCH_1):GND    I12 @T6G_MB_LIB.T6G(SCH_1):PAGE478
    35 P0V9_RETIMER_CPU1_VCC2 @T6G_MB_LIB.T6G(SCH_1):P0V9_RETIMER_CPU1_VCC2    I12 @T6G_MB_LIB.T6G(SCH_1):PAGE478
    31 NC_PV09_RETIMER_CPU1_DNC2 @T6G_MB_LIB.T6G(SCH_1):NC_PV09_RETIMER_CPU1_DNC2    I12 @T6G_MB_LIB.T6G(SCH_1):PAGE478
     6 NC_PV09_RETIMER_CPU1_GL1_2 @T6G_MB_LIB.T6G(SCH_1):NC_PV09_RETIMER_CPU1_GL1_2    I12 @T6G_MB_LIB.T6G(SCH_1):PAGE478
    41 NC_PV09_RETIMER_CPU1_GL2_2 @T6G_MB_LIB.T6G(SCH_1):NC_PV09_RETIMER_CPU1_GL2_2    I12 @T6G_MB_LIB.T6G(SCH_1):PAGE478
7_9-20_24    GND @T6G_MB_LIB.T6G(SCH_1):GND    I12 @T6G_MB_LIB.T6G(SCH_1):PAGE478

  Q1 MOSFET_NCH_DUAL-PJT138K,SMLF,IC,BAM138K0003
     1    GND @T6G_MB_LIB.T6G(SCH_1):GND    I97 @T6G_MB_LIB.T6G(SCH_1):PAGE273
     2 PWRGD_P5V_R1 @T6G_MB_LIB.T6G(SCH_1):PWRGD_P5V_R1    I97 @T6G_MB_LIB.T6G(SCH_1):PAGE273
     6 PWRGD_P5V_R_N @T6G_MB_LIB.T6G(SCH_1):PWRGD_P5V_R_N    I97 @T6G_MB_LIB.T6G(SCH_1):PAGE273
     3 PWRGD_P5V_R2 @T6G_MB_LIB.T6G(SCH_1):PWRGD_P5V_R2    I98 @T6G_MB_LIB.T6G(SCH_1):PAGE273
     5 PWRGD_P5V_N @T6G_MB_LIB.T6G(SCH_1):PWRGD_P5V_N    I98 @T6G_MB_LIB.T6G(SCH_1):PAGE273
     4    GND @T6G_MB_LIB.T6G(SCH_1):GND    I98 @T6G_MB_LIB.T6G(SCH_1):PAGE273

  Q2 MOSFET_DUAL_6P-2N7002KDW,SMLF,IC,BAM70020047
     2 BOOT_RDY_BUF_LED @T6G_MB_LIB.T6G(SCH_1):BOOT_RDY_BUF_LED    I16 @T6G_MB_LIB.T6G(SCH_1):PAGE143
     5 BOOT_RDY_LED @T6G_MB_LIB.T6G(SCH_1):BOOT_RDY_LED    I16 @T6G_MB_LIB.T6G(SCH_1):PAGE143
     1    GND @T6G_MB_LIB.T6G(SCH_1):GND    I16 @T6G_MB_LIB.T6G(SCH_1):PAGE143
     4    GND @T6G_MB_LIB.T6G(SCH_1):GND    I16 @T6G_MB_LIB.T6G(SCH_1):PAGE143
     6 BOOT_RDY_LED @T6G_MB_LIB.T6G(SCH_1):BOOT_RDY_LED    I16 @T6G_MB_LIB.T6G(SCH_1):PAGE143
     3 BOOT_RDY_LED_N @T6G_MB_LIB.T6G(SCH_1):BOOT_RDY_LED_N    I16 @T6G_MB_LIB.T6G(SCH_1):PAGE143

  Q3 MOSFET_NCH_DUAL-PJT138K,SMLF,IC,BAM138K0003
     1    GND @T6G_MB_LIB.T6G(SCH_1):GND   I107 @T6G_MB_LIB.T6G(SCH_1):PAGE273
     2 SW_P3V3_EN_R @T6G_MB_LIB.T6G(SCH_1):SW_P3V3_EN_R   I107 @T6G_MB_LIB.T6G(SCH_1):PAGE273
     6 SW_P3V3_EN_N @T6G_MB_LIB.T6G(SCH_1):SW_P3V3_EN_N   I107 @T6G_MB_LIB.T6G(SCH_1):PAGE273
     3 SW_P3V3_EN_ISO @T6G_MB_LIB.T6G(SCH_1):SW_P3V3_EN_ISO   I108 @T6G_MB_LIB.T6G(SCH_1):PAGE273
     5 SW_P3V3_EN_N @T6G_MB_LIB.T6G(SCH_1):SW_P3V3_EN_N   I108 @T6G_MB_LIB.T6G(SCH_1):PAGE273
     4    GND @T6G_MB_LIB.T6G(SCH_1):GND   I108 @T6G_MB_LIB.T6G(SCH_1):PAGE273

  Q4 MOSFET_DUAL_6P-2N7002KDW,SMLF,IC,BAM70020047
     2 IRQ_LVC3_WAKE_N @T6G_MB_LIB.T6G(SCH_1):IRQ_LVC3_WAKE_N    I12 @T6G_MB_LIB.T6G(SCH_1):PAGE132
     5 IRQ_LVC3_WAKE @T6G_MB_LIB.T6G(SCH_1):IRQ_LVC3_WAKE    I12 @T6G_MB_LIB.T6G(SCH_1):PAGE132
     1    GND @T6G_MB_LIB.T6G(SCH_1):GND    I12 @T6G_MB_LIB.T6G(SCH_1):PAGE132
     4    GND @T6G_MB_LIB.T6G(SCH_1):GND    I12 @T6G_MB_LIB.T6G(SCH_1):PAGE132
     6 IRQ_LVC3_WAKE @T6G_MB_LIB.T6G(SCH_1):IRQ_LVC3_WAKE    I12 @T6G_MB_LIB.T6G(SCH_1):PAGE132
     3 IRQ_WAKE_R_N @T6G_MB_LIB.T6G(SCH_1):IRQ_WAKE_R_N    I12 @T6G_MB_LIB.T6G(SCH_1):PAGE132

  Q8 MOSFET_DUAL_6P-2N7002KDW,SMLF,IC,BAM70020047
     2 CLR_CMOS @T6G_MB_LIB.T6G(SCH_1):CLR_CMOS   I104 @T6G_MB_LIB.T6G(SCH_1):PAGE156
     5 CLR_CMOS @T6G_MB_LIB.T6G(SCH_1):CLR_CMOS   I104 @T6G_MB_LIB.T6G(SCH_1):PAGE156
     1    GND @T6G_MB_LIB.T6G(SCH_1):GND   I104 @T6G_MB_LIB.T6G(SCH_1):PAGE156
     4    GND @T6G_MB_LIB.T6G(SCH_1):GND   I104 @T6G_MB_LIB.T6G(SCH_1):PAGE156
     6 CLR_CMOS_N @T6G_MB_LIB.T6G(SCH_1):CLR_CMOS_N   I104 @T6G_MB_LIB.T6G(SCH_1):PAGE156
     3 BAT_LDO_EN @T6G_MB_LIB.T6G(SCH_1):BAT_LDO_EN   I104 @T6G_MB_LIB.T6G(SCH_1):PAGE156

 Q11 MOSFET_DUAL_6P-2N7002KDW,SMLF,IC,BAM70020047
     2 FM_SMERR_BUF_R_LED_N @T6G_MB_LIB.T6G(SCH_1):FM_SMERR_BUF_R_LED_N    I19 @T6G_MB_LIB.T6G(SCH_1):PAGE143
     5 SMERR_LED @T6G_MB_LIB.T6G(SCH_1):SMERR_LED    I19 @T6G_MB_LIB.T6G(SCH_1):PAGE143
     1    GND @T6G_MB_LIB.T6G(SCH_1):GND    I19 @T6G_MB_LIB.T6G(SCH_1):PAGE143
     4    GND @T6G_MB_LIB.T6G(SCH_1):GND    I19 @T6G_MB_LIB.T6G(SCH_1):PAGE143
     6 SMERR_LED @T6G_MB_LIB.T6G(SCH_1):SMERR_LED    I19 @T6G_MB_LIB.T6G(SCH_1):PAGE143
     3 SMERR_LED_N @T6G_MB_LIB.T6G(SCH_1):SMERR_LED_N    I19 @T6G_MB_LIB.T6G(SCH_1):PAGE143

 Q12 MOSFET_N_GSD-NX138BK,SMLF,IC,BAM01380023
     G P12V_ALL_PWROK @T6G_MB_LIB.T6G(SCH_1):P12V_ALL_PWROK    I44 @T6G_MB_LIB.T6G(SCH_1):PAGE143
     S    GND @T6G_MB_LIB.T6G(SCH_1):GND    I44 @T6G_MB_LIB.T6G(SCH_1):PAGE143
     D P12V_ALL_PWROK_N @T6G_MB_LIB.T6G(SCH_1):P12V_ALL_PWROK_N    I44 @T6G_MB_LIB.T6G(SCH_1):PAGE143

 Q18 BSS138DW7F-BSS138DW-7-F,SMLF,IC,BAM01380032
     2 PWRGD_P12V_MEM_CPU0_EN @T6G_MB_LIB.T6G(SCH_1):PWRGD_P12V_MEM_CPU0_EN    I36 @T6G_MB_LIB.T6G(SCH_1):PAGE264
     5 PWRGD_P12V_MEM_CPU0_EN_N @T6G_MB_LIB.T6G(SCH_1):PWRGD_P12V_MEM_CPU0_EN_N    I36 @T6G_MB_LIB.T6G(SCH_1):PAGE264
     1    GND @T6G_MB_LIB.T6G(SCH_1):GND    I36 @T6G_MB_LIB.T6G(SCH_1):PAGE264
     4    GND @T6G_MB_LIB.T6G(SCH_1):GND    I36 @T6G_MB_LIB.T6G(SCH_1):PAGE264
     6 PWRGD_P12V_MEM_CPU0_EN_N @T6G_MB_LIB.T6G(SCH_1):PWRGD_P12V_MEM_CPU0_EN_N    I36 @T6G_MB_LIB.T6G(SCH_1):PAGE264
     3 PWRGD_P12V_MEM_CPU0 @T6G_MB_LIB.T6G(SCH_1):PWRGD_P12V_MEM_CPU0    I36 @T6G_MB_LIB.T6G(SCH_1):PAGE264

 Q19 BSS138DW7F-BSS138DW-7-F,SMLF,IC,BAM01380032
     2 PWRGD_P12V_MEM_CPU1_EN @T6G_MB_LIB.T6G(SCH_1):PWRGD_P12V_MEM_CPU1_EN    I33 @T6G_MB_LIB.T6G(SCH_1):PAGE264
     5 PWRGD_P12V_MEM_CPU1_EN_N @T6G_MB_LIB.T6G(SCH_1):PWRGD_P12V_MEM_CPU1_EN_N    I33 @T6G_MB_LIB.T6G(SCH_1):PAGE264
     1    GND @T6G_MB_LIB.T6G(SCH_1):GND    I33 @T6G_MB_LIB.T6G(SCH_1):PAGE264
     4    GND @T6G_MB_LIB.T6G(SCH_1):GND    I33 @T6G_MB_LIB.T6G(SCH_1):PAGE264
     6 PWRGD_P12V_MEM_CPU1_EN_N @T6G_MB_LIB.T6G(SCH_1):PWRGD_P12V_MEM_CPU1_EN_N    I33 @T6G_MB_LIB.T6G(SCH_1):PAGE264
     3 PWRGD_P12V_MEM_CPU1 @T6G_MB_LIB.T6G(SCH_1):PWRGD_P12V_MEM_CPU1    I33 @T6G_MB_LIB.T6G(SCH_1):PAGE264

 Q27 BSS138DW7F-BSS138DW-7-F,SMLF,IC,BAM01380032
     2 PWRGD_P3V3_EN @T6G_MB_LIB.T6G(SCH_1):PWRGD_P3V3_EN   I123 @T6G_MB_LIB.T6G(SCH_1):PAGE273
     5 PWRGD_P3V3_EN_N @T6G_MB_LIB.T6G(SCH_1):PWRGD_P3V3_EN_N   I123 @T6G_MB_LIB.T6G(SCH_1):PAGE273
     1    GND @T6G_MB_LIB.T6G(SCH_1):GND   I123 @T6G_MB_LIB.T6G(SCH_1):PAGE273
     4    GND @T6G_MB_LIB.T6G(SCH_1):GND   I123 @T6G_MB_LIB.T6G(SCH_1):PAGE273
     6 PWRGD_P3V3_EN_N @T6G_MB_LIB.T6G(SCH_1):PWRGD_P3V3_EN_N   I123 @T6G_MB_LIB.T6G(SCH_1):PAGE273
     3 PWRGD_P3V3_R1 @T6G_MB_LIB.T6G(SCH_1):PWRGD_P3V3_R1   I123 @T6G_MB_LIB.T6G(SCH_1):PAGE273

 Q28 MOSFET_DUAL_6P-2N7002KDW,SMLF,IC,BAM70020047
     2 BMC_FPGA_LED1 @T6G_MB_LIB.T6G(SCH_1):BMC_FPGA_LED1    I48 @T6G_MB_LIB.T6G(SCH_1):PAGE84
     5 BMC_FPGA_LED2 @T6G_MB_LIB.T6G(SCH_1):BMC_FPGA_LED2    I48 @T6G_MB_LIB.T6G(SCH_1):PAGE84
     1    GND @T6G_MB_LIB.T6G(SCH_1):GND    I48 @T6G_MB_LIB.T6G(SCH_1):PAGE84
     4    GND @T6G_MB_LIB.T6G(SCH_1):GND    I48 @T6G_MB_LIB.T6G(SCH_1):PAGE84
     6 BMC_FPGA_LED1_N @T6G_MB_LIB.T6G(SCH_1):BMC_FPGA_LED1_N    I48 @T6G_MB_LIB.T6G(SCH_1):PAGE84
     3 BMC_FPGA_LED2_N @T6G_MB_LIB.T6G(SCH_1):BMC_FPGA_LED2_N    I48 @T6G_MB_LIB.T6G(SCH_1):PAGE84

 Q29 MOSFET_N_GSD-NX138BK,SMLF,IC,BAM01380023
     G LED_BIOS_DBG_MODE_N @T6G_MB_LIB.T6G(SCH_1):LED_BIOS_DBG_MODE_N    I80 @T6G_MB_LIB.T6G(SCH_1):PAGE142
     S    GND @T6G_MB_LIB.T6G(SCH_1):GND    I80 @T6G_MB_LIB.T6G(SCH_1):PAGE142
     D LED_BIOS_DBG_MODE @T6G_MB_LIB.T6G(SCH_1):LED_BIOS_DBG_MODE    I80 @T6G_MB_LIB.T6G(SCH_1):PAGE142

 Q30 MOSFET_N_GSD-NX138BK,SMLF,IC,BAM01380023
     G BIOS_DEBUG_MODE @T6G_MB_LIB.T6G(SCH_1):BIOS_DEBUG_MODE    I81 @T6G_MB_LIB.T6G(SCH_1):PAGE142
     S    GND @T6G_MB_LIB.T6G(SCH_1):GND    I81 @T6G_MB_LIB.T6G(SCH_1):PAGE142
     D LED_BIOS_DBG_MODE_N @T6G_MB_LIB.T6G(SCH_1):LED_BIOS_DBG_MODE_N    I81 @T6G_MB_LIB.T6G(SCH_1):PAGE142

 Q37 MOSFET_NCH_DUAL-PJT138K,SMLF,IC,BAM138K0003
     1    GND @T6G_MB_LIB.T6G(SCH_1):GND     I9 @T6G_MB_LIB.T6G(SCH_1):PAGE273
     2 VR_P5V_EN @T6G_MB_LIB.T6G(SCH_1):VR_P5V_EN     I9 @T6G_MB_LIB.T6G(SCH_1):PAGE273
     6 VR_P5V_EN_N @T6G_MB_LIB.T6G(SCH_1):VR_P5V_EN_N     I9 @T6G_MB_LIB.T6G(SCH_1):PAGE273
     3 VR_P5V_EN_D_R1 @T6G_MB_LIB.T6G(SCH_1):VR_P5V_EN_D_R1    I14 @T6G_MB_LIB.T6G(SCH_1):PAGE273
     5 VR_P5V_EN_N @T6G_MB_LIB.T6G(SCH_1):VR_P5V_EN_N    I14 @T6G_MB_LIB.T6G(SCH_1):PAGE273
     4    GND @T6G_MB_LIB.T6G(SCH_1):GND    I14 @T6G_MB_LIB.T6G(SCH_1):PAGE273

 Q39 MOSFET_NCH_GDS_ESD_PROTECTED-2N7002K,SMLF,IC,BAM70A
     D P12V_SCM_EN @T6G_MB_LIB.T6G(SCH_1):P12V_SCM_EN     I9 @T6G_MB_LIB.T6G(SCH_1):PAGE350
     G FM_SCM_PRSNT1_R_N @T6G_MB_LIB.T6G(SCH_1):FM_SCM_PRSNT1_R_N     I9 @T6G_MB_LIB.T6G(SCH_1):PAGE350
     S    GND @T6G_MB_LIB.T6G(SCH_1):GND     I9 @T6G_MB_LIB.T6G(SCH_1):PAGE350

 Q50 MOSFET_NCH_DUAL-PJT138K,SMLF,IC,BAM138K0003
     1    GND @T6G_MB_LIB.T6G(SCH_1):GND    I65 @T6G_MB_LIB.T6G(SCH_1):PAGE84
     2 PWRGD_P5V_AUX @T6G_MB_LIB.T6G(SCH_1):PWRGD_P5V_AUX    I65 @T6G_MB_LIB.T6G(SCH_1):PAGE84
     6 PWRGD_P5V_AUX_R1 @T6G_MB_LIB.T6G(SCH_1):PWRGD_P5V_AUX_R1    I65 @T6G_MB_LIB.T6G(SCH_1):PAGE84
     3 PWRGD_P5V_AUX_R2 @T6G_MB_LIB.T6G(SCH_1):PWRGD_P5V_AUX_R2    I73 @T6G_MB_LIB.T6G(SCH_1):PAGE84
     5 PWRGD_P5V_AUX_R1 @T6G_MB_LIB.T6G(SCH_1):PWRGD_P5V_AUX_R1    I73 @T6G_MB_LIB.T6G(SCH_1):PAGE84
     4    GND @T6G_MB_LIB.T6G(SCH_1):GND    I73 @T6G_MB_LIB.T6G(SCH_1):PAGE84

 Q54 MOSFET_NCH_GDS_ESD_PROTECTED-2N7002K,SMLF,IC,BAM70A
     D P12V_AUX_BLEEDING @T6G_MB_LIB.T6G(SCH_1):P12V_AUX_BLEEDING    I14 @T6G_MB_LIB.T6G(SCH_1):PAGE365
     G FM_P12V_HSC_EN_R_N @T6G_MB_LIB.T6G(SCH_1):FM_P12V_HSC_EN_R_N    I14 @T6G_MB_LIB.T6G(SCH_1):PAGE365
     S    GND @T6G_MB_LIB.T6G(SCH_1):GND    I14 @T6G_MB_LIB.T6G(SCH_1):PAGE365

 Q56 MOSFET_NCH_1D3S-PSMNR58-30YLH,SMLF,IC,BAMNR580000
     3   P3V3 @T6G_MB_LIB.T6G(SCH_1):P3V3    I50 @T6G_MB_LIB.T6G(SCH_1):PAGE273
     5 P3V3_AUX @T6G_MB_LIB.T6G(SCH_1):P3V3_AUX    I50 @T6G_MB_LIB.T6G(SCH_1):PAGE273
     2   P3V3 @T6G_MB_LIB.T6G(SCH_1):P3V3    I50 @T6G_MB_LIB.T6G(SCH_1):PAGE273
     4 SW_P3V3_EN_ISO_R @T6G_MB_LIB.T6G(SCH_1):SW_P3V3_EN_ISO_R    I50 @T6G_MB_LIB.T6G(SCH_1):PAGE273
     1   P3V3 @T6G_MB_LIB.T6G(SCH_1):P3V3    I50 @T6G_MB_LIB.T6G(SCH_1):PAGE273

 Q57 MOSFET_NCH_1D3S-PSMNR58-30YLH,SMLF,IC,BAMNR580000
     3    P5V @T6G_MB_LIB.T6G(SCH_1):P5V    I23 @T6G_MB_LIB.T6G(SCH_1):PAGE273
     5 P5V_AUX @T6G_MB_LIB.T6G(SCH_1):P5V_AUX    I23 @T6G_MB_LIB.T6G(SCH_1):PAGE273
     2    P5V @T6G_MB_LIB.T6G(SCH_1):P5V    I23 @T6G_MB_LIB.T6G(SCH_1):PAGE273
     4 VR_P5V_EN_D_R @T6G_MB_LIB.T6G(SCH_1):VR_P5V_EN_D_R    I23 @T6G_MB_LIB.T6G(SCH_1):PAGE273
     1    P5V @T6G_MB_LIB.T6G(SCH_1):P5V    I23 @T6G_MB_LIB.T6G(SCH_1):PAGE273

 Q61 MOSFET_N_GSD-NX138BK,SMLF,IC,BAM01380023
     G UART_LS_EN @T6G_MB_LIB.T6G(SCH_1):UART_LS_EN    I89 @T6G_MB_LIB.T6G(SCH_1):PAGE141
     S    GND @T6G_MB_LIB.T6G(SCH_1):GND    I89 @T6G_MB_LIB.T6G(SCH_1):PAGE141
     D UART_LS_EN_R_N @T6G_MB_LIB.T6G(SCH_1):UART_LS_EN_R_N    I89 @T6G_MB_LIB.T6G(SCH_1):PAGE141

 Q62 MOSFET_N_SMLF-BSS138K,BSS138K,IC,BAM138K0000
     G JTAG_BMC_OE @T6G_MB_LIB.T6G(SCH_1):JTAG_BMC_OE   I102 @T6G_MB_LIB.T6G(SCH_1):PAGE149
     D JTAG_BMC_OE_N @T6G_MB_LIB.T6G(SCH_1):JTAG_BMC_OE_N   I102 @T6G_MB_LIB.T6G(SCH_1):PAGE149
     S    GND @T6G_MB_LIB.T6G(SCH_1):GND   I102 @T6G_MB_LIB.T6G(SCH_1):PAGE149

 Q63 MOSFET_N_SMLF-BSS138K,BSS138K,IC,BAM138K0000
     G CPU0_HDT_BYPASS_SEL @T6G_MB_LIB.T6G(SCH_1):CPU0_HDT_BYPASS_SEL    I45 @T6G_MB_LIB.T6G(SCH_1):PAGE151
     D FM_PLD_CPU0_PRSNT_HDT_N @T6G_MB_LIB.T6G(SCH_1):FM_PLD_CPU0_PRSNT_HDT_N    I45 @T6G_MB_LIB.T6G(SCH_1):PAGE151
     S    GND @T6G_MB_LIB.T6G(SCH_1):GND    I45 @T6G_MB_LIB.T6G(SCH_1):PAGE151

 Q64 MOSFET_N_SMLF-BSS138K,BSS138K,IC,BAM138K0000
     G CPU1_HDT_BYPASS_SEL @T6G_MB_LIB.T6G(SCH_1):CPU1_HDT_BYPASS_SEL    I46 @T6G_MB_LIB.T6G(SCH_1):PAGE151
     D FM_PLD_CPU1_PRSNT_HDT_N @T6G_MB_LIB.T6G(SCH_1):FM_PLD_CPU1_PRSNT_HDT_N    I46 @T6G_MB_LIB.T6G(SCH_1):PAGE151
     S    GND @T6G_MB_LIB.T6G(SCH_1):GND    I46 @T6G_MB_LIB.T6G(SCH_1):PAGE151

 Q67 MOSFET_NCH_DUAL-PJT138K,SMLF,IC,BAM138K0003
     1    GND @T6G_MB_LIB.T6G(SCH_1):GND    I33 @T6G_MB_LIB.T6G(SCH_1):PAGE333
     2 BIC_MONITER @T6G_MB_LIB.T6G(SCH_1):BIC_MONITER    I33 @T6G_MB_LIB.T6G(SCH_1):PAGE333
     6 BIC_MONITER_N @T6G_MB_LIB.T6G(SCH_1):BIC_MONITER_N    I33 @T6G_MB_LIB.T6G(SCH_1):PAGE333
     3 BIC_MONITER_ISO @T6G_MB_LIB.T6G(SCH_1):BIC_MONITER_ISO    I82 @T6G_MB_LIB.T6G(SCH_1):PAGE333
     5 BIC_MONITER_N @T6G_MB_LIB.T6G(SCH_1):BIC_MONITER_N    I82 @T6G_MB_LIB.T6G(SCH_1):PAGE333
     4    GND @T6G_MB_LIB.T6G(SCH_1):GND    I82 @T6G_MB_LIB.T6G(SCH_1):PAGE333

 Q69 MOSFET_NCH_DUAL-PJT138K,SMLF,IC,BAM138K0003
     1    GND @T6G_MB_LIB.T6G(SCH_1):GND   I117 @T6G_MB_LIB.T6G(SCH_1):PAGE333
     2 RST_BMC_FROM_SWB_N @T6G_MB_LIB.T6G(SCH_1):RST_BMC_FROM_SWB_N   I117 @T6G_MB_LIB.T6G(SCH_1):PAGE333
     6 RST_BMC_FROM_SWB @T6G_MB_LIB.T6G(SCH_1):RST_BMC_FROM_SWB   I117 @T6G_MB_LIB.T6G(SCH_1):PAGE333
     3 RST_BMC_FROM_SWB_ISO_N @T6G_MB_LIB.T6G(SCH_1):RST_BMC_FROM_SWB_ISO_N    I88 @T6G_MB_LIB.T6G(SCH_1):PAGE333
     5 RST_BMC_FROM_SWB @T6G_MB_LIB.T6G(SCH_1):RST_BMC_FROM_SWB    I88 @T6G_MB_LIB.T6G(SCH_1):PAGE333
     4    GND @T6G_MB_LIB.T6G(SCH_1):GND    I88 @T6G_MB_LIB.T6G(SCH_1):PAGE333

 Q70 MOSFET_NCH_DUAL-PJT138K,SMLF,IC,BAM138K0003
     1    GND @T6G_MB_LIB.T6G(SCH_1):GND    I35 @T6G_MB_LIB.T6G(SCH_1):PAGE333
     2 FM_SWB_BIC_READY_N @T6G_MB_LIB.T6G(SCH_1):FM_SWB_BIC_READY_N    I35 @T6G_MB_LIB.T6G(SCH_1):PAGE333
     6 FM_SWB_BIC_READY @T6G_MB_LIB.T6G(SCH_1):FM_SWB_BIC_READY    I35 @T6G_MB_LIB.T6G(SCH_1):PAGE333
     3 FM_SWB_BIC_READY_ISO_N @T6G_MB_LIB.T6G(SCH_1):FM_SWB_BIC_READY_ISO_N   I120 @T6G_MB_LIB.T6G(SCH_1):PAGE333
     5 FM_SWB_BIC_READY @T6G_MB_LIB.T6G(SCH_1):FM_SWB_BIC_READY   I120 @T6G_MB_LIB.T6G(SCH_1):PAGE333
     4    GND @T6G_MB_LIB.T6G(SCH_1):GND   I120 @T6G_MB_LIB.T6G(SCH_1):PAGE333

 Q71 MOSFET_NCH_DUAL-PJT138K,SMLF,IC,BAM138K0003
     1    GND @T6G_MB_LIB.T6G(SCH_1):GND   I118 @T6G_MB_LIB.T6G(SCH_1):PAGE333
     2 FM_SWB_PWRGD @T6G_MB_LIB.T6G(SCH_1):FM_SWB_PWRGD   I118 @T6G_MB_LIB.T6G(SCH_1):PAGE333
     6 FM_SWB_PWRGD_N @T6G_MB_LIB.T6G(SCH_1):FM_SWB_PWRGD_N   I118 @T6G_MB_LIB.T6G(SCH_1):PAGE333
     3 FM_SWB_PWRGD_ISO @T6G_MB_LIB.T6G(SCH_1):FM_SWB_PWRGD_ISO   I100 @T6G_MB_LIB.T6G(SCH_1):PAGE333
     5 FM_SWB_PWRGD_N @T6G_MB_LIB.T6G(SCH_1):FM_SWB_PWRGD_N   I100 @T6G_MB_LIB.T6G(SCH_1):PAGE333
     4    GND @T6G_MB_LIB.T6G(SCH_1):GND   I100 @T6G_MB_LIB.T6G(SCH_1):PAGE333

 Q72 MOSFET_NCH_DUAL-PJT138K,SMLF,IC,BAM138K0003
     1    GND @T6G_MB_LIB.T6G(SCH_1):GND    I37 @T6G_MB_LIB.T6G(SCH_1):PAGE333
     2 FM_GPU_PWRGD @T6G_MB_LIB.T6G(SCH_1):FM_GPU_PWRGD    I37 @T6G_MB_LIB.T6G(SCH_1):PAGE333
     6 FM_GPU_PWRGD_N @T6G_MB_LIB.T6G(SCH_1):FM_GPU_PWRGD_N    I37 @T6G_MB_LIB.T6G(SCH_1):PAGE333
     3 FM_GPU_PWRGD_ISO @T6G_MB_LIB.T6G(SCH_1):FM_GPU_PWRGD_ISO   I119 @T6G_MB_LIB.T6G(SCH_1):PAGE333
     5 FM_GPU_PWRGD_N @T6G_MB_LIB.T6G(SCH_1):FM_GPU_PWRGD_N   I119 @T6G_MB_LIB.T6G(SCH_1):PAGE333
     4    GND @T6G_MB_LIB.T6G(SCH_1):GND   I119 @T6G_MB_LIB.T6G(SCH_1):PAGE333

 Q74 MOSFET_NCH_DUAL-PJT138K,SMLF,IC,BAM138K0003
     1    GND @T6G_MB_LIB.T6G(SCH_1):GND   I121 @T6G_MB_LIB.T6G(SCH_1):PAGE333
     2 FM_SMB_2_ALERT_GPU_N @T6G_MB_LIB.T6G(SCH_1):FM_SMB_2_ALERT_GPU_N   I121 @T6G_MB_LIB.T6G(SCH_1):PAGE333
     6 FM_SMB_2_ALERT_GPU @T6G_MB_LIB.T6G(SCH_1):FM_SMB_2_ALERT_GPU   I121 @T6G_MB_LIB.T6G(SCH_1):PAGE333
     3 FM_SMB_2_ALERT_GPU_ISO_N @T6G_MB_LIB.T6G(SCH_1):FM_SMB_2_ALERT_GPU_ISO_N   I122 @T6G_MB_LIB.T6G(SCH_1):PAGE333
     5 FM_SMB_2_ALERT_GPU @T6G_MB_LIB.T6G(SCH_1):FM_SMB_2_ALERT_GPU   I122 @T6G_MB_LIB.T6G(SCH_1):PAGE333
     4    GND @T6G_MB_LIB.T6G(SCH_1):GND   I122 @T6G_MB_LIB.T6G(SCH_1):PAGE333

 Q75 MOSFET_NCH_DUAL-PJT138K,SMLF,IC,BAM138K0003
     1    GND @T6G_MB_LIB.T6G(SCH_1):GND   I152 @T6G_MB_LIB.T6G(SCH_1):PAGE333
     2 FM_SMB_1_ALERT_GPU_N @T6G_MB_LIB.T6G(SCH_1):FM_SMB_1_ALERT_GPU_N   I152 @T6G_MB_LIB.T6G(SCH_1):PAGE333
     6 FM_SMB_1_ALERT_GPU @T6G_MB_LIB.T6G(SCH_1):FM_SMB_1_ALERT_GPU   I152 @T6G_MB_LIB.T6G(SCH_1):PAGE333
     3 FM_SMB_1_ALERT_GPU_ISO_N @T6G_MB_LIB.T6G(SCH_1):FM_SMB_1_ALERT_GPU_ISO_N   I151 @T6G_MB_LIB.T6G(SCH_1):PAGE333
     5 FM_SMB_1_ALERT_GPU @T6G_MB_LIB.T6G(SCH_1):FM_SMB_1_ALERT_GPU   I151 @T6G_MB_LIB.T6G(SCH_1):PAGE333
     4    GND @T6G_MB_LIB.T6G(SCH_1):GND   I151 @T6G_MB_LIB.T6G(SCH_1):PAGE333

 Q78 MOSFET_NCH_DUAL-PJT138K,SMLF,IC,BAM138K0003
     1    GND @T6G_MB_LIB.T6G(SCH_1):GND    I24 @T6G_MB_LIB.T6G(SCH_1):PAGE254
     2 PWRGD_P1V8_AUX_R @T6G_MB_LIB.T6G(SCH_1):PWRGD_P1V8_AUX_R    I24 @T6G_MB_LIB.T6G(SCH_1):PAGE254
     6 LED_PWRGD_P1V8_AUX_D @T6G_MB_LIB.T6G(SCH_1):LED_PWRGD_P1V8_AUX_D    I24 @T6G_MB_LIB.T6G(SCH_1):PAGE254
     3 LED_PWRGD_PS_PWROK_PLD_D @T6G_MB_LIB.T6G(SCH_1):LED_PWRGD_PS_PWROK_PLD_D    I18 @T6G_MB_LIB.T6G(SCH_1):PAGE254
     5 PWRGD_PS_PWROK_PLD @T6G_MB_LIB.T6G(SCH_1):PWRGD_PS_PWROK_PLD    I18 @T6G_MB_LIB.T6G(SCH_1):PAGE254
     4    GND @T6G_MB_LIB.T6G(SCH_1):GND    I18 @T6G_MB_LIB.T6G(SCH_1):PAGE254

 Q79 MOSFET_NCH_DUAL-PJT138K,SMLF,IC,BAM138K0003
     1    GND @T6G_MB_LIB.T6G(SCH_1):GND    I18 @T6G_MB_LIB.T6G(SCH_1):PAGE374
     2 FM_LED_PWRGD_PVDD33_S5 @T6G_MB_LIB.T6G(SCH_1):FM_LED_PWRGD_PVDD33_S5    I18 @T6G_MB_LIB.T6G(SCH_1):PAGE374
     6 LED_PWRGD_PVDD33_S5_D @T6G_MB_LIB.T6G(SCH_1):LED_PWRGD_PVDD33_S5_D    I18 @T6G_MB_LIB.T6G(SCH_1):PAGE374
     3 LED_PWRGD_PVDDCR_CPU0_P0_D @T6G_MB_LIB.T6G(SCH_1):LED_PWRGD_PVDDCR_CPU0_P0_D     I8 @T6G_MB_LIB.T6G(SCH_1):PAGE374
     5 FM_LED_PWRGD_PVDDCR_CPU0_P0 @T6G_MB_LIB.T6G(SCH_1):FM_LED_PWRGD_PVDDCR_CPU0_P0     I8 @T6G_MB_LIB.T6G(SCH_1):PAGE374
     4    GND @T6G_MB_LIB.T6G(SCH_1):GND     I8 @T6G_MB_LIB.T6G(SCH_1):PAGE374

 Q80 MOSFET_NCH_DUAL-PJT138K,SMLF,IC,BAM138K0003
     1    GND @T6G_MB_LIB.T6G(SCH_1):GND     I6 @T6G_MB_LIB.T6G(SCH_1):PAGE374
     2 FM_LED_PWRGD_PVDDCR_SOC_P0 @T6G_MB_LIB.T6G(SCH_1):FM_LED_PWRGD_PVDDCR_SOC_P0     I6 @T6G_MB_LIB.T6G(SCH_1):PAGE374
     6 LED_PWRGD_PVDDCR_SOC_P0_D @T6G_MB_LIB.T6G(SCH_1):LED_PWRGD_PVDDCR_SOC_P0_D     I6 @T6G_MB_LIB.T6G(SCH_1):PAGE374
     3 LED_PWRGD_PVDDCR_CPU1_P0_D @T6G_MB_LIB.T6G(SCH_1):LED_PWRGD_PVDDCR_CPU1_P0_D     I3 @T6G_MB_LIB.T6G(SCH_1):PAGE374
     5 FM_LED_PWRGD_PVDDCR_CPU1_P0 @T6G_MB_LIB.T6G(SCH_1):FM_LED_PWRGD_PVDDCR_CPU1_P0     I3 @T6G_MB_LIB.T6G(SCH_1):PAGE374
     4    GND @T6G_MB_LIB.T6G(SCH_1):GND     I3 @T6G_MB_LIB.T6G(SCH_1):PAGE374

 Q81 MOSFET_NCH_DUAL-PJT138K,SMLF,IC,BAM138K0003
     1    GND @T6G_MB_LIB.T6G(SCH_1):GND    I35 @T6G_MB_LIB.T6G(SCH_1):PAGE374
     2 FM_LED_PWRGD_PVDDIO_P0 @T6G_MB_LIB.T6G(SCH_1):FM_LED_PWRGD_PVDDIO_P0    I35 @T6G_MB_LIB.T6G(SCH_1):PAGE374
     6 LED_PWRGD_PVDDIO_P0_D @T6G_MB_LIB.T6G(SCH_1):LED_PWRGD_PVDDIO_P0_D    I35 @T6G_MB_LIB.T6G(SCH_1):PAGE374
     3 LED_PWRGD_PVDD11_S3_P0_D @T6G_MB_LIB.T6G(SCH_1):LED_PWRGD_PVDD11_S3_P0_D    I27 @T6G_MB_LIB.T6G(SCH_1):PAGE374
     5 FM_LED_PWRGD_PVDD11_S3_P0 @T6G_MB_LIB.T6G(SCH_1):FM_LED_PWRGD_PVDD11_S3_P0    I27 @T6G_MB_LIB.T6G(SCH_1):PAGE374
     4    GND @T6G_MB_LIB.T6G(SCH_1):GND    I27 @T6G_MB_LIB.T6G(SCH_1):PAGE374

 Q83 MOSFET_NCH_DUAL-PJT138K,SMLF,IC,BAM138K0003
     1    GND @T6G_MB_LIB.T6G(SCH_1):GND    I23 @T6G_MB_LIB.T6G(SCH_1):PAGE374
     2 FM_LED_PWRGD_PVDD18_S5_P0 @T6G_MB_LIB.T6G(SCH_1):FM_LED_PWRGD_PVDD18_S5_P0    I23 @T6G_MB_LIB.T6G(SCH_1):PAGE374
     6 LED_PWRGD_PVDD18_S5_P0_D @T6G_MB_LIB.T6G(SCH_1):LED_PWRGD_PVDD18_S5_P0_D    I23 @T6G_MB_LIB.T6G(SCH_1):PAGE374
     3 NC_Q83_D2 @T6G_MB_LIB.T6G(SCH_1):NC_Q83_D2    I43 @T6G_MB_LIB.T6G(SCH_1):PAGE374
     5 NC_Q83_G2 @T6G_MB_LIB.T6G(SCH_1):NC_Q83_G2    I43 @T6G_MB_LIB.T6G(SCH_1):PAGE374
     4 NC_Q83_S2 @T6G_MB_LIB.T6G(SCH_1):NC_Q83_S2    I43 @T6G_MB_LIB.T6G(SCH_1):PAGE374

 Q84 MOSFET_NCH_DUAL-PJT138K,SMLF,IC,BAM138K0003
     1    GND @T6G_MB_LIB.T6G(SCH_1):GND    I11 @T6G_MB_LIB.T6G(SCH_1):PAGE375
     2 FM_LED_PWRGD_PVDDCR_CPU0_P1 @T6G_MB_LIB.T6G(SCH_1):FM_LED_PWRGD_PVDDCR_CPU0_P1    I11 @T6G_MB_LIB.T6G(SCH_1):PAGE375
     6 LED_PWRGD_PVDDCR_CPU0_P1_D @T6G_MB_LIB.T6G(SCH_1):LED_PWRGD_PVDDCR_CPU0_P1_D    I11 @T6G_MB_LIB.T6G(SCH_1):PAGE375
     3 LED_PWRGD_PVDDCR_SOC_P1_D @T6G_MB_LIB.T6G(SCH_1):LED_PWRGD_PVDDCR_SOC_P1_D    I10 @T6G_MB_LIB.T6G(SCH_1):PAGE375
     5 FM_LED_PWRGD_PVDDCR_SOC_P1 @T6G_MB_LIB.T6G(SCH_1):FM_LED_PWRGD_PVDDCR_SOC_P1    I10 @T6G_MB_LIB.T6G(SCH_1):PAGE375
     4    GND @T6G_MB_LIB.T6G(SCH_1):GND    I10 @T6G_MB_LIB.T6G(SCH_1):PAGE375

 Q85 MOSFET_NCH_DUAL-PJT138K,SMLF,IC,BAM138K0003
     1    GND @T6G_MB_LIB.T6G(SCH_1):GND     I7 @T6G_MB_LIB.T6G(SCH_1):PAGE375
     2 FM_LED_PWRGD_PVDDCR_CPU1_P1 @T6G_MB_LIB.T6G(SCH_1):FM_LED_PWRGD_PVDDCR_CPU1_P1     I7 @T6G_MB_LIB.T6G(SCH_1):PAGE375
     6 LED_PWRGD_PVDDCR_CPU1_P1_D @T6G_MB_LIB.T6G(SCH_1):LED_PWRGD_PVDDCR_CPU1_P1_D     I7 @T6G_MB_LIB.T6G(SCH_1):PAGE375
     3 LED_PWRGD_PVDDIO_P1_D @T6G_MB_LIB.T6G(SCH_1):LED_PWRGD_PVDDIO_P1_D     I2 @T6G_MB_LIB.T6G(SCH_1):PAGE375
     5 FM_LED_PWRGD_PVDDIO_P1 @T6G_MB_LIB.T6G(SCH_1):FM_LED_PWRGD_PVDDIO_P1     I2 @T6G_MB_LIB.T6G(SCH_1):PAGE375
     4    GND @T6G_MB_LIB.T6G(SCH_1):GND     I2 @T6G_MB_LIB.T6G(SCH_1):PAGE375

 Q86 MOSFET_NCH_DUAL-PJT138K,SMLF,IC,BAM138K0003
     1    GND @T6G_MB_LIB.T6G(SCH_1):GND    I30 @T6G_MB_LIB.T6G(SCH_1):PAGE375
     2 FM_LED_PWRGD_PVDD11_S3_P1 @T6G_MB_LIB.T6G(SCH_1):FM_LED_PWRGD_PVDD11_S3_P1    I30 @T6G_MB_LIB.T6G(SCH_1):PAGE375
     6 LED_PWRGD_PVDD11_S3_P1_D @T6G_MB_LIB.T6G(SCH_1):LED_PWRGD_PVDD11_S3_P1_D    I30 @T6G_MB_LIB.T6G(SCH_1):PAGE375
     3 LED_PWRGD_PVDD18_S5_P1_D @T6G_MB_LIB.T6G(SCH_1):LED_PWRGD_PVDD18_S5_P1_D    I29 @T6G_MB_LIB.T6G(SCH_1):PAGE375
     5 FM_LED_PWRGD_PVDD18_S5_P1 @T6G_MB_LIB.T6G(SCH_1):FM_LED_PWRGD_PVDD18_S5_P1    I29 @T6G_MB_LIB.T6G(SCH_1):PAGE375
     4    GND @T6G_MB_LIB.T6G(SCH_1):GND    I29 @T6G_MB_LIB.T6G(SCH_1):PAGE375

 Q87 MOSFET_NCH_DUAL-PJT138K,SMLF,IC,BAM138K0003
     1    GND @T6G_MB_LIB.T6G(SCH_1):GND    I38 @T6G_MB_LIB.T6G(SCH_1):PAGE254
     2 RST_CPU0_RSMRST_N @T6G_MB_LIB.T6G(SCH_1):RST_CPU0_RSMRST_N    I38 @T6G_MB_LIB.T6G(SCH_1):PAGE254
     6 LED_RST_RSMRST_PLD_R_N_D @T6G_MB_LIB.T6G(SCH_1):LED_RST_RSMRST_PLD_R_N_D    I38 @T6G_MB_LIB.T6G(SCH_1):PAGE254
     3 LED_PWRGD_SYS_PWROK_R_D @T6G_MB_LIB.T6G(SCH_1):LED_PWRGD_SYS_PWROK_R_D    I35 @T6G_MB_LIB.T6G(SCH_1):PAGE254
     5 SCM_SYS_PWROK_R2 @T6G_MB_LIB.T6G(SCH_1):SCM_SYS_PWROK_R2    I35 @T6G_MB_LIB.T6G(SCH_1):PAGE254
     4    GND @T6G_MB_LIB.T6G(SCH_1):GND    I35 @T6G_MB_LIB.T6G(SCH_1):PAGE254

 Q95 MOSFET_NCH_DUAL-PJT138K,SMLF,IC,BAM138K0003
     1    GND @T6G_MB_LIB.T6G(SCH_1):GND     I8 @T6G_MB_LIB.T6G(SCH_1):PAGE345
     2 HDD_ACTIVITY_BUF @T6G_MB_LIB.T6G(SCH_1):HDD_ACTIVITY_BUF     I8 @T6G_MB_LIB.T6G(SCH_1):PAGE345
     6 HDD_ACTIVITY_BUF_N @T6G_MB_LIB.T6G(SCH_1):HDD_ACTIVITY_BUF_N     I8 @T6G_MB_LIB.T6G(SCH_1):PAGE345
     3 NC_Q95_D2 @T6G_MB_LIB.T6G(SCH_1):NC_Q95_D2    I89 @T6G_MB_LIB.T6G(SCH_1):PAGE345
     5 NC_Q95_G2 @T6G_MB_LIB.T6G(SCH_1):NC_Q95_G2    I89 @T6G_MB_LIB.T6G(SCH_1):PAGE345
     4 NC_Q95_S2 @T6G_MB_LIB.T6G(SCH_1):NC_Q95_S2    I89 @T6G_MB_LIB.T6G(SCH_1):PAGE345

 Q96 MOSFET_NCH_DUAL-PJT138K,SMLF,IC,BAM138K0003
     1    GND @T6G_MB_LIB.T6G(SCH_1):GND   I154 @T6G_MB_LIB.T6G(SCH_1):PAGE333
     2 GPU_FPGA_READY @T6G_MB_LIB.T6G(SCH_1):GPU_FPGA_READY   I154 @T6G_MB_LIB.T6G(SCH_1):PAGE333
     6 GPU_FPGA_READY_N @T6G_MB_LIB.T6G(SCH_1):GPU_FPGA_READY_N   I154 @T6G_MB_LIB.T6G(SCH_1):PAGE333
     3 GPU_FPGA_READY_ISO @T6G_MB_LIB.T6G(SCH_1):GPU_FPGA_READY_ISO   I159 @T6G_MB_LIB.T6G(SCH_1):PAGE333
     5 GPU_FPGA_READY_N @T6G_MB_LIB.T6G(SCH_1):GPU_FPGA_READY_N   I159 @T6G_MB_LIB.T6G(SCH_1):PAGE333
     4    GND @T6G_MB_LIB.T6G(SCH_1):GND   I159 @T6G_MB_LIB.T6G(SCH_1):PAGE333

Q101 MOSFET_NCH_DUAL-PJT138K,SMLF,IC,BAM138K0003
     1    GND @T6G_MB_LIB.T6G(SCH_1):GND    I52 @T6G_MB_LIB.T6G(SCH_1):PAGE299
     2 GPU_FPGA_THERM_OVERT_N @T6G_MB_LIB.T6G(SCH_1):GPU_FPGA_THERM_OVERT_N    I52 @T6G_MB_LIB.T6G(SCH_1):PAGE299
     6 GPU_FPGA_THERM_OVERT @T6G_MB_LIB.T6G(SCH_1):GPU_FPGA_THERM_OVERT    I52 @T6G_MB_LIB.T6G(SCH_1):PAGE299
     3 GPU_FPGA_THERM_OVERT_ISO_N @T6G_MB_LIB.T6G(SCH_1):GPU_FPGA_THERM_OVERT_ISO_N    I57 @T6G_MB_LIB.T6G(SCH_1):PAGE299
     5 GPU_FPGA_THERM_OVERT @T6G_MB_LIB.T6G(SCH_1):GPU_FPGA_THERM_OVERT    I57 @T6G_MB_LIB.T6G(SCH_1):PAGE299
     4    GND @T6G_MB_LIB.T6G(SCH_1):GND    I57 @T6G_MB_LIB.T6G(SCH_1):PAGE299

Q102 MOSFET_NCH_DUAL-PJT138K,SMLF,IC,BAM138K0003
     1    GND @T6G_MB_LIB.T6G(SCH_1):GND    I40 @T6G_MB_LIB.T6G(SCH_1):PAGE299
     2 GPU_BASE_HMC_READY @T6G_MB_LIB.T6G(SCH_1):GPU_BASE_HMC_READY    I40 @T6G_MB_LIB.T6G(SCH_1):PAGE299
     6 GPU_BASE_HMC_READY_N @T6G_MB_LIB.T6G(SCH_1):GPU_BASE_HMC_READY_N    I40 @T6G_MB_LIB.T6G(SCH_1):PAGE299
     3 GPU_BASE_HMC_READY_ISO @T6G_MB_LIB.T6G(SCH_1):GPU_BASE_HMC_READY_ISO    I48 @T6G_MB_LIB.T6G(SCH_1):PAGE299
     5 GPU_BASE_HMC_READY_N @T6G_MB_LIB.T6G(SCH_1):GPU_BASE_HMC_READY_N    I48 @T6G_MB_LIB.T6G(SCH_1):PAGE299
     4    GND @T6G_MB_LIB.T6G(SCH_1):GND    I48 @T6G_MB_LIB.T6G(SCH_1):PAGE299

Q103 MOSFET_NCH_DUAL-PJT138K,SMLF,IC,BAM138K0003
     1    GND @T6G_MB_LIB.T6G(SCH_1):GND    I37 @T6G_MB_LIB.T6G(SCH_1):PAGE299
     2 GPU_HMC_PRSNT_N @T6G_MB_LIB.T6G(SCH_1):GPU_HMC_PRSNT_N    I37 @T6G_MB_LIB.T6G(SCH_1):PAGE299
     6 GPU_HMC_PRSNT @T6G_MB_LIB.T6G(SCH_1):GPU_HMC_PRSNT    I37 @T6G_MB_LIB.T6G(SCH_1):PAGE299
     3 GPU_HMC_PRSNT_ISO_N @T6G_MB_LIB.T6G(SCH_1):GPU_HMC_PRSNT_ISO_N    I43 @T6G_MB_LIB.T6G(SCH_1):PAGE299
     5 GPU_HMC_PRSNT @T6G_MB_LIB.T6G(SCH_1):GPU_HMC_PRSNT    I43 @T6G_MB_LIB.T6G(SCH_1):PAGE299
     4    GND @T6G_MB_LIB.T6G(SCH_1):GND    I43 @T6G_MB_LIB.T6G(SCH_1):PAGE299

Q104 MOSFET_NCH_DUAL-PJT138K,SMLF,IC,BAM138K0003
     1    GND @T6G_MB_LIB.T6G(SCH_1):GND    I21 @T6G_MB_LIB.T6G(SCH_1):PAGE299
     2 GPU_FPGA_OVERT_N @T6G_MB_LIB.T6G(SCH_1):GPU_FPGA_OVERT_N    I21 @T6G_MB_LIB.T6G(SCH_1):PAGE299
     6 GPU_FPGA_OVERT @T6G_MB_LIB.T6G(SCH_1):GPU_FPGA_OVERT    I21 @T6G_MB_LIB.T6G(SCH_1):PAGE299
     3 GPU_FPGA_OVERT_ISO_N @T6G_MB_LIB.T6G(SCH_1):GPU_FPGA_OVERT_ISO_N    I26 @T6G_MB_LIB.T6G(SCH_1):PAGE299
     5 GPU_FPGA_OVERT @T6G_MB_LIB.T6G(SCH_1):GPU_FPGA_OVERT    I26 @T6G_MB_LIB.T6G(SCH_1):PAGE299
     4    GND @T6G_MB_LIB.T6G(SCH_1):GND    I26 @T6G_MB_LIB.T6G(SCH_1):PAGE299

Q106 MOSFET_NCH_DUAL-PJT138K,SMLF,IC,BAM138K0003
     1    GND @T6G_MB_LIB.T6G(SCH_1):GND   I201 @T6G_MB_LIB.T6G(SCH_1):PAGE299
     2 GPU_WP_HW_CTRL_N @T6G_MB_LIB.T6G(SCH_1):GPU_WP_HW_CTRL_N   I201 @T6G_MB_LIB.T6G(SCH_1):PAGE299
     6 GPU_WP_HW_CTRL_ISO @T6G_MB_LIB.T6G(SCH_1):GPU_WP_HW_CTRL_ISO   I201 @T6G_MB_LIB.T6G(SCH_1):PAGE299
     3 GPU_WP_HW_CTRL_ISO_N @T6G_MB_LIB.T6G(SCH_1):GPU_WP_HW_CTRL_ISO_N   I200 @T6G_MB_LIB.T6G(SCH_1):PAGE299
     5 GPU_WP_HW_CTRL_ISO @T6G_MB_LIB.T6G(SCH_1):GPU_WP_HW_CTRL_ISO   I200 @T6G_MB_LIB.T6G(SCH_1):PAGE299
     4    GND @T6G_MB_LIB.T6G(SCH_1):GND   I200 @T6G_MB_LIB.T6G(SCH_1):PAGE299

Q107 MOSFET_NCH_DUAL-PJT138K,SMLF,IC,BAM138K0003
     1    GND @T6G_MB_LIB.T6G(SCH_1):GND   I160 @T6G_MB_LIB.T6G(SCH_1):PAGE299
     2 GPU_PRSNT_N @T6G_MB_LIB.T6G(SCH_1):GPU_PRSNT_N   I160 @T6G_MB_LIB.T6G(SCH_1):PAGE299
     6 GPU_PRSNT @T6G_MB_LIB.T6G(SCH_1):GPU_PRSNT   I160 @T6G_MB_LIB.T6G(SCH_1):PAGE299
     3 GPU_PRSNT_N_ISO @T6G_MB_LIB.T6G(SCH_1):GPU_PRSNT_N_ISO   I157 @T6G_MB_LIB.T6G(SCH_1):PAGE299
     5 GPU_PRSNT @T6G_MB_LIB.T6G(SCH_1):GPU_PRSNT   I157 @T6G_MB_LIB.T6G(SCH_1):PAGE299
     4    GND @T6G_MB_LIB.T6G(SCH_1):GND   I157 @T6G_MB_LIB.T6G(SCH_1):PAGE299

Q108 MOSFET_NCH_DUAL-PJT138K,SMLF,IC,BAM138K0003
     1    GND @T6G_MB_LIB.T6G(SCH_1):GND   I169 @T6G_MB_LIB.T6G(SCH_1):PAGE299
     2 GPU_FPGA_EROT_FATALERR_N @T6G_MB_LIB.T6G(SCH_1):GPU_FPGA_EROT_FATALERR_N   I169 @T6G_MB_LIB.T6G(SCH_1):PAGE299
     6 GPU_FPGA_EROT_FATALERR @T6G_MB_LIB.T6G(SCH_1):GPU_FPGA_EROT_FATALERR   I169 @T6G_MB_LIB.T6G(SCH_1):PAGE299
     3 GPU_FPGA_EROT_FATALERR_ISO_N @T6G_MB_LIB.T6G(SCH_1):GPU_FPGA_EROT_FATALERR_ISO_N   I168 @T6G_MB_LIB.T6G(SCH_1):PAGE299
     5 GPU_FPGA_EROT_FATALERR @T6G_MB_LIB.T6G(SCH_1):GPU_FPGA_EROT_FATALERR   I168 @T6G_MB_LIB.T6G(SCH_1):PAGE299
     4    GND @T6G_MB_LIB.T6G(SCH_1):GND   I168 @T6G_MB_LIB.T6G(SCH_1):PAGE299

Q118 MOSFET_NCH_DUAL-PJT138K,SMLF,IC,BAM138K0003
     1    GND @T6G_MB_LIB.T6G(SCH_1):GND    I10 @T6G_MB_LIB.T6G(SCH_1):PAGE343
     2 P12V_OCP_EN_2_R @T6G_MB_LIB.T6G(SCH_1):P12V_OCP_EN_2_R    I10 @T6G_MB_LIB.T6G(SCH_1):PAGE343
     6 P12V_OCP_2_EN_G @T6G_MB_LIB.T6G(SCH_1):P12V_OCP_2_EN_G    I10 @T6G_MB_LIB.T6G(SCH_1):PAGE343
     3 P12V_OCP_UV_2_R @T6G_MB_LIB.T6G(SCH_1):P12V_OCP_UV_2_R    I19 @T6G_MB_LIB.T6G(SCH_1):PAGE343
     5 P12V_OCP_2_EN_G @T6G_MB_LIB.T6G(SCH_1):P12V_OCP_2_EN_G    I19 @T6G_MB_LIB.T6G(SCH_1):PAGE343
     4    GND @T6G_MB_LIB.T6G(SCH_1):GND    I19 @T6G_MB_LIB.T6G(SCH_1):PAGE343

Q119 MOSFET_NCH_DUAL-PJT138K,SMLF,IC,BAM138K0003
     1    GND @T6G_MB_LIB.T6G(SCH_1):GND    I42 @T6G_MB_LIB.T6G(SCH_1):PAGE343
     2 P3V3_OCP_EN_2_R @T6G_MB_LIB.T6G(SCH_1):P3V3_OCP_EN_2_R    I42 @T6G_MB_LIB.T6G(SCH_1):PAGE343
     6 P3V3_OCP_2_EN_G @T6G_MB_LIB.T6G(SCH_1):P3V3_OCP_2_EN_G    I42 @T6G_MB_LIB.T6G(SCH_1):PAGE343
     3 P3V3_OCP_UV_2_R1 @T6G_MB_LIB.T6G(SCH_1):P3V3_OCP_UV_2_R1    I45 @T6G_MB_LIB.T6G(SCH_1):PAGE343
     5 P3V3_OCP_2_EN_G @T6G_MB_LIB.T6G(SCH_1):P3V3_OCP_2_EN_G    I45 @T6G_MB_LIB.T6G(SCH_1):PAGE343
     4    GND @T6G_MB_LIB.T6G(SCH_1):GND    I45 @T6G_MB_LIB.T6G(SCH_1):PAGE343

Q123 MOSFET_NCH_DUAL-PJT138K,SMLF,IC,BAM138K0003
     1    GND @T6G_MB_LIB.T6G(SCH_1):GND    I11 @T6G_MB_LIB.T6G(SCH_1):PAGE338
     2 P12V_OCP_EN_1_R @T6G_MB_LIB.T6G(SCH_1):P12V_OCP_EN_1_R    I11 @T6G_MB_LIB.T6G(SCH_1):PAGE338
     6 P12V_OCP_1_EN_G @T6G_MB_LIB.T6G(SCH_1):P12V_OCP_1_EN_G    I11 @T6G_MB_LIB.T6G(SCH_1):PAGE338
     3 P12V_OCP_UV_1_R @T6G_MB_LIB.T6G(SCH_1):P12V_OCP_UV_1_R    I19 @T6G_MB_LIB.T6G(SCH_1):PAGE338
     5 P12V_OCP_1_EN_G @T6G_MB_LIB.T6G(SCH_1):P12V_OCP_1_EN_G    I19 @T6G_MB_LIB.T6G(SCH_1):PAGE338
     4    GND @T6G_MB_LIB.T6G(SCH_1):GND    I19 @T6G_MB_LIB.T6G(SCH_1):PAGE338

Q124 MOSFET_NCH_DUAL-PJT138K,SMLF,IC,BAM138K0003
     1    GND @T6G_MB_LIB.T6G(SCH_1):GND    I23 @T6G_MB_LIB.T6G(SCH_1):PAGE338
     2 P3V3_OCP_EN_1_R @T6G_MB_LIB.T6G(SCH_1):P3V3_OCP_EN_1_R    I23 @T6G_MB_LIB.T6G(SCH_1):PAGE338
     6 P3V3_OCP_1_EN_G @T6G_MB_LIB.T6G(SCH_1):P3V3_OCP_1_EN_G    I23 @T6G_MB_LIB.T6G(SCH_1):PAGE338
     3 P3V3_OCP_UV_1_R1 @T6G_MB_LIB.T6G(SCH_1):P3V3_OCP_UV_1_R1   I112 @T6G_MB_LIB.T6G(SCH_1):PAGE338
     5 P3V3_OCP_1_EN_G @T6G_MB_LIB.T6G(SCH_1):P3V3_OCP_1_EN_G   I112 @T6G_MB_LIB.T6G(SCH_1):PAGE338
     4    GND @T6G_MB_LIB.T6G(SCH_1):GND   I112 @T6G_MB_LIB.T6G(SCH_1):PAGE338

Q125 MOSFET_NCH_DUAL-PJT138K,SMLF,IC,BAM138K0003
     1    GND @T6G_MB_LIB.T6G(SCH_1):GND    I22 @T6G_MB_LIB.T6G(SCH_1):PAGE350
     2 P12V_SCM_EN_R @T6G_MB_LIB.T6G(SCH_1):P12V_SCM_EN_R    I22 @T6G_MB_LIB.T6G(SCH_1):PAGE350
     6 P12V_SCM_EN_G @T6G_MB_LIB.T6G(SCH_1):P12V_SCM_EN_G    I22 @T6G_MB_LIB.T6G(SCH_1):PAGE350
     3 P12V_SCM_UV_R @T6G_MB_LIB.T6G(SCH_1):P12V_SCM_UV_R    I24 @T6G_MB_LIB.T6G(SCH_1):PAGE350
     5 P12V_SCM_EN_G @T6G_MB_LIB.T6G(SCH_1):P12V_SCM_EN_G    I24 @T6G_MB_LIB.T6G(SCH_1):PAGE350
     4    GND @T6G_MB_LIB.T6G(SCH_1):GND    I24 @T6G_MB_LIB.T6G(SCH_1):PAGE350

Q126 MOSFET_NCH_DUAL-PJT138K,SMLF,IC,BAM138K0003
     1    GND @T6G_MB_LIB.T6G(SCH_1):GND     I6 @T6G_MB_LIB.T6G(SCH_1):PAGE324
     2 P3V3_E1S_EN_0_R @T6G_MB_LIB.T6G(SCH_1):P3V3_E1S_EN_0_R     I6 @T6G_MB_LIB.T6G(SCH_1):PAGE324
     6 P3V3_E1S_0_EN_G @T6G_MB_LIB.T6G(SCH_1):P3V3_E1S_0_EN_G     I6 @T6G_MB_LIB.T6G(SCH_1):PAGE324
     3 P3V3_E1S_UV_0_R @T6G_MB_LIB.T6G(SCH_1):P3V3_E1S_UV_0_R     I7 @T6G_MB_LIB.T6G(SCH_1):PAGE324
     5 P3V3_E1S_0_EN_G @T6G_MB_LIB.T6G(SCH_1):P3V3_E1S_0_EN_G     I7 @T6G_MB_LIB.T6G(SCH_1):PAGE324
     4    GND @T6G_MB_LIB.T6G(SCH_1):GND     I7 @T6G_MB_LIB.T6G(SCH_1):PAGE324

Q127 MOSFET_NCH_DUAL-PJT138K,SMLF,IC,BAM138K0003
     1    GND @T6G_MB_LIB.T6G(SCH_1):GND    I12 @T6G_MB_LIB.T6G(SCH_1):PAGE324
     2 P12V_E1S_EN_0_R @T6G_MB_LIB.T6G(SCH_1):P12V_E1S_EN_0_R    I12 @T6G_MB_LIB.T6G(SCH_1):PAGE324
     6 P12V_E1S_0_EN_G @T6G_MB_LIB.T6G(SCH_1):P12V_E1S_0_EN_G    I12 @T6G_MB_LIB.T6G(SCH_1):PAGE324
     3 P12V_E1S_UV_0_R @T6G_MB_LIB.T6G(SCH_1):P12V_E1S_UV_0_R    I27 @T6G_MB_LIB.T6G(SCH_1):PAGE324
     5 P12V_E1S_0_EN_G @T6G_MB_LIB.T6G(SCH_1):P12V_E1S_0_EN_G    I27 @T6G_MB_LIB.T6G(SCH_1):PAGE324
     4    GND @T6G_MB_LIB.T6G(SCH_1):GND    I27 @T6G_MB_LIB.T6G(SCH_1):PAGE324

Q128 MOSFET_NCH_DUAL-PJT138K,SMLF,IC,BAM138K0003
     1    GND @T6G_MB_LIB.T6G(SCH_1):GND    I37 @T6G_MB_LIB.T6G(SCH_1):PAGE332
     2 GPU_3V3IO_RSVD0_FFU @T6G_MB_LIB.T6G(SCH_1):GPU_3V3IO_RSVD0_FFU    I37 @T6G_MB_LIB.T6G(SCH_1):PAGE332
     6 GPU_3V3IO_RSVD0_FFU_N @T6G_MB_LIB.T6G(SCH_1):GPU_3V3IO_RSVD0_FFU_N    I37 @T6G_MB_LIB.T6G(SCH_1):PAGE332
     3 GPU_3V3IO_RSVD0_FFU_ISO @T6G_MB_LIB.T6G(SCH_1):GPU_3V3IO_RSVD0_FFU_ISO    I42 @T6G_MB_LIB.T6G(SCH_1):PAGE332
     5 GPU_3V3IO_RSVD0_FFU_N @T6G_MB_LIB.T6G(SCH_1):GPU_3V3IO_RSVD0_FFU_N    I42 @T6G_MB_LIB.T6G(SCH_1):PAGE332
     4    GND @T6G_MB_LIB.T6G(SCH_1):GND    I42 @T6G_MB_LIB.T6G(SCH_1):PAGE332

Q129 MOSFET_NCH_DUAL-PJT138K,SMLF,IC,BAM138K0003
     1    GND @T6G_MB_LIB.T6G(SCH_1):GND    I86 @T6G_MB_LIB.T6G(SCH_1):PAGE332
     2 GPU_3V3IO_RSVD5_FFU @T6G_MB_LIB.T6G(SCH_1):GPU_3V3IO_RSVD5_FFU    I86 @T6G_MB_LIB.T6G(SCH_1):PAGE332
     6 GPU_3V3IO_RSVD5_FFU_N @T6G_MB_LIB.T6G(SCH_1):GPU_3V3IO_RSVD5_FFU_N    I86 @T6G_MB_LIB.T6G(SCH_1):PAGE332
     3 GPU_3V3IO_RSVD5_FFU_ISO @T6G_MB_LIB.T6G(SCH_1):GPU_3V3IO_RSVD5_FFU_ISO   I113 @T6G_MB_LIB.T6G(SCH_1):PAGE332
     5 GPU_3V3IO_RSVD5_FFU_N @T6G_MB_LIB.T6G(SCH_1):GPU_3V3IO_RSVD5_FFU_N   I113 @T6G_MB_LIB.T6G(SCH_1):PAGE332
     4    GND @T6G_MB_LIB.T6G(SCH_1):GND   I113 @T6G_MB_LIB.T6G(SCH_1):PAGE332

Q130 MOSFET_NCH_DUAL-PJT138K,SMLF,IC,BAM138K0003
     1    GND @T6G_MB_LIB.T6G(SCH_1):GND   I102 @T6G_MB_LIB.T6G(SCH_1):PAGE332
     2 GPU_3V3IO_RSVD3_FFU @T6G_MB_LIB.T6G(SCH_1):GPU_3V3IO_RSVD3_FFU   I102 @T6G_MB_LIB.T6G(SCH_1):PAGE332
     6 GPU_3V3IO_RSVD3_FFU_N @T6G_MB_LIB.T6G(SCH_1):GPU_3V3IO_RSVD3_FFU_N   I102 @T6G_MB_LIB.T6G(SCH_1):PAGE332
     3 GPU_3V3IO_RSVD3_FFU_ISO @T6G_MB_LIB.T6G(SCH_1):GPU_3V3IO_RSVD3_FFU_ISO   I123 @T6G_MB_LIB.T6G(SCH_1):PAGE332
     5 GPU_3V3IO_RSVD3_FFU_N @T6G_MB_LIB.T6G(SCH_1):GPU_3V3IO_RSVD3_FFU_N   I123 @T6G_MB_LIB.T6G(SCH_1):PAGE332
     4    GND @T6G_MB_LIB.T6G(SCH_1):GND   I123 @T6G_MB_LIB.T6G(SCH_1):PAGE332

Q131 MOSFET_NCH_DUAL-PJT138K,SMLF,IC,BAM138K0003
     1    GND @T6G_MB_LIB.T6G(SCH_1):GND    I30 @T6G_MB_LIB.T6G(SCH_1):PAGE332
     2 GPU_3V3IO_RSVD1_FFU @T6G_MB_LIB.T6G(SCH_1):GPU_3V3IO_RSVD1_FFU    I30 @T6G_MB_LIB.T6G(SCH_1):PAGE332
     6 GPU_3V3IO_RSVD1_FFU_N @T6G_MB_LIB.T6G(SCH_1):GPU_3V3IO_RSVD1_FFU_N    I30 @T6G_MB_LIB.T6G(SCH_1):PAGE332
     3 GPU_3V3IO_RSVD1_FFU_ISO @T6G_MB_LIB.T6G(SCH_1):GPU_3V3IO_RSVD1_FFU_ISO    I40 @T6G_MB_LIB.T6G(SCH_1):PAGE332
     5 GPU_3V3IO_RSVD1_FFU_N @T6G_MB_LIB.T6G(SCH_1):GPU_3V3IO_RSVD1_FFU_N    I40 @T6G_MB_LIB.T6G(SCH_1):PAGE332
     4    GND @T6G_MB_LIB.T6G(SCH_1):GND    I40 @T6G_MB_LIB.T6G(SCH_1):PAGE332

Q132 MOSFET_NCH_DUAL-PJT138K,SMLF,IC,BAM138K0003
     1    GND @T6G_MB_LIB.T6G(SCH_1):GND    I25 @T6G_MB_LIB.T6G(SCH_1):PAGE332
     2 PRSNT_CABLE_GPU_B3_N @T6G_MB_LIB.T6G(SCH_1):PRSNT_CABLE_GPU_B3_N    I25 @T6G_MB_LIB.T6G(SCH_1):PAGE332
     6 PRSNT_CABLE_GPU_B3 @T6G_MB_LIB.T6G(SCH_1):PRSNT_CABLE_GPU_B3    I25 @T6G_MB_LIB.T6G(SCH_1):PAGE332
     3 PRSNT_CABLE_GPU_B3_ISO_N @T6G_MB_LIB.T6G(SCH_1):PRSNT_CABLE_GPU_B3_ISO_N    I32 @T6G_MB_LIB.T6G(SCH_1):PAGE332
     5 PRSNT_CABLE_GPU_B3 @T6G_MB_LIB.T6G(SCH_1):PRSNT_CABLE_GPU_B3    I32 @T6G_MB_LIB.T6G(SCH_1):PAGE332
     4    GND @T6G_MB_LIB.T6G(SCH_1):GND    I32 @T6G_MB_LIB.T6G(SCH_1):PAGE332

Q133 MOSFET_NCH_DUAL-PJT138K,SMLF,IC,BAM138K0003
     1    GND @T6G_MB_LIB.T6G(SCH_1):GND    I98 @T6G_MB_LIB.T6G(SCH_1):PAGE332
     2 PRSNT_CABLE_GPU_A2_N @T6G_MB_LIB.T6G(SCH_1):PRSNT_CABLE_GPU_A2_N    I98 @T6G_MB_LIB.T6G(SCH_1):PAGE332
     6 PRSNT_CABLE_GPU_A2 @T6G_MB_LIB.T6G(SCH_1):PRSNT_CABLE_GPU_A2    I98 @T6G_MB_LIB.T6G(SCH_1):PAGE332
     3 PRSNT_CABLE_GPU_A2_ISO_N @T6G_MB_LIB.T6G(SCH_1):PRSNT_CABLE_GPU_A2_ISO_N   I120 @T6G_MB_LIB.T6G(SCH_1):PAGE332
     5 PRSNT_CABLE_GPU_A2 @T6G_MB_LIB.T6G(SCH_1):PRSNT_CABLE_GPU_A2   I120 @T6G_MB_LIB.T6G(SCH_1):PAGE332
     4    GND @T6G_MB_LIB.T6G(SCH_1):GND   I120 @T6G_MB_LIB.T6G(SCH_1):PAGE332

Q134 MOSFET_NCH_DUAL-PJT138K,SMLF,IC,BAM138K0003
     1    GND @T6G_MB_LIB.T6G(SCH_1):GND     I6 @T6G_MB_LIB.T6G(SCH_1):PAGE332
     2 PRSNT_CABLE_GPU_A1_N @T6G_MB_LIB.T6G(SCH_1):PRSNT_CABLE_GPU_A1_N     I6 @T6G_MB_LIB.T6G(SCH_1):PAGE332
     6 PRSNT_CABLE_GPU_A1 @T6G_MB_LIB.T6G(SCH_1):PRSNT_CABLE_GPU_A1     I6 @T6G_MB_LIB.T6G(SCH_1):PAGE332
     3 PRSNT_CABLE_GPU_A1_ISO_N @T6G_MB_LIB.T6G(SCH_1):PRSNT_CABLE_GPU_A1_ISO_N    I10 @T6G_MB_LIB.T6G(SCH_1):PAGE332
     5 PRSNT_CABLE_GPU_A1 @T6G_MB_LIB.T6G(SCH_1):PRSNT_CABLE_GPU_A1    I10 @T6G_MB_LIB.T6G(SCH_1):PAGE332
     4    GND @T6G_MB_LIB.T6G(SCH_1):GND    I10 @T6G_MB_LIB.T6G(SCH_1):PAGE332

Q135 MOSFET_NCH_DUAL-PJT138K,SMLF,IC,BAM138K0003
     1    GND @T6G_MB_LIB.T6G(SCH_1):GND    I25 @T6G_MB_LIB.T6G(SCH_1):PAGE331
     2 GPU_3V3IO_RSVD1 @T6G_MB_LIB.T6G(SCH_1):GPU_3V3IO_RSVD1    I25 @T6G_MB_LIB.T6G(SCH_1):PAGE331
     6 GPU_3V3IO_RSVD1_N @T6G_MB_LIB.T6G(SCH_1):GPU_3V3IO_RSVD1_N    I25 @T6G_MB_LIB.T6G(SCH_1):PAGE331
     3 GPU_3V3IO_RSVD1_ISO @T6G_MB_LIB.T6G(SCH_1):GPU_3V3IO_RSVD1_ISO    I29 @T6G_MB_LIB.T6G(SCH_1):PAGE331
     5 GPU_3V3IO_RSVD1_N @T6G_MB_LIB.T6G(SCH_1):GPU_3V3IO_RSVD1_N    I29 @T6G_MB_LIB.T6G(SCH_1):PAGE331
     4    GND @T6G_MB_LIB.T6G(SCH_1):GND    I29 @T6G_MB_LIB.T6G(SCH_1):PAGE331

Q136 MOSFET_NCH_DUAL-PJT138K,SMLF,IC,BAM138K0003
     1    GND @T6G_MB_LIB.T6G(SCH_1):GND    I17 @T6G_MB_LIB.T6G(SCH_1):PAGE331
     2 GPU_3V3IO_RSVD4 @T6G_MB_LIB.T6G(SCH_1):GPU_3V3IO_RSVD4    I17 @T6G_MB_LIB.T6G(SCH_1):PAGE331
     6 GPU_3V3IO_RSVD4_N @T6G_MB_LIB.T6G(SCH_1):GPU_3V3IO_RSVD4_N    I17 @T6G_MB_LIB.T6G(SCH_1):PAGE331
     3 GPU_3V3IO_RSVD4_ISO @T6G_MB_LIB.T6G(SCH_1):GPU_3V3IO_RSVD4_ISO    I22 @T6G_MB_LIB.T6G(SCH_1):PAGE331
     5 GPU_3V3IO_RSVD4_N @T6G_MB_LIB.T6G(SCH_1):GPU_3V3IO_RSVD4_N    I22 @T6G_MB_LIB.T6G(SCH_1):PAGE331
     4    GND @T6G_MB_LIB.T6G(SCH_1):GND    I22 @T6G_MB_LIB.T6G(SCH_1):PAGE331

Q137 MOSFET_NCH_DUAL-PJT138K,SMLF,IC,BAM138K0003
     1    GND @T6G_MB_LIB.T6G(SCH_1):GND    I21 @T6G_MB_LIB.T6G(SCH_1):PAGE331
     2 GPU_3V3IO_RSVD3 @T6G_MB_LIB.T6G(SCH_1):GPU_3V3IO_RSVD3    I21 @T6G_MB_LIB.T6G(SCH_1):PAGE331
     6 GPU_3V3IO_RSVD3_N @T6G_MB_LIB.T6G(SCH_1):GPU_3V3IO_RSVD3_N    I21 @T6G_MB_LIB.T6G(SCH_1):PAGE331
     3 GPU_3V3IO_RSVD3_ISO @T6G_MB_LIB.T6G(SCH_1):GPU_3V3IO_RSVD3_ISO    I28 @T6G_MB_LIB.T6G(SCH_1):PAGE331
     5 GPU_3V3IO_RSVD3_N @T6G_MB_LIB.T6G(SCH_1):GPU_3V3IO_RSVD3_N    I28 @T6G_MB_LIB.T6G(SCH_1):PAGE331
     4    GND @T6G_MB_LIB.T6G(SCH_1):GND    I28 @T6G_MB_LIB.T6G(SCH_1):PAGE331

Q144 MOSFET_NCH_DUAL-PJT138K,SMLF,IC,BAM138K0003
     1    GND @T6G_MB_LIB.T6G(SCH_1):GND     I3 @T6G_MB_LIB.T6G(SCH_1):PAGE368
     2 PWRGD_PS_PWROK_PLD @T6G_MB_LIB.T6G(SCH_1):PWRGD_PS_PWROK_PLD     I3 @T6G_MB_LIB.T6G(SCH_1):PAGE368
     6 PWRGD_PS_PWROK_PLD_N @T6G_MB_LIB.T6G(SCH_1):PWRGD_PS_PWROK_PLD_N     I3 @T6G_MB_LIB.T6G(SCH_1):PAGE368
     3 PWRGD_PS_PWROK_PLD_ISO @T6G_MB_LIB.T6G(SCH_1):PWRGD_PS_PWROK_PLD_ISO    I10 @T6G_MB_LIB.T6G(SCH_1):PAGE368
     5 PWRGD_PS_PWROK_PLD_N @T6G_MB_LIB.T6G(SCH_1):PWRGD_PS_PWROK_PLD_N    I10 @T6G_MB_LIB.T6G(SCH_1):PAGE368
     4    GND @T6G_MB_LIB.T6G(SCH_1):GND    I10 @T6G_MB_LIB.T6G(SCH_1):PAGE368

Q145 MOSFET_NCH_DUAL-PJT138K,SMLF,IC,BAM138K0003
     1    GND @T6G_MB_LIB.T6G(SCH_1):GND    I53 @T6G_MB_LIB.T6G(SCH_1):PAGE364
     2 HPDB_HSC_PWRGD @T6G_MB_LIB.T6G(SCH_1):HPDB_HSC_PWRGD    I53 @T6G_MB_LIB.T6G(SCH_1):PAGE364
     6 HPDB_HSC_PWRGD_N @T6G_MB_LIB.T6G(SCH_1):HPDB_HSC_PWRGD_N    I53 @T6G_MB_LIB.T6G(SCH_1):PAGE364
     3 HPDB_HSC_PWRGD_ISO @T6G_MB_LIB.T6G(SCH_1):HPDB_HSC_PWRGD_ISO    I58 @T6G_MB_LIB.T6G(SCH_1):PAGE364
     5 HPDB_HSC_PWRGD_N @T6G_MB_LIB.T6G(SCH_1):HPDB_HSC_PWRGD_N    I58 @T6G_MB_LIB.T6G(SCH_1):PAGE364
     4    GND @T6G_MB_LIB.T6G(SCH_1):GND    I58 @T6G_MB_LIB.T6G(SCH_1):PAGE364

Q146 MOSFET_NCH_DUAL-PJT138K,SMLF,IC,BAM138K0003
     1    GND @T6G_MB_LIB.T6G(SCH_1):GND    I57 @T6G_MB_LIB.T6G(SCH_1):PAGE332
     2 SWB_HSC_PWRGD @T6G_MB_LIB.T6G(SCH_1):SWB_HSC_PWRGD    I57 @T6G_MB_LIB.T6G(SCH_1):PAGE332
     6 SWB_HSC_PWRGD_N @T6G_MB_LIB.T6G(SCH_1):SWB_HSC_PWRGD_N    I57 @T6G_MB_LIB.T6G(SCH_1):PAGE332
     3 SWB_HSC_PWRGD_ISO @T6G_MB_LIB.T6G(SCH_1):SWB_HSC_PWRGD_ISO   I134 @T6G_MB_LIB.T6G(SCH_1):PAGE332
     5 SWB_HSC_PWRGD_N @T6G_MB_LIB.T6G(SCH_1):SWB_HSC_PWRGD_N   I134 @T6G_MB_LIB.T6G(SCH_1):PAGE332
     4    GND @T6G_MB_LIB.T6G(SCH_1):GND   I134 @T6G_MB_LIB.T6G(SCH_1):PAGE332

Q148 MOSFET_NCH_DUAL-PJT138K,SMLF,IC,BAM138K0003
     1    GND @T6G_MB_LIB.T6G(SCH_1):GND    I61 @T6G_MB_LIB.T6G(SCH_1):PAGE331
     2 HGX_DETECT_N @T6G_MB_LIB.T6G(SCH_1):HGX_DETECT_N    I61 @T6G_MB_LIB.T6G(SCH_1):PAGE331
     6 HGX_DETECT @T6G_MB_LIB.T6G(SCH_1):HGX_DETECT    I61 @T6G_MB_LIB.T6G(SCH_1):PAGE331
     3 HGX_DETECT_N_ISO @T6G_MB_LIB.T6G(SCH_1):HGX_DETECT_N_ISO    I55 @T6G_MB_LIB.T6G(SCH_1):PAGE331
     5 HGX_DETECT @T6G_MB_LIB.T6G(SCH_1):HGX_DETECT    I55 @T6G_MB_LIB.T6G(SCH_1):PAGE331
     4    GND @T6G_MB_LIB.T6G(SCH_1):GND    I55 @T6G_MB_LIB.T6G(SCH_1):PAGE331

Q6000 MOSFET_NCH_DUAL-PJT138K,SMLF,IC,BAM138K0003
     1    GND @T6G_MB_LIB.T6G(SCH_1):GND    I47 @T6G_MB_LIB.T6G(SCH_1):PAGE254
     2 PWRGD_P1V2_AUX_R @T6G_MB_LIB.T6G(SCH_1):PWRGD_P1V2_AUX_R    I47 @T6G_MB_LIB.T6G(SCH_1):PAGE254
     6 LED_PWRGD_P1V2_AUX_D @T6G_MB_LIB.T6G(SCH_1):LED_PWRGD_P1V2_AUX_D    I47 @T6G_MB_LIB.T6G(SCH_1):PAGE254

Q6001 METR3904G-METR3904-G,SMLF,IC,BA039040020
     B P12V_HSC_TEMP_R @T6G_MB_LIB.T6G(SCH_1):P12V_HSC_TEMP_R     I1 @T6G_MB_LIB.T6G(SCH_1):PAGE371
     E P12V_HSC_TEMP_E @T6G_MB_LIB.T6G(SCH_1):P12V_HSC_TEMP_E     I1 @T6G_MB_LIB.T6G(SCH_1):PAGE371
     C P12V_HSC_TEMP_R @T6G_MB_LIB.T6G(SCH_1):P12V_HSC_TEMP_R     I1 @T6G_MB_LIB.T6G(SCH_1):PAGE371

Q7000 MOSFET_PCH_GDS_ESD_PROTECTED-DMP2035U-7,SMLF,EMPTYA
     D P12V_AUX_DSC_G2 @T6G_MB_LIB.T6G(SCH_1):P12V_AUX_DSC_G2    I10 @T6G_MB_LIB.T6G(SCH_1):PAGE146
     G P12V_AUX_DSC_G1 @T6G_MB_LIB.T6G(SCH_1):P12V_AUX_DSC_G1    I10 @T6G_MB_LIB.T6G(SCH_1):PAGE146
     S P12V_AUX_DSC_S1 @T6G_MB_LIB.T6G(SCH_1):P12V_AUX_DSC_S1    I10 @T6G_MB_LIB.T6G(SCH_1):PAGE146

Q7001 MOSFET_NCH_1D3S-PSMNR58-30YLH,SMLF,EMPTY,BAMNR5800A
     3    GND @T6G_MB_LIB.T6G(SCH_1):GND    I16 @T6G_MB_LIB.T6G(SCH_1):PAGE146
     5 P12V_AUX_DSC @T6G_MB_LIB.T6G(SCH_1):P12V_AUX_DSC    I16 @T6G_MB_LIB.T6G(SCH_1):PAGE146
     2    GND @T6G_MB_LIB.T6G(SCH_1):GND    I16 @T6G_MB_LIB.T6G(SCH_1):PAGE146
     4 P12V_AUX_DSC_G2 @T6G_MB_LIB.T6G(SCH_1):P12V_AUX_DSC_G2    I16 @T6G_MB_LIB.T6G(SCH_1):PAGE146
     1    GND @T6G_MB_LIB.T6G(SCH_1):GND    I16 @T6G_MB_LIB.T6G(SCH_1):PAGE146

Q7002 MOSFET_PCH_GDS_ESD_PROTECTED-DMP2035U-7,SMLF,EMPTYA
     D P3V3_AUX_DSC_G2 @T6G_MB_LIB.T6G(SCH_1):P3V3_AUX_DSC_G2    I23 @T6G_MB_LIB.T6G(SCH_1):PAGE146
     G P3V3_AUX_DSC_G1 @T6G_MB_LIB.T6G(SCH_1):P3V3_AUX_DSC_G1    I23 @T6G_MB_LIB.T6G(SCH_1):PAGE146
     S P3V3_AUX_DSC_S1 @T6G_MB_LIB.T6G(SCH_1):P3V3_AUX_DSC_S1    I23 @T6G_MB_LIB.T6G(SCH_1):PAGE146

Q7003 MOSFET_NCH_1D3S-PSMNR58-30YLH,SMLF,EMPTY,BAMNR5800A
     3    GND @T6G_MB_LIB.T6G(SCH_1):GND    I22 @T6G_MB_LIB.T6G(SCH_1):PAGE146
     5 P3V3_AUX_DSC @T6G_MB_LIB.T6G(SCH_1):P3V3_AUX_DSC    I22 @T6G_MB_LIB.T6G(SCH_1):PAGE146
     2    GND @T6G_MB_LIB.T6G(SCH_1):GND    I22 @T6G_MB_LIB.T6G(SCH_1):PAGE146
     4 P3V3_AUX_DSC_G2 @T6G_MB_LIB.T6G(SCH_1):P3V3_AUX_DSC_G2    I22 @T6G_MB_LIB.T6G(SCH_1):PAGE146
     1    GND @T6G_MB_LIB.T6G(SCH_1):GND    I22 @T6G_MB_LIB.T6G(SCH_1):PAGE146

Q8000 MOSFET_NCH_DUAL-PJT138K,SMLF,IC,BAM138K0003
     1    GND @T6G_MB_LIB.T6G(SCH_1):GND    I29 @T6G_MB_LIB.T6G(SCH_1):PAGE330
     2 PRSNT_SWB_N @T6G_MB_LIB.T6G(SCH_1):PRSNT_SWB_N    I29 @T6G_MB_LIB.T6G(SCH_1):PAGE330
     6 PRSNT_SWB @T6G_MB_LIB.T6G(SCH_1):PRSNT_SWB    I29 @T6G_MB_LIB.T6G(SCH_1):PAGE330
     3 PRSNT_SWB_ISO_N @T6G_MB_LIB.T6G(SCH_1):PRSNT_SWB_ISO_N    I30 @T6G_MB_LIB.T6G(SCH_1):PAGE330
     5 PRSNT_SWB @T6G_MB_LIB.T6G(SCH_1):PRSNT_SWB    I30 @T6G_MB_LIB.T6G(SCH_1):PAGE330
     4    GND @T6G_MB_LIB.T6G(SCH_1):GND    I30 @T6G_MB_LIB.T6G(SCH_1):PAGE330

Q8001 MOSFET_NCH_DUAL-PJT138K,SMLF,IC,BAM138K0003
     1    GND @T6G_MB_LIB.T6G(SCH_1):GND    I57 @T6G_MB_LIB.T6G(SCH_1):PAGE375
     2 P12V_SCM_FAULT_R_N @T6G_MB_LIB.T6G(SCH_1):P12V_SCM_FAULT_R_N    I57 @T6G_MB_LIB.T6G(SCH_1):PAGE375
     6 LED_P12V_SCM_FAULT_D1 @T6G_MB_LIB.T6G(SCH_1):LED_P12V_SCM_FAULT_D1    I57 @T6G_MB_LIB.T6G(SCH_1):PAGE375
     3 LED_P12V_SCM_FAULT_D2 @T6G_MB_LIB.T6G(SCH_1):LED_P12V_SCM_FAULT_D2    I58 @T6G_MB_LIB.T6G(SCH_1):PAGE375
     5 LED_P12V_SCM_FAULT_D1 @T6G_MB_LIB.T6G(SCH_1):LED_P12V_SCM_FAULT_D1    I58 @T6G_MB_LIB.T6G(SCH_1):PAGE375
     4    GND @T6G_MB_LIB.T6G(SCH_1):GND    I58 @T6G_MB_LIB.T6G(SCH_1):PAGE375

Q9000 MOSFET_NCH_DUAL-PJT138K,SMLF,IC,BAM138K0003
     1    GND @T6G_MB_LIB.T6G(SCH_1):GND    I21 @T6G_MB_LIB.T6G(SCH_1):PAGE330
     2 PRSNT_CABLE_SWB_B1_N @T6G_MB_LIB.T6G(SCH_1):PRSNT_CABLE_SWB_B1_N    I21 @T6G_MB_LIB.T6G(SCH_1):PAGE330
     6 PRSNT_CABLE_SWB_B1 @T6G_MB_LIB.T6G(SCH_1):PRSNT_CABLE_SWB_B1    I21 @T6G_MB_LIB.T6G(SCH_1):PAGE330
     3 PRSNT_CABLE_SWB_B1_ISO_N @T6G_MB_LIB.T6G(SCH_1):PRSNT_CABLE_SWB_B1_ISO_N    I31 @T6G_MB_LIB.T6G(SCH_1):PAGE330
     5 PRSNT_CABLE_SWB_B1 @T6G_MB_LIB.T6G(SCH_1):PRSNT_CABLE_SWB_B1    I31 @T6G_MB_LIB.T6G(SCH_1):PAGE330
     4    GND @T6G_MB_LIB.T6G(SCH_1):GND    I31 @T6G_MB_LIB.T6G(SCH_1):PAGE330

Q9001 MOSFET_NCH_DUAL-PJT138K,SMLF,IC,BAM138K0003
     1    GND @T6G_MB_LIB.T6G(SCH_1):GND     I3 @T6G_MB_LIB.T6G(SCH_1):PAGE330
     2 PRSNT_CABLE_SWB_B2_N @T6G_MB_LIB.T6G(SCH_1):PRSNT_CABLE_SWB_B2_N     I3 @T6G_MB_LIB.T6G(SCH_1):PAGE330
     6 PRSNT_CABLE_SWB_B2 @T6G_MB_LIB.T6G(SCH_1):PRSNT_CABLE_SWB_B2     I3 @T6G_MB_LIB.T6G(SCH_1):PAGE330
     3 PRSNT_CABLE_SWB_B2_ISO_N @T6G_MB_LIB.T6G(SCH_1):PRSNT_CABLE_SWB_B2_ISO_N    I22 @T6G_MB_LIB.T6G(SCH_1):PAGE330
     5 PRSNT_CABLE_SWB_B2 @T6G_MB_LIB.T6G(SCH_1):PRSNT_CABLE_SWB_B2    I22 @T6G_MB_LIB.T6G(SCH_1):PAGE330
     4    GND @T6G_MB_LIB.T6G(SCH_1):GND    I22 @T6G_MB_LIB.T6G(SCH_1):PAGE330

Q9002 MOSFET_NCH_DUAL-PJT138K,SMLF,IC,BAM138K0003
     1    GND @T6G_MB_LIB.T6G(SCH_1):GND    I52 @T6G_MB_LIB.T6G(SCH_1):PAGE330
     2 PRSNT_CABLE_GPU_A3_N @T6G_MB_LIB.T6G(SCH_1):PRSNT_CABLE_GPU_A3_N    I52 @T6G_MB_LIB.T6G(SCH_1):PAGE330
     6 PRSNT_CABLE_GPU_A3 @T6G_MB_LIB.T6G(SCH_1):PRSNT_CABLE_GPU_A3    I52 @T6G_MB_LIB.T6G(SCH_1):PAGE330
     3 PRSNT_CABLE_GPU_A3_ISO_N @T6G_MB_LIB.T6G(SCH_1):PRSNT_CABLE_GPU_A3_ISO_N    I75 @T6G_MB_LIB.T6G(SCH_1):PAGE330
     5 PRSNT_CABLE_GPU_A3 @T6G_MB_LIB.T6G(SCH_1):PRSNT_CABLE_GPU_A3    I75 @T6G_MB_LIB.T6G(SCH_1):PAGE330
     4    GND @T6G_MB_LIB.T6G(SCH_1):GND    I75 @T6G_MB_LIB.T6G(SCH_1):PAGE330

Q9003 MOSFET_NCH_DUAL-PJT138K,SMLF,IC,BAM138K0003
     1    GND @T6G_MB_LIB.T6G(SCH_1):GND   I111 @T6G_MB_LIB.T6G(SCH_1):PAGE84
     2 IRQ_HSC_FAULT_N @T6G_MB_LIB.T6G(SCH_1):IRQ_HSC_FAULT_N   I111 @T6G_MB_LIB.T6G(SCH_1):PAGE84
     6 IRQ_HSC_FAULT @T6G_MB_LIB.T6G(SCH_1):IRQ_HSC_FAULT   I111 @T6G_MB_LIB.T6G(SCH_1):PAGE84
     3 IRQ_HSC_FAULT_BUF_N @T6G_MB_LIB.T6G(SCH_1):IRQ_HSC_FAULT_BUF_N   I121 @T6G_MB_LIB.T6G(SCH_1):PAGE84
     5 IRQ_HSC_FAULT @T6G_MB_LIB.T6G(SCH_1):IRQ_HSC_FAULT   I121 @T6G_MB_LIB.T6G(SCH_1):PAGE84
     4    GND @T6G_MB_LIB.T6G(SCH_1):GND   I121 @T6G_MB_LIB.T6G(SCH_1):PAGE84

  R1 Q_RES_0402LF-49.9,1%,1/16W,CHIP,CS04992FB07
     1 I3C_SPD_DDRAF_CPU0_SCL @T6G_MB_LIB.T6G(SCH_1):I3C_SPD_DDRAF_CPU0_SCL   I421 @T6G_MB_LIB.T6G(SCH_1):PAGE88
     2 I3C_SPD_DDRD_CPU0_SCL @T6G_MB_LIB.T6G(SCH_1):I3C_SPD_DDRD_CPU0_SCL   I421 @T6G_MB_LIB.T6G(SCH_1):PAGE88

  R2 Q_RES_0402LF-33.2,1%,1/16W,CHIP,CS03322FB03
     1 RST_PERST_CPU1_SWB_1_N @T6G_MB_LIB.T6G(SCH_1):RST_PERST_CPU1_SWB_1_N    I94 @T6G_MB_LIB.T6G(SCH_1):PAGE84
     2 RST_PERST_CPU1_SWB_1_R_N @T6G_MB_LIB.T6G(SCH_1):RST_PERST_CPU1_SWB_1_R_N    I94 @T6G_MB_LIB.T6G(SCH_1):PAGE84

  R3 Q_RES_0402LF-2K,1%,1/16W,CHIP,CS22002FB07
     1 RST_PERST_CPU1_SWB_1_N @T6G_MB_LIB.T6G(SCH_1):RST_PERST_CPU1_SWB_1_N   I154 @T6G_MB_LIB.T6G(SCH_1):PAGE82
     2    GND @T6G_MB_LIB.T6G(SCH_1):GND   I154 @T6G_MB_LIB.T6G(SCH_1):PAGE82

  R4 Q_RES_0402LF-4.7K,5%,1/16W,EMPTY,CS24702JB10
     1 P3V3_AUX @T6G_MB_LIB.T6G(SCH_1):P3V3_AUX   I114 @T6G_MB_LIB.T6G(SCH_1):PAGE361
     2 SMB_CPU_FRU_3V3AUX_SCL @T6G_MB_LIB.T6G(SCH_1):SMB_CPU_FRU_3V3AUX_SCL   I114 @T6G_MB_LIB.T6G(SCH_1):PAGE361

  R5 Q_RES_0402LF-54.9K,1%,1/16W,CHIP,CS35492FB03
     1 PD_CHE_CPU0_DIMM_SAA @T6G_MB_LIB.T6G(SCH_1):PD_CHE_CPU0_DIMM_SAA   I331 @T6G_MB_LIB.T6G(SCH_1):PAGE89
     2    GND @T6G_MB_LIB.T6G(SCH_1):GND   I331 @T6G_MB_LIB.T6G(SCH_1):PAGE89

  R6 Q_RES_0402LF-54.9K,1%,1/16W,CHIP,CS35492FB03
     1 PD_CHE_CPU1_DIMM_SAA @T6G_MB_LIB.T6G(SCH_1):PD_CHE_CPU1_DIMM_SAA   I127 @T6G_MB_LIB.T6G(SCH_1):PAGE101
     2    GND @T6G_MB_LIB.T6G(SCH_1):GND   I127 @T6G_MB_LIB.T6G(SCH_1):PAGE101

  R7 Q_RES_0402LF-10K,1%,1/16W,CHIP,CS31002FB08
     1 PD_CHA_CPU0_DIMM0_SAA @T6G_MB_LIB.T6G(SCH_1):PD_CHA_CPU0_DIMM0_SAA   I499 @T6G_MB_LIB.T6G(SCH_1):PAGE85
     2    GND @T6G_MB_LIB.T6G(SCH_1):GND   I499 @T6G_MB_LIB.T6G(SCH_1):PAGE85

  R8 Q_RES_0402LF-100K,1%,1/16W,CHIP,CS41002FB09
     1    GND @T6G_MB_LIB.T6G(SCH_1):GND    I47 @T6G_MB_LIB.T6G(SCH_1):PAGE144
     2 JTAG_BMC_OE @T6G_MB_LIB.T6G(SCH_1):JTAG_BMC_OE    I47 @T6G_MB_LIB.T6G(SCH_1):PAGE144

  R9 Q_RES_0402LF-0,5%,1/16W,CHIP,CS00002JB13
     1 JTAG_PLD_TDI @T6G_MB_LIB.T6G(SCH_1):JTAG_PLD_TDI    I37 @T6G_MB_LIB.T6G(SCH_1):PAGE84
     2 JTAG_SCM_PLD_TDI @T6G_MB_LIB.T6G(SCH_1):JTAG_SCM_PLD_TDI    I37 @T6G_MB_LIB.T6G(SCH_1):PAGE84

 R10 Q_RES_0402LF-10K,1%,1/16W,CHIP,CS31002FB08
     1 FM_I3C_CPU0_MUX0_OE_N @T6G_MB_LIB.T6G(SCH_1):FM_I3C_CPU0_MUX0_OE_N    I93 @T6G_MB_LIB.T6G(SCH_1):PAGE82
     2    GND @T6G_MB_LIB.T6G(SCH_1):GND    I93 @T6G_MB_LIB.T6G(SCH_1):PAGE82

 R11 Q_RES_0402LF-10K,1%,1/16W,CHIP,CS31002FB08
     1 FM_I3C_CPU0_MUX1_OE_N @T6G_MB_LIB.T6G(SCH_1):FM_I3C_CPU0_MUX1_OE_N    I94 @T6G_MB_LIB.T6G(SCH_1):PAGE82
     2    GND @T6G_MB_LIB.T6G(SCH_1):GND    I94 @T6G_MB_LIB.T6G(SCH_1):PAGE82

 R12 Q_RES_0402LF-10K,1%,1/16W,CHIP,CS31002FB08
     1 FM_I3C_CPU1_MUX0_OE_N @T6G_MB_LIB.T6G(SCH_1):FM_I3C_CPU1_MUX0_OE_N    I95 @T6G_MB_LIB.T6G(SCH_1):PAGE82
     2    GND @T6G_MB_LIB.T6G(SCH_1):GND    I95 @T6G_MB_LIB.T6G(SCH_1):PAGE82

 R13 Q_RES_0402LF-0,5%,1/16W,CHIP,CS00002JB13
     1 JTAG_PLD_TDO @T6G_MB_LIB.T6G(SCH_1):JTAG_PLD_TDO    I38 @T6G_MB_LIB.T6G(SCH_1):PAGE84
     2 JTAG_SCM_PLD_TDO @T6G_MB_LIB.T6G(SCH_1):JTAG_SCM_PLD_TDO    I38 @T6G_MB_LIB.T6G(SCH_1):PAGE84

 R14 Q_RES_0402LF-0,5%,1/16W,CHIP,CS00002JB13
     1 JTAG_PLD_TMS @T6G_MB_LIB.T6G(SCH_1):JTAG_PLD_TMS    I36 @T6G_MB_LIB.T6G(SCH_1):PAGE84
     2 JTAG_SCM_PLD_TMS @T6G_MB_LIB.T6G(SCH_1):JTAG_SCM_PLD_TMS    I36 @T6G_MB_LIB.T6G(SCH_1):PAGE84

 R15 Q_RES_0402LF-0,5%,1/16W,CHIP,CS00002JB13
     1 JTAG_PLD_TCK @T6G_MB_LIB.T6G(SCH_1):JTAG_PLD_TCK    I35 @T6G_MB_LIB.T6G(SCH_1):PAGE84
     2 JTAG_SCM_PLD_TCK @T6G_MB_LIB.T6G(SCH_1):JTAG_SCM_PLD_TCK    I35 @T6G_MB_LIB.T6G(SCH_1):PAGE84

 R16 Q_RES_0402LF-10K,1%,1/16W,CHIP,CS31002FB08
     1 RST_CPU0_PERST0_N @T6G_MB_LIB.T6G(SCH_1):RST_CPU0_PERST0_N   I124 @T6G_MB_LIB.T6G(SCH_1):PAGE82
     2    GND @T6G_MB_LIB.T6G(SCH_1):GND   I124 @T6G_MB_LIB.T6G(SCH_1):PAGE82

 R17 Q_RES_0402LF-10K,1%,1/16W,CHIP,CS31002FB08
     1 RST_CPU0_PERST1_N @T6G_MB_LIB.T6G(SCH_1):RST_CPU0_PERST1_N   I125 @T6G_MB_LIB.T6G(SCH_1):PAGE82
     2    GND @T6G_MB_LIB.T6G(SCH_1):GND   I125 @T6G_MB_LIB.T6G(SCH_1):PAGE82

 R18 Q_RES_0402LF-10K,1%,1/16W,CHIP,CS31002FB08
     1 RST_CPU1_PERST0_N @T6G_MB_LIB.T6G(SCH_1):RST_CPU1_PERST0_N   I126 @T6G_MB_LIB.T6G(SCH_1):PAGE82
     2    GND @T6G_MB_LIB.T6G(SCH_1):GND   I126 @T6G_MB_LIB.T6G(SCH_1):PAGE82

 R19 Q_RES_0402LF-10K,1%,1/16W,CHIP,CS31002FB08
     1 RST_CPU1_PERST1_N @T6G_MB_LIB.T6G(SCH_1):RST_CPU1_PERST1_N   I128 @T6G_MB_LIB.T6G(SCH_1):PAGE82
     2    GND @T6G_MB_LIB.T6G(SCH_1):GND   I128 @T6G_MB_LIB.T6G(SCH_1):PAGE82

 R20 Q_RES_0402LF-10K,1%,1/16W,CHIP,CS31002FB08
     1 P3V3_AUX @T6G_MB_LIB.T6G(SCH_1):P3V3_AUX   I115 @T6G_MB_LIB.T6G(SCH_1):PAGE76
     2 SPI_CPU0_LVC3_SCM_CLK @T6G_MB_LIB.T6G(SCH_1):SPI_CPU0_LVC3_SCM_CLK   I115 @T6G_MB_LIB.T6G(SCH_1):PAGE76

 R21 Q_RES_0402LF-1K,1%,1/16W,EMPTY,CS21002FB06
     1 P3V3_AUX @T6G_MB_LIB.T6G(SCH_1):P3V3_AUX   I116 @T6G_MB_LIB.T6G(SCH_1):PAGE76
     2 SPI_CPU0_LVC3_SCM_D0 @T6G_MB_LIB.T6G(SCH_1):SPI_CPU0_LVC3_SCM_D0   I116 @T6G_MB_LIB.T6G(SCH_1):PAGE76

 R22 Q_RES_0402LF-100,1%,1/16W,CHIP,CS11002FB07
     1 P1V8_AUX @T6G_MB_LIB.T6G(SCH_1):P1V8_AUX    I54 @T6G_MB_LIB.T6G(SCH_1):PAGE144
     2 PU_BIOS_USB_RECOVERY @T6G_MB_LIB.T6G(SCH_1):PU_BIOS_USB_RECOVERY    I54 @T6G_MB_LIB.T6G(SCH_1):PAGE144

 R23 Q_RES_0402LF-33,5%,1/16W,CHIP,CS03302JB10
     1 P3V3_OCP_SFF_EN @T6G_MB_LIB.T6G(SCH_1):P3V3_OCP_SFF_EN    I23 @T6G_MB_LIB.T6G(SCH_1):PAGE79
     2 P3V3_OCP_SFF_EN_R @T6G_MB_LIB.T6G(SCH_1):P3V3_OCP_SFF_EN_R    I23 @T6G_MB_LIB.T6G(SCH_1):PAGE79

 R24 Q_RES_0402LF-4.7K,5%,1/16W,EMPTY,CS24702JB10
     1 P3V3_AUX @T6G_MB_LIB.T6G(SCH_1):P3V3_AUX   I113 @T6G_MB_LIB.T6G(SCH_1):PAGE361
     2 SMB_CPU_FRU_3V3AUX_SDA @T6G_MB_LIB.T6G(SCH_1):SMB_CPU_FRU_3V3AUX_SDA   I113 @T6G_MB_LIB.T6G(SCH_1):PAGE361

 R25 Q_RES_0402LF-10K,1%,1/16W,CHIP,CS31002FB08
     1 FM_I3C_CPU1_MUX1_OE_N @T6G_MB_LIB.T6G(SCH_1):FM_I3C_CPU1_MUX1_OE_N    I97 @T6G_MB_LIB.T6G(SCH_1):PAGE82
     2    GND @T6G_MB_LIB.T6G(SCH_1):GND    I97 @T6G_MB_LIB.T6G(SCH_1):PAGE82

 R26 Q_RES_0402LF-4.7K,5%,1/16W,EMPTY,CS24702JB10
     1 P3V3_AUX @T6G_MB_LIB.T6G(SCH_1):P3V3_AUX    I95 @T6G_MB_LIB.T6G(SCH_1):PAGE361
     2 SMB_FRU_3V3AUX_R1_SCL @T6G_MB_LIB.T6G(SCH_1):SMB_FRU_3V3AUX_R1_SCL    I95 @T6G_MB_LIB.T6G(SCH_1):PAGE361

 R27 Q_RES_0402LF-0,5%,1/16W,CHIP,CS00002JB13
     1 SMB_CPU0_2_R_SCL @T6G_MB_LIB.T6G(SCH_1):SMB_CPU0_2_R_SCL   I206 @T6G_MB_LIB.T6G(SCH_1):PAGE28
     2 SMB_CPU0_2_SCL @T6G_MB_LIB.T6G(SCH_1):SMB_CPU0_2_SCL   I206 @T6G_MB_LIB.T6G(SCH_1):PAGE28

 R28 Q_RES_0402LF-0,5%,1/16W,CHIP,CS00002JB13
     1 SMB_CPU0_2_R_SDA @T6G_MB_LIB.T6G(SCH_1):SMB_CPU0_2_R_SDA   I207 @T6G_MB_LIB.T6G(SCH_1):PAGE28
     2 SMB_CPU0_2_SDA @T6G_MB_LIB.T6G(SCH_1):SMB_CPU0_2_SDA   I207 @T6G_MB_LIB.T6G(SCH_1):PAGE28

 R29 Q_RES_0402LF-0,5%,1/16W,CHIP,CS00002JB13
     1 SMB_CPU0_3_R_SCL @T6G_MB_LIB.T6G(SCH_1):SMB_CPU0_3_R_SCL   I208 @T6G_MB_LIB.T6G(SCH_1):PAGE28
     2 SMB_CPU0_3_SCL @T6G_MB_LIB.T6G(SCH_1):SMB_CPU0_3_SCL   I208 @T6G_MB_LIB.T6G(SCH_1):PAGE28

 R30 Q_RES_0402LF-0,5%,1/16W,CHIP,CS00002JB13
     1 SMB_CPU0_3_R_SDA @T6G_MB_LIB.T6G(SCH_1):SMB_CPU0_3_R_SDA   I209 @T6G_MB_LIB.T6G(SCH_1):PAGE28
     2 SMB_CPU0_3_SDA @T6G_MB_LIB.T6G(SCH_1):SMB_CPU0_3_SDA   I209 @T6G_MB_LIB.T6G(SCH_1):PAGE28

 R31 Q_RES_0402LF-4.7K,1%,1/16W,EMPTY,CS24702FB06
     1 P3V3_OCP_SFF @T6G_MB_LIB.T6G(SCH_1):P3V3_OCP_SFF     I3 @T6G_MB_LIB.T6G(SCH_1):PAGE335
     2 OCP_SFF_ID0 @T6G_MB_LIB.T6G(SCH_1):OCP_SFF_ID0     I3 @T6G_MB_LIB.T6G(SCH_1):PAGE335

 R32 Q_RES_0402LF-4.7K,1%,1/16W,CHIP,CS24702FB06
     1 OCP_SFF_ID0 @T6G_MB_LIB.T6G(SCH_1):OCP_SFF_ID0     I2 @T6G_MB_LIB.T6G(SCH_1):PAGE335
     2    GND @T6G_MB_LIB.T6G(SCH_1):GND     I2 @T6G_MB_LIB.T6G(SCH_1):PAGE335

 R33 Q_RES_0402LF-4.7K,1%,1/16W,EMPTY,CS24702FB06
     1 P3V3_OCP_SFF @T6G_MB_LIB.T6G(SCH_1):P3V3_OCP_SFF    I17 @T6G_MB_LIB.T6G(SCH_1):PAGE335
     2 OCP_SFF_ID1 @T6G_MB_LIB.T6G(SCH_1):OCP_SFF_ID1    I17 @T6G_MB_LIB.T6G(SCH_1):PAGE335

 R34 Q_RES_0402LF-4.7K,1%,1/16W,CHIP,CS24702FB06
     1 OCP_SFF_ID1 @T6G_MB_LIB.T6G(SCH_1):OCP_SFF_ID1    I12 @T6G_MB_LIB.T6G(SCH_1):PAGE335
     2    GND @T6G_MB_LIB.T6G(SCH_1):GND    I12 @T6G_MB_LIB.T6G(SCH_1):PAGE335

 R35 Q_RES_0402LF-10K,1%,1/16W,CHIP,CS31002FB08
     1 PD_CHG_CPU0_DIMM0_SAA @T6G_MB_LIB.T6G(SCH_1):PD_CHG_CPU0_DIMM0_SAA   I129 @T6G_MB_LIB.T6G(SCH_1):PAGE91
     2    GND @T6G_MB_LIB.T6G(SCH_1):GND   I129 @T6G_MB_LIB.T6G(SCH_1):PAGE91

 R36 Q_RES_0402LF-10K,1%,1/16W,CHIP,CS31002FB08
     1 PD_CHA_CPU1_DIMM0_SAA @T6G_MB_LIB.T6G(SCH_1):PD_CHA_CPU1_DIMM0_SAA   I129 @T6G_MB_LIB.T6G(SCH_1):PAGE97
     2    GND @T6G_MB_LIB.T6G(SCH_1):GND   I129 @T6G_MB_LIB.T6G(SCH_1):PAGE97

 R37 Q_RES_0402LF-10K,1%,1/16W,CHIP,CS31002FB08
     1 PD_CHG_CPU1_DIMM0_SAA @T6G_MB_LIB.T6G(SCH_1):PD_CHG_CPU1_DIMM0_SAA   I129 @T6G_MB_LIB.T6G(SCH_1):PAGE103
     2    GND @T6G_MB_LIB.T6G(SCH_1):GND   I129 @T6G_MB_LIB.T6G(SCH_1):PAGE103

 R38 Q_RES_0402LF-0,5%,1/16W,CHIP,CS00002JB13
     1 OCP_SFF_MAIN_PWR_EN @T6G_MB_LIB.T6G(SCH_1):OCP_SFF_MAIN_PWR_EN    I59 @T6G_MB_LIB.T6G(SCH_1):PAGE335
     2 OCP_SFF_MAIN_PWR_EN_R @T6G_MB_LIB.T6G(SCH_1):OCP_SFF_MAIN_PWR_EN_R    I59 @T6G_MB_LIB.T6G(SCH_1):PAGE335

 R39 Q_RES_0402LF-0,5%,1/16W,CHIP,CS00002JB13
     1 OCP_SFF_ISO_BIF0_EN @T6G_MB_LIB.T6G(SCH_1):OCP_SFF_ISO_BIF0_EN    I57 @T6G_MB_LIB.T6G(SCH_1):PAGE335
     2 OCP_SFF_BIF0_R_N @T6G_MB_LIB.T6G(SCH_1):OCP_SFF_BIF0_R_N    I57 @T6G_MB_LIB.T6G(SCH_1):PAGE335

 R40 Q_RES_0402LF-0,5%,1/16W,CHIP,CS00002JB13
     1 OCP_SFF_ISO_BIF1_EN @T6G_MB_LIB.T6G(SCH_1):OCP_SFF_ISO_BIF1_EN    I56 @T6G_MB_LIB.T6G(SCH_1):PAGE335
     2 OCP_SFF_BIF1_R_N @T6G_MB_LIB.T6G(SCH_1):OCP_SFF_BIF1_R_N    I56 @T6G_MB_LIB.T6G(SCH_1):PAGE335

 R41 Q_RES_0402LF-0,5%,1/16W,CHIP,CS00002JB13
     1 OCP_SFF_ISO_BIF2_EN @T6G_MB_LIB.T6G(SCH_1):OCP_SFF_ISO_BIF2_EN    I55 @T6G_MB_LIB.T6G(SCH_1):PAGE335
     2 OCP_SFF_BIF2_R_N @T6G_MB_LIB.T6G(SCH_1):OCP_SFF_BIF2_R_N    I55 @T6G_MB_LIB.T6G(SCH_1):PAGE335

 R42 Q_RES_0402LF-0,5%,1/16W,CHIP,CS00002JB13
     1 USB2_P11_DN @T6G_MB_LIB.T6G(SCH_1):USB2_P11_DN   I166 @T6G_MB_LIB.T6G(SCH_1):PAGE335
     2 USB2_CPU0_P11_DN @T6G_MB_LIB.T6G(SCH_1):USB2_CPU0_P11_DN   I166 @T6G_MB_LIB.T6G(SCH_1):PAGE335

 R43 Q_RES_0402LF-4.7K,5%,1/16W,EMPTY,CS24702JB10
     1 P3V3_AUX @T6G_MB_LIB.T6G(SCH_1):P3V3_AUX    I93 @T6G_MB_LIB.T6G(SCH_1):PAGE361
     2 SMB_FRU_3V3AUX_R1_SDA @T6G_MB_LIB.T6G(SCH_1):SMB_FRU_3V3AUX_R1_SDA    I93 @T6G_MB_LIB.T6G(SCH_1):PAGE361

 R44 Q_RES_0402LF-1K,1%,1/16W,CHIP,CS21002FB06
     1 PD_CPU_FRU_WP @T6G_MB_LIB.T6G(SCH_1):PD_CPU_FRU_WP   I115 @T6G_MB_LIB.T6G(SCH_1):PAGE361
     2    GND @T6G_MB_LIB.T6G(SCH_1):GND   I115 @T6G_MB_LIB.T6G(SCH_1):PAGE361

 R45 Q_RES_0402LF-10K,1%,1/16W,CHIP,CS31002FB08
     1 P3V3_OCP_SFF @T6G_MB_LIB.T6G(SCH_1):P3V3_OCP_SFF    I12 @T6G_MB_LIB.T6G(SCH_1):PAGE337
     2 PU_OCP_SFF_WAKE_OE @T6G_MB_LIB.T6G(SCH_1):PU_OCP_SFF_WAKE_OE    I12 @T6G_MB_LIB.T6G(SCH_1):PAGE337

 R46 Q_RES_0402LF-0,5%,1/16W,CHIP,CS00002JB13
     1 USB2_P11_DP @T6G_MB_LIB.T6G(SCH_1):USB2_P11_DP   I108 @T6G_MB_LIB.T6G(SCH_1):PAGE335
     2 USB2_CPU0_P11_DP @T6G_MB_LIB.T6G(SCH_1):USB2_CPU0_P11_DP   I108 @T6G_MB_LIB.T6G(SCH_1):PAGE335

 R47 Q_RES_0402LF-200,1%,1/16W,CHIP,CS12002FB06
     1 SMB_OCP_SFF_3V3AUX_BUF_R_SCL @T6G_MB_LIB.T6G(SCH_1):SMB_OCP_SFF_3V3AUX_BUF_R_SCL   I171 @T6G_MB_LIB.T6G(SCH_1):PAGE335
     2 SMB_OCP_SFF_3V3AUX_BUF_SCL @T6G_MB_LIB.T6G(SCH_1):SMB_OCP_SFF_3V3AUX_BUF_SCL   I171 @T6G_MB_LIB.T6G(SCH_1):PAGE335

 R48 Q_RES_0402LF-200,1%,1/16W,CHIP,CS12002FB06
     1 SMB_OCP_SFF_3V3AUX_BUF_R_SDA @T6G_MB_LIB.T6G(SCH_1):SMB_OCP_SFF_3V3AUX_BUF_R_SDA   I170 @T6G_MB_LIB.T6G(SCH_1):PAGE335
     2 SMB_OCP_SFF_3V3AUX_BUF_SDA @T6G_MB_LIB.T6G(SCH_1):SMB_OCP_SFF_3V3AUX_BUF_SDA   I170 @T6G_MB_LIB.T6G(SCH_1):PAGE335

 R49 Q_RES_0402LF-33,5%,1/16W,CHIP,CS03302JB10
     1 SCM_JTAG_MUX_R_S0 @T6G_MB_LIB.T6G(SCH_1):SCM_JTAG_MUX_R_S0    I46 @T6G_MB_LIB.T6G(SCH_1):PAGE79
     2 SCM_JTAG_MUX_S0 @T6G_MB_LIB.T6G(SCH_1):SCM_JTAG_MUX_S0    I46 @T6G_MB_LIB.T6G(SCH_1):PAGE79

 R50 Q_RES_0402LF-33,5%,1/16W,CHIP,CS03302JB10
     1 SCM_JTAG_MUX_R_S1 @T6G_MB_LIB.T6G(SCH_1):SCM_JTAG_MUX_R_S1    I49 @T6G_MB_LIB.T6G(SCH_1):PAGE79
     2 SCM_JTAG_MUX_S1 @T6G_MB_LIB.T6G(SCH_1):SCM_JTAG_MUX_S1    I49 @T6G_MB_LIB.T6G(SCH_1):PAGE79

 R51 Q_RES_0402LF-0,5%,1/16W,CHIP,CS00002JB13
     1 SMB_1_PLD_3V3AUX_SCL_R1 @T6G_MB_LIB.T6G(SCH_1):SMB_1_PLD_3V3AUX_SCL_R1    I83 @T6G_MB_LIB.T6G(SCH_1):PAGE79
     2 SMB_1_PLD_3V3AUX_SCL_R2 @T6G_MB_LIB.T6G(SCH_1):SMB_1_PLD_3V3AUX_SCL_R2    I83 @T6G_MB_LIB.T6G(SCH_1):PAGE79

 R52 Q_RES_0402LF-10K,1%,1/16W,EMPTY,CS31002FB08
     1 P3V3_AUX @T6G_MB_LIB.T6G(SCH_1):P3V3_AUX   I103 @T6G_MB_LIB.T6G(SCH_1):PAGE361
     2 CPU_FRU_ADDR2 @T6G_MB_LIB.T6G(SCH_1):CPU_FRU_ADDR2   I103 @T6G_MB_LIB.T6G(SCH_1):PAGE361

 R53 Q_RES_0402LF-4.7K,1%,1/16W,CHIP,CS24702FB06
     1 P3V3_AUX @T6G_MB_LIB.T6G(SCH_1):P3V3_AUX    I42 @T6G_MB_LIB.T6G(SCH_1):PAGE337
     2 OCP_SFF_PWRBRK_BUFF_N @T6G_MB_LIB.T6G(SCH_1):OCP_SFF_PWRBRK_BUFF_N    I42 @T6G_MB_LIB.T6G(SCH_1):PAGE337

 R54 Q_RES_0402LF-1K,1%,1/16W,CHIP,CS21002FB06
     1 CPU_FRU_ADDR2 @T6G_MB_LIB.T6G(SCH_1):CPU_FRU_ADDR2   I107 @T6G_MB_LIB.T6G(SCH_1):PAGE361
     2    GND @T6G_MB_LIB.T6G(SCH_1):GND   I107 @T6G_MB_LIB.T6G(SCH_1):PAGE361

 R55 Q_RES_0402LF-33.2,1%,1/16W,CHIP,CS03322FB03
     1 SMB_PCIE0_3V3AUX_SDA @T6G_MB_LIB.T6G(SCH_1):SMB_PCIE0_3V3AUX_SDA    I73 @T6G_MB_LIB.T6G(SCH_1):PAGE252
     2 SMB_PCIE0_3V3AUX_SDA_R @T6G_MB_LIB.T6G(SCH_1):SMB_PCIE0_3V3AUX_SDA_R    I73 @T6G_MB_LIB.T6G(SCH_1):PAGE252

 R56 Q_RES_0402LF-0,5%,1/16W,CHIP,CS00002JB13
     1 SMB_1_PLD_3V3AUX_SDA_R1 @T6G_MB_LIB.T6G(SCH_1):SMB_1_PLD_3V3AUX_SDA_R1    I82 @T6G_MB_LIB.T6G(SCH_1):PAGE79
     2 SMB_1_PLD_3V3AUX_SDA_R2 @T6G_MB_LIB.T6G(SCH_1):SMB_1_PLD_3V3AUX_SDA_R2    I82 @T6G_MB_LIB.T6G(SCH_1):PAGE79

 R57 Q_RES_0402LF-0,5%,1/16W,CHIP,CS00002JB13
     1 RST_CPU1_RESETL_N @T6G_MB_LIB.T6G(SCH_1):RST_CPU1_RESETL_N   I113 @T6G_MB_LIB.T6G(SCH_1):PAGE80
     2 FM_RST_CPU1_RESETL_N @T6G_MB_LIB.T6G(SCH_1):FM_RST_CPU1_RESETL_N   I113 @T6G_MB_LIB.T6G(SCH_1):PAGE80

 R58 Q_RES_0402LF-33,5%,1/16W,CHIP,CS03302JB10
     1 SGPIO_SCM_INTR_R_N @T6G_MB_LIB.T6G(SCH_1):SGPIO_SCM_INTR_R_N    I44 @T6G_MB_LIB.T6G(SCH_1):PAGE79
     2 SGPIO_SCM_INTR_N @T6G_MB_LIB.T6G(SCH_1):SGPIO_SCM_INTR_N    I44 @T6G_MB_LIB.T6G(SCH_1):PAGE79

 R59 Q_RES_0402LF-22,1%,1/16W,CHIP,CS02202FB02
     1 NCSI_BMC_CRS_DV_R @T6G_MB_LIB.T6G(SCH_1):NCSI_BMC_CRS_DV_R    I99 @T6G_MB_LIB.T6G(SCH_1):PAGE336
     2 RMII_OCP_BMC_CRSDV @T6G_MB_LIB.T6G(SCH_1):RMII_OCP_BMC_CRSDV    I99 @T6G_MB_LIB.T6G(SCH_1):PAGE336

 R60 Q_RES_0402LF-10K,1%,1/16W,EMPTY,CS31002FB08
     1 P3V3_AUX @T6G_MB_LIB.T6G(SCH_1):P3V3_AUX   I101 @T6G_MB_LIB.T6G(SCH_1):PAGE361
     2 CPU_FRU_ADDR1 @T6G_MB_LIB.T6G(SCH_1):CPU_FRU_ADDR1   I101 @T6G_MB_LIB.T6G(SCH_1):PAGE361

 R61 Q_RES_0402LF-49.9,1%,1/16W,CHIP,CS04992FB07
     1 SVID_PVDDCR_CPU1_P0_SVTO @T6G_MB_LIB.T6G(SCH_1):SVID_PVDDCR_CPU1_P0_SVTO    I83 @T6G_MB_LIB.T6G(SCH_1):PAGE175
     2 SVID_PVDDCR_CPU1_P0_SVTO_R @T6G_MB_LIB.T6G(SCH_1):SVID_PVDDCR_CPU1_P0_SVTO_R    I83 @T6G_MB_LIB.T6G(SCH_1):PAGE175

 R62 Q_RES_0402LF-1K,1%,1/16W,CHIP,CS21002FB06
     1 CPU_FRU_ADDR1 @T6G_MB_LIB.T6G(SCH_1):CPU_FRU_ADDR1   I104 @T6G_MB_LIB.T6G(SCH_1):PAGE361
     2    GND @T6G_MB_LIB.T6G(SCH_1):GND   I104 @T6G_MB_LIB.T6G(SCH_1):PAGE361

 R63 Q_RES_0402LF-33,5%,1/16W,CHIP,CS03302JB10
     1 SCM_SYS_PWROK_R @T6G_MB_LIB.T6G(SCH_1):SCM_SYS_PWROK_R    I79 @T6G_MB_LIB.T6G(SCH_1):PAGE79
     2 SCM_SYS_PWROK @T6G_MB_LIB.T6G(SCH_1):SCM_SYS_PWROK    I79 @T6G_MB_LIB.T6G(SCH_1):PAGE79

 R64 Q_RES_0402LF-1K,1%,1/16W,EMPTY,CS21002FB06
     1 SCM_SYS_PWRBTN_N @T6G_MB_LIB.T6G(SCH_1):SCM_SYS_PWRBTN_N   I166 @T6G_MB_LIB.T6G(SCH_1):PAGE82
     2 P3V3_AUX @T6G_MB_LIB.T6G(SCH_1):P3V3_AUX   I166 @T6G_MB_LIB.T6G(SCH_1):PAGE82

 R65 Q_RES_0402LF-33.2,1%,1/16W,CHIP,CS03322FB03
     1 SMB_PCIE0_3V3AUX_SCL @T6G_MB_LIB.T6G(SCH_1):SMB_PCIE0_3V3AUX_SCL    I74 @T6G_MB_LIB.T6G(SCH_1):PAGE252
     2 SMB_PCIE0_3V3AUX_SCL_R @T6G_MB_LIB.T6G(SCH_1):SMB_PCIE0_3V3AUX_SCL_R    I74 @T6G_MB_LIB.T6G(SCH_1):PAGE252

 R66 Q_RES_0402LF-2.2K,5%,1/16W,CHIP,CS22202JB07
     1 P3V3_AUX @T6G_MB_LIB.T6G(SCH_1):P3V3_AUX    I40 @T6G_MB_LIB.T6G(SCH_1):PAGE252
     2 SMB_FRU_3V3AUX_SCL @T6G_MB_LIB.T6G(SCH_1):SMB_FRU_3V3AUX_SCL    I40 @T6G_MB_LIB.T6G(SCH_1):PAGE252

 R67 Q_RES_0402LF-2.2K,5%,1/16W,CHIP,CS22202JB07
     1 P3V3_AUX @T6G_MB_LIB.T6G(SCH_1):P3V3_AUX    I39 @T6G_MB_LIB.T6G(SCH_1):PAGE252
     2 SMB_FRU_3V3AUX_SDA @T6G_MB_LIB.T6G(SCH_1):SMB_FRU_3V3AUX_SDA    I39 @T6G_MB_LIB.T6G(SCH_1):PAGE252

 R68 Q_RES_0402LF-1K,1%,1/16W,EMPTY,CS21002FB06
     1 P3V3_AUX @T6G_MB_LIB.T6G(SCH_1):P3V3_AUX   I120 @T6G_MB_LIB.T6G(SCH_1):PAGE361
     2 CPU_FRU_ADDR0 @T6G_MB_LIB.T6G(SCH_1):CPU_FRU_ADDR0   I120 @T6G_MB_LIB.T6G(SCH_1):PAGE361

 R69 Q_RES_0402LF-10K,1%,1/16W,CHIP,CS31002FB08
     1 CPU_FRU_ADDR0 @T6G_MB_LIB.T6G(SCH_1):CPU_FRU_ADDR0   I121 @T6G_MB_LIB.T6G(SCH_1):PAGE361
     2    GND @T6G_MB_LIB.T6G(SCH_1):GND   I121 @T6G_MB_LIB.T6G(SCH_1):PAGE361

 R70 Q_RES_0402LF-0,5%,1/16W,CHIP,CS00002JB13
     1 SMB_CPU0_4_XLTR_R_SCL @T6G_MB_LIB.T6G(SCH_1):SMB_CPU0_4_XLTR_R_SCL    I19 @T6G_MB_LIB.T6G(SCH_1):PAGE79
     2 SMB_CPU0_4_XLTR_SCL @T6G_MB_LIB.T6G(SCH_1):SMB_CPU0_4_XLTR_SCL    I19 @T6G_MB_LIB.T6G(SCH_1):PAGE79

 R71 Q_RES_0402LF-33,5%,1/16W,CHIP,CS03302JB10
     1 SCM_IRQ_R_N @T6G_MB_LIB.T6G(SCH_1):SCM_IRQ_R_N    I27 @T6G_MB_LIB.T6G(SCH_1):PAGE83
     2 SCM_IRQ_N @T6G_MB_LIB.T6G(SCH_1):SCM_IRQ_N    I27 @T6G_MB_LIB.T6G(SCH_1):PAGE83

 R72 Q_RES_0402LF-22,1%,1/16W,CHIP,CS02202FB02
     1 NCSI_BMC_RXD0_R @T6G_MB_LIB.T6G(SCH_1):NCSI_BMC_RXD0_R   I100 @T6G_MB_LIB.T6G(SCH_1):PAGE336
     2 RMII_OCP_BMC_RXD_0 @T6G_MB_LIB.T6G(SCH_1):RMII_OCP_BMC_RXD_0   I100 @T6G_MB_LIB.T6G(SCH_1):PAGE336

 R73 Q_RES_0402LF-22,1%,1/16W,CHIP,CS02202FB02
     1 NCSI_BMC_RXD1_R @T6G_MB_LIB.T6G(SCH_1):NCSI_BMC_RXD1_R   I101 @T6G_MB_LIB.T6G(SCH_1):PAGE336
     2 RMII_OCP_BMC_RXD_1 @T6G_MB_LIB.T6G(SCH_1):RMII_OCP_BMC_RXD_1   I101 @T6G_MB_LIB.T6G(SCH_1):PAGE336

 R74 Q_RES_0402LF-0,5%,1/16W,CHIP,CS00002JB13
     1 NCSI_BMC_TX_EN_R @T6G_MB_LIB.T6G(SCH_1):NCSI_BMC_TX_EN_R   I102 @T6G_MB_LIB.T6G(SCH_1):PAGE336
     2 RMII_BMC_OCP_TX_EN @T6G_MB_LIB.T6G(SCH_1):RMII_BMC_OCP_TX_EN   I102 @T6G_MB_LIB.T6G(SCH_1):PAGE336

 R75 Q_RES_0402LF-0,5%,1/16W,CHIP,CS00002JB13
     1 NCSI_BMC_TXD0_R @T6G_MB_LIB.T6G(SCH_1):NCSI_BMC_TXD0_R   I103 @T6G_MB_LIB.T6G(SCH_1):PAGE336
     2 RMII_BMC_OCP_TXD_0 @T6G_MB_LIB.T6G(SCH_1):RMII_BMC_OCP_TXD_0   I103 @T6G_MB_LIB.T6G(SCH_1):PAGE336

 R76 Q_RES_0402LF-0,5%,1/16W,CHIP,CS00002JB13
     1 NCSI_BMC_TXD1_R @T6G_MB_LIB.T6G(SCH_1):NCSI_BMC_TXD1_R   I104 @T6G_MB_LIB.T6G(SCH_1):PAGE336
     2 RMII_BMC_OCP_TXD_1 @T6G_MB_LIB.T6G(SCH_1):RMII_BMC_OCP_TXD_1   I104 @T6G_MB_LIB.T6G(SCH_1):PAGE336

 R77 Q_RES_0402LF-100K,1%,1/16W,CHIP,CS41002FB09
     1 RMII_OCP_BMC_CRSDV @T6G_MB_LIB.T6G(SCH_1):RMII_OCP_BMC_CRSDV   I131 @T6G_MB_LIB.T6G(SCH_1):PAGE336
     2    GND @T6G_MB_LIB.T6G(SCH_1):GND   I131 @T6G_MB_LIB.T6G(SCH_1):PAGE336

 R78 Q_RES_0402LF-4.7K,5%,1/16W,EMPTY,CS24702JB10
     1   P3V3 @T6G_MB_LIB.T6G(SCH_1):P3V3    I31 @T6G_MB_LIB.T6G(SCH_1):PAGE137
     2 PU_U5_EN @T6G_MB_LIB.T6G(SCH_1):PU_U5_EN    I31 @T6G_MB_LIB.T6G(SCH_1):PAGE137

 R79 Q_RES_0402LF-100K,1%,1/16W,CHIP,CS41002FB09
     1 RMII_OCP_BMC_RXD_0 @T6G_MB_LIB.T6G(SCH_1):RMII_OCP_BMC_RXD_0   I132 @T6G_MB_LIB.T6G(SCH_1):PAGE336
     2    GND @T6G_MB_LIB.T6G(SCH_1):GND   I132 @T6G_MB_LIB.T6G(SCH_1):PAGE336

 R80 Q_RES_0402LF-100K,1%,1/16W,CHIP,CS41002FB09
     1 RMII_OCP_BMC_RXD_1 @T6G_MB_LIB.T6G(SCH_1):RMII_OCP_BMC_RXD_1   I133 @T6G_MB_LIB.T6G(SCH_1):PAGE336
     2    GND @T6G_MB_LIB.T6G(SCH_1):GND   I133 @T6G_MB_LIB.T6G(SCH_1):PAGE336

 R81 Q_RES_0402LF-33,5%,1/16W,CHIP,CS03302JB10
     1 FM_INT_CPU0_HP_UBM_R_N @T6G_MB_LIB.T6G(SCH_1):FM_INT_CPU0_HP_UBM_R_N   I106 @T6G_MB_LIB.T6G(SCH_1):PAGE81
     2 FM_INT_CPU0_HP_UBM_N @T6G_MB_LIB.T6G(SCH_1):FM_INT_CPU0_HP_UBM_N   I106 @T6G_MB_LIB.T6G(SCH_1):PAGE81

 R82 Q_RES_0402LF-100K,1%,1/16W,CHIP,CS41002FB09
     1 RMII_BMC_OCP_TX_EN @T6G_MB_LIB.T6G(SCH_1):RMII_BMC_OCP_TX_EN   I134 @T6G_MB_LIB.T6G(SCH_1):PAGE336
     2    GND @T6G_MB_LIB.T6G(SCH_1):GND   I134 @T6G_MB_LIB.T6G(SCH_1):PAGE336

 R83 Q_RES_0402LF-100K,1%,1/16W,CHIP,CS41002FB09
     1 RMII_BMC_OCP_TXD_0 @T6G_MB_LIB.T6G(SCH_1):RMII_BMC_OCP_TXD_0   I135 @T6G_MB_LIB.T6G(SCH_1):PAGE336
     2    GND @T6G_MB_LIB.T6G(SCH_1):GND   I135 @T6G_MB_LIB.T6G(SCH_1):PAGE336

 R84 Q_RES_0402LF-100K,1%,1/16W,CHIP,CS41002FB09
     1 RMII_BMC_OCP_TXD_1 @T6G_MB_LIB.T6G(SCH_1):RMII_BMC_OCP_TXD_1   I129 @T6G_MB_LIB.T6G(SCH_1):PAGE336
     2    GND @T6G_MB_LIB.T6G(SCH_1):GND   I129 @T6G_MB_LIB.T6G(SCH_1):PAGE336

 R85 Q_RES_0402LF-0,5%,1/16W,CHIP,CS00002JB13
     1 SMB_FRU_3V3AUX_SCL @T6G_MB_LIB.T6G(SCH_1):SMB_FRU_3V3AUX_SCL   I124 @T6G_MB_LIB.T6G(SCH_1):PAGE361
     2 SMB_FRU_3V3AUX_R1_SCL @T6G_MB_LIB.T6G(SCH_1):SMB_FRU_3V3AUX_R1_SCL   I124 @T6G_MB_LIB.T6G(SCH_1):PAGE361

 R86 Q_RES_0402LF-0,5%,1/16W,CHIP,CS00002JB13
     1 SMB_FRU_3V3AUX_SDA @T6G_MB_LIB.T6G(SCH_1):SMB_FRU_3V3AUX_SDA   I125 @T6G_MB_LIB.T6G(SCH_1):PAGE361
     2 SMB_FRU_3V3AUX_R1_SDA @T6G_MB_LIB.T6G(SCH_1):SMB_FRU_3V3AUX_R1_SDA   I125 @T6G_MB_LIB.T6G(SCH_1):PAGE361

 R87 Q_RES_0402LF-1K,1%,1/16W,CHIP,CS21002FB06
     1 RMII_BMC_OCP_RX_ER @T6G_MB_LIB.T6G(SCH_1):RMII_BMC_OCP_RX_ER   I136 @T6G_MB_LIB.T6G(SCH_1):PAGE336
     2    GND @T6G_MB_LIB.T6G(SCH_1):GND   I136 @T6G_MB_LIB.T6G(SCH_1):PAGE336

 R88 Q_RES_0402LF-1K,1%,1/16W,EMPTY,CS21002FB06
     1   P3V3 @T6G_MB_LIB.T6G(SCH_1):P3V3   I526 @T6G_MB_LIB.T6G(SCH_1):PAGE85
     2 PWRGD_CHAF_CPU0 @T6G_MB_LIB.T6G(SCH_1):PWRGD_CHAF_CPU0   I526 @T6G_MB_LIB.T6G(SCH_1):PAGE85

 R89 Q_RES_0402LF-1K,1%,1/16W,EMPTY,CS21002FB06
     1   P3V3 @T6G_MB_LIB.T6G(SCH_1):P3V3   I528 @T6G_MB_LIB.T6G(SCH_1):PAGE85
     2 PWRGD_CHA_CPU0_DIMM0 @T6G_MB_LIB.T6G(SCH_1):PWRGD_CHA_CPU0_DIMM0   I528 @T6G_MB_LIB.T6G(SCH_1):PAGE85

 R90 Q_RES_0402LF-1K,1%,1/16W,EMPTY,CS21002FB06
     1   P3V3 @T6G_MB_LIB.T6G(SCH_1):P3V3   I365 @T6G_MB_LIB.T6G(SCH_1):PAGE86
     2 PWRGD_CHB_CPU0_DIMM @T6G_MB_LIB.T6G(SCH_1):PWRGD_CHB_CPU0_DIMM   I365 @T6G_MB_LIB.T6G(SCH_1):PAGE86

 R91 Q_RES_0402LF-1K,1%,1/16W,EMPTY,CS21002FB06
     1   P3V3 @T6G_MB_LIB.T6G(SCH_1):P3V3   I365 @T6G_MB_LIB.T6G(SCH_1):PAGE87
     2 PWRGD_CHC_CPU0_DIMM @T6G_MB_LIB.T6G(SCH_1):PWRGD_CHC_CPU0_DIMM   I365 @T6G_MB_LIB.T6G(SCH_1):PAGE87

 R92 Q_RES_0402LF-1K,1%,1/16W,EMPTY,CS21002FB06
     1   P3V3 @T6G_MB_LIB.T6G(SCH_1):P3V3   I367 @T6G_MB_LIB.T6G(SCH_1):PAGE88
     2 PWRGD_CHD_CPU0_DIMM @T6G_MB_LIB.T6G(SCH_1):PWRGD_CHD_CPU0_DIMM   I367 @T6G_MB_LIB.T6G(SCH_1):PAGE88

 R93 Q_RES_0402LF-1K,1%,1/16W,EMPTY,CS21002FB06
     1   P3V3 @T6G_MB_LIB.T6G(SCH_1):P3V3   I364 @T6G_MB_LIB.T6G(SCH_1):PAGE89
     2 PWRGD_CHE_CPU0_DIMM @T6G_MB_LIB.T6G(SCH_1):PWRGD_CHE_CPU0_DIMM   I364 @T6G_MB_LIB.T6G(SCH_1):PAGE89

 R94 Q_RES_0402LF-1K,1%,1/16W,EMPTY,CS21002FB06
     1   P3V3 @T6G_MB_LIB.T6G(SCH_1):P3V3   I365 @T6G_MB_LIB.T6G(SCH_1):PAGE90
     2 PWRGD_CHF_CPU0_DIMM @T6G_MB_LIB.T6G(SCH_1):PWRGD_CHF_CPU0_DIMM   I365 @T6G_MB_LIB.T6G(SCH_1):PAGE90

 R95 Q_RES_0402LF-1K,1%,1/16W,EMPTY,CS21002FB06
     1   P3V3 @T6G_MB_LIB.T6G(SCH_1):P3V3   I190 @T6G_MB_LIB.T6G(SCH_1):PAGE91
     2 PWRGD_CHGL_CPU0 @T6G_MB_LIB.T6G(SCH_1):PWRGD_CHGL_CPU0   I190 @T6G_MB_LIB.T6G(SCH_1):PAGE91

 R96 Q_RES_0402LF-1K,1%,1/16W,EMPTY,CS21002FB06
     1   P3V3 @T6G_MB_LIB.T6G(SCH_1):P3V3   I187 @T6G_MB_LIB.T6G(SCH_1):PAGE91
     2 PWRGD_CHG_CPU0_DIMM0 @T6G_MB_LIB.T6G(SCH_1):PWRGD_CHG_CPU0_DIMM0   I187 @T6G_MB_LIB.T6G(SCH_1):PAGE91

 R97 Q_RES_0402LF-1K,1%,1/16W,EMPTY,CS21002FB06
     1   P3V3 @T6G_MB_LIB.T6G(SCH_1):P3V3   I191 @T6G_MB_LIB.T6G(SCH_1):PAGE92
     2 PWRGD_CHH_CPU0_DIMM @T6G_MB_LIB.T6G(SCH_1):PWRGD_CHH_CPU0_DIMM   I191 @T6G_MB_LIB.T6G(SCH_1):PAGE92

 R98 Q_RES_0402LF-1K,1%,1/16W,EMPTY,CS21002FB06
     1   P3V3 @T6G_MB_LIB.T6G(SCH_1):P3V3   I189 @T6G_MB_LIB.T6G(SCH_1):PAGE93
     2 PWRGD_CHI_CPU0_DIMM @T6G_MB_LIB.T6G(SCH_1):PWRGD_CHI_CPU0_DIMM   I189 @T6G_MB_LIB.T6G(SCH_1):PAGE93

 R99 Q_RES_0402LF-1K,1%,1/16W,EMPTY,CS21002FB06
     1   P3V3 @T6G_MB_LIB.T6G(SCH_1):P3V3   I189 @T6G_MB_LIB.T6G(SCH_1):PAGE94
     2 PWRGD_CHJ_CPU0_DIMM @T6G_MB_LIB.T6G(SCH_1):PWRGD_CHJ_CPU0_DIMM   I189 @T6G_MB_LIB.T6G(SCH_1):PAGE94

R100 Q_RES_0402LF-1K,1%,1/16W,EMPTY,CS21002FB06
     1   P3V3 @T6G_MB_LIB.T6G(SCH_1):P3V3   I189 @T6G_MB_LIB.T6G(SCH_1):PAGE95
     2 PWRGD_CHK_CPU0_DIMM @T6G_MB_LIB.T6G(SCH_1):PWRGD_CHK_CPU0_DIMM   I189 @T6G_MB_LIB.T6G(SCH_1):PAGE95

R101 Q_RES_0402LF-1K,1%,1/16W,EMPTY,CS21002FB06
     1   P3V3 @T6G_MB_LIB.T6G(SCH_1):P3V3   I189 @T6G_MB_LIB.T6G(SCH_1):PAGE96
     2 PWRGD_CHL_CPU0_DIMM @T6G_MB_LIB.T6G(SCH_1):PWRGD_CHL_CPU0_DIMM   I189 @T6G_MB_LIB.T6G(SCH_1):PAGE96

R102 Q_RES_0402LF-1K,1%,1/16W,EMPTY,CS21002FB06
     1   P3V3 @T6G_MB_LIB.T6G(SCH_1):P3V3   I189 @T6G_MB_LIB.T6G(SCH_1):PAGE97
     2 PWRGD_CHAF_CPU1 @T6G_MB_LIB.T6G(SCH_1):PWRGD_CHAF_CPU1   I189 @T6G_MB_LIB.T6G(SCH_1):PAGE97

R103 Q_RES_0402LF-1K,1%,1/16W,EMPTY,CS21002FB06
     1   P3V3 @T6G_MB_LIB.T6G(SCH_1):P3V3   I191 @T6G_MB_LIB.T6G(SCH_1):PAGE97
     2 PWRGD_CHA_CPU1_DIMM0 @T6G_MB_LIB.T6G(SCH_1):PWRGD_CHA_CPU1_DIMM0   I191 @T6G_MB_LIB.T6G(SCH_1):PAGE97

R104 Q_RES_0402LF-1K,1%,1/16W,EMPTY,CS21002FB06
     1   P3V3 @T6G_MB_LIB.T6G(SCH_1):P3V3   I190 @T6G_MB_LIB.T6G(SCH_1):PAGE98
     2 PWRGD_CHB_CPU1_DIMM @T6G_MB_LIB.T6G(SCH_1):PWRGD_CHB_CPU1_DIMM   I190 @T6G_MB_LIB.T6G(SCH_1):PAGE98

R105 Q_RES_0402LF-1K,1%,1/16W,EMPTY,CS21002FB06
     1   P3V3 @T6G_MB_LIB.T6G(SCH_1):P3V3   I190 @T6G_MB_LIB.T6G(SCH_1):PAGE99
     2 PWRGD_CHC_CPU1_DIMM @T6G_MB_LIB.T6G(SCH_1):PWRGD_CHC_CPU1_DIMM   I190 @T6G_MB_LIB.T6G(SCH_1):PAGE99

R106 Q_RES_0402LF-1K,1%,1/16W,EMPTY,CS21002FB06
     1   P3V3 @T6G_MB_LIB.T6G(SCH_1):P3V3   I190 @T6G_MB_LIB.T6G(SCH_1):PAGE100
     2 PWRGD_CHD_CPU1_DIMM @T6G_MB_LIB.T6G(SCH_1):PWRGD_CHD_CPU1_DIMM   I190 @T6G_MB_LIB.T6G(SCH_1):PAGE100

R107 Q_RES_0402LF-1K,1%,1/16W,EMPTY,CS21002FB06
     1   P3V3 @T6G_MB_LIB.T6G(SCH_1):P3V3   I190 @T6G_MB_LIB.T6G(SCH_1):PAGE101
     2 PWRGD_CHE_CPU1_DIMM @T6G_MB_LIB.T6G(SCH_1):PWRGD_CHE_CPU1_DIMM   I190 @T6G_MB_LIB.T6G(SCH_1):PAGE101

R108 Q_RES_0402LF-1K,1%,1/16W,EMPTY,CS21002FB06
     1   P3V3 @T6G_MB_LIB.T6G(SCH_1):P3V3   I190 @T6G_MB_LIB.T6G(SCH_1):PAGE102
     2 PWRGD_CHF_CPU1_DIMM @T6G_MB_LIB.T6G(SCH_1):PWRGD_CHF_CPU1_DIMM   I190 @T6G_MB_LIB.T6G(SCH_1):PAGE102

R109 Q_RES_0402LF-1K,1%,1/16W,EMPTY,CS21002FB06
     1   P3V3 @T6G_MB_LIB.T6G(SCH_1):P3V3   I189 @T6G_MB_LIB.T6G(SCH_1):PAGE103
     2 PWRGD_CHGL_CPU1 @T6G_MB_LIB.T6G(SCH_1):PWRGD_CHGL_CPU1   I189 @T6G_MB_LIB.T6G(SCH_1):PAGE103

R110 Q_RES_0402LF-1K,1%,1/16W,EMPTY,CS21002FB06
     1   P3V3 @T6G_MB_LIB.T6G(SCH_1):P3V3   I192 @T6G_MB_LIB.T6G(SCH_1):PAGE103
     2 PWRGD_CHG_CPU1_DIMM0 @T6G_MB_LIB.T6G(SCH_1):PWRGD_CHG_CPU1_DIMM0   I192 @T6G_MB_LIB.T6G(SCH_1):PAGE103

R111 Q_RES_0402LF-1K,1%,1/16W,EMPTY,CS21002FB06
     1   P3V3 @T6G_MB_LIB.T6G(SCH_1):P3V3   I190 @T6G_MB_LIB.T6G(SCH_1):PAGE104
     2 PWRGD_CHH_CPU1_DIMM @T6G_MB_LIB.T6G(SCH_1):PWRGD_CHH_CPU1_DIMM   I190 @T6G_MB_LIB.T6G(SCH_1):PAGE104

R112 Q_RES_0402LF-1K,1%,1/16W,EMPTY,CS21002FB06
     1   P3V3 @T6G_MB_LIB.T6G(SCH_1):P3V3   I190 @T6G_MB_LIB.T6G(SCH_1):PAGE105
     2 PWRGD_CHI_CPU1_DIMM @T6G_MB_LIB.T6G(SCH_1):PWRGD_CHI_CPU1_DIMM   I190 @T6G_MB_LIB.T6G(SCH_1):PAGE105

R113 Q_RES_0402LF-1K,1%,1/16W,EMPTY,CS21002FB06
     1   P3V3 @T6G_MB_LIB.T6G(SCH_1):P3V3   I190 @T6G_MB_LIB.T6G(SCH_1):PAGE106
     2 PWRGD_CHJ_CPU1_DIMM @T6G_MB_LIB.T6G(SCH_1):PWRGD_CHJ_CPU1_DIMM   I190 @T6G_MB_LIB.T6G(SCH_1):PAGE106

R114 Q_RES_0402LF-1K,1%,1/16W,EMPTY,CS21002FB06
     1   P3V3 @T6G_MB_LIB.T6G(SCH_1):P3V3   I190 @T6G_MB_LIB.T6G(SCH_1):PAGE107
     2 PWRGD_CHK_CPU1_DIMM @T6G_MB_LIB.T6G(SCH_1):PWRGD_CHK_CPU1_DIMM   I190 @T6G_MB_LIB.T6G(SCH_1):PAGE107

R115 Q_RES_0402LF-1K,1%,1/16W,EMPTY,CS21002FB06
     1   P3V3 @T6G_MB_LIB.T6G(SCH_1):P3V3   I190 @T6G_MB_LIB.T6G(SCH_1):PAGE108
     2 PWRGD_CHL_CPU1_DIMM @T6G_MB_LIB.T6G(SCH_1):PWRGD_CHL_CPU1_DIMM   I190 @T6G_MB_LIB.T6G(SCH_1):PAGE108

R116 Q_RES_0402LF-33,5%,1/16W,CHIP,CS03302JB10
     1 IRQ_OCP_SFF_WAKE_BUF_N @T6G_MB_LIB.T6G(SCH_1):IRQ_OCP_SFF_WAKE_BUF_N     I5 @T6G_MB_LIB.T6G(SCH_1):PAGE132
     2 IRQ_LVC3_WAKE_N @T6G_MB_LIB.T6G(SCH_1):IRQ_LVC3_WAKE_N     I5 @T6G_MB_LIB.T6G(SCH_1):PAGE132

R117 Q_RES_0402LF-1K,1%,1/16W,CHIP,CS21002FB06
     1 P3V3_AUX @T6G_MB_LIB.T6G(SCH_1):P3V3_AUX    I38 @T6G_MB_LIB.T6G(SCH_1):PAGE182
     2 PWRGD_PVDD11_S3_P0_R @T6G_MB_LIB.T6G(SCH_1):PWRGD_PVDD11_S3_P0_R    I38 @T6G_MB_LIB.T6G(SCH_1):PAGE182

R118 Q_RES_0402LF-0,5%,1/16W,CHIP,CS00002JB13
     1 SMB_SCM_2_R6_SCL @T6G_MB_LIB.T6G(SCH_1):SMB_SCM_2_R6_SCL    I41 @T6G_MB_LIB.T6G(SCH_1):PAGE182
     2 PVDD11_S3_P0_PMSCL_R @T6G_MB_LIB.T6G(SCH_1):PVDD11_S3_P0_PMSCL_R    I41 @T6G_MB_LIB.T6G(SCH_1):PAGE182

R119 Q_RES_0402LF-0,5%,1/16W,CHIP,CS00002JB13
     1 SMB_SCM_2_R6_SDA @T6G_MB_LIB.T6G(SCH_1):SMB_SCM_2_R6_SDA    I40 @T6G_MB_LIB.T6G(SCH_1):PAGE182
     2 PVDD11_S3_P0_PMSDA_R @T6G_MB_LIB.T6G(SCH_1):PVDD11_S3_P0_PMSDA_R    I40 @T6G_MB_LIB.T6G(SCH_1):PAGE182

R120 Q_RES_0402LF-33,5%,1/16W,CHIP,CS03302JB10
     1 PVDD11_S3_P0_PMALERT @T6G_MB_LIB.T6G(SCH_1):PVDD11_S3_P0_PMALERT    I39 @T6G_MB_LIB.T6G(SCH_1):PAGE182
     2 PVDD11_S3_P0_PMALERT_R @T6G_MB_LIB.T6G(SCH_1):PVDD11_S3_P0_PMALERT_R    I39 @T6G_MB_LIB.T6G(SCH_1):PAGE182

R121 Q_RES_0402LF-0,5%,1/16W,CHIP,CS00002JB13
     1 SMB_FRU_3V3AUX_SCL @T6G_MB_LIB.T6G(SCH_1):SMB_FRU_3V3AUX_SCL   I122 @T6G_MB_LIB.T6G(SCH_1):PAGE361
     2 SMB_CPU_FRU_3V3AUX_SCL @T6G_MB_LIB.T6G(SCH_1):SMB_CPU_FRU_3V3AUX_SCL   I122 @T6G_MB_LIB.T6G(SCH_1):PAGE361

R122 Q_RES_0402LF-0,5%,1/16W,CHIP,CS00002JB13
     1 PWRGD_PVDD11_S3_P0 @T6G_MB_LIB.T6G(SCH_1):PWRGD_PVDD11_S3_P0    I44 @T6G_MB_LIB.T6G(SCH_1):PAGE182
     2 PWRGD_PVDD11_S3_P0_R @T6G_MB_LIB.T6G(SCH_1):PWRGD_PVDD11_S3_P0_R    I44 @T6G_MB_LIB.T6G(SCH_1):PAGE182

R123 Q_RES_0402LF-0,5%,1/16W,CHIP,CS00002JB13
     1 PVDD11_S3_P0_EN @T6G_MB_LIB.T6G(SCH_1):PVDD11_S3_P0_EN    I43 @T6G_MB_LIB.T6G(SCH_1):PAGE182
     2 PVDD11_S3_P0_EN_R @T6G_MB_LIB.T6G(SCH_1):PVDD11_S3_P0_EN_R    I43 @T6G_MB_LIB.T6G(SCH_1):PAGE182

R124 Q_RES_0402LF-1K,1%,1/16W,EMPTY,CS21002FB06
     1 PVDD18_S5_P0 @T6G_MB_LIB.T6G(SCH_1):PVDD18_S5_P0    I25 @T6G_MB_LIB.T6G(SCH_1):PAGE182
     2 PVDD11_S3_P0_OCP_N_R @T6G_MB_LIB.T6G(SCH_1):PVDD11_S3_P0_OCP_N_R    I25 @T6G_MB_LIB.T6G(SCH_1):PAGE182

R125 Q_RES_0402LF-0,5%,1/16W,CHIP,CS00002JB13
     1 SMB_FRU_3V3AUX_SDA @T6G_MB_LIB.T6G(SCH_1):SMB_FRU_3V3AUX_SDA   I123 @T6G_MB_LIB.T6G(SCH_1):PAGE361
     2 SMB_CPU_FRU_3V3AUX_SDA @T6G_MB_LIB.T6G(SCH_1):SMB_CPU_FRU_3V3AUX_SDA   I123 @T6G_MB_LIB.T6G(SCH_1):PAGE361

R126 Q_RES_0402LF-10K,1%,1/16W,CHIP,CS31002FB08
     1 FM_APML_MUX2_OE_N @T6G_MB_LIB.T6G(SCH_1):FM_APML_MUX2_OE_N   I163 @T6G_MB_LIB.T6G(SCH_1):PAGE82
     2    GND @T6G_MB_LIB.T6G(SCH_1):GND   I163 @T6G_MB_LIB.T6G(SCH_1):PAGE82

R127 Q_RES_0402LF-1K,1%,1/16W,EMPTY,CS21002FB06
     1 P3V3_AUX @T6G_MB_LIB.T6G(SCH_1):P3V3_AUX   I117 @T6G_MB_LIB.T6G(SCH_1):PAGE76
     2 SPI_CPU0_LVC3_SCM_D1 @T6G_MB_LIB.T6G(SCH_1):SPI_CPU0_LVC3_SCM_D1   I117 @T6G_MB_LIB.T6G(SCH_1):PAGE76

R128 Q_RES_0402LF-1K,1%,1/16W,EMPTY,CS21002FB06
     1 P3V3_AUX @T6G_MB_LIB.T6G(SCH_1):P3V3_AUX   I118 @T6G_MB_LIB.T6G(SCH_1):PAGE76
     2 SPI_CPU0_LVC3_SCM_D2 @T6G_MB_LIB.T6G(SCH_1):SPI_CPU0_LVC3_SCM_D2   I118 @T6G_MB_LIB.T6G(SCH_1):PAGE76

R129 Q_RES_0402LF-1K,1%,1/16W,EMPTY,CS21002FB06
     1 P3V3_AUX @T6G_MB_LIB.T6G(SCH_1):P3V3_AUX   I119 @T6G_MB_LIB.T6G(SCH_1):PAGE76
     2 SPI_CPU0_LVC3_SCM_D3 @T6G_MB_LIB.T6G(SCH_1):SPI_CPU0_LVC3_SCM_D3   I119 @T6G_MB_LIB.T6G(SCH_1):PAGE76

R130 Q_RES_0402LF-10K,5%,1/16W,EMPTY,CS31002JB08
     1 UART_VCC_J8 @T6G_MB_LIB.T6G(SCH_1):UART_VCC_J8   I113 @T6G_MB_LIB.T6G(SCH_1):PAGE349
     2 P5V_AUX @T6G_MB_LIB.T6G(SCH_1):P5V_AUX   I113 @T6G_MB_LIB.T6G(SCH_1):PAGE349

R131 Q_RES_0402LF-10K,5%,1/16W,CHIP,CS31002JB08
     1 P3V3_AUX @T6G_MB_LIB.T6G(SCH_1):P3V3_AUX   I116 @T6G_MB_LIB.T6G(SCH_1):PAGE349
     2 UART_VCC_J8 @T6G_MB_LIB.T6G(SCH_1):UART_VCC_J8   I116 @T6G_MB_LIB.T6G(SCH_1):PAGE349

R132 Q_RES_0402LF-0,5%,1/16W,CHIP,CS00002JB13
     1 FM_APML_MUX2_OE_N @T6G_MB_LIB.T6G(SCH_1):FM_APML_MUX2_OE_N   I168 @T6G_MB_LIB.T6G(SCH_1):PAGE81
     2 FM_APML_MUX2_OE_R_N @T6G_MB_LIB.T6G(SCH_1):FM_APML_MUX2_OE_R_N   I168 @T6G_MB_LIB.T6G(SCH_1):PAGE81

R133 Q_RES_0402LF-0,5%,1/16W,CHIP,CS00002JB13
     1 FM_APML_MUX2_SEL @T6G_MB_LIB.T6G(SCH_1):FM_APML_MUX2_SEL   I169 @T6G_MB_LIB.T6G(SCH_1):PAGE81
     2 FM_APML_MUX2_SEL_R @T6G_MB_LIB.T6G(SCH_1):FM_APML_MUX2_SEL_R   I169 @T6G_MB_LIB.T6G(SCH_1):PAGE81

R134 Q_RES_0402LF-4.7K,5%,1/16W,EMPTY,CS24702JB10
     1 FM_APML_MUX2_OE_N @T6G_MB_LIB.T6G(SCH_1):FM_APML_MUX2_OE_N   I156 @T6G_MB_LIB.T6G(SCH_1):PAGE82
     2 P3V3_AUX @T6G_MB_LIB.T6G(SCH_1):P3V3_AUX   I156 @T6G_MB_LIB.T6G(SCH_1):PAGE82

R135 Q_RES_0402LF-4.7K,5%,1/16W,EMPTY,CS24702JB10
     1 FM_APML_MUX2_SEL @T6G_MB_LIB.T6G(SCH_1):FM_APML_MUX2_SEL   I157 @T6G_MB_LIB.T6G(SCH_1):PAGE82
     2 P3V3_AUX @T6G_MB_LIB.T6G(SCH_1):P3V3_AUX   I157 @T6G_MB_LIB.T6G(SCH_1):PAGE82

R136 Q_RES_0402LF-10K,1%,1/16W,EMPTY,CS31002FB08
     1 FM_APML_MUX2_SEL @T6G_MB_LIB.T6G(SCH_1):FM_APML_MUX2_SEL   I162 @T6G_MB_LIB.T6G(SCH_1):PAGE82
     2    GND @T6G_MB_LIB.T6G(SCH_1):GND   I162 @T6G_MB_LIB.T6G(SCH_1):PAGE82

R137 Q_RES_0402LF-0,5%,1/16W,CHIP,CS00002JB13
     1 PVDDCR_CPU1_P0_OCP_N @T6G_MB_LIB.T6G(SCH_1):PVDDCR_CPU1_P0_OCP_N    I59 @T6G_MB_LIB.T6G(SCH_1):PAGE81
     2 FM_PVDDCR_CPU1_P0_OCP_N @T6G_MB_LIB.T6G(SCH_1):FM_PVDDCR_CPU1_P0_OCP_N    I59 @T6G_MB_LIB.T6G(SCH_1):PAGE81

R138 Q_RES_0402LF-4.7K,1%,1/16W,EMPTY,CS24702FB06
     1 M2_SSD0_CLKREQ_EN_N @T6G_MB_LIB.T6G(SCH_1):M2_SSD0_CLKREQ_EN_N    I15 @T6G_MB_LIB.T6G(SCH_1):PAGE345
     2    GND @T6G_MB_LIB.T6G(SCH_1):GND    I15 @T6G_MB_LIB.T6G(SCH_1):PAGE345

R139 Q_RES_0402LF-0,5%,1/16W,EMPTY,CS00002JB13
     1 I3C_MUX_CPU0_VIO @T6G_MB_LIB.T6G(SCH_1):I3C_MUX_CPU0_VIO    I30 @T6G_MB_LIB.T6G(SCH_1):PAGE138
     2 PVDD18_S5_P0 @T6G_MB_LIB.T6G(SCH_1):PVDD18_S5_P0    I30 @T6G_MB_LIB.T6G(SCH_1):PAGE138

R140 Q_RES_0402LF-0,5%,1/16W,EMPTY,CS00002JB13
     1 SMB_CPU0_CPU1_APML_SCL @T6G_MB_LIB.T6G(SCH_1):SMB_CPU0_CPU1_APML_SCL    I98 @T6G_MB_LIB.T6G(SCH_1):PAGE137
     2 SMB_CPU0_CPU1_APML_BUF1_SCL @T6G_MB_LIB.T6G(SCH_1):SMB_CPU0_CPU1_APML_BUF1_SCL    I98 @T6G_MB_LIB.T6G(SCH_1):PAGE137

R141 Q_RES_0402LF-0,5%,1/16W,CHIP,CS00002JB13
     1 PVDDCR_CPU1_P1_OCP_N @T6G_MB_LIB.T6G(SCH_1):PVDDCR_CPU1_P1_OCP_N    I57 @T6G_MB_LIB.T6G(SCH_1):PAGE81
     2 FM_PVDDCR_CPU1_P1_OCP_N @T6G_MB_LIB.T6G(SCH_1):FM_PVDDCR_CPU1_P1_OCP_N    I57 @T6G_MB_LIB.T6G(SCH_1):PAGE81

R142 Q_RES_0402LF-0,5%,1/16W,EMPTY,CS00002JB13
     1 SMB_CPU0_CPU1_APML_MUX1_SCL @T6G_MB_LIB.T6G(SCH_1):SMB_CPU0_CPU1_APML_MUX1_SCL    I35 @T6G_MB_LIB.T6G(SCH_1):PAGE138
     2 SMB_APML_CPU0_R_SCL @T6G_MB_LIB.T6G(SCH_1):SMB_APML_CPU0_R_SCL    I35 @T6G_MB_LIB.T6G(SCH_1):PAGE138

R143 Q_RES_0402LF-0,5%,1/16W,EMPTY,CS00002JB13
     1 SMB_CPU0_CPU1_APML_MUX1_SDA @T6G_MB_LIB.T6G(SCH_1):SMB_CPU0_CPU1_APML_MUX1_SDA    I34 @T6G_MB_LIB.T6G(SCH_1):PAGE138
     2 SMB_APML_CPU0_R_SDA @T6G_MB_LIB.T6G(SCH_1):SMB_APML_CPU0_R_SDA    I34 @T6G_MB_LIB.T6G(SCH_1):PAGE138

R144 Q_RES_0402LF-0,5%,1/16W,EMPTY,CS00002JB13
     1 SMB_CPU0_CPU1_SEC_SDA_R2 @T6G_MB_LIB.T6G(SCH_1):SMB_CPU0_CPU1_SEC_SDA_R2    I15 @T6G_MB_LIB.T6G(SCH_1):PAGE138
     2 SMB_CPU0_SEC_R_SDA @T6G_MB_LIB.T6G(SCH_1):SMB_CPU0_SEC_R_SDA    I15 @T6G_MB_LIB.T6G(SCH_1):PAGE138

R145 Q_RES_0402LF-0,5%,1/16W,EMPTY,CS00002JB13
     1 SMB_CPU0_CPU1_SEC_SCL_R2 @T6G_MB_LIB.T6G(SCH_1):SMB_CPU0_CPU1_SEC_SCL_R2    I14 @T6G_MB_LIB.T6G(SCH_1):PAGE138
     2 SMB_CPU0_SEC_R_SCL @T6G_MB_LIB.T6G(SCH_1):SMB_CPU0_SEC_R_SCL    I14 @T6G_MB_LIB.T6G(SCH_1):PAGE138

R146 Q_RES_0402LF-0,5%,1/16W,EMPTY,CS00002JB13
     1 SMB_CPU0_CPU1_APML_MUX1_SCL @T6G_MB_LIB.T6G(SCH_1):SMB_CPU0_CPU1_APML_MUX1_SCL    I17 @T6G_MB_LIB.T6G(SCH_1):PAGE138
     2 SMB_APML_CPU1_R_SCL @T6G_MB_LIB.T6G(SCH_1):SMB_APML_CPU1_R_SCL    I17 @T6G_MB_LIB.T6G(SCH_1):PAGE138

R147 Q_RES_0402LF-0,5%,1/16W,EMPTY,CS00002JB13
     1 SMB_CPU0_CPU1_APML_MUX1_SDA @T6G_MB_LIB.T6G(SCH_1):SMB_CPU0_CPU1_APML_MUX1_SDA    I16 @T6G_MB_LIB.T6G(SCH_1):PAGE138
     2 SMB_APML_CPU1_R_SDA @T6G_MB_LIB.T6G(SCH_1):SMB_APML_CPU1_R_SDA    I16 @T6G_MB_LIB.T6G(SCH_1):PAGE138

R148 Q_RES_0402LF-0,5%,1/16W,EMPTY,CS00002JB13
     1 SMB_CPU0_CPU1_SEC_SDA_R2 @T6G_MB_LIB.T6G(SCH_1):SMB_CPU0_CPU1_SEC_SDA_R2     I6 @T6G_MB_LIB.T6G(SCH_1):PAGE138
     2 SMB_CPU1_SEC_R_SDA @T6G_MB_LIB.T6G(SCH_1):SMB_CPU1_SEC_R_SDA     I6 @T6G_MB_LIB.T6G(SCH_1):PAGE138

R149 Q_RES_0402LF-0,5%,1/16W,CHIP,CS00002JB13
     1 PVDDCR_SOC_P1_EN @T6G_MB_LIB.T6G(SCH_1):PVDDCR_SOC_P1_EN     I2 @T6G_MB_LIB.T6G(SCH_1):PAGE185
     2 PVDDCR_SOC_P1_EN_RC @T6G_MB_LIB.T6G(SCH_1):PVDDCR_SOC_P1_EN_RC     I2 @T6G_MB_LIB.T6G(SCH_1):PAGE185

R150 Q_RES_0402LF-0,5%,1/16W,EMPTY,CS00002JB13
     1 SMB_CPU0_CPU1_APML_SDA @T6G_MB_LIB.T6G(SCH_1):SMB_CPU0_CPU1_APML_SDA    I97 @T6G_MB_LIB.T6G(SCH_1):PAGE137
     2 SMB_CPU0_CPU1_APML_BUF1_SDA @T6G_MB_LIB.T6G(SCH_1):SMB_CPU0_CPU1_APML_BUF1_SDA    I97 @T6G_MB_LIB.T6G(SCH_1):PAGE137

R151 Q_RES_0402LF-0,5%,1/16W,CHIP,CS00002JB13
     1 SMB_CPU0_CPU1_APML_SCL @T6G_MB_LIB.T6G(SCH_1):SMB_CPU0_CPU1_APML_SCL    I79 @T6G_MB_LIB.T6G(SCH_1):PAGE137
     2 SMB_CPU0_CPU1_APML_BUF2_SCL @T6G_MB_LIB.T6G(SCH_1):SMB_CPU0_CPU1_APML_BUF2_SCL    I79 @T6G_MB_LIB.T6G(SCH_1):PAGE137

R152 Q_RES_0402LF-33,5%,1/16W,CHIP,CS03302JB10
     1 P12V_OCP_SFF_EN @T6G_MB_LIB.T6G(SCH_1):P12V_OCP_SFF_EN   I153 @T6G_MB_LIB.T6G(SCH_1):PAGE79
     2 P12V_OCP_SFF_EN_R @T6G_MB_LIB.T6G(SCH_1):P12V_OCP_SFF_EN_R   I153 @T6G_MB_LIB.T6G(SCH_1):PAGE79

R153 Q_RES_0402LF-0,5%,1/16W,CHIP,CS00002JB13
     1 M2_SSD0_CLKREQ_EN_N @T6G_MB_LIB.T6G(SCH_1):M2_SSD0_CLKREQ_EN_N    I27 @T6G_MB_LIB.T6G(SCH_1):PAGE345
     2 M2_SSD0_CLKREQ_EN_N_BUF @T6G_MB_LIB.T6G(SCH_1):M2_SSD0_CLKREQ_EN_N_BUF    I27 @T6G_MB_LIB.T6G(SCH_1):PAGE345

R154 Q_RES_0402LF-1K,1%,1/16W,EMPTY,CS21002FB06
     1 PVDD18_S5_P1 @T6G_MB_LIB.T6G(SCH_1):PVDD18_S5_P1    I67 @T6G_MB_LIB.T6G(SCH_1):PAGE185
     2 SVID_PVDDCR_CPU0_P1_SVTO @T6G_MB_LIB.T6G(SCH_1):SVID_PVDDCR_CPU0_P1_SVTO    I67 @T6G_MB_LIB.T6G(SCH_1):PAGE185

R155 Q_RES_0402LF-1K,1%,1/16W,EMPTY,CS21002FB06
     1 P3V3_AUX @T6G_MB_LIB.T6G(SCH_1):P3V3_AUX    I32 @T6G_MB_LIB.T6G(SCH_1):PAGE345
     2 M2_SSD0_CLKREQ_EN_N_BUF @T6G_MB_LIB.T6G(SCH_1):M2_SSD0_CLKREQ_EN_N_BUF    I32 @T6G_MB_LIB.T6G(SCH_1):PAGE345

R156 Q_RES_0402LF-0,5%,1/16W,CHIP,CS00002JB13
     1 CPU0_XTRIG_R2_L4 @T6G_MB_LIB.T6G(SCH_1):CPU0_XTRIG_R2_L4   I346 @T6G_MB_LIB.T6G(SCH_1):PAGE27
     2 CPU0_XTRIG_L4 @T6G_MB_LIB.T6G(SCH_1):CPU0_XTRIG_L4   I346 @T6G_MB_LIB.T6G(SCH_1):PAGE27

R157 Q_RES_0402LF-0,5%,1/16W,CHIP,CS00002JB13
     1 CPU0_XTRIG_R2_L5 @T6G_MB_LIB.T6G(SCH_1):CPU0_XTRIG_R2_L5   I347 @T6G_MB_LIB.T6G(SCH_1):PAGE27
     2 CPU0_XTRIG_L5 @T6G_MB_LIB.T6G(SCH_1):CPU0_XTRIG_L5   I347 @T6G_MB_LIB.T6G(SCH_1):PAGE27

R158 Q_RES_0402LF-33,5%,1/16W,CHIP,CS03302JB10
     1 FM_PLD_CPU0_PRSNT_HDT @T6G_MB_LIB.T6G(SCH_1):FM_PLD_CPU0_PRSNT_HDT   I154 @T6G_MB_LIB.T6G(SCH_1):PAGE80
     2 CPU0_HDT_BYPASS_SEL @T6G_MB_LIB.T6G(SCH_1):CPU0_HDT_BYPASS_SEL   I154 @T6G_MB_LIB.T6G(SCH_1):PAGE80

R159 Q_RES_0402LF-33,5%,1/16W,CHIP,CS03302JB10
     1 CPU0_JTAG_BUF_OE @T6G_MB_LIB.T6G(SCH_1):CPU0_JTAG_BUF_OE   I111 @T6G_MB_LIB.T6G(SCH_1):PAGE80
     2 CPU0_JTAG_BUF_R_OE @T6G_MB_LIB.T6G(SCH_1):CPU0_JTAG_BUF_R_OE   I111 @T6G_MB_LIB.T6G(SCH_1):PAGE80

R160 Q_RES_0402LF-33,5%,1/16W,CHIP,CS03302JB10
     1 JTAG_SCM_TRST_R_N @T6G_MB_LIB.T6G(SCH_1):JTAG_SCM_TRST_R_N    I16 @T6G_MB_LIB.T6G(SCH_1):PAGE79
     2 JTAG_SCM_TRST_N @T6G_MB_LIB.T6G(SCH_1):JTAG_SCM_TRST_N    I16 @T6G_MB_LIB.T6G(SCH_1):PAGE79

R161 Q_RES_0402LF-33,5%,1/16W,CHIP,CS03302JB10
     1 CPU1_JTAG_BUF_R_OE @T6G_MB_LIB.T6G(SCH_1):CPU1_JTAG_BUF_R_OE   I161 @T6G_MB_LIB.T6G(SCH_1):PAGE80
     2 CPU1_JTAG_BUF_OE @T6G_MB_LIB.T6G(SCH_1):CPU1_JTAG_BUF_OE   I161 @T6G_MB_LIB.T6G(SCH_1):PAGE80

R162 Q_RES_0402LF-0,5%,1/16W,CHIP,CS00002JB13
     1 SMB_CPU0_CPU1_APML_SDA @T6G_MB_LIB.T6G(SCH_1):SMB_CPU0_CPU1_APML_SDA    I80 @T6G_MB_LIB.T6G(SCH_1):PAGE137
     2 SMB_CPU0_CPU1_APML_BUF2_SDA @T6G_MB_LIB.T6G(SCH_1):SMB_CPU0_CPU1_APML_BUF2_SDA    I80 @T6G_MB_LIB.T6G(SCH_1):PAGE137

R163 Q_RES_0402LF-33,5%,1/16W,CHIP,CS03302JB10
     1 FM_I3C_CPU0_MUX0_OE_R_N @T6G_MB_LIB.T6G(SCH_1):FM_I3C_CPU0_MUX0_OE_R_N    I54 @T6G_MB_LIB.T6G(SCH_1):PAGE79
     2 FM_I3C_CPU0_MUX0_OE_N @T6G_MB_LIB.T6G(SCH_1):FM_I3C_CPU0_MUX0_OE_N    I54 @T6G_MB_LIB.T6G(SCH_1):PAGE79

R164 Q_RES_0402LF-33,5%,1/16W,CHIP,CS03302JB10
     1 FM_I3C_CPU0_MUX0_R_SEL @T6G_MB_LIB.T6G(SCH_1):FM_I3C_CPU0_MUX0_R_SEL    I50 @T6G_MB_LIB.T6G(SCH_1):PAGE79
     2 FM_I3C_CPU0_MUX0_SEL @T6G_MB_LIB.T6G(SCH_1):FM_I3C_CPU0_MUX0_SEL    I50 @T6G_MB_LIB.T6G(SCH_1):PAGE79

R165 Q_RES_0402LF-33,5%,1/16W,CHIP,CS03302JB10
     1 FM_I3C_CPU0_MUX1_OE_R_N @T6G_MB_LIB.T6G(SCH_1):FM_I3C_CPU0_MUX1_OE_R_N    I47 @T6G_MB_LIB.T6G(SCH_1):PAGE79
     2 FM_I3C_CPU0_MUX1_OE_N @T6G_MB_LIB.T6G(SCH_1):FM_I3C_CPU0_MUX1_OE_N    I47 @T6G_MB_LIB.T6G(SCH_1):PAGE79

R166 Q_RES_0402LF-33,5%,1/16W,CHIP,CS03302JB10
     1 FM_I3C_CPU0_MUX1_R_SEL @T6G_MB_LIB.T6G(SCH_1):FM_I3C_CPU0_MUX1_R_SEL    I51 @T6G_MB_LIB.T6G(SCH_1):PAGE79
     2 FM_I3C_CPU0_MUX1_SEL @T6G_MB_LIB.T6G(SCH_1):FM_I3C_CPU0_MUX1_SEL    I51 @T6G_MB_LIB.T6G(SCH_1):PAGE79

R167 Q_RES_0402LF-0,5%,1/16W,CHIP,CS00002JB13
     1 SGPIO_SCM_DI_R<0> @T6G_MB_LIB.T6G(SCH_1):SGPIO_SCM_DI_R(0)    I45 @T6G_MB_LIB.T6G(SCH_1):PAGE79
     2 SGPIO_SCM_DI_<0> @T6G_MB_LIB.T6G(SCH_1):SGPIO_SCM_DI_(0)    I45 @T6G_MB_LIB.T6G(SCH_1):PAGE79

R168 Q_RES_0402LF-0,5%,1/16W,CHIP,CS00002JB13
     1 SGPIO_SCM_DI_R<1> @T6G_MB_LIB.T6G(SCH_1):SGPIO_SCM_DI_R(1)    I24 @T6G_MB_LIB.T6G(SCH_1):PAGE79
     2 SGPIO_SCM_DI_<1> @T6G_MB_LIB.T6G(SCH_1):SGPIO_SCM_DI_(1)    I24 @T6G_MB_LIB.T6G(SCH_1):PAGE79

R169 Q_RES_0402LF-33,5%,1/16W,CHIP,CS03302JB10
     1 FM_I3C_CPU1_MUX0_OE_R_N @T6G_MB_LIB.T6G(SCH_1):FM_I3C_CPU1_MUX0_OE_R_N    I48 @T6G_MB_LIB.T6G(SCH_1):PAGE79
     2 FM_I3C_CPU1_MUX0_OE_N @T6G_MB_LIB.T6G(SCH_1):FM_I3C_CPU1_MUX0_OE_N    I48 @T6G_MB_LIB.T6G(SCH_1):PAGE79

R170 Q_RES_0402LF-33,5%,1/16W,CHIP,CS03302JB10
     1 FM_I3C_CPU1_MUX0_R_SEL @T6G_MB_LIB.T6G(SCH_1):FM_I3C_CPU1_MUX0_R_SEL    I53 @T6G_MB_LIB.T6G(SCH_1):PAGE79
     2 FM_I3C_CPU1_MUX0_SEL @T6G_MB_LIB.T6G(SCH_1):FM_I3C_CPU1_MUX0_SEL    I53 @T6G_MB_LIB.T6G(SCH_1):PAGE79

R171 Q_RES_0402LF-33,5%,1/16W,CHIP,CS03302JB10
     1 FM_I3C_CPU1_MUX1_OE_R_N @T6G_MB_LIB.T6G(SCH_1):FM_I3C_CPU1_MUX1_OE_R_N    I52 @T6G_MB_LIB.T6G(SCH_1):PAGE79
     2 FM_I3C_CPU1_MUX1_OE_N @T6G_MB_LIB.T6G(SCH_1):FM_I3C_CPU1_MUX1_OE_N    I52 @T6G_MB_LIB.T6G(SCH_1):PAGE79

R172 Q_RES_0402LF-33,5%,1/16W,CHIP,CS03302JB10
     1 FM_I3C_CPU1_MUX1_R_SEL @T6G_MB_LIB.T6G(SCH_1):FM_I3C_CPU1_MUX1_R_SEL    I43 @T6G_MB_LIB.T6G(SCH_1):PAGE79
     2 FM_I3C_CPU1_MUX1_SEL @T6G_MB_LIB.T6G(SCH_1):FM_I3C_CPU1_MUX1_SEL    I43 @T6G_MB_LIB.T6G(SCH_1):PAGE79

R173 Q_RES_0402LF-33,5%,1/16W,CHIP,CS03302JB10
     1 FM_PLD_CPU1_PRSNT_HDT @T6G_MB_LIB.T6G(SCH_1):FM_PLD_CPU1_PRSNT_HDT   I163 @T6G_MB_LIB.T6G(SCH_1):PAGE80
     2 CPU1_HDT_BYPASS_SEL @T6G_MB_LIB.T6G(SCH_1):CPU1_HDT_BYPASS_SEL   I163 @T6G_MB_LIB.T6G(SCH_1):PAGE80

R174 Q_RES_0402LF-33,5%,1/16W,CHIP,CS03302JB10
     1 SCM_IRQ_1V8_R_N @T6G_MB_LIB.T6G(SCH_1):SCM_IRQ_1V8_R_N   I160 @T6G_MB_LIB.T6G(SCH_1):PAGE80
     2 SCM_IRQ_1V8_N @T6G_MB_LIB.T6G(SCH_1):SCM_IRQ_1V8_N   I160 @T6G_MB_LIB.T6G(SCH_1):PAGE80

R175 Q_RES_0402LF-0,5%,1/16W,CHIP,CS00002JB13
     1 SMB_VR_3V3STBY_SCL @T6G_MB_LIB.T6G(SCH_1):SMB_VR_3V3STBY_SCL    I81 @T6G_MB_LIB.T6G(SCH_1):PAGE185
     2 PVDDCR_CPU0_P1_PMSCL_R @T6G_MB_LIB.T6G(SCH_1):PVDDCR_CPU0_P1_PMSCL_R    I81 @T6G_MB_LIB.T6G(SCH_1):PAGE185

R176 Q_RES_0402LF-33,5%,1/16W,CHIP,CS03302JB10
     1 PVDD18_S5_P0_EN @T6G_MB_LIB.T6G(SCH_1):PVDD18_S5_P0_EN    I33 @T6G_MB_LIB.T6G(SCH_1):PAGE80
     2 FM_PVDD18_S5_P0_EN @T6G_MB_LIB.T6G(SCH_1):FM_PVDD18_S5_P0_EN    I33 @T6G_MB_LIB.T6G(SCH_1):PAGE80

R177 Q_RES_0402LF-33,5%,1/16W,CHIP,CS03302JB10
     1 PWRGD_PVDD18_S5_P0 @T6G_MB_LIB.T6G(SCH_1):PWRGD_PVDD18_S5_P0    I52 @T6G_MB_LIB.T6G(SCH_1):PAGE184
     2 FM_PWRGD_PVDD18_S5_P0 @T6G_MB_LIB.T6G(SCH_1):FM_PWRGD_PVDD18_S5_P0    I52 @T6G_MB_LIB.T6G(SCH_1):PAGE184

R178 Q_RES_0402LF-1K,1%,1/16W,CHIP,CS21002FB06
     1 P3V3_AUX @T6G_MB_LIB.T6G(SCH_1):P3V3_AUX    I24 @T6G_MB_LIB.T6G(SCH_1):PAGE345
     2 PCIE_M2_SSD0_PRSNT_N @T6G_MB_LIB.T6G(SCH_1):PCIE_M2_SSD0_PRSNT_N    I24 @T6G_MB_LIB.T6G(SCH_1):PAGE345

R179 Q_RES_0402LF-33,5%,1/16W,CHIP,CS03302JB10
     1 FM_CPU0_PROCHOT_R_N @T6G_MB_LIB.T6G(SCH_1):FM_CPU0_PROCHOT_R_N   I110 @T6G_MB_LIB.T6G(SCH_1):PAGE81
     2 CPU0_PROCHOT_N @T6G_MB_LIB.T6G(SCH_1):CPU0_PROCHOT_N   I110 @T6G_MB_LIB.T6G(SCH_1):PAGE81

R180 Q_RES_0402LF-0,5%,1/16W,CHIP,CS00002JB13
     1 CPU0_SP5R1 @T6G_MB_LIB.T6G(SCH_1):CPU0_SP5R1    I45 @T6G_MB_LIB.T6G(SCH_1):PAGE81
     2 FM_CPU0_SP5R1 @T6G_MB_LIB.T6G(SCH_1):FM_CPU0_SP5R1    I45 @T6G_MB_LIB.T6G(SCH_1):PAGE81

R181 Q_RES_0402LF-0,5%,1/16W,CHIP,CS00002JB13
     1 CPU0_SP5R2 @T6G_MB_LIB.T6G(SCH_1):CPU0_SP5R2    I46 @T6G_MB_LIB.T6G(SCH_1):PAGE81
     2 FM_CPU0_SP5R2 @T6G_MB_LIB.T6G(SCH_1):FM_CPU0_SP5R2    I46 @T6G_MB_LIB.T6G(SCH_1):PAGE81

R182 Q_RES_0402LF-0,5%,1/16W,CHIP,CS00002JB13
     1 FM_PRSNT_CPU0_R_N @T6G_MB_LIB.T6G(SCH_1):FM_PRSNT_CPU0_R_N   I101 @T6G_MB_LIB.T6G(SCH_1):PAGE81
     2 FM_PRSNT_CPU0_N @T6G_MB_LIB.T6G(SCH_1):FM_PRSNT_CPU0_N   I101 @T6G_MB_LIB.T6G(SCH_1):PAGE81

R183 Q_RES_0402LF-0,5%,1/16W,CHIP,CS00002JB13
     1 CPU0_CORETYPE0 @T6G_MB_LIB.T6G(SCH_1):CPU0_CORETYPE0    I82 @T6G_MB_LIB.T6G(SCH_1):PAGE81
     2 FM_CPU0_CORETYPE0 @T6G_MB_LIB.T6G(SCH_1):FM_CPU0_CORETYPE0    I82 @T6G_MB_LIB.T6G(SCH_1):PAGE81

R184 Q_RES_0402LF-0,5%,1/16W,CHIP,CS00002JB13
     1 CPU0_CORETYPE1 @T6G_MB_LIB.T6G(SCH_1):CPU0_CORETYPE1    I48 @T6G_MB_LIB.T6G(SCH_1):PAGE81
     2 FM_CPU0_CORETYPE1 @T6G_MB_LIB.T6G(SCH_1):FM_CPU0_CORETYPE1    I48 @T6G_MB_LIB.T6G(SCH_1):PAGE81

R185 Q_RES_0402LF-0,5%,1/16W,CHIP,CS00002JB13
     1 CPU0_CORETYPE2 @T6G_MB_LIB.T6G(SCH_1):CPU0_CORETYPE2    I80 @T6G_MB_LIB.T6G(SCH_1):PAGE81
     2 FM_CPU0_CORETYPE2 @T6G_MB_LIB.T6G(SCH_1):FM_CPU0_CORETYPE2    I80 @T6G_MB_LIB.T6G(SCH_1):PAGE81

R186 Q_RES_0402LF-33,5%,1/16W,CHIP,CS03302JB10
     1 FM_CPU0_FORCE_SELFREFRESH @T6G_MB_LIB.T6G(SCH_1):FM_CPU0_FORCE_SELFREFRESH   I129 @T6G_MB_LIB.T6G(SCH_1):PAGE80
     2 CPU0_FORCE_SELFREFRESH @T6G_MB_LIB.T6G(SCH_1):CPU0_FORCE_SELFREFRESH   I129 @T6G_MB_LIB.T6G(SCH_1):PAGE80

R187 Q_RES_0402LF-0,5%,1/16W,CHIP,CS00002JB13
     1 IRQ_CPU_BMC_NMI_N @T6G_MB_LIB.T6G(SCH_1):IRQ_CPU_BMC_NMI_N    I68 @T6G_MB_LIB.T6G(SCH_1):PAGE81
     2 IRQ_CPU_BMC_NMI_R_N @T6G_MB_LIB.T6G(SCH_1):IRQ_CPU_BMC_NMI_R_N    I68 @T6G_MB_LIB.T6G(SCH_1):PAGE81

R188 Q_RES_0402LF-0,5%,1/16W,CHIP,CS00002JB13
     1 FM_BMC_READY_N @T6G_MB_LIB.T6G(SCH_1):FM_BMC_READY_N    I61 @T6G_MB_LIB.T6G(SCH_1):PAGE81
     2 FM_BMC_READY_R_N @T6G_MB_LIB.T6G(SCH_1):FM_BMC_READY_R_N    I61 @T6G_MB_LIB.T6G(SCH_1):PAGE81

R189 Q_RES_0402LF-0,5%,1/16W,CHIP,CS00002JB13
     1 FM_BMC_TPM_PRES_N @T6G_MB_LIB.T6G(SCH_1):FM_BMC_TPM_PRES_N    I58 @T6G_MB_LIB.T6G(SCH_1):PAGE81
     2 FM_BMC_TPM_PRES_N_R @T6G_MB_LIB.T6G(SCH_1):FM_BMC_TPM_PRES_N_R    I58 @T6G_MB_LIB.T6G(SCH_1):PAGE81

R190 Q_RES_0402LF-0,5%,1/16W,CHIP,CS00002JB13
     1 FM_CPU1_BMC_RST_N @T6G_MB_LIB.T6G(SCH_1):FM_CPU1_BMC_RST_N    I64 @T6G_MB_LIB.T6G(SCH_1):PAGE81
     2 FM_CPU1_BMC_RST_R_N @T6G_MB_LIB.T6G(SCH_1):FM_CPU1_BMC_RST_R_N    I64 @T6G_MB_LIB.T6G(SCH_1):PAGE81

R191 Q_RES_0402LF-0,5%,1/16W,EMPTY,CS00002JB13
     1 FM_CPU1_SLP_S5_N @T6G_MB_LIB.T6G(SCH_1):FM_CPU1_SLP_S5_N   I297 @T6G_MB_LIB.T6G(SCH_1):PAGE55
     2 CPU1_SLP_S5_N @T6G_MB_LIB.T6G(SCH_1):CPU1_SLP_S5_N   I297 @T6G_MB_LIB.T6G(SCH_1):PAGE55

R192 Q_RES_0402LF-0,5%,1/16W,EMPTY,CS00002JB13
     1 FM_CPU1_SLP_S3_N @T6G_MB_LIB.T6G(SCH_1):FM_CPU1_SLP_S3_N   I298 @T6G_MB_LIB.T6G(SCH_1):PAGE55
     2 CPU1_SLP_S3_N @T6G_MB_LIB.T6G(SCH_1):CPU1_SLP_S3_N   I298 @T6G_MB_LIB.T6G(SCH_1):PAGE55

R193 Q_RES_0402LF-0,5%,1/16W,CHIP,CS00002JB13
     1 FM_CPU1_SMERR_N @T6G_MB_LIB.T6G(SCH_1):FM_CPU1_SMERR_N   I179 @T6G_MB_LIB.T6G(SCH_1):PAGE80
     2 CPU1_SMERR_N @T6G_MB_LIB.T6G(SCH_1):CPU1_SMERR_N   I179 @T6G_MB_LIB.T6G(SCH_1):PAGE80

R194 Q_RES_0402LF-0,5%,1/16W,CHIP,CS00002JB13
     1 CPU1_SPD_HOST_CTRL_N @T6G_MB_LIB.T6G(SCH_1):CPU1_SPD_HOST_CTRL_N   I100 @T6G_MB_LIB.T6G(SCH_1):PAGE80
     2 CPU1_SPD_HOST_CTRL_R1_N @T6G_MB_LIB.T6G(SCH_1):CPU1_SPD_HOST_CTRL_R1_N   I100 @T6G_MB_LIB.T6G(SCH_1):PAGE80

R195 Q_RES_0402LF-33,5%,1/16W,CHIP,CS03302JB10
     1 FM_CPU1_PWRGD_OUT @T6G_MB_LIB.T6G(SCH_1):FM_CPU1_PWRGD_OUT   I303 @T6G_MB_LIB.T6G(SCH_1):PAGE80
     2 CPU1_PWRGD_OUT @T6G_MB_LIB.T6G(SCH_1):CPU1_PWRGD_OUT   I303 @T6G_MB_LIB.T6G(SCH_1):PAGE80

R196 Q_RES_0402LF-0,5%,1/16W,CHIP,CS00002JB13
     1 CPU1_NV_SAVE_N @T6G_MB_LIB.T6G(SCH_1):CPU1_NV_SAVE_N   I109 @T6G_MB_LIB.T6G(SCH_1):PAGE80
     2 FM_CPU1_NV_SAVE_N @T6G_MB_LIB.T6G(SCH_1):FM_CPU1_NV_SAVE_N   I109 @T6G_MB_LIB.T6G(SCH_1):PAGE80

R197 Q_RES_0402LF-0,5%,1/16W,CHIP,CS00002JB13
     1 RST_CPU1_PERST0_N @T6G_MB_LIB.T6G(SCH_1):RST_CPU1_PERST0_N   I120 @T6G_MB_LIB.T6G(SCH_1):PAGE80
     2 RST_CPU1_PERST0_R_N @T6G_MB_LIB.T6G(SCH_1):RST_CPU1_PERST0_R_N   I120 @T6G_MB_LIB.T6G(SCH_1):PAGE80

R198 Q_RES_0402LF-0,5%,1/16W,CHIP,CS00002JB13
     1 RST_CPU1_PERST1_N @T6G_MB_LIB.T6G(SCH_1):RST_CPU1_PERST1_N   I122 @T6G_MB_LIB.T6G(SCH_1):PAGE80
     2 RST_CPU1_PERST1_R_N @T6G_MB_LIB.T6G(SCH_1):RST_CPU1_PERST1_R_N   I122 @T6G_MB_LIB.T6G(SCH_1):PAGE80

R199 Q_RES_0402LF-33,5%,1/16W,CHIP,CS03302JB10
     1 E1S_0_P12V_EN @T6G_MB_LIB.T6G(SCH_1):E1S_0_P12V_EN    I22 @T6G_MB_LIB.T6G(SCH_1):PAGE80
     2 P12V_E1S_0_EN @T6G_MB_LIB.T6G(SCH_1):P12V_E1S_0_EN    I22 @T6G_MB_LIB.T6G(SCH_1):PAGE80

R200 Q_RES_0402LF-4.7K,5%,1/16W,EMPTY,CS24702JB10
     1 P3V3_AUX @T6G_MB_LIB.T6G(SCH_1):P3V3_AUX    I13 @T6G_MB_LIB.T6G(SCH_1):PAGE137
     2 PU_U96_EN @T6G_MB_LIB.T6G(SCH_1):PU_U96_EN    I13 @T6G_MB_LIB.T6G(SCH_1):PAGE137

R201 Q_RES_0402LF-4.7K,5%,1/16W,EMPTY,CS24702JB10
     1 P3V3_AUX @T6G_MB_LIB.T6G(SCH_1):P3V3_AUX    I62 @T6G_MB_LIB.T6G(SCH_1):PAGE137
     2 PU_U2_EN @T6G_MB_LIB.T6G(SCH_1):PU_U2_EN    I62 @T6G_MB_LIB.T6G(SCH_1):PAGE137

R202 Q_RES_0402LF-0,5%,1/16W,CHIP,CS00002JB13
     1 SMB_CPU0_CPU1_APML_BUF2_SCL_R1 @T6G_MB_LIB.T6G(SCH_1):SMB_CPU0_CPU1_APML_BUF2_SCL_R1    I67 @T6G_MB_LIB.T6G(SCH_1):PAGE137
     2 SMB_CPU0_CPU1_APML_BUF2_SCL_R2 @T6G_MB_LIB.T6G(SCH_1):SMB_CPU0_CPU1_APML_BUF2_SCL_R2    I67 @T6G_MB_LIB.T6G(SCH_1):PAGE137

R203 Q_RES_0402LF-0,5%,1/16W,CHIP,CS00002JB13
     1 PWRGD_CPU1_PWROK @T6G_MB_LIB.T6G(SCH_1):PWRGD_CPU1_PWROK   I106 @T6G_MB_LIB.T6G(SCH_1):PAGE80
     2 FM_PWRGD_CPU1_PWROK @T6G_MB_LIB.T6G(SCH_1):FM_PWRGD_CPU1_PWROK   I106 @T6G_MB_LIB.T6G(SCH_1):PAGE80

R204 Q_RES_0402LF-0,5%,1/16W,CHIP,CS00002JB13
     1 CPU1_XTRIG_L4 @T6G_MB_LIB.T6G(SCH_1):CPU1_XTRIG_L4    I77 @T6G_MB_LIB.T6G(SCH_1):PAGE81
     2 FM_CPU1_XTRIG_L4 @T6G_MB_LIB.T6G(SCH_1):FM_CPU1_XTRIG_L4    I77 @T6G_MB_LIB.T6G(SCH_1):PAGE81

R205 Q_RES_0402LF-0,5%,1/16W,CHIP,CS00002JB13
     1 CPU1_XTRIG_L5 @T6G_MB_LIB.T6G(SCH_1):CPU1_XTRIG_L5    I74 @T6G_MB_LIB.T6G(SCH_1):PAGE81
     2 FM_CPU1_XTRIG_L5 @T6G_MB_LIB.T6G(SCH_1):FM_CPU1_XTRIG_L5    I74 @T6G_MB_LIB.T6G(SCH_1):PAGE81

R206 Q_RES_0402LF-0,5%,1/16W,CHIP,CS00002JB13
     1 SMB_CPU0_CPU1_APML_BUF2_SDA_R1 @T6G_MB_LIB.T6G(SCH_1):SMB_CPU0_CPU1_APML_BUF2_SDA_R1    I68 @T6G_MB_LIB.T6G(SCH_1):PAGE137
     2 SMB_CPU0_CPU1_APML_BUF2_SDA_R2 @T6G_MB_LIB.T6G(SCH_1):SMB_CPU0_CPU1_APML_BUF2_SDA_R2    I68 @T6G_MB_LIB.T6G(SCH_1):PAGE137

R207 Q_RES_0402LF-2.2K,5%,1/16W,CHIP,CS22202JB07
     1 FM_INT_CPU0_HP_UBM_N @T6G_MB_LIB.T6G(SCH_1):FM_INT_CPU0_HP_UBM_N    I44 @T6G_MB_LIB.T6G(SCH_1):PAGE28
     2 PVDD18_S5_P0 @T6G_MB_LIB.T6G(SCH_1):PVDD18_S5_P0    I44 @T6G_MB_LIB.T6G(SCH_1):PAGE28

R208 Q_RES_0402LF-33,5%,1/16W,CHIP,CS03302JB10
     1 PVDDCR_CPU0_P1_EN @T6G_MB_LIB.T6G(SCH_1):PVDDCR_CPU0_P1_EN    I65 @T6G_MB_LIB.T6G(SCH_1):PAGE80
     2 FM_PVDDCR_CPU0_P1_R_EN @T6G_MB_LIB.T6G(SCH_1):FM_PVDDCR_CPU0_P1_R_EN    I65 @T6G_MB_LIB.T6G(SCH_1):PAGE80

R209 Q_RES_0402LF-0,5%,1/16W,CHIP,CS00002JB13
     1 PWRGD_PVDDCR_CPU0_P1 @T6G_MB_LIB.T6G(SCH_1):PWRGD_PVDDCR_CPU0_P1    I61 @T6G_MB_LIB.T6G(SCH_1):PAGE80
     2 FM_PWRGD_PVDDCR_CPU0_P1 @T6G_MB_LIB.T6G(SCH_1):FM_PWRGD_PVDDCR_CPU0_P1    I61 @T6G_MB_LIB.T6G(SCH_1):PAGE80

R210 Q_RES_0402LF-0,5%,1/16W,CHIP,CS00002JB13
     1 SMB_2_PLD_3V3AUX_SCL_R1 @T6G_MB_LIB.T6G(SCH_1):SMB_2_PLD_3V3AUX_SCL_R1    I81 @T6G_MB_LIB.T6G(SCH_1):PAGE79
     2 SMB_2_PLD_3V3AUX_SCL_R2 @T6G_MB_LIB.T6G(SCH_1):SMB_2_PLD_3V3AUX_SCL_R2    I81 @T6G_MB_LIB.T6G(SCH_1):PAGE79

R211 Q_RES_0402LF-0,5%,1/16W,CHIP,CS00002JB13
     1 SMB_2_PLD_3V3AUX_SDA_R1 @T6G_MB_LIB.T6G(SCH_1):SMB_2_PLD_3V3AUX_SDA_R1    I80 @T6G_MB_LIB.T6G(SCH_1):PAGE79
     2 SMB_2_PLD_3V3AUX_SDA_R2 @T6G_MB_LIB.T6G(SCH_1):SMB_2_PLD_3V3AUX_SDA_R2    I80 @T6G_MB_LIB.T6G(SCH_1):PAGE79

R212 Q_RES_0402LF-33,5%,1/16W,CHIP,CS03302JB10
     1 SMB_CPU_5_R_SCL @T6G_MB_LIB.T6G(SCH_1):SMB_CPU_5_R_SCL    I96 @T6G_MB_LIB.T6G(SCH_1):PAGE28
     2 SMB_CPU_5_SCL @T6G_MB_LIB.T6G(SCH_1):SMB_CPU_5_SCL    I96 @T6G_MB_LIB.T6G(SCH_1):PAGE28

R213 Q_RES_0402LF-0,5%,1/16W,CHIP,CS00002JB13
     1 SMB_CPU_5_R_SDA @T6G_MB_LIB.T6G(SCH_1):SMB_CPU_5_R_SDA    I95 @T6G_MB_LIB.T6G(SCH_1):PAGE28
     2 SMB_CPU_5_SDA @T6G_MB_LIB.T6G(SCH_1):SMB_CPU_5_SDA    I95 @T6G_MB_LIB.T6G(SCH_1):PAGE28

R214 Q_RES_0402LF-33,5%,1/16W,CHIP,CS03302JB10
     1 PWRGD_P1V8_AUX @T6G_MB_LIB.T6G(SCH_1):PWRGD_P1V8_AUX    I44 @T6G_MB_LIB.T6G(SCH_1):PAGE315
     2 PWRGD_P1V8_AUX_R @T6G_MB_LIB.T6G(SCH_1):PWRGD_P1V8_AUX_R    I44 @T6G_MB_LIB.T6G(SCH_1):PAGE315

R215 Q_RES_0402LF-33,5%,1/16W,CHIP,CS03302JB10
     1 CPU0_PWR_BTN_N @T6G_MB_LIB.T6G(SCH_1):CPU0_PWR_BTN_N   I104 @T6G_MB_LIB.T6G(SCH_1):PAGE80
     2 FM_CPU0_PWR_BTN_N @T6G_MB_LIB.T6G(SCH_1):FM_CPU0_PWR_BTN_N   I104 @T6G_MB_LIB.T6G(SCH_1):PAGE80

R216 Q_RES_0402LF-33,5%,1/16W,CHIP,CS03302JB10
     1 RST_CPU0_SYS_N @T6G_MB_LIB.T6G(SCH_1):RST_CPU0_SYS_N   I117 @T6G_MB_LIB.T6G(SCH_1):PAGE80
     2 FM_CPU0_SYS_RESET_N @T6G_MB_LIB.T6G(SCH_1):FM_CPU0_SYS_RESET_N   I117 @T6G_MB_LIB.T6G(SCH_1):PAGE80

R217 Q_RES_0402LF-33,5%,1/16W,CHIP,CS03302JB10
     1 RST_CPU0_RSMRST_N @T6G_MB_LIB.T6G(SCH_1):RST_CPU0_RSMRST_N   I118 @T6G_MB_LIB.T6G(SCH_1):PAGE80
     2 FM_CPU0_RSMRST_N @T6G_MB_LIB.T6G(SCH_1):FM_CPU0_RSMRST_N   I118 @T6G_MB_LIB.T6G(SCH_1):PAGE80

R218 Q_RES_0402LF-33,5%,1/16W,CHIP,CS03302JB10
     1 CPU0_PWR_GOOD @T6G_MB_LIB.T6G(SCH_1):CPU0_PWR_GOOD    I32 @T6G_MB_LIB.T6G(SCH_1):PAGE80
     2 FM_CPU0_PWR_GOOD @T6G_MB_LIB.T6G(SCH_1):FM_CPU0_PWR_GOOD    I32 @T6G_MB_LIB.T6G(SCH_1):PAGE80

R219 Q_RES_0402LF-33,5%,1/16W,CHIP,CS03302JB10
     1 CPU0_NMI_SYNC_FLOOD_N @T6G_MB_LIB.T6G(SCH_1):CPU0_NMI_SYNC_FLOOD_N   I108 @T6G_MB_LIB.T6G(SCH_1):PAGE80
     2 FM_CPU0_NMI_SYNC_FLOOD_N @T6G_MB_LIB.T6G(SCH_1):FM_CPU0_NMI_SYNC_FLOOD_N   I108 @T6G_MB_LIB.T6G(SCH_1):PAGE80

R220 Q_RES_0402LF-33,5%,1/16W,CHIP,CS03302JB10
     1 FM_CPU0_SA0 @T6G_MB_LIB.T6G(SCH_1):FM_CPU0_SA0   I109 @T6G_MB_LIB.T6G(SCH_1):PAGE81
     2 CPU0_SA0 @T6G_MB_LIB.T6G(SCH_1):CPU0_SA0   I109 @T6G_MB_LIB.T6G(SCH_1):PAGE81

R221 Q_RES_0402LF-33,5%,1/16W,CHIP,CS03302JB10
     1 FM_CPU0_SA1 @T6G_MB_LIB.T6G(SCH_1):FM_CPU0_SA1   I107 @T6G_MB_LIB.T6G(SCH_1):PAGE81
     2 CPU0_SA1 @T6G_MB_LIB.T6G(SCH_1):CPU0_SA1   I107 @T6G_MB_LIB.T6G(SCH_1):PAGE81

R222 Q_RES_0402LF-0,5%,1/16W,CHIP,CS00002JB13
     1 CPU0_SP5R3 @T6G_MB_LIB.T6G(SCH_1):CPU0_SP5R3    I52 @T6G_MB_LIB.T6G(SCH_1):PAGE81
     2 FM_CPU0_SP5R3 @T6G_MB_LIB.T6G(SCH_1):FM_CPU0_SP5R3    I52 @T6G_MB_LIB.T6G(SCH_1):PAGE81

R223 Q_RES_0402LF-0,5%,1/16W,CHIP,CS00002JB13
     1 FM_CPU0_SP5R4 @T6G_MB_LIB.T6G(SCH_1):FM_CPU0_SP5R4   I100 @T6G_MB_LIB.T6G(SCH_1):PAGE81
     2 CPU0_SP5R4 @T6G_MB_LIB.T6G(SCH_1):CPU0_SP5R4   I100 @T6G_MB_LIB.T6G(SCH_1):PAGE81

R224 Q_RES_0402LF-33,5%,1/16W,CHIP,CS03302JB10
     1 PVDD33_S5_EN @T6G_MB_LIB.T6G(SCH_1):PVDD33_S5_EN    I36 @T6G_MB_LIB.T6G(SCH_1):PAGE80
     2 FM_PVDD33_S5_EN @T6G_MB_LIB.T6G(SCH_1):FM_PVDD33_S5_EN    I36 @T6G_MB_LIB.T6G(SCH_1):PAGE80

R225 Q_RES_0402LF-33,5%,1/16W,CHIP,CS03302JB10
     1 PWRGD_PVDD33_S5 @T6G_MB_LIB.T6G(SCH_1):PWRGD_PVDD33_S5    I33 @T6G_MB_LIB.T6G(SCH_1):PAGE167
     2 FM_PWRGD_PVDD33_S5 @T6G_MB_LIB.T6G(SCH_1):FM_PWRGD_PVDD33_S5    I33 @T6G_MB_LIB.T6G(SCH_1):PAGE167

R226 Q_RES_0402LF-0,5%,1/16W,CHIP,CS00002JB13
     1 FM_PVDD11_S3_P0_OCP_N @T6G_MB_LIB.T6G(SCH_1):FM_PVDD11_S3_P0_OCP_N   I111 @T6G_MB_LIB.T6G(SCH_1):PAGE81
     2 PVDD11_S3_P0_OCP_N @T6G_MB_LIB.T6G(SCH_1):PVDD11_S3_P0_OCP_N   I111 @T6G_MB_LIB.T6G(SCH_1):PAGE81

R227 Q_RES_0402LF-33,5%,1/16W,CHIP,CS03302JB10
     1 FM_PVDD11_S3_P0_EN @T6G_MB_LIB.T6G(SCH_1):FM_PVDD11_S3_P0_EN   I103 @T6G_MB_LIB.T6G(SCH_1):PAGE81
     2 PVDD11_S3_P0_EN @T6G_MB_LIB.T6G(SCH_1):PVDD11_S3_P0_EN   I103 @T6G_MB_LIB.T6G(SCH_1):PAGE81

R228 Q_RES_0402LF-0,5%,1/16W,CHIP,CS00002JB13
     1 PWRGD_PVDD11_S3_P0 @T6G_MB_LIB.T6G(SCH_1):PWRGD_PVDD11_S3_P0    I66 @T6G_MB_LIB.T6G(SCH_1):PAGE80
     2 FM_PWRGD_PVDD11_S3_P0 @T6G_MB_LIB.T6G(SCH_1):FM_PWRGD_PVDD11_S3_P0    I66 @T6G_MB_LIB.T6G(SCH_1):PAGE80

R229 Q_RES_0402LF-33,5%,1/16W,CHIP,CS03302JB10
     1 PVDDIO_P0_EN @T6G_MB_LIB.T6G(SCH_1):PVDDIO_P0_EN    I68 @T6G_MB_LIB.T6G(SCH_1):PAGE80
     2 FM_PVDDIO_P0_EN @T6G_MB_LIB.T6G(SCH_1):FM_PVDDIO_P0_EN    I68 @T6G_MB_LIB.T6G(SCH_1):PAGE80

R230 Q_RES_0402LF-0,5%,1/16W,CHIP,CS00002JB13
     1 PWRGD_PVDDIO_P0 @T6G_MB_LIB.T6G(SCH_1):PWRGD_PVDDIO_P0    I67 @T6G_MB_LIB.T6G(SCH_1):PAGE80
     2 FM_PWRGD_PVDDIO_P0 @T6G_MB_LIB.T6G(SCH_1):FM_PWRGD_PVDDIO_P0    I67 @T6G_MB_LIB.T6G(SCH_1):PAGE80

R231 Q_RES_0402LF-0,5%,1/16W,CHIP,CS00002JB13
     1 PVDDCR_CPU0_P0_OCP_N @T6G_MB_LIB.T6G(SCH_1):PVDDCR_CPU0_P0_OCP_N    I60 @T6G_MB_LIB.T6G(SCH_1):PAGE81
     2 FM_PVDDCR_CPU0_P0_OCP_N @T6G_MB_LIB.T6G(SCH_1):FM_PVDDCR_CPU0_P0_OCP_N    I60 @T6G_MB_LIB.T6G(SCH_1):PAGE81

R232 Q_RES_0402LF-33,5%,1/16W,CHIP,CS03302JB10
     1 FM_PVDDCR_CPU1_P0_EN @T6G_MB_LIB.T6G(SCH_1):FM_PVDDCR_CPU1_P0_EN    I51 @T6G_MB_LIB.T6G(SCH_1):PAGE81
     2 FM_PVDDCR_CPU1_P0_R_EN @T6G_MB_LIB.T6G(SCH_1):FM_PVDDCR_CPU1_P0_R_EN    I51 @T6G_MB_LIB.T6G(SCH_1):PAGE81

R233 Q_RES_0402LF-0,5%,1/16W,CHIP,CS00002JB13
     1 PWRGD_PVDDCR_CPU1_P0 @T6G_MB_LIB.T6G(SCH_1):PWRGD_PVDDCR_CPU1_P0    I54 @T6G_MB_LIB.T6G(SCH_1):PAGE81
     2 FM_PWRGD_PVDDCR_CPU1_P0 @T6G_MB_LIB.T6G(SCH_1):FM_PWRGD_PVDDCR_CPU1_P0    I54 @T6G_MB_LIB.T6G(SCH_1):PAGE81

R234 Q_RES_0402LF-0,5%,1/16W,CHIP,CS00002JB13
     1 CPU1_XTRIG_L6 @T6G_MB_LIB.T6G(SCH_1):CPU1_XTRIG_L6    I75 @T6G_MB_LIB.T6G(SCH_1):PAGE81
     2 FM_CPU1_XTRIG_L6 @T6G_MB_LIB.T6G(SCH_1):FM_CPU1_XTRIG_L6    I75 @T6G_MB_LIB.T6G(SCH_1):PAGE81

R235 Q_RES_0402LF-0,5%,1/16W,CHIP,CS00002JB13
     1 CPU1_XTRIG_L7 @T6G_MB_LIB.T6G(SCH_1):CPU1_XTRIG_L7    I70 @T6G_MB_LIB.T6G(SCH_1):PAGE81
     2 FM_CPU1_XTRIG_L7 @T6G_MB_LIB.T6G(SCH_1):FM_CPU1_XTRIG_L7    I70 @T6G_MB_LIB.T6G(SCH_1):PAGE81

R236 Q_RES_0402LF-0,5%,1/16W,CHIP,CS00002JB13
     1 CPU0_XTRIG_L4 @T6G_MB_LIB.T6G(SCH_1):CPU0_XTRIG_L4    I66 @T6G_MB_LIB.T6G(SCH_1):PAGE81
     2 FM_CPU0_XTRIG_L4 @T6G_MB_LIB.T6G(SCH_1):FM_CPU0_XTRIG_L4    I66 @T6G_MB_LIB.T6G(SCH_1):PAGE81

R237 Q_RES_0402LF-0,5%,1/16W,CHIP,CS00002JB13
     1 CPU0_XTRIG_L5 @T6G_MB_LIB.T6G(SCH_1):CPU0_XTRIG_L5    I69 @T6G_MB_LIB.T6G(SCH_1):PAGE81
     2 FM_CPU0_XTRIG_L5 @T6G_MB_LIB.T6G(SCH_1):FM_CPU0_XTRIG_L5    I69 @T6G_MB_LIB.T6G(SCH_1):PAGE81

R238 Q_RES_0402LF-0,5%,1/16W,CHIP,CS00002JB13
     1 CPU0_XTRIG_L6 @T6G_MB_LIB.T6G(SCH_1):CPU0_XTRIG_L6    I71 @T6G_MB_LIB.T6G(SCH_1):PAGE81
     2 FM_CPU0_XTRIG_L6 @T6G_MB_LIB.T6G(SCH_1):FM_CPU0_XTRIG_L6    I71 @T6G_MB_LIB.T6G(SCH_1):PAGE81

R239 Q_RES_0402LF-0,5%,1/16W,CHIP,CS00002JB13
     1 CPU0_XTRIG_L7 @T6G_MB_LIB.T6G(SCH_1):CPU0_XTRIG_L7    I62 @T6G_MB_LIB.T6G(SCH_1):PAGE81
     2 FM_CPU0_XTRIG_L7 @T6G_MB_LIB.T6G(SCH_1):FM_CPU0_XTRIG_L7    I62 @T6G_MB_LIB.T6G(SCH_1):PAGE81

R240 Q_RES_0402LF-100,1%,1/16W,CHIP,CS11002FB07
     1 PVDDCR_CPU1_P1_RESET_N @T6G_MB_LIB.T6G(SCH_1):PVDDCR_CPU1_P1_RESET_N    I65 @T6G_MB_LIB.T6G(SCH_1):PAGE192
     2 PVDDCR_CPU1_P1_RESET_N_R @T6G_MB_LIB.T6G(SCH_1):PVDDCR_CPU1_P1_RESET_N_R    I65 @T6G_MB_LIB.T6G(SCH_1):PAGE192

R241 Q_RES_0402LF-0,5%,1/16W,CHIP,CS00002JB13
     1 RST_CPU0_RESETL_N @T6G_MB_LIB.T6G(SCH_1):RST_CPU0_RESETL_N   I114 @T6G_MB_LIB.T6G(SCH_1):PAGE80
     2 FM_RST_CPU0_RESETL_N @T6G_MB_LIB.T6G(SCH_1):FM_RST_CPU0_RESETL_N   I114 @T6G_MB_LIB.T6G(SCH_1):PAGE80

R242 Q_RES_0402LF-0,5%,1/16W,CHIP,CS00002JB13
     1 PWRGD_CPU0_PWROK @T6G_MB_LIB.T6G(SCH_1):PWRGD_CPU0_PWROK   I110 @T6G_MB_LIB.T6G(SCH_1):PAGE80
     2 FM_PWRGD_CPU0_PWROK @T6G_MB_LIB.T6G(SCH_1):FM_PWRGD_CPU0_PWROK   I110 @T6G_MB_LIB.T6G(SCH_1):PAGE80

R243 Q_RES_0402LF-0,5%,1/16W,CHIP,CS00002JB13
     1 FM_SMM_CRASHDUMP @T6G_MB_LIB.T6G(SCH_1):FM_SMM_CRASHDUMP    I63 @T6G_MB_LIB.T6G(SCH_1):PAGE81
     2 FM_SMM_CRASHDUMP_R @T6G_MB_LIB.T6G(SCH_1):FM_SMM_CRASHDUMP_R    I63 @T6G_MB_LIB.T6G(SCH_1):PAGE81

R244 Q_RES_0402LF-0,5%,1/16W,CHIP,CS00002JB13
     1 IRQ_BMC_SMI_N @T6G_MB_LIB.T6G(SCH_1):IRQ_BMC_SMI_N    I72 @T6G_MB_LIB.T6G(SCH_1):PAGE81
     2 IRQ_BMC_SMI_R_N @T6G_MB_LIB.T6G(SCH_1):IRQ_BMC_SMI_R_N    I72 @T6G_MB_LIB.T6G(SCH_1):PAGE81

R245 Q_RES_0402LF-0,5%,1/16W,CHIP,CS00002JB13
     1 IRQ_SMI_ACTIVE_N @T6G_MB_LIB.T6G(SCH_1):IRQ_SMI_ACTIVE_N    I67 @T6G_MB_LIB.T6G(SCH_1):PAGE81
     2 IRQ_SMI_ACTIVE_N_R @T6G_MB_LIB.T6G(SCH_1):IRQ_SMI_ACTIVE_N_R    I67 @T6G_MB_LIB.T6G(SCH_1):PAGE81

R246 Q_RES_0402LF-0,5%,1/16W,CHIP,CS00002JB13
     1 IRQ_TPM_SPI_R_N @T6G_MB_LIB.T6G(SCH_1):IRQ_TPM_SPI_R_N    I65 @T6G_MB_LIB.T6G(SCH_1):PAGE81
     2 IRQ_TPM_SPI_R1_N @T6G_MB_LIB.T6G(SCH_1):IRQ_TPM_SPI_R1_N    I65 @T6G_MB_LIB.T6G(SCH_1):PAGE81

R247 Q_RES_0402LF-33,5%,1/16W,CHIP,CS03302JB10
     1 APML_CPU0_ALERT_N @T6G_MB_LIB.T6G(SCH_1):APML_CPU0_ALERT_N   I401 @T6G_MB_LIB.T6G(SCH_1):PAGE27
     2 APML_CPU0_ALERT_R_N @T6G_MB_LIB.T6G(SCH_1):APML_CPU0_ALERT_R_N   I401 @T6G_MB_LIB.T6G(SCH_1):PAGE27

R248 Q_RES_0402LF-33,5%,1/16W,CHIP,CS03302JB10
     1 FM_CPU0_SLP_S5_N @T6G_MB_LIB.T6G(SCH_1):FM_CPU0_SLP_S5_N   I136 @T6G_MB_LIB.T6G(SCH_1):PAGE28
     2 CPU0_SLP_S5_N @T6G_MB_LIB.T6G(SCH_1):CPU0_SLP_S5_N   I136 @T6G_MB_LIB.T6G(SCH_1):PAGE28

R249 Q_RES_0402LF-33,5%,1/16W,CHIP,CS03302JB10
     1 FM_CPU0_SLP_S3_N @T6G_MB_LIB.T6G(SCH_1):FM_CPU0_SLP_S3_N   I135 @T6G_MB_LIB.T6G(SCH_1):PAGE28
     2 CPU0_SLP_S3_N @T6G_MB_LIB.T6G(SCH_1):CPU0_SLP_S3_N   I135 @T6G_MB_LIB.T6G(SCH_1):PAGE28

R250 Q_RES_0402LF-0,5%,1/16W,CHIP,CS00002JB13
     1 FM_CPU0_SMERR_N @T6G_MB_LIB.T6G(SCH_1):FM_CPU0_SMERR_N   I180 @T6G_MB_LIB.T6G(SCH_1):PAGE80
     2 CPU0_SMERR_N @T6G_MB_LIB.T6G(SCH_1):CPU0_SMERR_N   I180 @T6G_MB_LIB.T6G(SCH_1):PAGE80

R251 Q_RES_0402LF-0,5%,1/16W,CHIP,CS00002JB13
     1 CPU0_SPD_HOST_CTRL_R1_N @T6G_MB_LIB.T6G(SCH_1):CPU0_SPD_HOST_CTRL_R1_N   I162 @T6G_MB_LIB.T6G(SCH_1):PAGE80
     2 CPU0_SPD_HOST_CTRL_N @T6G_MB_LIB.T6G(SCH_1):CPU0_SPD_HOST_CTRL_N   I162 @T6G_MB_LIB.T6G(SCH_1):PAGE80

R252 Q_RES_0402LF-0,5%,1/16W,CHIP,CS00002JB13
     1 FM_CPU1_PWR_GD_IN @T6G_MB_LIB.T6G(SCH_1):FM_CPU1_PWR_GD_IN   I128 @T6G_MB_LIB.T6G(SCH_1):PAGE80
     2 CPU1_PWR_GD_IN @T6G_MB_LIB.T6G(SCH_1):CPU1_PWR_GD_IN   I128 @T6G_MB_LIB.T6G(SCH_1):PAGE80

R253 Q_RES_0402LF-0,5%,1/16W,CHIP,CS00002JB13
     1 CPU0_NV_SAVE_N @T6G_MB_LIB.T6G(SCH_1):CPU0_NV_SAVE_N   I116 @T6G_MB_LIB.T6G(SCH_1):PAGE80
     2 FM_CPU0_NV_SAVE_N @T6G_MB_LIB.T6G(SCH_1):FM_CPU0_NV_SAVE_N   I116 @T6G_MB_LIB.T6G(SCH_1):PAGE80

R254 Q_RES_0402LF-0,5%,1/16W,CHIP,CS00002JB13
     1 RST_CPU0_PERST0_N @T6G_MB_LIB.T6G(SCH_1):RST_CPU0_PERST0_N   I123 @T6G_MB_LIB.T6G(SCH_1):PAGE80
     2 RST_CPU0_PERST0_R_N @T6G_MB_LIB.T6G(SCH_1):RST_CPU0_PERST0_R_N   I123 @T6G_MB_LIB.T6G(SCH_1):PAGE80

R255 Q_RES_0402LF-0,5%,1/16W,CHIP,CS00002JB13
     1 RST_CPU0_PERST1_N @T6G_MB_LIB.T6G(SCH_1):RST_CPU0_PERST1_N   I121 @T6G_MB_LIB.T6G(SCH_1):PAGE80
     2 RST_CPU0_PERST1_R_N @T6G_MB_LIB.T6G(SCH_1):RST_CPU0_PERST1_R_N   I121 @T6G_MB_LIB.T6G(SCH_1):PAGE80

R256 Q_RES_0402LF-0,5%,1/16W,EMPTY,CS00002JB13
     1 SMB_CPU0_CPU1_APML_BUF1_SCL_R2 @T6G_MB_LIB.T6G(SCH_1):SMB_CPU0_CPU1_APML_BUF1_SCL_R2    I92 @T6G_MB_LIB.T6G(SCH_1):PAGE137
     2 SMB_CPU0_CPU1_APML_SCL_R2 @T6G_MB_LIB.T6G(SCH_1):SMB_CPU0_CPU1_APML_SCL_R2    I92 @T6G_MB_LIB.T6G(SCH_1):PAGE137

R257 Q_RES_0402LF-0,5%,1/16W,EMPTY,CS00002JB13
     1 SMB_CPU0_CPU1_APML_BUF1_SDA_R2 @T6G_MB_LIB.T6G(SCH_1):SMB_CPU0_CPU1_APML_BUF1_SDA_R2    I91 @T6G_MB_LIB.T6G(SCH_1):PAGE137
     2 SMB_CPU0_CPU1_APML_SDA_R2 @T6G_MB_LIB.T6G(SCH_1):SMB_CPU0_CPU1_APML_SDA_R2    I91 @T6G_MB_LIB.T6G(SCH_1):PAGE137

R258 Q_RES_0402LF-0,5%,1/16W,CHIP,CS00002JB13
     1 FM_CPU0_HDT_CONN_TESTEN @T6G_MB_LIB.T6G(SCH_1):FM_CPU0_HDT_CONN_TESTEN   I177 @T6G_MB_LIB.T6G(SCH_1):PAGE80
     2 CPU0_HDT_CONN_TESTEN @T6G_MB_LIB.T6G(SCH_1):CPU0_HDT_CONN_TESTEN   I177 @T6G_MB_LIB.T6G(SCH_1):PAGE80

R259 Q_RES_0402LF-33,5%,1/16W,CHIP,CS03302JB10
     1 PWRGD_PVDD18_S5_P1 @T6G_MB_LIB.T6G(SCH_1):PWRGD_PVDD18_S5_P1    I48 @T6G_MB_LIB.T6G(SCH_1):PAGE201
     2 PWRGD_PVDD18_S5_R_P1 @T6G_MB_LIB.T6G(SCH_1):PWRGD_PVDD18_S5_R_P1    I48 @T6G_MB_LIB.T6G(SCH_1):PAGE201

R260 Q_RES_0402LF-0,5%,1/16W,CHIP,CS00002JB13
     1 CPU1_SP5R1 @T6G_MB_LIB.T6G(SCH_1):CPU1_SP5R1    I49 @T6G_MB_LIB.T6G(SCH_1):PAGE81
     2 FM_CPU1_SP5R1 @T6G_MB_LIB.T6G(SCH_1):FM_CPU1_SP5R1    I49 @T6G_MB_LIB.T6G(SCH_1):PAGE81

R261 Q_RES_0402LF-0,5%,1/16W,CHIP,CS00002JB13
     1 CPU1_SP5R2 @T6G_MB_LIB.T6G(SCH_1):CPU1_SP5R2    I50 @T6G_MB_LIB.T6G(SCH_1):PAGE81
     2 FM_CPU1_SP5R2 @T6G_MB_LIB.T6G(SCH_1):FM_CPU1_SP5R2    I50 @T6G_MB_LIB.T6G(SCH_1):PAGE81

R262 Q_RES_0402LF-0,5%,1/16W,CHIP,CS00002JB13
     1 CPU1_CORETYPE0 @T6G_MB_LIB.T6G(SCH_1):CPU1_CORETYPE0    I44 @T6G_MB_LIB.T6G(SCH_1):PAGE81
     2 FM_CPU1_CORETYPE0 @T6G_MB_LIB.T6G(SCH_1):FM_CPU1_CORETYPE0    I44 @T6G_MB_LIB.T6G(SCH_1):PAGE81

R263 Q_RES_0402LF-0,5%,1/16W,CHIP,CS00002JB13
     1 CPU1_CORETYPE1 @T6G_MB_LIB.T6G(SCH_1):CPU1_CORETYPE1    I47 @T6G_MB_LIB.T6G(SCH_1):PAGE81
     2 FM_CPU1_CORETYPE1 @T6G_MB_LIB.T6G(SCH_1):FM_CPU1_CORETYPE1    I47 @T6G_MB_LIB.T6G(SCH_1):PAGE81

R264 Q_RES_0402LF-0,5%,1/16W,CHIP,CS00002JB13
     1 CPU1_CORETYPE2 @T6G_MB_LIB.T6G(SCH_1):CPU1_CORETYPE2    I53 @T6G_MB_LIB.T6G(SCH_1):PAGE81
     2 FM_CPU1_CORETYPE2 @T6G_MB_LIB.T6G(SCH_1):FM_CPU1_CORETYPE2    I53 @T6G_MB_LIB.T6G(SCH_1):PAGE81

R265 Q_RES_0402LF-33,5%,1/16W,CHIP,CS03302JB10
     1 FM_CPU1_FORCE_SELFREFRESH @T6G_MB_LIB.T6G(SCH_1):FM_CPU1_FORCE_SELFREFRESH   I126 @T6G_MB_LIB.T6G(SCH_1):PAGE80
     2 CPU1_FORCE_SELFREFRESH @T6G_MB_LIB.T6G(SCH_1):CPU1_FORCE_SELFREFRESH   I126 @T6G_MB_LIB.T6G(SCH_1):PAGE80

R266 Q_RES_0402LF-33,5%,1/16W,CHIP,CS03302JB10
     1 FM_CPU1_SA0 @T6G_MB_LIB.T6G(SCH_1):FM_CPU1_SA0   I108 @T6G_MB_LIB.T6G(SCH_1):PAGE81
     2 CPU1_SA0 @T6G_MB_LIB.T6G(SCH_1):CPU1_SA0   I108 @T6G_MB_LIB.T6G(SCH_1):PAGE81

R267 Q_RES_0402LF-33,5%,1/16W,CHIP,CS03302JB10
     1 CPU1_SA1 @T6G_MB_LIB.T6G(SCH_1):CPU1_SA1    I73 @T6G_MB_LIB.T6G(SCH_1):PAGE81
     2 FM_CPU1_SA1 @T6G_MB_LIB.T6G(SCH_1):FM_CPU1_SA1    I73 @T6G_MB_LIB.T6G(SCH_1):PAGE81

R268 Q_RES_0402LF-0,5%,1/16W,CHIP,CS00002JB13
     1 CPU1_SP5R3 @T6G_MB_LIB.T6G(SCH_1):CPU1_SP5R3    I55 @T6G_MB_LIB.T6G(SCH_1):PAGE81
     2 FM_CPU1_SP5R3 @T6G_MB_LIB.T6G(SCH_1):FM_CPU1_SP5R3    I55 @T6G_MB_LIB.T6G(SCH_1):PAGE81

R269 Q_RES_0402LF-0,5%,1/16W,CHIP,CS00002JB13
     1 CPU1_SP5R4 @T6G_MB_LIB.T6G(SCH_1):CPU1_SP5R4    I56 @T6G_MB_LIB.T6G(SCH_1):PAGE81
     2 FM_CPU1_SP5R4 @T6G_MB_LIB.T6G(SCH_1):FM_CPU1_SP5R4    I56 @T6G_MB_LIB.T6G(SCH_1):PAGE81

R270 Q_RES_0402LF-33,5%,1/16W,CHIP,CS03302JB10
     1 FM_CPU1_PROCHOT_R_N @T6G_MB_LIB.T6G(SCH_1):FM_CPU1_PROCHOT_R_N   I112 @T6G_MB_LIB.T6G(SCH_1):PAGE81
     2 CPU1_PROCHOT_N @T6G_MB_LIB.T6G(SCH_1):CPU1_PROCHOT_N   I112 @T6G_MB_LIB.T6G(SCH_1):PAGE81

R271 Q_RES_0402LF-0,5%,1/16W,CHIP,CS00002JB13
     1 FM_PRSNT_CPU1_R_N @T6G_MB_LIB.T6G(SCH_1):FM_PRSNT_CPU1_R_N   I104 @T6G_MB_LIB.T6G(SCH_1):PAGE81
     2 FM_PRSNT_CPU1_N @T6G_MB_LIB.T6G(SCH_1):FM_PRSNT_CPU1_N   I104 @T6G_MB_LIB.T6G(SCH_1):PAGE81

R272 Q_RES_0402LF-0,5%,1/16W,EMPTY,CS00002JB13
     1 RST_CPU1_SYS_N @T6G_MB_LIB.T6G(SCH_1):RST_CPU1_SYS_N   I115 @T6G_MB_LIB.T6G(SCH_1):PAGE80
     2 FM_CPU1_SYS_RESET_N @T6G_MB_LIB.T6G(SCH_1):FM_CPU1_SYS_RESET_N   I115 @T6G_MB_LIB.T6G(SCH_1):PAGE80

R273 Q_RES_0402LF-33,5%,1/16W,CHIP,CS03302JB10
     1 RST_CPU1_RSMRST_N @T6G_MB_LIB.T6G(SCH_1):RST_CPU1_RSMRST_N   I119 @T6G_MB_LIB.T6G(SCH_1):PAGE80
     2 FM_CPU1_RSMRST_N @T6G_MB_LIB.T6G(SCH_1):FM_CPU1_RSMRST_N   I119 @T6G_MB_LIB.T6G(SCH_1):PAGE80

R274 Q_RES_0402LF-0,5%,1/16W,CHIP,CS00002JB13
     1 SMB_CPU0_CPU1_APML_BUF2_SCL_R2 @T6G_MB_LIB.T6G(SCH_1):SMB_CPU0_CPU1_APML_BUF2_SCL_R2    I71 @T6G_MB_LIB.T6G(SCH_1):PAGE137
     2 SMB_CPU0_CPU1_APML_SCL_R2 @T6G_MB_LIB.T6G(SCH_1):SMB_CPU0_CPU1_APML_SCL_R2    I71 @T6G_MB_LIB.T6G(SCH_1):PAGE137

R275 Q_RES_0402LF-33,5%,1/16W,CHIP,CS03302JB10
     1 CLR_CMOS @T6G_MB_LIB.T6G(SCH_1):CLR_CMOS    I84 @T6G_MB_LIB.T6G(SCH_1):PAGE81
     2 FM_CLR_CMOS @T6G_MB_LIB.T6G(SCH_1):FM_CLR_CMOS    I84 @T6G_MB_LIB.T6G(SCH_1):PAGE81

R276 Q_RES_0402LF-4.7K,5%,1/16W,CHIP,CS24702JB10
     1 CPU0_PWR_GOOD @T6G_MB_LIB.T6G(SCH_1):CPU0_PWR_GOOD    I41 @T6G_MB_LIB.T6G(SCH_1):PAGE28
     2 PVDD18_S5_P0 @T6G_MB_LIB.T6G(SCH_1):PVDD18_S5_P0    I41 @T6G_MB_LIB.T6G(SCH_1):PAGE28

R277 Q_RES_0402LF-33,5%,1/16W,CHIP,CS03302JB10
     1 FM_CPU1_NMI_SYNC_FLOOD_N @T6G_MB_LIB.T6G(SCH_1):FM_CPU1_NMI_SYNC_FLOOD_N   I165 @T6G_MB_LIB.T6G(SCH_1):PAGE80
     2 CPU1_NMI_SYNC_FLOOD_N @T6G_MB_LIB.T6G(SCH_1):CPU1_NMI_SYNC_FLOOD_N   I165 @T6G_MB_LIB.T6G(SCH_1):PAGE80

R278 Q_RES_0402LF-0,5%,1/16W,CHIP,CS00002JB13
     1 FM_PVDD11_S3_P1_OCP_N @T6G_MB_LIB.T6G(SCH_1):FM_PVDD11_S3_P1_OCP_N   I113 @T6G_MB_LIB.T6G(SCH_1):PAGE81
     2 PVDD11_S3_P1_OCP_N @T6G_MB_LIB.T6G(SCH_1):PVDD11_S3_P1_OCP_N   I113 @T6G_MB_LIB.T6G(SCH_1):PAGE81

R279 Q_RES_0402LF-33,5%,1/16W,CHIP,CS03302JB10
     1 PVDD11_S3_P1_EN @T6G_MB_LIB.T6G(SCH_1):PVDD11_S3_P1_EN    I58 @T6G_MB_LIB.T6G(SCH_1):PAGE80
     2 FM_PVDD11_S3_P1_EN @T6G_MB_LIB.T6G(SCH_1):FM_PVDD11_S3_P1_EN    I58 @T6G_MB_LIB.T6G(SCH_1):PAGE80

R280 Q_RES_0402LF-0,5%,1/16W,CHIP,CS00002JB13
     1 PWRGD_PVDD11_S3_P1 @T6G_MB_LIB.T6G(SCH_1):PWRGD_PVDD11_S3_P1    I59 @T6G_MB_LIB.T6G(SCH_1):PAGE80
     2 FM_PWRGD_PVDD11_S3_P1 @T6G_MB_LIB.T6G(SCH_1):FM_PWRGD_PVDD11_S3_P1    I59 @T6G_MB_LIB.T6G(SCH_1):PAGE80

R281 Q_RES_0402LF-0,5%,1/16W,CHIP,CS00002JB13
     1 SMB_CPU0_CPU1_APML_BUF2_SDA_R2 @T6G_MB_LIB.T6G(SCH_1):SMB_CPU0_CPU1_APML_BUF2_SDA_R2    I72 @T6G_MB_LIB.T6G(SCH_1):PAGE137
     2 SMB_CPU0_CPU1_APML_SDA_R2 @T6G_MB_LIB.T6G(SCH_1):SMB_CPU0_CPU1_APML_SDA_R2    I72 @T6G_MB_LIB.T6G(SCH_1):PAGE137

R282 Q_RES_0402LF-33,5%,1/16W,CHIP,CS03302JB10
     1 PVDDIO_P1_EN @T6G_MB_LIB.T6G(SCH_1):PVDDIO_P1_EN    I31 @T6G_MB_LIB.T6G(SCH_1):PAGE80
     2 FM_PVDDIO_P1_EN @T6G_MB_LIB.T6G(SCH_1):FM_PVDDIO_P1_EN    I31 @T6G_MB_LIB.T6G(SCH_1):PAGE80

R283 Q_RES_0402LF-0,5%,1/16W,CHIP,CS00002JB13
     1 PWRGD_PVDDIO_P1 @T6G_MB_LIB.T6G(SCH_1):PWRGD_PVDDIO_P1    I30 @T6G_MB_LIB.T6G(SCH_1):PAGE80
     2 FM_PWRGD_PVDDIO_P1 @T6G_MB_LIB.T6G(SCH_1):FM_PWRGD_PVDDIO_P1    I30 @T6G_MB_LIB.T6G(SCH_1):PAGE80

R284 Q_RES_0402LF-0,5%,1/16W,CHIP,CS00002JB13
     1 FM_PVDDCR_CPU0_P1_OCP_N @T6G_MB_LIB.T6G(SCH_1):FM_PVDDCR_CPU0_P1_OCP_N   I140 @T6G_MB_LIB.T6G(SCH_1):PAGE81
     2 PVDDCR_CPU0_P1_OCP_N @T6G_MB_LIB.T6G(SCH_1):PVDDCR_CPU0_P1_OCP_N   I140 @T6G_MB_LIB.T6G(SCH_1):PAGE81

R285 Q_RES_0402LF-33,5%,1/16W,CHIP,CS03302JB10
     1 FM_PVDDCR_CPU1_P1_R_EN @T6G_MB_LIB.T6G(SCH_1):FM_PVDDCR_CPU1_P1_R_EN   I105 @T6G_MB_LIB.T6G(SCH_1):PAGE81
     2 FM_PVDDCR_CPU1_P1_EN @T6G_MB_LIB.T6G(SCH_1):FM_PVDDCR_CPU1_P1_EN   I105 @T6G_MB_LIB.T6G(SCH_1):PAGE81

R286 Q_RES_0402LF-0,5%,1/16W,CHIP,CS00002JB13
     1 PWRGD_PVDDCR_CPU1_P1 @T6G_MB_LIB.T6G(SCH_1):PWRGD_PVDDCR_CPU1_P1    I62 @T6G_MB_LIB.T6G(SCH_1):PAGE80
     2 FM_PWRGD_PVDDCR_CPU1_P1 @T6G_MB_LIB.T6G(SCH_1):FM_PWRGD_PVDDCR_CPU1_P1    I62 @T6G_MB_LIB.T6G(SCH_1):PAGE80

R287 Q_RES_0402LF-4.7K,5%,1/16W,EMPTY,CS24702JB10
     1    GND @T6G_MB_LIB.T6G(SCH_1):GND    I36 @T6G_MB_LIB.T6G(SCH_1):PAGE28
     2 CPU0_PWR_GOOD @T6G_MB_LIB.T6G(SCH_1):CPU0_PWR_GOOD    I36 @T6G_MB_LIB.T6G(SCH_1):PAGE28

R288 Q_RES_0402LF-4.7K,5%,1/16W,EMPTY,CS24702JB10
     1 CPU0_PWR_GD_OUT @T6G_MB_LIB.T6G(SCH_1):CPU0_PWR_GD_OUT    I42 @T6G_MB_LIB.T6G(SCH_1):PAGE28
     2 PVDD18_S5_P0 @T6G_MB_LIB.T6G(SCH_1):PVDD18_S5_P0    I42 @T6G_MB_LIB.T6G(SCH_1):PAGE28

R289 Q_RES_0402LF-33,5%,1/16W,CHIP,CS03302JB10
     1 PVDD18_S5_P1_EN @T6G_MB_LIB.T6G(SCH_1):PVDD18_S5_P1_EN    I57 @T6G_MB_LIB.T6G(SCH_1):PAGE80
     2 PVDD18_S5_P1_R_EN @T6G_MB_LIB.T6G(SCH_1):PVDD18_S5_P1_R_EN    I57 @T6G_MB_LIB.T6G(SCH_1):PAGE80

R290 Q_RES_0402LF-1K,1%,1/16W,EMPTY,CS21002FB06
     1 PVDD11_S3_P0 @T6G_MB_LIB.T6G(SCH_1):PVDD11_S3_P0    I78 @T6G_MB_LIB.T6G(SCH_1):PAGE137
     2 SMB_CPU0_CPU1_APML_BUF2_SDA_R2 @T6G_MB_LIB.T6G(SCH_1):SMB_CPU0_CPU1_APML_BUF2_SDA_R2    I78 @T6G_MB_LIB.T6G(SCH_1):PAGE137

R291 Q_RES_0402LF-1K,1%,1/16W,CHIP,CS21002FB06
     1 PWRGD_CHA_CPU0_DIMM0 @T6G_MB_LIB.T6G(SCH_1):PWRGD_CHA_CPU0_DIMM0   I525 @T6G_MB_LIB.T6G(SCH_1):PAGE85
     2 PWRGD_CHAF_CPU0 @T6G_MB_LIB.T6G(SCH_1):PWRGD_CHAF_CPU0   I525 @T6G_MB_LIB.T6G(SCH_1):PAGE85

R292 Q_RES_0402LF-1K,1%,1/16W,CHIP,CS21002FB06
     1 PWRGD_CHB_CPU0_DIMM @T6G_MB_LIB.T6G(SCH_1):PWRGD_CHB_CPU0_DIMM   I364 @T6G_MB_LIB.T6G(SCH_1):PAGE86
     2 PWRGD_CHAF_CPU0 @T6G_MB_LIB.T6G(SCH_1):PWRGD_CHAF_CPU0   I364 @T6G_MB_LIB.T6G(SCH_1):PAGE86

R293 Q_RES_0402LF-1K,1%,1/16W,CHIP,CS21002FB06
     1 PWRGD_CHC_CPU0_DIMM @T6G_MB_LIB.T6G(SCH_1):PWRGD_CHC_CPU0_DIMM   I364 @T6G_MB_LIB.T6G(SCH_1):PAGE87
     2 PWRGD_CHAF_CPU0 @T6G_MB_LIB.T6G(SCH_1):PWRGD_CHAF_CPU0   I364 @T6G_MB_LIB.T6G(SCH_1):PAGE87

R294 Q_RES_0402LF-1K,1%,1/16W,CHIP,CS21002FB06
     1 PWRGD_CHD_CPU0_DIMM @T6G_MB_LIB.T6G(SCH_1):PWRGD_CHD_CPU0_DIMM   I369 @T6G_MB_LIB.T6G(SCH_1):PAGE88
     2 PWRGD_CHAF_CPU0 @T6G_MB_LIB.T6G(SCH_1):PWRGD_CHAF_CPU0   I369 @T6G_MB_LIB.T6G(SCH_1):PAGE88

R295 Q_RES_0402LF-1K,1%,1/16W,CHIP,CS21002FB06
     1 PWRGD_CHE_CPU0_DIMM @T6G_MB_LIB.T6G(SCH_1):PWRGD_CHE_CPU0_DIMM   I362 @T6G_MB_LIB.T6G(SCH_1):PAGE89
     2 PWRGD_CHAF_CPU0 @T6G_MB_LIB.T6G(SCH_1):PWRGD_CHAF_CPU0   I362 @T6G_MB_LIB.T6G(SCH_1):PAGE89

R296 Q_RES_0402LF-1K,1%,1/16W,CHIP,CS21002FB06
     1 PWRGD_CHF_CPU0_DIMM @T6G_MB_LIB.T6G(SCH_1):PWRGD_CHF_CPU0_DIMM   I364 @T6G_MB_LIB.T6G(SCH_1):PAGE90
     2 PWRGD_CHAF_CPU0 @T6G_MB_LIB.T6G(SCH_1):PWRGD_CHAF_CPU0   I364 @T6G_MB_LIB.T6G(SCH_1):PAGE90

R297 Q_RES_0402LF-1K,1%,1/16W,CHIP,CS21002FB06
     1 PWRGD_CHG_CPU0_DIMM0 @T6G_MB_LIB.T6G(SCH_1):PWRGD_CHG_CPU0_DIMM0   I186 @T6G_MB_LIB.T6G(SCH_1):PAGE91
     2 PWRGD_CHGL_CPU0 @T6G_MB_LIB.T6G(SCH_1):PWRGD_CHGL_CPU0   I186 @T6G_MB_LIB.T6G(SCH_1):PAGE91

R298 Q_RES_0402LF-1K,1%,1/16W,CHIP,CS21002FB06
     1 PWRGD_CHH_CPU0_DIMM @T6G_MB_LIB.T6G(SCH_1):PWRGD_CHH_CPU0_DIMM   I189 @T6G_MB_LIB.T6G(SCH_1):PAGE92
     2 PWRGD_CHGL_CPU0 @T6G_MB_LIB.T6G(SCH_1):PWRGD_CHGL_CPU0   I189 @T6G_MB_LIB.T6G(SCH_1):PAGE92

R299 Q_RES_0402LF-1K,1%,1/16W,CHIP,CS21002FB06
     1 PWRGD_CHI_CPU0_DIMM @T6G_MB_LIB.T6G(SCH_1):PWRGD_CHI_CPU0_DIMM   I188 @T6G_MB_LIB.T6G(SCH_1):PAGE93
     2 PWRGD_CHGL_CPU0 @T6G_MB_LIB.T6G(SCH_1):PWRGD_CHGL_CPU0   I188 @T6G_MB_LIB.T6G(SCH_1):PAGE93

R300 Q_RES_0402LF-1K,1%,1/16W,CHIP,CS21002FB06
     1 PWRGD_CHJ_CPU0_DIMM @T6G_MB_LIB.T6G(SCH_1):PWRGD_CHJ_CPU0_DIMM   I188 @T6G_MB_LIB.T6G(SCH_1):PAGE94
     2 PWRGD_CHGL_CPU0 @T6G_MB_LIB.T6G(SCH_1):PWRGD_CHGL_CPU0   I188 @T6G_MB_LIB.T6G(SCH_1):PAGE94

R301 Q_RES_0402LF-1K,1%,1/16W,CHIP,CS21002FB06
     1 PWRGD_CHK_CPU0_DIMM @T6G_MB_LIB.T6G(SCH_1):PWRGD_CHK_CPU0_DIMM   I188 @T6G_MB_LIB.T6G(SCH_1):PAGE95
     2 PWRGD_CHGL_CPU0 @T6G_MB_LIB.T6G(SCH_1):PWRGD_CHGL_CPU0   I188 @T6G_MB_LIB.T6G(SCH_1):PAGE95

R302 Q_RES_0402LF-1K,1%,1/16W,CHIP,CS21002FB06
     1 PWRGD_CHL_CPU0_DIMM @T6G_MB_LIB.T6G(SCH_1):PWRGD_CHL_CPU0_DIMM   I188 @T6G_MB_LIB.T6G(SCH_1):PAGE96
     2 PWRGD_CHGL_CPU0 @T6G_MB_LIB.T6G(SCH_1):PWRGD_CHGL_CPU0   I188 @T6G_MB_LIB.T6G(SCH_1):PAGE96

R303 Q_RES_0402LF-1K,1%,1/16W,CHIP,CS21002FB06
     1 PWRGD_CHA_CPU1_DIMM0 @T6G_MB_LIB.T6G(SCH_1):PWRGD_CHA_CPU1_DIMM0   I190 @T6G_MB_LIB.T6G(SCH_1):PAGE97
     2 PWRGD_CHAF_CPU1 @T6G_MB_LIB.T6G(SCH_1):PWRGD_CHAF_CPU1   I190 @T6G_MB_LIB.T6G(SCH_1):PAGE97

R304 Q_RES_0402LF-1K,1%,1/16W,CHIP,CS21002FB06
     1 PWRGD_CHB_CPU1_DIMM @T6G_MB_LIB.T6G(SCH_1):PWRGD_CHB_CPU1_DIMM   I188 @T6G_MB_LIB.T6G(SCH_1):PAGE98
     2 PWRGD_CHAF_CPU1 @T6G_MB_LIB.T6G(SCH_1):PWRGD_CHAF_CPU1   I188 @T6G_MB_LIB.T6G(SCH_1):PAGE98

R305 Q_RES_0402LF-1K,1%,1/16W,CHIP,CS21002FB06
     1 PWRGD_CHC_CPU1_DIMM @T6G_MB_LIB.T6G(SCH_1):PWRGD_CHC_CPU1_DIMM   I188 @T6G_MB_LIB.T6G(SCH_1):PAGE99
     2 PWRGD_CHAF_CPU1 @T6G_MB_LIB.T6G(SCH_1):PWRGD_CHAF_CPU1   I188 @T6G_MB_LIB.T6G(SCH_1):PAGE99

R306 Q_RES_0402LF-1K,1%,1/16W,CHIP,CS21002FB06
     1 PWRGD_CHD_CPU1_DIMM @T6G_MB_LIB.T6G(SCH_1):PWRGD_CHD_CPU1_DIMM   I188 @T6G_MB_LIB.T6G(SCH_1):PAGE100
     2 PWRGD_CHAF_CPU1 @T6G_MB_LIB.T6G(SCH_1):PWRGD_CHAF_CPU1   I188 @T6G_MB_LIB.T6G(SCH_1):PAGE100

R307 Q_RES_0402LF-1K,1%,1/16W,CHIP,CS21002FB06
     1 PWRGD_CHE_CPU1_DIMM @T6G_MB_LIB.T6G(SCH_1):PWRGD_CHE_CPU1_DIMM   I188 @T6G_MB_LIB.T6G(SCH_1):PAGE101
     2 PWRGD_CHAF_CPU1 @T6G_MB_LIB.T6G(SCH_1):PWRGD_CHAF_CPU1   I188 @T6G_MB_LIB.T6G(SCH_1):PAGE101

R308 Q_RES_0402LF-33,5%,1/16W,CHIP,CS03302JB10
     1 SMB_VR_3V3AUX_SCL @T6G_MB_LIB.T6G(SCH_1):SMB_VR_3V3AUX_SCL   I224 @T6G_MB_LIB.T6G(SCH_1):PAGE349
     2 SMB_VR_3V3STBY_SCL @T6G_MB_LIB.T6G(SCH_1):SMB_VR_3V3STBY_SCL   I224 @T6G_MB_LIB.T6G(SCH_1):PAGE349

R309 Q_RES_0402LF-33,5%,1/16W,CHIP,CS03302JB10
     1 SMB_VR_3V3AUX_SDA @T6G_MB_LIB.T6G(SCH_1):SMB_VR_3V3AUX_SDA   I225 @T6G_MB_LIB.T6G(SCH_1):PAGE349
     2 SMB_VR_3V3STBY_SDA @T6G_MB_LIB.T6G(SCH_1):SMB_VR_3V3STBY_SDA   I225 @T6G_MB_LIB.T6G(SCH_1):PAGE349

R310 Q_RES_0402LF-1K,1%,1/16W,CHIP,CS21002FB06
     1 PWRGD_CHH_CPU1_DIMM @T6G_MB_LIB.T6G(SCH_1):PWRGD_CHH_CPU1_DIMM   I189 @T6G_MB_LIB.T6G(SCH_1):PAGE104
     2 PWRGD_CHGL_CPU1 @T6G_MB_LIB.T6G(SCH_1):PWRGD_CHGL_CPU1   I189 @T6G_MB_LIB.T6G(SCH_1):PAGE104

R311 Q_RES_0402LF-1K,1%,1/16W,CHIP,CS21002FB06
     1 PWRGD_CHI_CPU1_DIMM @T6G_MB_LIB.T6G(SCH_1):PWRGD_CHI_CPU1_DIMM   I188 @T6G_MB_LIB.T6G(SCH_1):PAGE105
     2 PWRGD_CHGL_CPU1 @T6G_MB_LIB.T6G(SCH_1):PWRGD_CHGL_CPU1   I188 @T6G_MB_LIB.T6G(SCH_1):PAGE105

R312 Q_RES_0402LF-1K,1%,1/16W,CHIP,CS21002FB06
     1 PWRGD_CHJ_CPU1_DIMM @T6G_MB_LIB.T6G(SCH_1):PWRGD_CHJ_CPU1_DIMM   I188 @T6G_MB_LIB.T6G(SCH_1):PAGE106
     2 PWRGD_CHGL_CPU1 @T6G_MB_LIB.T6G(SCH_1):PWRGD_CHGL_CPU1   I188 @T6G_MB_LIB.T6G(SCH_1):PAGE106

R313 Q_RES_0402LF-1K,1%,1/16W,CHIP,CS21002FB06
     1 PWRGD_CHK_CPU1_DIMM @T6G_MB_LIB.T6G(SCH_1):PWRGD_CHK_CPU1_DIMM   I188 @T6G_MB_LIB.T6G(SCH_1):PAGE107
     2 PWRGD_CHGL_CPU1 @T6G_MB_LIB.T6G(SCH_1):PWRGD_CHGL_CPU1   I188 @T6G_MB_LIB.T6G(SCH_1):PAGE107

R314 Q_RES_0402LF-1K,1%,1/16W,CHIP,CS21002FB06
     1 PWRGD_CHL_CPU1_DIMM @T6G_MB_LIB.T6G(SCH_1):PWRGD_CHL_CPU1_DIMM   I188 @T6G_MB_LIB.T6G(SCH_1):PAGE108
     2 PWRGD_CHGL_CPU1 @T6G_MB_LIB.T6G(SCH_1):PWRGD_CHGL_CPU1   I188 @T6G_MB_LIB.T6G(SCH_1):PAGE108

R315 Q_RES_0402LF-49.9,1%,1/16W,CHIP,CS04992FB07
     1 PVDDCR_CPU0_P0_RESET_N @T6G_MB_LIB.T6G(SCH_1):PVDDCR_CPU0_P0_RESET_N    I57 @T6G_MB_LIB.T6G(SCH_1):PAGE168
     2 PVDDCR_CPU0_P0_RESET_N_R @T6G_MB_LIB.T6G(SCH_1):PVDDCR_CPU0_P0_RESET_N_R    I57 @T6G_MB_LIB.T6G(SCH_1):PAGE168

R316 Q_RES_0402LF-10K,1%,1/16W,EMPTY,CS31002FB08
     1 P3V3_AUX @T6G_MB_LIB.T6G(SCH_1):P3V3_AUX     I7 @T6G_MB_LIB.T6G(SCH_1):PAGE252
     2 PCA9548_PCIE3_ADDR2 @T6G_MB_LIB.T6G(SCH_1):PCA9548_PCIE3_ADDR2     I7 @T6G_MB_LIB.T6G(SCH_1):PAGE252

R317 Q_RES_0402LF-1K,1%,1/16W,CHIP,CS21002FB06
     1 PCA9548_PCIE3_ADDR2 @T6G_MB_LIB.T6G(SCH_1):PCA9548_PCIE3_ADDR2     I2 @T6G_MB_LIB.T6G(SCH_1):PAGE252
     2    GND @T6G_MB_LIB.T6G(SCH_1):GND     I2 @T6G_MB_LIB.T6G(SCH_1):PAGE252

R318 Q_RES_0402LF-10K,1%,1/16W,EMPTY,CS31002FB08
     1 P3V3_AUX @T6G_MB_LIB.T6G(SCH_1):P3V3_AUX     I8 @T6G_MB_LIB.T6G(SCH_1):PAGE252
     2 PCA9548_PCIE3_ADDR1 @T6G_MB_LIB.T6G(SCH_1):PCA9548_PCIE3_ADDR1     I8 @T6G_MB_LIB.T6G(SCH_1):PAGE252

R319 Q_RES_0402LF-1K,1%,1/16W,CHIP,CS21002FB06
     1 PCA9548_PCIE3_ADDR1 @T6G_MB_LIB.T6G(SCH_1):PCA9548_PCIE3_ADDR1     I4 @T6G_MB_LIB.T6G(SCH_1):PAGE252
     2    GND @T6G_MB_LIB.T6G(SCH_1):GND     I4 @T6G_MB_LIB.T6G(SCH_1):PAGE252

R320 Q_RES_0402LF-10K,1%,1/16W,EMPTY,CS31002FB08
     1 P3V3_AUX @T6G_MB_LIB.T6G(SCH_1):P3V3_AUX    I10 @T6G_MB_LIB.T6G(SCH_1):PAGE252
     2 PCA9548_PCIE3_ADDR0 @T6G_MB_LIB.T6G(SCH_1):PCA9548_PCIE3_ADDR0    I10 @T6G_MB_LIB.T6G(SCH_1):PAGE252

R321 Q_RES_0402LF-0,5%,1/16W,CHIP,CS00002JB13
     1 SCM_IRQ_N @T6G_MB_LIB.T6G(SCH_1):SCM_IRQ_N    I24 @T6G_MB_LIB.T6G(SCH_1):PAGE348
     2 IRQ0_A56 @T6G_MB_LIB.T6G(SCH_1):IRQ0_A56    I24 @T6G_MB_LIB.T6G(SCH_1):PAGE348

R322 Q_RES_0402LF-1K,1%,1/16W,EMPTY,CS21002FB06
     1 PVDD11_S3_P0 @T6G_MB_LIB.T6G(SCH_1):PVDD11_S3_P0    I73 @T6G_MB_LIB.T6G(SCH_1):PAGE137
     2 SMB_CPU0_CPU1_APML_BUF2_SCL_R2 @T6G_MB_LIB.T6G(SCH_1):SMB_CPU0_CPU1_APML_BUF2_SCL_R2    I73 @T6G_MB_LIB.T6G(SCH_1):PAGE137

R323 Q_RES_0402LF-0,5%,1/16W,EMPTY,CS00002JB13
     1 SMB_CPU0_CPU1_APML_SDA_R2 @T6G_MB_LIB.T6G(SCH_1):SMB_CPU0_CPU1_APML_SDA_R2   I109 @T6G_MB_LIB.T6G(SCH_1):PAGE138
     2 SMB_CPU0_CPU1_APML_MUX1_SDA @T6G_MB_LIB.T6G(SCH_1):SMB_CPU0_CPU1_APML_MUX1_SDA   I109 @T6G_MB_LIB.T6G(SCH_1):PAGE138

R324 Q_RES_0402LF-0,5%,1/16W,EMPTY,CS00002JB13
     1 SMB_CPU0_CPU1_APML_SCL_R2 @T6G_MB_LIB.T6G(SCH_1):SMB_CPU0_CPU1_APML_SCL_R2   I110 @T6G_MB_LIB.T6G(SCH_1):PAGE138
     2 SMB_CPU0_CPU1_APML_MUX1_SCL @T6G_MB_LIB.T6G(SCH_1):SMB_CPU0_CPU1_APML_MUX1_SCL   I110 @T6G_MB_LIB.T6G(SCH_1):PAGE138

R325 Q_RES_0402LF-0,5%,1/16W,CHIP,CS00002JB13
     1 SMB_CPU0_CPU1_APML_SCL_R2 @T6G_MB_LIB.T6G(SCH_1):SMB_CPU0_CPU1_APML_SCL_R2    I99 @T6G_MB_LIB.T6G(SCH_1):PAGE138
     2 SMB_CPU0_CPU1_APML_MUX2_SCL @T6G_MB_LIB.T6G(SCH_1):SMB_CPU0_CPU1_APML_MUX2_SCL    I99 @T6G_MB_LIB.T6G(SCH_1):PAGE138

R326 Q_RES_0402LF-0,5%,1/16W,CHIP,CS00002JB13
     1 SMB_CPU0_CPU1_APML_SDA_R2 @T6G_MB_LIB.T6G(SCH_1):SMB_CPU0_CPU1_APML_SDA_R2   I100 @T6G_MB_LIB.T6G(SCH_1):PAGE138
     2 SMB_CPU0_CPU1_APML_MUX2_SDA @T6G_MB_LIB.T6G(SCH_1):SMB_CPU0_CPU1_APML_MUX2_SDA   I100 @T6G_MB_LIB.T6G(SCH_1):PAGE138

R327 Q_RES_0402LF-0,5%,1/16W,CHIP,CS00002JB13
     1 SMB_APML_CPU0_MUX2_SCL @T6G_MB_LIB.T6G(SCH_1):SMB_APML_CPU0_MUX2_SCL    I91 @T6G_MB_LIB.T6G(SCH_1):PAGE138
     2 SMB_APML_CPU0_SCL @T6G_MB_LIB.T6G(SCH_1):SMB_APML_CPU0_SCL    I91 @T6G_MB_LIB.T6G(SCH_1):PAGE138

R328 Q_RES_0402LF-0,5%,1/16W,CHIP,CS00002JB13
     1 SMB_APML_CPU0_MUX2_SDA @T6G_MB_LIB.T6G(SCH_1):SMB_APML_CPU0_MUX2_SDA    I92 @T6G_MB_LIB.T6G(SCH_1):PAGE138
     2 SMB_APML_CPU0_SDA @T6G_MB_LIB.T6G(SCH_1):SMB_APML_CPU0_SDA    I92 @T6G_MB_LIB.T6G(SCH_1):PAGE138

R329 Q_RES_0402LF-2K,1%,1/16W,EMPTY,CS22002FB07
     1 SMB_PMBUS_3V3AUX_SDA @T6G_MB_LIB.T6G(SCH_1):SMB_PMBUS_3V3AUX_SDA   I133 @T6G_MB_LIB.T6G(SCH_1):PAGE349
     2 P3V3_AUX @T6G_MB_LIB.T6G(SCH_1):P3V3_AUX   I133 @T6G_MB_LIB.T6G(SCH_1):PAGE349

R330 Q_RES_0402LF-2.2K,5%,1/16W,EMPTY,CS22202JB07
     1 SMB_FAN_3V3AUX_SCL @T6G_MB_LIB.T6G(SCH_1):SMB_FAN_3V3AUX_SCL   I130 @T6G_MB_LIB.T6G(SCH_1):PAGE349
     2 P3V3_AUX @T6G_MB_LIB.T6G(SCH_1):P3V3_AUX   I130 @T6G_MB_LIB.T6G(SCH_1):PAGE349

R331 Q_RES_0402LF-2.2K,5%,1/16W,EMPTY,CS22202JB07
     1 SMB_FAN_3V3AUX_SDA @T6G_MB_LIB.T6G(SCH_1):SMB_FAN_3V3AUX_SDA   I129 @T6G_MB_LIB.T6G(SCH_1):PAGE349
     2 P3V3_AUX @T6G_MB_LIB.T6G(SCH_1):P3V3_AUX   I129 @T6G_MB_LIB.T6G(SCH_1):PAGE349

R332 Q_RES_0402LF-2.2K,5%,1/16W,EMPTY,CS22202JB07
     1 I3C_BMC_SWB_SCL @T6G_MB_LIB.T6G(SCH_1):I3C_BMC_SWB_SCL   I128 @T6G_MB_LIB.T6G(SCH_1):PAGE349
     2 P3V3_AUX @T6G_MB_LIB.T6G(SCH_1):P3V3_AUX   I128 @T6G_MB_LIB.T6G(SCH_1):PAGE349

R333 Q_RES_0402LF-0,5%,1/16W,CHIP,CS00002JB13
     1 FM_P5V_EN @T6G_MB_LIB.T6G(SCH_1):FM_P5V_EN     I4 @T6G_MB_LIB.T6G(SCH_1):PAGE273
     2 VR_P5V_EN @T6G_MB_LIB.T6G(SCH_1):VR_P5V_EN     I4 @T6G_MB_LIB.T6G(SCH_1):PAGE273

R334 Q_RES_0402LF-100K,1%,1/16W,CHIP,CS41002FB09
     1 VR_P5V_EN @T6G_MB_LIB.T6G(SCH_1):VR_P5V_EN     I7 @T6G_MB_LIB.T6G(SCH_1):PAGE273
     2    GND @T6G_MB_LIB.T6G(SCH_1):GND     I7 @T6G_MB_LIB.T6G(SCH_1):PAGE273

R335 Q_RES_0402LF-10K,1%,1/16W,CHIP,CS31002FB08
     1 P12V_AUX @T6G_MB_LIB.T6G(SCH_1):P12V_AUX    I15 @T6G_MB_LIB.T6G(SCH_1):PAGE273
     2 VR_P5V_EN_D_R @T6G_MB_LIB.T6G(SCH_1):VR_P5V_EN_D_R    I15 @T6G_MB_LIB.T6G(SCH_1):PAGE273

R336 Q_RES_0402LF-100K,1%,1/16W,CHIP,CS41002FB09
     1 P12V_AUX @T6G_MB_LIB.T6G(SCH_1):P12V_AUX    I10 @T6G_MB_LIB.T6G(SCH_1):PAGE273
     2 VR_P5V_EN_N @T6G_MB_LIB.T6G(SCH_1):VR_P5V_EN_N    I10 @T6G_MB_LIB.T6G(SCH_1):PAGE273

R337 Q_RES_0402LF-0,5%,1/16W,CHIP,CS00002JB13
     1 SMB_APML_CPU1_MUX2_SCL @T6G_MB_LIB.T6G(SCH_1):SMB_APML_CPU1_MUX2_SCL    I93 @T6G_MB_LIB.T6G(SCH_1):PAGE138
     2 SMB_APML_CPU1_SCL @T6G_MB_LIB.T6G(SCH_1):SMB_APML_CPU1_SCL    I93 @T6G_MB_LIB.T6G(SCH_1):PAGE138

R338 Q_RES_0402LF-0,5%,1/16W,CHIP,CS00002JB13
     1 SMB_APML_CPU1_MUX2_SDA @T6G_MB_LIB.T6G(SCH_1):SMB_APML_CPU1_MUX2_SDA    I94 @T6G_MB_LIB.T6G(SCH_1):PAGE138
     2 SMB_APML_CPU1_SDA @T6G_MB_LIB.T6G(SCH_1):SMB_APML_CPU1_SDA    I94 @T6G_MB_LIB.T6G(SCH_1):PAGE138

R339 Q_RES_0201LF-49.9,1%,1/20W,EMPTY,CS04991FE06
     1 USB2_CPU0_P0_DP @T6G_MB_LIB.T6G(SCH_1):USB2_CPU0_P0_DP   I120 @T6G_MB_LIB.T6G(SCH_1):PAGE158
     2    GND @T6G_MB_LIB.T6G(SCH_1):GND   I120 @T6G_MB_LIB.T6G(SCH_1):PAGE158

R340 Q_RES_0201LF-49.9,1%,1/20W,EMPTY,CS04991FE06
     1 USB2_CPU0_P0_DN @T6G_MB_LIB.T6G(SCH_1):USB2_CPU0_P0_DN   I121 @T6G_MB_LIB.T6G(SCH_1):PAGE158
     2    GND @T6G_MB_LIB.T6G(SCH_1):GND   I121 @T6G_MB_LIB.T6G(SCH_1):PAGE158

R341 Q_RES_0402LF-51,5%,1/16W,EMPTY,CS05102JB04
     1 USB3_CPU0_BMC_TX_DP @T6G_MB_LIB.T6G(SCH_1):USB3_CPU0_BMC_TX_DP   I145 @T6G_MB_LIB.T6G(SCH_1):PAGE158
     2    GND @T6G_MB_LIB.T6G(SCH_1):GND   I145 @T6G_MB_LIB.T6G(SCH_1):PAGE158

R342 Q_RES_0402LF-51,5%,1/16W,EMPTY,CS05102JB04
     1 USB3_CPU0_BMC_TX_DN @T6G_MB_LIB.T6G(SCH_1):USB3_CPU0_BMC_TX_DN   I146 @T6G_MB_LIB.T6G(SCH_1):PAGE158
     2    GND @T6G_MB_LIB.T6G(SCH_1):GND   I146 @T6G_MB_LIB.T6G(SCH_1):PAGE158

R343 Q_RES_0201LF-49.9,1%,1/20W,EMPTY,CS04991FE06
     1 USB2_CPU0_P0_R2_DP @T6G_MB_LIB.T6G(SCH_1):USB2_CPU0_P0_R2_DP   I125 @T6G_MB_LIB.T6G(SCH_1):PAGE158
     2    GND @T6G_MB_LIB.T6G(SCH_1):GND   I125 @T6G_MB_LIB.T6G(SCH_1):PAGE158

R344 Q_RES_0201LF-49.9,1%,1/20W,EMPTY,CS04991FE06
     1 USB3_CPU0_BMC_TX_C2_DP @T6G_MB_LIB.T6G(SCH_1):USB3_CPU0_BMC_TX_C2_DP   I127 @T6G_MB_LIB.T6G(SCH_1):PAGE158
     2    GND @T6G_MB_LIB.T6G(SCH_1):GND   I127 @T6G_MB_LIB.T6G(SCH_1):PAGE158

R345 Q_RES_0201LF-49.9,1%,1/20W,EMPTY,CS04991FE06
     1 USB2_CPU0_P0_R2_DN @T6G_MB_LIB.T6G(SCH_1):USB2_CPU0_P0_R2_DN   I124 @T6G_MB_LIB.T6G(SCH_1):PAGE158
     2    GND @T6G_MB_LIB.T6G(SCH_1):GND   I124 @T6G_MB_LIB.T6G(SCH_1):PAGE158

R346 Q_RES_0201LF-49.9,1%,1/20W,EMPTY,CS04991FE06
     1 USB3_CPU0_BMC_TX_C2_DN @T6G_MB_LIB.T6G(SCH_1):USB3_CPU0_BMC_TX_C2_DN   I126 @T6G_MB_LIB.T6G(SCH_1):PAGE158
     2    GND @T6G_MB_LIB.T6G(SCH_1):GND   I126 @T6G_MB_LIB.T6G(SCH_1):PAGE158

R347 Q_RES_0402LF-33.2,1%,1/16W,CHIP,CS03322FB03
     1 SMB_SML1_PMBUS_HSC_SCL @T6G_MB_LIB.T6G(SCH_1):SMB_SML1_PMBUS_HSC_SCL   I173 @T6G_MB_LIB.T6G(SCH_1):PAGE349
     2 SMB_SML1_PMBUS_HSC_R1_SCL @T6G_MB_LIB.T6G(SCH_1):SMB_SML1_PMBUS_HSC_R1_SCL   I173 @T6G_MB_LIB.T6G(SCH_1):PAGE349

R348 Q_RES_0402LF-33.2,1%,1/16W,CHIP,CS03322FB03
     1 SMB_SML1_PMBUS_HSC_SDA @T6G_MB_LIB.T6G(SCH_1):SMB_SML1_PMBUS_HSC_SDA   I172 @T6G_MB_LIB.T6G(SCH_1):PAGE349
     2 SMB_SML1_PMBUS_HSC_R1_SDA @T6G_MB_LIB.T6G(SCH_1):SMB_SML1_PMBUS_HSC_R1_SDA   I172 @T6G_MB_LIB.T6G(SCH_1):PAGE349

R349 Q_RES_0402LF-33,5%,1/16W,CHIP,CS03302JB10
     1 SMB_SCM_2_R2_SCL @T6G_MB_LIB.T6G(SCH_1):SMB_SCM_2_R2_SCL   I185 @T6G_MB_LIB.T6G(SCH_1):PAGE349
     2 SMB_SCM_2_R5_SCL @T6G_MB_LIB.T6G(SCH_1):SMB_SCM_2_R5_SCL   I185 @T6G_MB_LIB.T6G(SCH_1):PAGE349

R350 Q_RES_0402LF-33,5%,1/16W,CHIP,CS03302JB10
     1 SMB_SCM_2_R2_SDA @T6G_MB_LIB.T6G(SCH_1):SMB_SCM_2_R2_SDA   I184 @T6G_MB_LIB.T6G(SCH_1):PAGE349
     2 SMB_SCM_2_R5_SDA @T6G_MB_LIB.T6G(SCH_1):SMB_SCM_2_R5_SDA   I184 @T6G_MB_LIB.T6G(SCH_1):PAGE349

R351 Q_RES_0402LF-33,5%,1/16W,CHIP,CS03302JB10
     1 SMB_SCM_2_R5_SCL @T6G_MB_LIB.T6G(SCH_1):SMB_SCM_2_R5_SCL   I187 @T6G_MB_LIB.T6G(SCH_1):PAGE349
     2 SMB_SCM_2_R6_SCL @T6G_MB_LIB.T6G(SCH_1):SMB_SCM_2_R6_SCL   I187 @T6G_MB_LIB.T6G(SCH_1):PAGE349

R352 Q_RES_0402LF-33,5%,1/16W,CHIP,CS03302JB10
     1 SMB_SCM_2_R5_SDA @T6G_MB_LIB.T6G(SCH_1):SMB_SCM_2_R5_SDA   I186 @T6G_MB_LIB.T6G(SCH_1):PAGE349
     2 SMB_SCM_2_R6_SDA @T6G_MB_LIB.T6G(SCH_1):SMB_SCM_2_R6_SDA   I186 @T6G_MB_LIB.T6G(SCH_1):PAGE349

R353 Q_RES_0402LF-0,5%,1/16W,CHIP,CS00002JB13
     1 P12V_HSC_T_CRIT_N @T6G_MB_LIB.T6G(SCH_1):P12V_HSC_T_CRIT_N    I74 @T6G_MB_LIB.T6G(SCH_1):PAGE371
     2 P12V_HSC_T_CRIT_R_N @T6G_MB_LIB.T6G(SCH_1):P12V_HSC_T_CRIT_R_N    I74 @T6G_MB_LIB.T6G(SCH_1):PAGE371

R354 Q_RES_0402LF-10.5K,1%,1/16W,CHIP,CS31052FB03
     1 P3V3_AUX @T6G_MB_LIB.T6G(SCH_1):P3V3_AUX    I76 @T6G_MB_LIB.T6G(SCH_1):PAGE371
     2 P12V_HSC_T_CRIT_R_N @T6G_MB_LIB.T6G(SCH_1):P12V_HSC_T_CRIT_R_N    I76 @T6G_MB_LIB.T6G(SCH_1):PAGE371

R355 Q_RES_0402LF-10.5K,1%,1/16W,CHIP,CS31052FB03
     1 P3V3_AUX @T6G_MB_LIB.T6G(SCH_1):P3V3_AUX    I79 @T6G_MB_LIB.T6G(SCH_1):PAGE371
     2 P12V_HSC_TEMP_ALERT_R_N @T6G_MB_LIB.T6G(SCH_1):P12V_HSC_TEMP_ALERT_R_N    I79 @T6G_MB_LIB.T6G(SCH_1):PAGE371

R356 Q_RES_0402LF-0,5%,1/16W,CHIP,CS00002JB13
     1 CPU0_XTRIG_R2_L6 @T6G_MB_LIB.T6G(SCH_1):CPU0_XTRIG_R2_L6   I349 @T6G_MB_LIB.T6G(SCH_1):PAGE27
     2 CPU0_XTRIG_L6 @T6G_MB_LIB.T6G(SCH_1):CPU0_XTRIG_L6   I349 @T6G_MB_LIB.T6G(SCH_1):PAGE27

R357 Q_RES_0402LF-0,5%,1/16W,CHIP,CS00002JB13
     1 CPU0_XTRIG_R2_L7 @T6G_MB_LIB.T6G(SCH_1):CPU0_XTRIG_R2_L7   I348 @T6G_MB_LIB.T6G(SCH_1):PAGE27
     2 CPU0_XTRIG_L7 @T6G_MB_LIB.T6G(SCH_1):CPU0_XTRIG_L7   I348 @T6G_MB_LIB.T6G(SCH_1):PAGE27

R358 Q_RES_0402LF-0,5%,1/16W,EMPTY,CS00002JB13
     1 SMB_CPU0_CPU1_SEC_SCL_R2 @T6G_MB_LIB.T6G(SCH_1):SMB_CPU0_CPU1_SEC_SCL_R2     I5 @T6G_MB_LIB.T6G(SCH_1):PAGE138
     2 SMB_CPU1_SEC_R_SCL @T6G_MB_LIB.T6G(SCH_1):SMB_CPU1_SEC_R_SCL     I5 @T6G_MB_LIB.T6G(SCH_1):PAGE138

R359 Q_RES_0402LF-1K,1%,1/16W,CHIP,CS21002FB06
     1 PVDD11_S3_P1 @T6G_MB_LIB.T6G(SCH_1):PVDD11_S3_P1    I52 @T6G_MB_LIB.T6G(SCH_1):PAGE138
     2 SMB_APML_CPU1_SDA @T6G_MB_LIB.T6G(SCH_1):SMB_APML_CPU1_SDA    I52 @T6G_MB_LIB.T6G(SCH_1):PAGE138

R360 Q_RES_0402LF-1K,1%,1/16W,CHIP,CS21002FB06
     1 PVDD11_S3_P0 @T6G_MB_LIB.T6G(SCH_1):PVDD11_S3_P0    I55 @T6G_MB_LIB.T6G(SCH_1):PAGE138
     2 SMB_APML_CPU0_SDA @T6G_MB_LIB.T6G(SCH_1):SMB_APML_CPU0_SDA    I55 @T6G_MB_LIB.T6G(SCH_1):PAGE138

R361 Q_RES_0402LF-4.7K,5%,1/16W,EMPTY,CS24702JB10
     1   P3V3 @T6G_MB_LIB.T6G(SCH_1):P3V3    I40 @T6G_MB_LIB.T6G(SCH_1):PAGE137
     2 SMB_CPU0_CPU1_APML_BUF1_SCL_R2 @T6G_MB_LIB.T6G(SCH_1):SMB_CPU0_CPU1_APML_BUF1_SCL_R2    I40 @T6G_MB_LIB.T6G(SCH_1):PAGE137

R362 Q_RES_0402LF-1K,1%,1/16W,CHIP,CS21002FB06
     1 PVDD11_S3_P1 @T6G_MB_LIB.T6G(SCH_1):PVDD11_S3_P1    I53 @T6G_MB_LIB.T6G(SCH_1):PAGE138
     2 SMB_APML_CPU1_SCL @T6G_MB_LIB.T6G(SCH_1):SMB_APML_CPU1_SCL    I53 @T6G_MB_LIB.T6G(SCH_1):PAGE138

R363 Q_RES_0402LF-1K,1%,1/16W,CHIP,CS21002FB06
     1 PVDD11_S3_P0 @T6G_MB_LIB.T6G(SCH_1):PVDD11_S3_P0    I56 @T6G_MB_LIB.T6G(SCH_1):PAGE138
     2 SMB_APML_CPU0_SCL @T6G_MB_LIB.T6G(SCH_1):SMB_APML_CPU0_SCL    I56 @T6G_MB_LIB.T6G(SCH_1):PAGE138

R364 Q_RES_0402LF-0,5%,1/16W,CHIP,CS00002JB13
     1 P3V_BAT_R @T6G_MB_LIB.T6G(SCH_1):P3V_BAT_R   I231 @T6G_MB_LIB.T6G(SCH_1):PAGE349
     2 SCM_VDD_RTC @T6G_MB_LIB.T6G(SCH_1):SCM_VDD_RTC   I231 @T6G_MB_LIB.T6G(SCH_1):PAGE349

R365 Q_RES_0402LF-4.7K,5%,1/16W,EMPTY,CS24702JB10
     1   P3V3 @T6G_MB_LIB.T6G(SCH_1):P3V3    I41 @T6G_MB_LIB.T6G(SCH_1):PAGE137
     2 SMB_CPU0_CPU1_APML_BUF1_SDA_R2 @T6G_MB_LIB.T6G(SCH_1):SMB_CPU0_CPU1_APML_BUF1_SDA_R2    I41 @T6G_MB_LIB.T6G(SCH_1):PAGE137

R366 Q_RES_0402LF-1K,1%,1/16W,CHIP,CS21002FB06
     1 PVDD18_S5_P1 @T6G_MB_LIB.T6G(SCH_1):PVDD18_S5_P1    I54 @T6G_MB_LIB.T6G(SCH_1):PAGE138
     2 SMB_CPU1_SEC_SCL @T6G_MB_LIB.T6G(SCH_1):SMB_CPU1_SEC_SCL    I54 @T6G_MB_LIB.T6G(SCH_1):PAGE138

R367 Q_RES_0402LF-1K,1%,1/16W,CHIP,CS21002FB06
     1 PVDD18_S5_P0 @T6G_MB_LIB.T6G(SCH_1):PVDD18_S5_P0    I57 @T6G_MB_LIB.T6G(SCH_1):PAGE138
     2 SMB_CPU0_SEC_SCL @T6G_MB_LIB.T6G(SCH_1):SMB_CPU0_SEC_SCL    I57 @T6G_MB_LIB.T6G(SCH_1):PAGE138

R368 Q_RES_0402LF-4.7K,5%,1/16W,EMPTY,CS24702JB10
     1 PVDD18_S5_P0 @T6G_MB_LIB.T6G(SCH_1):PVDD18_S5_P0    I44 @T6G_MB_LIB.T6G(SCH_1):PAGE137
     2 SMB_CPU0_CPU1_SEC_SCL_R2 @T6G_MB_LIB.T6G(SCH_1):SMB_CPU0_CPU1_SEC_SCL_R2    I44 @T6G_MB_LIB.T6G(SCH_1):PAGE137

R369 Q_RES_0402LF-1K,1%,1/16W,CHIP,CS21002FB06
     1 PVDD18_S5_P1 @T6G_MB_LIB.T6G(SCH_1):PVDD18_S5_P1    I58 @T6G_MB_LIB.T6G(SCH_1):PAGE138
     2 SMB_CPU1_SEC_SDA @T6G_MB_LIB.T6G(SCH_1):SMB_CPU1_SEC_SDA    I58 @T6G_MB_LIB.T6G(SCH_1):PAGE138

R370 Q_RES_0402LF-1K,1%,1/16W,CHIP,CS21002FB06
     1 PVDD18_S5_P0 @T6G_MB_LIB.T6G(SCH_1):PVDD18_S5_P0    I60 @T6G_MB_LIB.T6G(SCH_1):PAGE138
     2 SMB_CPU0_SEC_SDA @T6G_MB_LIB.T6G(SCH_1):SMB_CPU0_SEC_SDA    I60 @T6G_MB_LIB.T6G(SCH_1):PAGE138

R371 Q_RES_0402LF-33,5%,1/16W,CHIP,CS03302JB10
     1 FPGA_DEBUG_LED_CTRL @T6G_MB_LIB.T6G(SCH_1):FPGA_DEBUG_LED_CTRL   I107 @T6G_MB_LIB.T6G(SCH_1):PAGE80
     2 FM_FPGA_DEBUG_LED_CTRL @T6G_MB_LIB.T6G(SCH_1):FM_FPGA_DEBUG_LED_CTRL   I107 @T6G_MB_LIB.T6G(SCH_1):PAGE80

R372 Q_RES_0402LF-33,5%,1/16W,CHIP,CS03302JB10
     1 P12V_ALL_PWROK_R @T6G_MB_LIB.T6G(SCH_1):P12V_ALL_PWROK_R   I159 @T6G_MB_LIB.T6G(SCH_1):PAGE80
     2 P12V_ALL_PWROK @T6G_MB_LIB.T6G(SCH_1):P12V_ALL_PWROK   I159 @T6G_MB_LIB.T6G(SCH_1):PAGE80

R373 Q_RES_0402LF-0,5%,1/16W,EMPTY,CS00002JB13
     1 P1V5_BAT @T6G_MB_LIB.T6G(SCH_1):P1V5_BAT    I52 @T6G_MB_LIB.T6G(SCH_1):PAGE57
     2 CPU1_VDDBT_RTC_G @T6G_MB_LIB.T6G(SCH_1):CPU1_VDDBT_RTC_G    I52 @T6G_MB_LIB.T6G(SCH_1):PAGE57

R374 Q_RES_0402LF-0,5%,1/16W,CHIP,CS00002JB13
     1 PVDD18_S5_P1 @T6G_MB_LIB.T6G(SCH_1):PVDD18_S5_P1    I51 @T6G_MB_LIB.T6G(SCH_1):PAGE57
     2 CPU1_VDDBT_RTC_G @T6G_MB_LIB.T6G(SCH_1):CPU1_VDDBT_RTC_G    I51 @T6G_MB_LIB.T6G(SCH_1):PAGE57

R375 Q_RES_0402LF-15,1%,1/16W,CHIP,CS01502FB03
     1 M_A_CPU0_ALERT_N @T6G_MB_LIB.T6G(SCH_1):M_A_CPU0_ALERT_N   I837 @T6G_MB_LIB.T6G(SCH_1):PAGE10
     2 M_A_CPU0_ALERT_R_N @T6G_MB_LIB.T6G(SCH_1):M_A_CPU0_ALERT_R_N   I837 @T6G_MB_LIB.T6G(SCH_1):PAGE10

R376 Q_RES_0402LF-15,1%,1/16W,CHIP,CS01502FB03
     1 M_B_CPU0_ALERT_N @T6G_MB_LIB.T6G(SCH_1):M_B_CPU0_ALERT_N   I327 @T6G_MB_LIB.T6G(SCH_1):PAGE11
     2 M_B_CPU0_ALERT_R_N @T6G_MB_LIB.T6G(SCH_1):M_B_CPU0_ALERT_R_N   I327 @T6G_MB_LIB.T6G(SCH_1):PAGE11

R377 Q_RES_0402LF-15,1%,1/16W,CHIP,CS01502FB03
     1 M_C_CPU0_ALERT_N @T6G_MB_LIB.T6G(SCH_1):M_C_CPU0_ALERT_N   I314 @T6G_MB_LIB.T6G(SCH_1):PAGE12
     2 M_C_CPU0_ALERT_R_N @T6G_MB_LIB.T6G(SCH_1):M_C_CPU0_ALERT_R_N   I314 @T6G_MB_LIB.T6G(SCH_1):PAGE12

R378 Q_RES_0402LF-15,1%,1/16W,CHIP,CS01502FB03
     1 M_D_CPU0_ALERT_N @T6G_MB_LIB.T6G(SCH_1):M_D_CPU0_ALERT_N   I314 @T6G_MB_LIB.T6G(SCH_1):PAGE13
     2 M_D_CPU0_ALERT_R_N @T6G_MB_LIB.T6G(SCH_1):M_D_CPU0_ALERT_R_N   I314 @T6G_MB_LIB.T6G(SCH_1):PAGE13

R379 Q_RES_0402LF-15,1%,1/16W,CHIP,CS01502FB03
     1 M_E_CPU0_ALERT_N @T6G_MB_LIB.T6G(SCH_1):M_E_CPU0_ALERT_N   I315 @T6G_MB_LIB.T6G(SCH_1):PAGE14
     2 M_E_CPU0_ALERT_R_N @T6G_MB_LIB.T6G(SCH_1):M_E_CPU0_ALERT_R_N   I315 @T6G_MB_LIB.T6G(SCH_1):PAGE14

R380 Q_RES_0402LF-15,1%,1/16W,CHIP,CS01502FB03
     1 M_F_CPU0_ALERT_N @T6G_MB_LIB.T6G(SCH_1):M_F_CPU0_ALERT_N   I314 @T6G_MB_LIB.T6G(SCH_1):PAGE15
     2 M_F_CPU0_ALERT_R_N @T6G_MB_LIB.T6G(SCH_1):M_F_CPU0_ALERT_R_N   I314 @T6G_MB_LIB.T6G(SCH_1):PAGE15

R381 Q_RES_0402LF-15,1%,1/16W,CHIP,CS01502FB03
     1 M_G_CPU0_ALERT_N @T6G_MB_LIB.T6G(SCH_1):M_G_CPU0_ALERT_N   I323 @T6G_MB_LIB.T6G(SCH_1):PAGE16
     2 M_G_CPU0_ALERT_R_N @T6G_MB_LIB.T6G(SCH_1):M_G_CPU0_ALERT_R_N   I323 @T6G_MB_LIB.T6G(SCH_1):PAGE16

R382 Q_RES_0402LF-15,1%,1/16W,CHIP,CS01502FB03
     1 M_H_CPU0_ALERT_N @T6G_MB_LIB.T6G(SCH_1):M_H_CPU0_ALERT_N   I314 @T6G_MB_LIB.T6G(SCH_1):PAGE17
     2 M_H_CPU0_ALERT_R_N @T6G_MB_LIB.T6G(SCH_1):M_H_CPU0_ALERT_R_N   I314 @T6G_MB_LIB.T6G(SCH_1):PAGE17

R383 Q_RES_0402LF-15,1%,1/16W,CHIP,CS01502FB03
     1 M_I_CPU0_ALERT_N @T6G_MB_LIB.T6G(SCH_1):M_I_CPU0_ALERT_N   I314 @T6G_MB_LIB.T6G(SCH_1):PAGE18
     2 M_I_CPU0_ALERT_R_N @T6G_MB_LIB.T6G(SCH_1):M_I_CPU0_ALERT_R_N   I314 @T6G_MB_LIB.T6G(SCH_1):PAGE18

R384 Q_RES_0402LF-15,1%,1/16W,CHIP,CS01502FB03
     1 M_J_CPU0_ALERT_N @T6G_MB_LIB.T6G(SCH_1):M_J_CPU0_ALERT_N   I314 @T6G_MB_LIB.T6G(SCH_1):PAGE19
     2 M_J_CPU0_ALERT_R_N @T6G_MB_LIB.T6G(SCH_1):M_J_CPU0_ALERT_R_N   I314 @T6G_MB_LIB.T6G(SCH_1):PAGE19

R385 Q_RES_0402LF-15,1%,1/16W,CHIP,CS01502FB03
     1 M_K_CPU0_ALERT_N @T6G_MB_LIB.T6G(SCH_1):M_K_CPU0_ALERT_N   I314 @T6G_MB_LIB.T6G(SCH_1):PAGE20
     2 M_K_CPU0_ALERT_R_N @T6G_MB_LIB.T6G(SCH_1):M_K_CPU0_ALERT_R_N   I314 @T6G_MB_LIB.T6G(SCH_1):PAGE20

R386 Q_RES_0402LF-15,1%,1/16W,CHIP,CS01502FB03
     1 M_L_CPU0_ALERT_N @T6G_MB_LIB.T6G(SCH_1):M_L_CPU0_ALERT_N   I314 @T6G_MB_LIB.T6G(SCH_1):PAGE21
     2 M_L_CPU0_ALERT_R_N @T6G_MB_LIB.T6G(SCH_1):M_L_CPU0_ALERT_R_N   I314 @T6G_MB_LIB.T6G(SCH_1):PAGE21

R387 Q_RES_0402LF-2.2K,5%,1/16W,CHIP,CS22202JB07
     1 P3V3_AUX @T6G_MB_LIB.T6G(SCH_1):P3V3_AUX   I388 @T6G_MB_LIB.T6G(SCH_1):PAGE27
     2 CPU0_CORETYPE2 @T6G_MB_LIB.T6G(SCH_1):CPU0_CORETYPE2   I388 @T6G_MB_LIB.T6G(SCH_1):PAGE27

R388 Q_RES_0402LF-2.2K,5%,1/16W,CHIP,CS22202JB07
     1 P3V3_AUX @T6G_MB_LIB.T6G(SCH_1):P3V3_AUX   I389 @T6G_MB_LIB.T6G(SCH_1):PAGE27
     2 CPU0_CORETYPE1 @T6G_MB_LIB.T6G(SCH_1):CPU0_CORETYPE1   I389 @T6G_MB_LIB.T6G(SCH_1):PAGE27

R389 Q_RES_0402LF-2.2K,5%,1/16W,CHIP,CS22202JB07
     1 P3V3_AUX @T6G_MB_LIB.T6G(SCH_1):P3V3_AUX   I391 @T6G_MB_LIB.T6G(SCH_1):PAGE27
     2 CPU0_SP5R4 @T6G_MB_LIB.T6G(SCH_1):CPU0_SP5R4   I391 @T6G_MB_LIB.T6G(SCH_1):PAGE27

R390 Q_RES_0402LF-2.2K,5%,1/16W,CHIP,CS22202JB07
     1 P3V3_AUX @T6G_MB_LIB.T6G(SCH_1):P3V3_AUX   I390 @T6G_MB_LIB.T6G(SCH_1):PAGE27
     2 CPU0_CORETYPE0 @T6G_MB_LIB.T6G(SCH_1):CPU0_CORETYPE0   I390 @T6G_MB_LIB.T6G(SCH_1):PAGE27

R391 Q_RES_0402LF-2.2K,5%,1/16W,CHIP,CS22202JB07
     1 P3V3_AUX @T6G_MB_LIB.T6G(SCH_1):P3V3_AUX   I392 @T6G_MB_LIB.T6G(SCH_1):PAGE27
     2 CPU0_SP5R3 @T6G_MB_LIB.T6G(SCH_1):CPU0_SP5R3   I392 @T6G_MB_LIB.T6G(SCH_1):PAGE27

R392 Q_RES_0402LF-2.2K,5%,1/16W,EMPTY,CS22202JB07
     1 PVDD18_S5_P0 @T6G_MB_LIB.T6G(SCH_1):PVDD18_S5_P0   I395 @T6G_MB_LIB.T6G(SCH_1):PAGE27
     2 CPU0_SA0 @T6G_MB_LIB.T6G(SCH_1):CPU0_SA0   I395 @T6G_MB_LIB.T6G(SCH_1):PAGE27

R393 Q_RES_0402LF-2.2K,5%,1/16W,CHIP,CS22202JB07
     1 CPU0_SA0 @T6G_MB_LIB.T6G(SCH_1):CPU0_SA0   I396 @T6G_MB_LIB.T6G(SCH_1):PAGE27
     2    GND @T6G_MB_LIB.T6G(SCH_1):GND   I396 @T6G_MB_LIB.T6G(SCH_1):PAGE27

R394 Q_RES_0402LF-2.2K,5%,1/16W,CHIP,CS22202JB07
     1 CPU0_SA1 @T6G_MB_LIB.T6G(SCH_1):CPU0_SA1   I397 @T6G_MB_LIB.T6G(SCH_1):PAGE27
     2    GND @T6G_MB_LIB.T6G(SCH_1):GND   I397 @T6G_MB_LIB.T6G(SCH_1):PAGE27

R395 Q_RES_0402LF-0,5%,1/16W,CHIP,CS00002JB13
     1 FM_SPD_CPU0_SWITCH_CTRL_R_N @T6G_MB_LIB.T6G(SCH_1):FM_SPD_CPU0_SWITCH_CTRL_R_N   I155 @T6G_MB_LIB.T6G(SCH_1):PAGE80
     2 FM_SPD_CPU0_SWITCH_CTRL_N @T6G_MB_LIB.T6G(SCH_1):FM_SPD_CPU0_SWITCH_CTRL_N   I155 @T6G_MB_LIB.T6G(SCH_1):PAGE80

R396 Q_RES_0402LF-2.2K,5%,1/16W,CHIP,CS22202JB07
     1 P3V3_AUX @T6G_MB_LIB.T6G(SCH_1):P3V3_AUX   I393 @T6G_MB_LIB.T6G(SCH_1):PAGE27
     2 CPU0_SP5R2 @T6G_MB_LIB.T6G(SCH_1):CPU0_SP5R2   I393 @T6G_MB_LIB.T6G(SCH_1):PAGE27

R397 Q_RES_0402LF-2.2K,5%,1/16W,CHIP,CS22202JB07
     1 P3V3_AUX @T6G_MB_LIB.T6G(SCH_1):P3V3_AUX   I394 @T6G_MB_LIB.T6G(SCH_1):PAGE27
     2 CPU0_SP5R1 @T6G_MB_LIB.T6G(SCH_1):CPU0_SP5R1   I394 @T6G_MB_LIB.T6G(SCH_1):PAGE27

R398 Q_RES_0402LF-1K,1%,1/16W,CHIP,CS21002FB06
     1 PVDD18_S5_P0 @T6G_MB_LIB.T6G(SCH_1):PVDD18_S5_P0   I305 @T6G_MB_LIB.T6G(SCH_1):PAGE27
     2 JTAG_CPU0_TDO @T6G_MB_LIB.T6G(SCH_1):JTAG_CPU0_TDO   I305 @T6G_MB_LIB.T6G(SCH_1):PAGE27

R399 Q_RES_0402LF-1K,1%,1/16W,CHIP,CS21002FB06
     1 PVDD18_S5_P0 @T6G_MB_LIB.T6G(SCH_1):PVDD18_S5_P0   I304 @T6G_MB_LIB.T6G(SCH_1):PAGE27
     2 JTAG_CPU0_TDI @T6G_MB_LIB.T6G(SCH_1):JTAG_CPU0_TDI   I304 @T6G_MB_LIB.T6G(SCH_1):PAGE27

R400 Q_RES_0402LF-1K,1%,1/16W,CHIP,CS21002FB06
     1 PVDD18_S5_P0 @T6G_MB_LIB.T6G(SCH_1):PVDD18_S5_P0   I301 @T6G_MB_LIB.T6G(SCH_1):PAGE27
     2 JTAG_CPU0_TRST_N @T6G_MB_LIB.T6G(SCH_1):JTAG_CPU0_TRST_N   I301 @T6G_MB_LIB.T6G(SCH_1):PAGE27

R401 Q_RES_0402LF-1K,1%,1/16W,CHIP,CS21002FB06
     1 PVDD18_S5_P0 @T6G_MB_LIB.T6G(SCH_1):PVDD18_S5_P0   I300 @T6G_MB_LIB.T6G(SCH_1):PAGE27
     2 JTAG_CPU0_TCK @T6G_MB_LIB.T6G(SCH_1):JTAG_CPU0_TCK   I300 @T6G_MB_LIB.T6G(SCH_1):PAGE27

R402 Q_RES_0402LF-1K,1%,1/16W,CHIP,CS21002FB06
     1 PVDD18_S5_P0 @T6G_MB_LIB.T6G(SCH_1):PVDD18_S5_P0   I296 @T6G_MB_LIB.T6G(SCH_1):PAGE27
     2 JTAG_CPU0_TMS @T6G_MB_LIB.T6G(SCH_1):JTAG_CPU0_TMS   I296 @T6G_MB_LIB.T6G(SCH_1):PAGE27

R403 Q_RES_0402LF-1K,1%,1/16W,CHIP,CS21002FB06
     1 PVDD18_S5_P0 @T6G_MB_LIB.T6G(SCH_1):PVDD18_S5_P0   I294 @T6G_MB_LIB.T6G(SCH_1):PAGE27
     2 JTAG_CPU0_DBREQ_N @T6G_MB_LIB.T6G(SCH_1):JTAG_CPU0_DBREQ_N   I294 @T6G_MB_LIB.T6G(SCH_1):PAGE27

R404 Q_RES_0402LF-0,5%,1/16W,CHIP,CS00002JB13
     1 JTAG_CPU0_R_TDO @T6G_MB_LIB.T6G(SCH_1):JTAG_CPU0_R_TDO   I170 @T6G_MB_LIB.T6G(SCH_1):PAGE27
     2 JTAG_CPU0_TDO @T6G_MB_LIB.T6G(SCH_1):JTAG_CPU0_TDO   I170 @T6G_MB_LIB.T6G(SCH_1):PAGE27

R405 Q_RES_0402LF-0,5%,1/16W,CHIP,CS00002JB13
     1 UART_CPU0_UART0_TX @T6G_MB_LIB.T6G(SCH_1):UART_CPU0_UART0_TX   I279 @T6G_MB_LIB.T6G(SCH_1):PAGE27
     2 UART_CPU0_UART0_R_TX @T6G_MB_LIB.T6G(SCH_1):UART_CPU0_UART0_R_TX   I279 @T6G_MB_LIB.T6G(SCH_1):PAGE27

R406 Q_RES_0402LF-4.7K,5%,1/16W,EMPTY,CS24702JB10
     1 PVDD18_S5_P0 @T6G_MB_LIB.T6G(SCH_1):PVDD18_S5_P0    I46 @T6G_MB_LIB.T6G(SCH_1):PAGE137
     2 SMB_CPU0_CPU1_SEC_SDA_R2 @T6G_MB_LIB.T6G(SCH_1):SMB_CPU0_CPU1_SEC_SDA_R2    I46 @T6G_MB_LIB.T6G(SCH_1):PAGE137

R407 Q_RES_0402LF-0,5%,1/16W,CHIP,CS00002JB13
     1 P12V_OCP_V3_2_PLD_PWRGD @T6G_MB_LIB.T6G(SCH_1):P12V_OCP_V3_2_PLD_PWRGD   I139 @T6G_MB_LIB.T6G(SCH_1):PAGE79
     2 HP_LVC3_OCP_V3_2_P12V_PWRGD_R @T6G_MB_LIB.T6G(SCH_1):HP_LVC3_OCP_V3_2_P12V_PWRGD_R   I139 @T6G_MB_LIB.T6G(SCH_1):PAGE79

R408 Q_RES_0402LF-2.2K,5%,1/16W,CHIP,CS22202JB07
     1 CPU0_BP0 @T6G_MB_LIB.T6G(SCH_1):CPU0_BP0   I380 @T6G_MB_LIB.T6G(SCH_1):PAGE27
     2 PVDD18_S5_P0 @T6G_MB_LIB.T6G(SCH_1):PVDD18_S5_P0   I380 @T6G_MB_LIB.T6G(SCH_1):PAGE27

R409 Q_RES_0402LF-2.2K,5%,1/16W,CHIP,CS22202JB07
     1 CPU0_BP1 @T6G_MB_LIB.T6G(SCH_1):CPU0_BP1   I381 @T6G_MB_LIB.T6G(SCH_1):PAGE27
     2 PVDD18_S5_P0 @T6G_MB_LIB.T6G(SCH_1):PVDD18_S5_P0   I381 @T6G_MB_LIB.T6G(SCH_1):PAGE27

R410 Q_RES_0402LF-2.2K,5%,1/16W,CHIP,CS22202JB07
     1 CPU0_BP2 @T6G_MB_LIB.T6G(SCH_1):CPU0_BP2   I382 @T6G_MB_LIB.T6G(SCH_1):PAGE27
     2 PVDD18_S5_P0 @T6G_MB_LIB.T6G(SCH_1):PVDD18_S5_P0   I382 @T6G_MB_LIB.T6G(SCH_1):PAGE27

R411 Q_RES_0402LF-2.2K,5%,1/16W,CHIP,CS22202JB07
     1 CPU0_BP3 @T6G_MB_LIB.T6G(SCH_1):CPU0_BP3   I383 @T6G_MB_LIB.T6G(SCH_1):PAGE27
     2 PVDD18_S5_P0 @T6G_MB_LIB.T6G(SCH_1):PVDD18_S5_P0   I383 @T6G_MB_LIB.T6G(SCH_1):PAGE27

R412 Q_RES_0402LF-2.2K,5%,1/16W,CHIP,CS22202JB07
     1 CPU0_PROCHOT_N @T6G_MB_LIB.T6G(SCH_1):CPU0_PROCHOT_N   I377 @T6G_MB_LIB.T6G(SCH_1):PAGE27
     2 PVDD18_S5_P0 @T6G_MB_LIB.T6G(SCH_1):PVDD18_S5_P0   I377 @T6G_MB_LIB.T6G(SCH_1):PAGE27

R413 Q_RES_0402LF-2.2K,5%,1/16W,CHIP,CS22202JB07
     1 CPU0_XTRIG_L4 @T6G_MB_LIB.T6G(SCH_1):CPU0_XTRIG_L4   I384 @T6G_MB_LIB.T6G(SCH_1):PAGE27
     2 PVDD18_S5_P0 @T6G_MB_LIB.T6G(SCH_1):PVDD18_S5_P0   I384 @T6G_MB_LIB.T6G(SCH_1):PAGE27

R414 Q_RES_0402LF-2.2K,5%,1/16W,CHIP,CS22202JB07
     1 CPU0_XTRIG_L5 @T6G_MB_LIB.T6G(SCH_1):CPU0_XTRIG_L5   I385 @T6G_MB_LIB.T6G(SCH_1):PAGE27
     2 PVDD18_S5_P0 @T6G_MB_LIB.T6G(SCH_1):PVDD18_S5_P0   I385 @T6G_MB_LIB.T6G(SCH_1):PAGE27

R415 Q_RES_0402LF-2.2K,5%,1/16W,CHIP,CS22202JB07
     1 CPU0_XTRIG_L6 @T6G_MB_LIB.T6G(SCH_1):CPU0_XTRIG_L6   I386 @T6G_MB_LIB.T6G(SCH_1):PAGE27
     2 PVDD18_S5_P0 @T6G_MB_LIB.T6G(SCH_1):PVDD18_S5_P0   I386 @T6G_MB_LIB.T6G(SCH_1):PAGE27

R416 Q_RES_0402LF-2.2K,5%,1/16W,CHIP,CS22202JB07
     1 CPU0_XTRIG_L7 @T6G_MB_LIB.T6G(SCH_1):CPU0_XTRIG_L7   I387 @T6G_MB_LIB.T6G(SCH_1):PAGE27
     2 PVDD18_S5_P0 @T6G_MB_LIB.T6G(SCH_1):PVDD18_S5_P0   I387 @T6G_MB_LIB.T6G(SCH_1):PAGE27

R417 Q_RES_0402LF-2.2K,5%,1/16W,CHIP,CS22202JB07
     1 CPU0_THERMTRIP_N @T6G_MB_LIB.T6G(SCH_1):CPU0_THERMTRIP_N   I379 @T6G_MB_LIB.T6G(SCH_1):PAGE27
     2 PVDD18_S5_P0 @T6G_MB_LIB.T6G(SCH_1):PVDD18_S5_P0   I379 @T6G_MB_LIB.T6G(SCH_1):PAGE27

R418 Q_RES_0402LF-2.2K,5%,1/16W,CHIP,CS22202JB07
     1 APML_CPU0_ALERT_N @T6G_MB_LIB.T6G(SCH_1):APML_CPU0_ALERT_N   I378 @T6G_MB_LIB.T6G(SCH_1):PAGE27
     2 PVDD18_S5_P0 @T6G_MB_LIB.T6G(SCH_1):PVDD18_S5_P0   I378 @T6G_MB_LIB.T6G(SCH_1):PAGE27

R419 Q_RES_0402LF-0,5%,1/16W,CHIP,CS00002JB13
     1 RST_SRST_PLD_BMC_N @T6G_MB_LIB.T6G(SCH_1):RST_SRST_PLD_BMC_N   I141 @T6G_MB_LIB.T6G(SCH_1):PAGE79
     2 RST_SRST_PLD_BMC_R_N @T6G_MB_LIB.T6G(SCH_1):RST_SRST_PLD_BMC_R_N   I141 @T6G_MB_LIB.T6G(SCH_1):PAGE79

R420 Q_RES_0402LF-1K,1%,1/16W,EMPTY,CS21002FB06
     1 PVDD11_S3_P0 @T6G_MB_LIB.T6G(SCH_1):PVDD11_S3_P0    I22 @T6G_MB_LIB.T6G(SCH_1):PAGE28
     2 I3C_1_SPD_DDRGL_CPU0_R_SDA @T6G_MB_LIB.T6G(SCH_1):I3C_1_SPD_DDRGL_CPU0_R_SDA    I22 @T6G_MB_LIB.T6G(SCH_1):PAGE28

R421 Q_RES_0402LF-1K,1%,1/16W,EMPTY,CS21002FB06
     1 PVDD11_S3_P0 @T6G_MB_LIB.T6G(SCH_1):PVDD11_S3_P0    I23 @T6G_MB_LIB.T6G(SCH_1):PAGE28
     2 I3C_1_SPD_DDRGL_CPU0_R_SCL @T6G_MB_LIB.T6G(SCH_1):I3C_1_SPD_DDRGL_CPU0_R_SCL    I23 @T6G_MB_LIB.T6G(SCH_1):PAGE28

R422 Q_RES_0402LF-2.2K,5%,1/16W,CHIP,CS22202JB07
     1 PVDD18_S5_P0 @T6G_MB_LIB.T6G(SCH_1):PVDD18_S5_P0    I29 @T6G_MB_LIB.T6G(SCH_1):PAGE28
     2 RST_CPU0_SYS_N @T6G_MB_LIB.T6G(SCH_1):RST_CPU0_SYS_N    I29 @T6G_MB_LIB.T6G(SCH_1):PAGE28

R423 Q_RES_0402LF-1K,1%,1/16W,EMPTY,CS21002FB06
     1 PVDD11_S3_P0 @T6G_MB_LIB.T6G(SCH_1):PVDD11_S3_P0    I24 @T6G_MB_LIB.T6G(SCH_1):PAGE28
     2 I3C_0_SPD_DDRAF_CPU0_R_SDA @T6G_MB_LIB.T6G(SCH_1):I3C_0_SPD_DDRAF_CPU0_R_SDA    I24 @T6G_MB_LIB.T6G(SCH_1):PAGE28

R424 Q_RES_0402LF-2.2K,5%,1/16W,CHIP,CS22202JB07
     1 PVDD18_S5_P0 @T6G_MB_LIB.T6G(SCH_1):PVDD18_S5_P0    I30 @T6G_MB_LIB.T6G(SCH_1):PAGE28
     2 CPU0_PWR_BTN_N @T6G_MB_LIB.T6G(SCH_1):CPU0_PWR_BTN_N    I30 @T6G_MB_LIB.T6G(SCH_1):PAGE28

R425 Q_RES_0402LF-1K,1%,1/16W,EMPTY,CS21002FB06
     1 PVDD11_S3_P0 @T6G_MB_LIB.T6G(SCH_1):PVDD11_S3_P0    I25 @T6G_MB_LIB.T6G(SCH_1):PAGE28
     2 I3C_0_SPD_DDRAF_CPU0_R_SCL @T6G_MB_LIB.T6G(SCH_1):I3C_0_SPD_DDRAF_CPU0_R_SCL    I25 @T6G_MB_LIB.T6G(SCH_1):PAGE28

R426 Q_RES_0402LF-0,5%,1/16W,CHIP,CS00002JB13
     1 I3C_0_SPD_DDRAF_CPU0_SCL @T6G_MB_LIB.T6G(SCH_1):I3C_0_SPD_DDRAF_CPU0_SCL    I99 @T6G_MB_LIB.T6G(SCH_1):PAGE136
     2 I3C_0_SPD_DDRAF_CPU0_R_SCL @T6G_MB_LIB.T6G(SCH_1):I3C_0_SPD_DDRAF_CPU0_R_SCL    I99 @T6G_MB_LIB.T6G(SCH_1):PAGE136

R427 Q_RES_0402LF-0,5%,1/16W,CHIP,CS00002JB13
     1 I3C_0_SPD_DDRAF_CPU0_SDA @T6G_MB_LIB.T6G(SCH_1):I3C_0_SPD_DDRAF_CPU0_SDA   I100 @T6G_MB_LIB.T6G(SCH_1):PAGE136
     2 I3C_0_SPD_DDRAF_CPU0_R_SDA @T6G_MB_LIB.T6G(SCH_1):I3C_0_SPD_DDRAF_CPU0_R_SDA   I100 @T6G_MB_LIB.T6G(SCH_1):PAGE136

R428 Q_RES_0402LF-0,5%,1/16W,CHIP,CS00002JB13
     1 I3C_1_SPD_DDRGL_CPU0_SCL @T6G_MB_LIB.T6G(SCH_1):I3C_1_SPD_DDRGL_CPU0_SCL   I103 @T6G_MB_LIB.T6G(SCH_1):PAGE136
     2 I3C_1_SPD_DDRGL_CPU0_R_SCL @T6G_MB_LIB.T6G(SCH_1):I3C_1_SPD_DDRGL_CPU0_R_SCL   I103 @T6G_MB_LIB.T6G(SCH_1):PAGE136

R429 Q_RES_0402LF-0,5%,1/16W,CHIP,CS00002JB13
     1 I3C_1_SPD_DDRGL_CPU0_SDA @T6G_MB_LIB.T6G(SCH_1):I3C_1_SPD_DDRGL_CPU0_SDA   I104 @T6G_MB_LIB.T6G(SCH_1):PAGE136
     2 I3C_1_SPD_DDRGL_CPU0_R_SDA @T6G_MB_LIB.T6G(SCH_1):I3C_1_SPD_DDRGL_CPU0_R_SDA   I104 @T6G_MB_LIB.T6G(SCH_1):PAGE136

R430 Q_RES_0402LF-0,5%,1/16W,CHIP,CS00002JB13
     1 SMB_CPU0_4_R_SCL @T6G_MB_LIB.T6G(SCH_1):SMB_CPU0_4_R_SCL    I98 @T6G_MB_LIB.T6G(SCH_1):PAGE28
     2 SMB_CPU0_4_SCL @T6G_MB_LIB.T6G(SCH_1):SMB_CPU0_4_SCL    I98 @T6G_MB_LIB.T6G(SCH_1):PAGE28

R431 Q_RES_0402LF-0,5%,1/16W,CHIP,CS00002JB13
     1 SMB_CPU0_4_R_SDA @T6G_MB_LIB.T6G(SCH_1):SMB_CPU0_4_R_SDA    I97 @T6G_MB_LIB.T6G(SCH_1):PAGE28
     2 SMB_CPU0_4_SDA @T6G_MB_LIB.T6G(SCH_1):SMB_CPU0_4_SDA    I97 @T6G_MB_LIB.T6G(SCH_1):PAGE28

R432 Q_RES_0402LF-10M,1%,1/16W,CHIP,CS61002FB02
     1 XTAL_CPU0_X48M_X1 @T6G_MB_LIB.T6G(SCH_1):XTAL_CPU0_X48M_X1   I104 @T6G_MB_LIB.T6G(SCH_1):PAGE28
     2 XTAL_CPU0_X48M_X2_R @T6G_MB_LIB.T6G(SCH_1):XTAL_CPU0_X48M_X2_R   I104 @T6G_MB_LIB.T6G(SCH_1):PAGE28

R433 Q_RES_0402LF-20M,1%,1/16W,CHIP,CS62002FB01
     1 XTAL_CPU0_X32K_X1 @T6G_MB_LIB.T6G(SCH_1):XTAL_CPU0_X32K_X1   I221 @T6G_MB_LIB.T6G(SCH_1):PAGE28
     2 XTAL_CPU0_X32K_X2 @T6G_MB_LIB.T6G(SCH_1):XTAL_CPU0_X32K_X2   I221 @T6G_MB_LIB.T6G(SCH_1):PAGE28

R434 Q_RES_0402LF-33,5%,1/16W,CHIP,CS03302JB10
     1 CPU0_PWR_GD_OUT @T6G_MB_LIB.T6G(SCH_1):CPU0_PWR_GD_OUT   I165 @T6G_MB_LIB.T6G(SCH_1):PAGE28
     2 CPU1_PWR_GD_IN @T6G_MB_LIB.T6G(SCH_1):CPU1_PWR_GD_IN   I165 @T6G_MB_LIB.T6G(SCH_1):PAGE28

R435 Q_RES_0402LF-0,5%,1/16W,CHIP,CS00002JB13
     1 CLK_100M_REF_OUT_DP @T6G_MB_LIB.T6G(SCH_1):CLK_100M_REF_OUT_DP   I171 @T6G_MB_LIB.T6G(SCH_1):PAGE28
     2 CLK_100M_REF_IN_DP @T6G_MB_LIB.T6G(SCH_1):CLK_100M_REF_IN_DP   I171 @T6G_MB_LIB.T6G(SCH_1):PAGE28

R436 Q_RES_0402LF-0,5%,1/16W,CHIP,CS00002JB13
     1 CLK_100M_REF_OUT_DN @T6G_MB_LIB.T6G(SCH_1):CLK_100M_REF_OUT_DN   I172 @T6G_MB_LIB.T6G(SCH_1):PAGE28
     2 CLK_100M_REF_IN_DN @T6G_MB_LIB.T6G(SCH_1):CLK_100M_REF_IN_DN   I172 @T6G_MB_LIB.T6G(SCH_1):PAGE28

R437 Q_RES_0402LF-2.2K,5%,1/16W,CHIP,CS22202JB07
     1 PVDD18_S5_P0 @T6G_MB_LIB.T6G(SCH_1):PVDD18_S5_P0    I18 @T6G_MB_LIB.T6G(SCH_1):PAGE132
     2 IRQ_WAKE_N @T6G_MB_LIB.T6G(SCH_1):IRQ_WAKE_N    I18 @T6G_MB_LIB.T6G(SCH_1):PAGE132

R438 Q_RES_0402LF-4.7K,5%,1/16W,EMPTY,CS24702JB10
     1 CPU0_FORCE_SELFREFRESH @T6G_MB_LIB.T6G(SCH_1):CPU0_FORCE_SELFREFRESH   I222 @T6G_MB_LIB.T6G(SCH_1):PAGE28
     2 PVDD18_S5_P0 @T6G_MB_LIB.T6G(SCH_1):PVDD18_S5_P0   I222 @T6G_MB_LIB.T6G(SCH_1):PAGE28

R439 Q_RES_0402LF-0,5%,1/16W,CHIP,CS00002JB13
     1 PWRGD_P5V @T6G_MB_LIB.T6G(SCH_1):PWRGD_P5V   I144 @T6G_MB_LIB.T6G(SCH_1):PAGE79
     2 PWRGD_P5V_R2 @T6G_MB_LIB.T6G(SCH_1):PWRGD_P5V_R2   I144 @T6G_MB_LIB.T6G(SCH_1):PAGE79

R440 Q_RES_0402LF-4.7K,5%,1/16W,EMPTY,CS24702JB10
     1    GND @T6G_MB_LIB.T6G(SCH_1):GND    I37 @T6G_MB_LIB.T6G(SCH_1):PAGE28
     2 CPU0_PWR_GD_OUT @T6G_MB_LIB.T6G(SCH_1):CPU0_PWR_GD_OUT    I37 @T6G_MB_LIB.T6G(SCH_1):PAGE28

R441 Q_RES_0402LF-2.2K,5%,1/16W,CHIP,CS22202JB07
     1 CPU0_NMI_SYNC_FLOOD_N @T6G_MB_LIB.T6G(SCH_1):CPU0_NMI_SYNC_FLOOD_N    I55 @T6G_MB_LIB.T6G(SCH_1):PAGE28
     2 PVDD18_S5_P0 @T6G_MB_LIB.T6G(SCH_1):PVDD18_S5_P0    I55 @T6G_MB_LIB.T6G(SCH_1):PAGE28

R442 Q_RES_0402LF-1K,1%,1/16W,CHIP,CS21002FB06
     1 RST_CPU0_RESETL_N @T6G_MB_LIB.T6G(SCH_1):RST_CPU0_RESETL_N    I56 @T6G_MB_LIB.T6G(SCH_1):PAGE28
     2 PVDD18_S5_P0 @T6G_MB_LIB.T6G(SCH_1):PVDD18_S5_P0    I56 @T6G_MB_LIB.T6G(SCH_1):PAGE28

R443 Q_RES_0402LF-1K,1%,1/16W,CHIP,CS21002FB06
     1 PWRGD_CPU0_PWROK @T6G_MB_LIB.T6G(SCH_1):PWRGD_CPU0_PWROK    I53 @T6G_MB_LIB.T6G(SCH_1):PAGE28
     2 PVDD18_S5_P0 @T6G_MB_LIB.T6G(SCH_1):PVDD18_S5_P0    I53 @T6G_MB_LIB.T6G(SCH_1):PAGE28

R444 Q_RES_0402LF-4.7K,5%,1/16W,CHIP,CS24702JB10
     1 FM_SMM_CRASHDUMP @T6G_MB_LIB.T6G(SCH_1):FM_SMM_CRASHDUMP    I43 @T6G_MB_LIB.T6G(SCH_1):PAGE28
     2 PVDD18_S5_P0 @T6G_MB_LIB.T6G(SCH_1):PVDD18_S5_P0    I43 @T6G_MB_LIB.T6G(SCH_1):PAGE28

R445 Q_RES_0402LF-4.7K,5%,1/16W,CHIP,CS24702JB10
     1 IRQ_BMC_SMI_N @T6G_MB_LIB.T6G(SCH_1):IRQ_BMC_SMI_N    I66 @T6G_MB_LIB.T6G(SCH_1):PAGE28
     2 PVDD18_S5_P0 @T6G_MB_LIB.T6G(SCH_1):PVDD18_S5_P0    I66 @T6G_MB_LIB.T6G(SCH_1):PAGE28

R446 Q_RES_0402LF-4.7K,5%,1/16W,CHIP,CS24702JB10
     1 IRQ_SMI_ACTIVE_N @T6G_MB_LIB.T6G(SCH_1):IRQ_SMI_ACTIVE_N    I64 @T6G_MB_LIB.T6G(SCH_1):PAGE28
     2 PVDD18_S5_P0 @T6G_MB_LIB.T6G(SCH_1):PVDD18_S5_P0    I64 @T6G_MB_LIB.T6G(SCH_1):PAGE28

R447 Q_RES_0402LF-4.7K,5%,1/16W,CHIP,CS24702JB10
     1 IRQ_TPM_SPI_R_N @T6G_MB_LIB.T6G(SCH_1):IRQ_TPM_SPI_R_N    I65 @T6G_MB_LIB.T6G(SCH_1):PAGE28
     2 PVDD18_S5_P0 @T6G_MB_LIB.T6G(SCH_1):PVDD18_S5_P0    I65 @T6G_MB_LIB.T6G(SCH_1):PAGE28

R448 Q_RES_0402LF-4.7K,5%,1/16W,EMPTY,CS24702JB10
     1 CPU0_SLP_S5_N @T6G_MB_LIB.T6G(SCH_1):CPU0_SLP_S5_N    I49 @T6G_MB_LIB.T6G(SCH_1):PAGE28
     2 PVDD18_S5_P0 @T6G_MB_LIB.T6G(SCH_1):PVDD18_S5_P0    I49 @T6G_MB_LIB.T6G(SCH_1):PAGE28

R449 Q_RES_0402LF-4.7K,5%,1/16W,EMPTY,CS24702JB10
     1 CPU0_SLP_S3_N @T6G_MB_LIB.T6G(SCH_1):CPU0_SLP_S3_N    I48 @T6G_MB_LIB.T6G(SCH_1):PAGE28
     2 PVDD18_S5_P0 @T6G_MB_LIB.T6G(SCH_1):PVDD18_S5_P0    I48 @T6G_MB_LIB.T6G(SCH_1):PAGE28

R450 Q_RES_0402LF-4.7K,5%,1/16W,CHIP,CS24702JB10
     1 CPU0_SMERR_N @T6G_MB_LIB.T6G(SCH_1):CPU0_SMERR_N    I47 @T6G_MB_LIB.T6G(SCH_1):PAGE28
     2 PVDD18_S5_P0 @T6G_MB_LIB.T6G(SCH_1):PVDD18_S5_P0    I47 @T6G_MB_LIB.T6G(SCH_1):PAGE28

R451 Q_RES_0402LF-4.7K,5%,1/16W,CHIP,CS24702JB10
     1 CPU0_SPD_HOST_CTRL_N @T6G_MB_LIB.T6G(SCH_1):CPU0_SPD_HOST_CTRL_N    I46 @T6G_MB_LIB.T6G(SCH_1):PAGE28
     2 PVDD18_S5_P0 @T6G_MB_LIB.T6G(SCH_1):PVDD18_S5_P0    I46 @T6G_MB_LIB.T6G(SCH_1):PAGE28

R452 Q_RES_0402LF-4.7K,5%,1/16W,CHIP,CS24702JB10
     1 CPU0_NV_SAVE_N @T6G_MB_LIB.T6G(SCH_1):CPU0_NV_SAVE_N    I45 @T6G_MB_LIB.T6G(SCH_1):PAGE28
     2 PVDD18_S5_P0 @T6G_MB_LIB.T6G(SCH_1):PVDD18_S5_P0    I45 @T6G_MB_LIB.T6G(SCH_1):PAGE28

R453 Q_RES_0402LF-10K,5%,1/16W,CHIP,CS31002JB08
     1 PVDD_33_S5_VCC @T6G_MB_LIB.T6G(SCH_1):PVDD_33_S5_VCC    I31 @T6G_MB_LIB.T6G(SCH_1):PAGE167
     2 PWRGD_PVDD33_S5 @T6G_MB_LIB.T6G(SCH_1):PWRGD_PVDD33_S5    I31 @T6G_MB_LIB.T6G(SCH_1):PAGE167

R454 Q_RES_0402LF-10K,5%,1/16W,CHIP,CS31002JB08
     1 PVDD18_S5_P0 @T6G_MB_LIB.T6G(SCH_1):PVDD18_S5_P0   I383 @T6G_MB_LIB.T6G(SCH_1):PAGE29
     2 SCM_USB_OC_BUF_N @T6G_MB_LIB.T6G(SCH_1):SCM_USB_OC_BUF_N   I383 @T6G_MB_LIB.T6G(SCH_1):PAGE29

R455 Q_RES_0402LF-4.7K,5%,1/16W,EMPTY,CS24702JB10
     1 PVDD18_S5_P0 @T6G_MB_LIB.T6G(SCH_1):PVDD18_S5_P0   I284 @T6G_MB_LIB.T6G(SCH_1):PAGE29
     2 ESPI_CPU0_CS1_N @T6G_MB_LIB.T6G(SCH_1):ESPI_CPU0_CS1_N   I284 @T6G_MB_LIB.T6G(SCH_1):PAGE29

R456 Q_RES_0402LF-4.7K,5%,1/16W,EMPTY,CS24702JB10
     1 CPU1_PWRGD_OUT @T6G_MB_LIB.T6G(SCH_1):CPU1_PWRGD_OUT   I339 @T6G_MB_LIB.T6G(SCH_1):PAGE55
     2 PVDD18_S5_P1 @T6G_MB_LIB.T6G(SCH_1):PVDD18_S5_P1   I339 @T6G_MB_LIB.T6G(SCH_1):PAGE55

R457 Q_RES_0402LF-4.7K,5%,1/16W,EMPTY,CS24702JB10
     1 PVDD18_S5_P0 @T6G_MB_LIB.T6G(SCH_1):PVDD18_S5_P0   I282 @T6G_MB_LIB.T6G(SCH_1):PAGE29
     2 RST_ESPI_CPU0_RSTOUT_N @T6G_MB_LIB.T6G(SCH_1):RST_ESPI_CPU0_RSTOUT_N   I282 @T6G_MB_LIB.T6G(SCH_1):PAGE29

R458 Q_RES_0402LF-30K,1%,1/16W,EMPTY,CS33002FB02
     1 PVDD18_S5_P0 @T6G_MB_LIB.T6G(SCH_1):PVDD18_S5_P0   I405 @T6G_MB_LIB.T6G(SCH_1):PAGE29
     2 ESPI_CPU0_ALERT_P0_N @T6G_MB_LIB.T6G(SCH_1):ESPI_CPU0_ALERT_P0_N   I405 @T6G_MB_LIB.T6G(SCH_1):PAGE29

R459 Q_RES_0402LF-33,5%,1/16W,CHIP,CS03302JB10
     1 SPI_CPU0_CS0_N @T6G_MB_LIB.T6G(SCH_1):SPI_CPU0_CS0_N   I407 @T6G_MB_LIB.T6G(SCH_1):PAGE29
     2 SPI_CPU0_R_CS0_N @T6G_MB_LIB.T6G(SCH_1):SPI_CPU0_R_CS0_N   I407 @T6G_MB_LIB.T6G(SCH_1):PAGE29

R460 Q_RES_0402LF-33,5%,1/16W,CHIP,CS03302JB10
     1 SPI_CPU0_CS1_N @T6G_MB_LIB.T6G(SCH_1):SPI_CPU0_CS1_N   I408 @T6G_MB_LIB.T6G(SCH_1):PAGE29
     2 SPI_CPU0_R_CS1_N @T6G_MB_LIB.T6G(SCH_1):SPI_CPU0_R_CS1_N   I408 @T6G_MB_LIB.T6G(SCH_1):PAGE29

R461 Q_RES_0402LF-33,5%,1/16W,CHIP,CS03302JB10
     1 SPI_CPU0_CLK @T6G_MB_LIB.T6G(SCH_1):SPI_CPU0_CLK   I409 @T6G_MB_LIB.T6G(SCH_1):PAGE29
     2 SPI_CPU0_R_CLK @T6G_MB_LIB.T6G(SCH_1):SPI_CPU0_R_CLK   I409 @T6G_MB_LIB.T6G(SCH_1):PAGE29

R462 Q_RES_0402LF-33,5%,1/16W,EMPTY,CS03302JB10
     1 ESPI_CPU0_CS1_N @T6G_MB_LIB.T6G(SCH_1):ESPI_CPU0_CS1_N   I425 @T6G_MB_LIB.T6G(SCH_1):PAGE29
     2 ESPI_CPU0_R_CS1_N @T6G_MB_LIB.T6G(SCH_1):ESPI_CPU0_R_CS1_N   I425 @T6G_MB_LIB.T6G(SCH_1):PAGE29

R463 Q_RES_0402LF-33,5%,1/16W,CHIP,CS03302JB10
     1 RST_CPU0_KBRST_R_N @T6G_MB_LIB.T6G(SCH_1):RST_CPU0_KBRST_R_N   I112 @T6G_MB_LIB.T6G(SCH_1):PAGE80
     2 RST_CPU0_KBRST_N @T6G_MB_LIB.T6G(SCH_1):RST_CPU0_KBRST_N   I112 @T6G_MB_LIB.T6G(SCH_1):PAGE80

R464 Q_RES_0402LF-33,5%,1/16W,CHIP,CS03302JB10
     1 SPI_CPU0_D0 @T6G_MB_LIB.T6G(SCH_1):SPI_CPU0_D0   I410 @T6G_MB_LIB.T6G(SCH_1):PAGE29
     2 SPI_CPU0_R_D0 @T6G_MB_LIB.T6G(SCH_1):SPI_CPU0_R_D0   I410 @T6G_MB_LIB.T6G(SCH_1):PAGE29

R465 Q_RES_0402LF-49.9,1%,1/16W,CHIP,CS04992FB07
     1 SPI_CPU0_D1 @T6G_MB_LIB.T6G(SCH_1):SPI_CPU0_D1   I411 @T6G_MB_LIB.T6G(SCH_1):PAGE29
     2 SPI_CPU0_R_D1 @T6G_MB_LIB.T6G(SCH_1):SPI_CPU0_R_D1   I411 @T6G_MB_LIB.T6G(SCH_1):PAGE29

R466 Q_RES_0402LF-33,5%,1/16W,CHIP,CS03302JB10
     1 SPI_CPU0_D2 @T6G_MB_LIB.T6G(SCH_1):SPI_CPU0_D2   I412 @T6G_MB_LIB.T6G(SCH_1):PAGE29
     2 SPI_CPU0_R_D2 @T6G_MB_LIB.T6G(SCH_1):SPI_CPU0_R_D2   I412 @T6G_MB_LIB.T6G(SCH_1):PAGE29

R467 Q_RES_0402LF-33,5%,1/16W,CHIP,CS03302JB10
     1 SPI_CPU0_D3 @T6G_MB_LIB.T6G(SCH_1):SPI_CPU0_D3   I413 @T6G_MB_LIB.T6G(SCH_1):PAGE29
     2 SPI_CPU0_R_D3 @T6G_MB_LIB.T6G(SCH_1):SPI_CPU0_R_D3   I413 @T6G_MB_LIB.T6G(SCH_1):PAGE29

R468 Q_RES_0402LF-33,5%,1/16W,CHIP,CS03302JB10
     1 ESPI_CPU0_D0 @T6G_MB_LIB.T6G(SCH_1):ESPI_CPU0_D0   I329 @T6G_MB_LIB.T6G(SCH_1):PAGE29
     2 ESPI_CPU0_R_D0 @T6G_MB_LIB.T6G(SCH_1):ESPI_CPU0_R_D0   I329 @T6G_MB_LIB.T6G(SCH_1):PAGE29

R469 Q_RES_0402LF-33,5%,1/16W,CHIP,CS03302JB10
     1 ESPI_CPU0_D1 @T6G_MB_LIB.T6G(SCH_1):ESPI_CPU0_D1   I328 @T6G_MB_LIB.T6G(SCH_1):PAGE29
     2 ESPI_CPU0_R_D1 @T6G_MB_LIB.T6G(SCH_1):ESPI_CPU0_R_D1   I328 @T6G_MB_LIB.T6G(SCH_1):PAGE29

R470 Q_RES_0402LF-33,5%,1/16W,CHIP,CS03302JB10
     1 ESPI_CPU0_D2 @T6G_MB_LIB.T6G(SCH_1):ESPI_CPU0_D2   I327 @T6G_MB_LIB.T6G(SCH_1):PAGE29
     2 ESPI_CPU0_R_D2 @T6G_MB_LIB.T6G(SCH_1):ESPI_CPU0_R_D2   I327 @T6G_MB_LIB.T6G(SCH_1):PAGE29

R471 Q_RES_0402LF-33,5%,1/16W,CHIP,CS03302JB10
     1 ESPI_CPU0_D3 @T6G_MB_LIB.T6G(SCH_1):ESPI_CPU0_D3   I330 @T6G_MB_LIB.T6G(SCH_1):PAGE29
     2 ESPI_CPU0_R_D3 @T6G_MB_LIB.T6G(SCH_1):ESPI_CPU0_R_D3   I330 @T6G_MB_LIB.T6G(SCH_1):PAGE29

R472 Q_RES_0402LF-33,5%,1/16W,EMPTY,CS03302JB10
     1 ESPI_CPU0_ALERT_P0_N @T6G_MB_LIB.T6G(SCH_1):ESPI_CPU0_ALERT_P0_N   I428 @T6G_MB_LIB.T6G(SCH_1):PAGE29
     2 ESPI_CPU0_R_ALERT_N @T6G_MB_LIB.T6G(SCH_1):ESPI_CPU0_R_ALERT_N   I428 @T6G_MB_LIB.T6G(SCH_1):PAGE29

R473 Q_RES_0402LF-0,5%,1/16W,CHIP,CS00002JB13
     1 CLK_ESPI_CPU0_CLK1 @T6G_MB_LIB.T6G(SCH_1):CLK_ESPI_CPU0_CLK1   I430 @T6G_MB_LIB.T6G(SCH_1):PAGE29
     2 CLK_ESPI_CPU0_R_CLK1 @T6G_MB_LIB.T6G(SCH_1):CLK_ESPI_CPU0_R_CLK1   I430 @T6G_MB_LIB.T6G(SCH_1):PAGE29

R474 Q_RES_0402LF-0,5%,1/16W,CHIP,CS00002JB13
     1 RST_ESPI_CPU0_RSTOUT_N @T6G_MB_LIB.T6G(SCH_1):RST_ESPI_CPU0_RSTOUT_N   I332 @T6G_MB_LIB.T6G(SCH_1):PAGE29
     2 RST_ESPI_CPU0_R_RSTOUT_N @T6G_MB_LIB.T6G(SCH_1):RST_ESPI_CPU0_R_RSTOUT_N   I332 @T6G_MB_LIB.T6G(SCH_1):PAGE29

R475 Q_RES_0402LF-33,5%,1/16W,CHIP,CS03302JB10
     1 SPI_CPU0_TPM_CS_N @T6G_MB_LIB.T6G(SCH_1):SPI_CPU0_TPM_CS_N   I414 @T6G_MB_LIB.T6G(SCH_1):PAGE29
     2 SPI_CPU0_R_TPM_CS_N @T6G_MB_LIB.T6G(SCH_1):SPI_CPU0_R_TPM_CS_N   I414 @T6G_MB_LIB.T6G(SCH_1):PAGE29

R476 Q_RES_0402LF-33,5%,1/16W,CHIP,CS03302JB10
     1 CPU0_XTRIG_L6 @T6G_MB_LIB.T6G(SCH_1):CPU0_XTRIG_L6   I148 @T6G_MB_LIB.T6G(SCH_1):PAGE149
     2 HDT_CPU0_XTRIG_L6 @T6G_MB_LIB.T6G(SCH_1):HDT_CPU0_XTRIG_L6   I148 @T6G_MB_LIB.T6G(SCH_1):PAGE149

R477 Q_RES_0402LF-33,5%,1/16W,CHIP,CS03302JB10
     1 CPU0_XTRIG_L7 @T6G_MB_LIB.T6G(SCH_1):CPU0_XTRIG_L7   I147 @T6G_MB_LIB.T6G(SCH_1):PAGE149
     2 HDT_CPU0_XTRIG_L7 @T6G_MB_LIB.T6G(SCH_1):HDT_CPU0_XTRIG_L7   I147 @T6G_MB_LIB.T6G(SCH_1):PAGE149

R478 Q_RES_0402LF-33,5%,1/16W,CHIP,CS03302JB10
     1 CPU0_XTRIG_L5 @T6G_MB_LIB.T6G(SCH_1):CPU0_XTRIG_L5   I150 @T6G_MB_LIB.T6G(SCH_1):PAGE149
     2 HDT_CPU0_XTRIG_L5 @T6G_MB_LIB.T6G(SCH_1):HDT_CPU0_XTRIG_L5   I150 @T6G_MB_LIB.T6G(SCH_1):PAGE149

R479 Q_RES_0402LF-10K,1%,1/16W,CHIP,CS31002FB08
     1    P5V @T6G_MB_LIB.T6G(SCH_1):P5V    I83 @T6G_MB_LIB.T6G(SCH_1):PAGE273
     2 PWRGD_P5V_R @T6G_MB_LIB.T6G(SCH_1):PWRGD_P5V_R    I83 @T6G_MB_LIB.T6G(SCH_1):PAGE273

R480 Q_RES_0402LF-100K,1%,1/16W,CHIP,CS41002FB09
     1 PWRGD_P5V_R @T6G_MB_LIB.T6G(SCH_1):PWRGD_P5V_R    I84 @T6G_MB_LIB.T6G(SCH_1):PAGE273
     2    GND @T6G_MB_LIB.T6G(SCH_1):GND    I84 @T6G_MB_LIB.T6G(SCH_1):PAGE273

R481 Q_RES_0402LF-0,5%,1/16W,CHIP,CS00002JB13
     1 CPU0_XTRIG_L4 @T6G_MB_LIB.T6G(SCH_1):CPU0_XTRIG_L4   I335 @T6G_MB_LIB.T6G(SCH_1):PAGE27
     2 CPU0_XTRIG_R1_L4 @T6G_MB_LIB.T6G(SCH_1):CPU0_XTRIG_R1_L4   I335 @T6G_MB_LIB.T6G(SCH_1):PAGE27

R482 Q_RES_0402LF-0,5%,1/16W,CHIP,CS00002JB13
     1 PWRGD_P5V_R @T6G_MB_LIB.T6G(SCH_1):PWRGD_P5V_R    I96 @T6G_MB_LIB.T6G(SCH_1):PAGE273
     2 PWRGD_P5V_R1 @T6G_MB_LIB.T6G(SCH_1):PWRGD_P5V_R1    I96 @T6G_MB_LIB.T6G(SCH_1):PAGE273

R483 Q_RES_0402LF-0,5%,1/16W,CHIP,CS00002JB13
     1 CPU0_XTRIG_L5 @T6G_MB_LIB.T6G(SCH_1):CPU0_XTRIG_L5   I334 @T6G_MB_LIB.T6G(SCH_1):PAGE27
     2 CPU0_XTRIG_R1_L5 @T6G_MB_LIB.T6G(SCH_1):CPU0_XTRIG_R1_L5   I334 @T6G_MB_LIB.T6G(SCH_1):PAGE27

R484 Q_RES_0402LF-0,5%,1/16W,CHIP,CS00002JB13
     1 CPU0_XTRIG_L6 @T6G_MB_LIB.T6G(SCH_1):CPU0_XTRIG_L6   I336 @T6G_MB_LIB.T6G(SCH_1):PAGE27
     2 CPU0_XTRIG_R1_L6 @T6G_MB_LIB.T6G(SCH_1):CPU0_XTRIG_R1_L6   I336 @T6G_MB_LIB.T6G(SCH_1):PAGE27

R485 Q_RES_0402LF-0,5%,1/16W,CHIP,CS00002JB13
     1 CPU0_XTRIG_L7 @T6G_MB_LIB.T6G(SCH_1):CPU0_XTRIG_L7   I337 @T6G_MB_LIB.T6G(SCH_1):PAGE27
     2 CPU0_XTRIG_R1_L7 @T6G_MB_LIB.T6G(SCH_1):CPU0_XTRIG_R1_L7   I337 @T6G_MB_LIB.T6G(SCH_1):PAGE27

R486 Q_RES_0402LF-0,5%,1/16W,CHIP,CS00002JB13
     1 CPU1_XTRIG_R2_L4 @T6G_MB_LIB.T6G(SCH_1):CPU1_XTRIG_R2_L4   I362 @T6G_MB_LIB.T6G(SCH_1):PAGE54
     2 CPU1_XTRIG_L4 @T6G_MB_LIB.T6G(SCH_1):CPU1_XTRIG_L4   I362 @T6G_MB_LIB.T6G(SCH_1):PAGE54

R487 Q_RES_0402LF-0,5%,1/16W,CHIP,CS00002JB13
     1 SW_P3V3_EN @T6G_MB_LIB.T6G(SCH_1):SW_P3V3_EN    I95 @T6G_MB_LIB.T6G(SCH_1):PAGE273
     2 SW_P3V3_EN_R @T6G_MB_LIB.T6G(SCH_1):SW_P3V3_EN_R    I95 @T6G_MB_LIB.T6G(SCH_1):PAGE273

R488 Q_RES_0402LF-33,5%,1/16W,CHIP,CS03302JB10
     1 CPU1_THERMTRIP_N @T6G_MB_LIB.T6G(SCH_1):CPU1_THERMTRIP_N   I415 @T6G_MB_LIB.T6G(SCH_1):PAGE54
     2 CPU1_THERMTRIP_R_N @T6G_MB_LIB.T6G(SCH_1):CPU1_THERMTRIP_R_N   I415 @T6G_MB_LIB.T6G(SCH_1):PAGE54

R489 Q_RES_0402LF-33,5%,1/16W,CHIP,CS03302JB10
     1 CPU0_THERMTRIP_N @T6G_MB_LIB.T6G(SCH_1):CPU0_THERMTRIP_N   I399 @T6G_MB_LIB.T6G(SCH_1):PAGE27
     2 CPU0_THERMTRIP_R_N @T6G_MB_LIB.T6G(SCH_1):CPU0_THERMTRIP_R_N   I399 @T6G_MB_LIB.T6G(SCH_1):PAGE27

R490 Q_RES_0402LF-0,5%,1/16W,EMPTY,CS00002JB13
     1 PWRGD_P5V_R @T6G_MB_LIB.T6G(SCH_1):PWRGD_P5V_R    I88 @T6G_MB_LIB.T6G(SCH_1):PAGE273
     2 SW_P3V3_EN_R @T6G_MB_LIB.T6G(SCH_1):SW_P3V3_EN_R    I88 @T6G_MB_LIB.T6G(SCH_1):PAGE273

R491 Q_RES_0402LF-4.7K,5%,1/16W,EMPTY,CS24702JB10
     1    GND @T6G_MB_LIB.T6G(SCH_1):GND   I335 @T6G_MB_LIB.T6G(SCH_1):PAGE55
     2 CPU1_PWRGD_OUT @T6G_MB_LIB.T6G(SCH_1):CPU1_PWRGD_OUT   I335 @T6G_MB_LIB.T6G(SCH_1):PAGE55

R492 Q_RES_0402LF-4.7K,5%,1/16W,CHIP,CS24702JB10
     1 P3V3_AUX @T6G_MB_LIB.T6G(SCH_1):P3V3_AUX    I99 @T6G_MB_LIB.T6G(SCH_1):PAGE273
     2 PWRGD_P5V_R_N @T6G_MB_LIB.T6G(SCH_1):PWRGD_P5V_R_N    I99 @T6G_MB_LIB.T6G(SCH_1):PAGE273

R493 Q_RES_0402LF-0,5%,1/16W,CHIP,CS00002JB13
     1 SMB_CPU0_4_XLTR_R_SDA @T6G_MB_LIB.T6G(SCH_1):SMB_CPU0_4_XLTR_R_SDA    I18 @T6G_MB_LIB.T6G(SCH_1):PAGE79
     2 SMB_CPU0_4_XLTR_SDA @T6G_MB_LIB.T6G(SCH_1):SMB_CPU0_4_XLTR_SDA    I18 @T6G_MB_LIB.T6G(SCH_1):PAGE79

R494 Q_RES_0402LF-0,5%,1/16W,CHIP,CS00002JB13
     1 PWRGD_P5V_R_N @T6G_MB_LIB.T6G(SCH_1):PWRGD_P5V_R_N   I102 @T6G_MB_LIB.T6G(SCH_1):PAGE273
     2 PWRGD_P5V_N @T6G_MB_LIB.T6G(SCH_1):PWRGD_P5V_N   I102 @T6G_MB_LIB.T6G(SCH_1):PAGE273

R495 Q_RES_0402LF-4.7K,5%,1/16W,CHIP,CS24702JB10
     1 PVDD18_S5_P0 @T6G_MB_LIB.T6G(SCH_1):PVDD18_S5_P0   I106 @T6G_MB_LIB.T6G(SCH_1):PAGE34
     2 SMB_CPU0_4_SCL @T6G_MB_LIB.T6G(SCH_1):SMB_CPU0_4_SCL   I106 @T6G_MB_LIB.T6G(SCH_1):PAGE34

R496 Q_RES_0402LF-10K,1%,1/16W,EMPTY,CS31002FB08
     1 P3V3_AUX @T6G_MB_LIB.T6G(SCH_1):P3V3_AUX    I93 @T6G_MB_LIB.T6G(SCH_1):PAGE273
     2 SW_P3V3_EN @T6G_MB_LIB.T6G(SCH_1):SW_P3V3_EN    I93 @T6G_MB_LIB.T6G(SCH_1):PAGE273

R497 Q_RES_0402LF-33,5%,1/16W,CHIP,CS03302JB10
     1 APML_CPU1_ALERT_N @T6G_MB_LIB.T6G(SCH_1):APML_CPU1_ALERT_N   I417 @T6G_MB_LIB.T6G(SCH_1):PAGE54
     2 APML_CPU1_ALERT_R_N @T6G_MB_LIB.T6G(SCH_1):APML_CPU1_ALERT_R_N   I417 @T6G_MB_LIB.T6G(SCH_1):PAGE54

R498 Q_RES_0402LF-2.2K,5%,1/16W,CHIP,CS22202JB07
     1 PVDD18_S5_P0 @T6G_MB_LIB.T6G(SCH_1):PVDD18_S5_P0   I107 @T6G_MB_LIB.T6G(SCH_1):PAGE34
     2 SMB_CPU0_4_SDA @T6G_MB_LIB.T6G(SCH_1):SMB_CPU0_4_SDA   I107 @T6G_MB_LIB.T6G(SCH_1):PAGE34

R499 Q_RES_0402LF-4.7K,5%,1/16W,CHIP,CS24702JB10
     1 P3V3_AUX @T6G_MB_LIB.T6G(SCH_1):P3V3_AUX     I4 @T6G_MB_LIB.T6G(SCH_1):PAGE34
     2 SMB_CPU0_4_XLTR_SCL @T6G_MB_LIB.T6G(SCH_1):SMB_CPU0_4_XLTR_SCL     I4 @T6G_MB_LIB.T6G(SCH_1):PAGE34

R500 Q_RES_0402LF-15,1%,1/16W,CHIP,CS01502FB03
     1 M_A_CPU1_ALERT_N @T6G_MB_LIB.T6G(SCH_1):M_A_CPU1_ALERT_N   I322 @T6G_MB_LIB.T6G(SCH_1):PAGE37
     2 M_A_CPU1_ALERT_R_N @T6G_MB_LIB.T6G(SCH_1):M_A_CPU1_ALERT_R_N   I322 @T6G_MB_LIB.T6G(SCH_1):PAGE37

R501 Q_RES_0402LF-15,1%,1/16W,CHIP,CS01502FB03
     1 M_B_CPU1_ALERT_N @T6G_MB_LIB.T6G(SCH_1):M_B_CPU1_ALERT_N   I314 @T6G_MB_LIB.T6G(SCH_1):PAGE38
     2 M_B_CPU1_ALERT_R_N @T6G_MB_LIB.T6G(SCH_1):M_B_CPU1_ALERT_R_N   I314 @T6G_MB_LIB.T6G(SCH_1):PAGE38

R502 Q_RES_0402LF-15,1%,1/16W,CHIP,CS01502FB03
     1 M_C_CPU1_ALERT_N @T6G_MB_LIB.T6G(SCH_1):M_C_CPU1_ALERT_N   I313 @T6G_MB_LIB.T6G(SCH_1):PAGE39
     2 M_C_CPU1_ALERT_R_N @T6G_MB_LIB.T6G(SCH_1):M_C_CPU1_ALERT_R_N   I313 @T6G_MB_LIB.T6G(SCH_1):PAGE39

R503 Q_RES_0402LF-15,1%,1/16W,CHIP,CS01502FB03
     1 M_D_CPU1_ALERT_N @T6G_MB_LIB.T6G(SCH_1):M_D_CPU1_ALERT_N   I314 @T6G_MB_LIB.T6G(SCH_1):PAGE40
     2 M_D_CPU1_ALERT_R_N @T6G_MB_LIB.T6G(SCH_1):M_D_CPU1_ALERT_R_N   I314 @T6G_MB_LIB.T6G(SCH_1):PAGE40

R504 Q_RES_0402LF-15,1%,1/16W,CHIP,CS01502FB03
     1 M_E_CPU1_ALERT_N @T6G_MB_LIB.T6G(SCH_1):M_E_CPU1_ALERT_N   I314 @T6G_MB_LIB.T6G(SCH_1):PAGE41
     2 M_E_CPU1_ALERT_R_N @T6G_MB_LIB.T6G(SCH_1):M_E_CPU1_ALERT_R_N   I314 @T6G_MB_LIB.T6G(SCH_1):PAGE41

R505 Q_RES_0402LF-15,1%,1/16W,CHIP,CS01502FB03
     1 M_F_CPU1_ALERT_N @T6G_MB_LIB.T6G(SCH_1):M_F_CPU1_ALERT_N   I314 @T6G_MB_LIB.T6G(SCH_1):PAGE42
     2 M_F_CPU1_ALERT_R_N @T6G_MB_LIB.T6G(SCH_1):M_F_CPU1_ALERT_R_N   I314 @T6G_MB_LIB.T6G(SCH_1):PAGE42

R506 Q_RES_0402LF-15,1%,1/16W,CHIP,CS01502FB03
     1 M_G_CPU1_ALERT_N @T6G_MB_LIB.T6G(SCH_1):M_G_CPU1_ALERT_N   I322 @T6G_MB_LIB.T6G(SCH_1):PAGE43
     2 M_G_CPU1_ALERT_R_N @T6G_MB_LIB.T6G(SCH_1):M_G_CPU1_ALERT_R_N   I322 @T6G_MB_LIB.T6G(SCH_1):PAGE43

R507 Q_RES_0402LF-15,1%,1/16W,CHIP,CS01502FB03
     1 M_H_CPU1_ALERT_N @T6G_MB_LIB.T6G(SCH_1):M_H_CPU1_ALERT_N   I314 @T6G_MB_LIB.T6G(SCH_1):PAGE44
     2 M_H_CPU1_ALERT_R_N @T6G_MB_LIB.T6G(SCH_1):M_H_CPU1_ALERT_R_N   I314 @T6G_MB_LIB.T6G(SCH_1):PAGE44

R508 Q_RES_0402LF-15,1%,1/16W,CHIP,CS01502FB03
     1 M_I_CPU1_ALERT_N @T6G_MB_LIB.T6G(SCH_1):M_I_CPU1_ALERT_N   I314 @T6G_MB_LIB.T6G(SCH_1):PAGE45
     2 M_I_CPU1_ALERT_R_N @T6G_MB_LIB.T6G(SCH_1):M_I_CPU1_ALERT_R_N   I314 @T6G_MB_LIB.T6G(SCH_1):PAGE45

R509 Q_RES_0402LF-15,1%,1/16W,CHIP,CS01502FB03
     1 M_J_CPU1_ALERT_N @T6G_MB_LIB.T6G(SCH_1):M_J_CPU1_ALERT_N   I314 @T6G_MB_LIB.T6G(SCH_1):PAGE46
     2 M_J_CPU1_ALERT_R_N @T6G_MB_LIB.T6G(SCH_1):M_J_CPU1_ALERT_R_N   I314 @T6G_MB_LIB.T6G(SCH_1):PAGE46

R510 Q_RES_0402LF-15,1%,1/16W,CHIP,CS01502FB03
     1 M_K_CPU1_ALERT_N @T6G_MB_LIB.T6G(SCH_1):M_K_CPU1_ALERT_N   I314 @T6G_MB_LIB.T6G(SCH_1):PAGE47
     2 M_K_CPU1_ALERT_R_N @T6G_MB_LIB.T6G(SCH_1):M_K_CPU1_ALERT_R_N   I314 @T6G_MB_LIB.T6G(SCH_1):PAGE47

R511 Q_RES_0402LF-15,1%,1/16W,CHIP,CS01502FB03
     1 M_L_CPU1_ALERT_N @T6G_MB_LIB.T6G(SCH_1):M_L_CPU1_ALERT_N   I313 @T6G_MB_LIB.T6G(SCH_1):PAGE48
     2 M_L_CPU1_ALERT_R_N @T6G_MB_LIB.T6G(SCH_1):M_L_CPU1_ALERT_R_N   I313 @T6G_MB_LIB.T6G(SCH_1):PAGE48

R512 Q_RES_0402LF-2.2K,5%,1/16W,CHIP,CS22202JB07
     1 P3V3_AUX @T6G_MB_LIB.T6G(SCH_1):P3V3_AUX   I400 @T6G_MB_LIB.T6G(SCH_1):PAGE54
     2 CPU1_CORETYPE2 @T6G_MB_LIB.T6G(SCH_1):CPU1_CORETYPE2   I400 @T6G_MB_LIB.T6G(SCH_1):PAGE54

R513 Q_RES_0402LF-2.2K,5%,1/16W,CHIP,CS22202JB07
     1 P3V3_AUX @T6G_MB_LIB.T6G(SCH_1):P3V3_AUX   I390 @T6G_MB_LIB.T6G(SCH_1):PAGE54
     2 CPU1_SP5R4 @T6G_MB_LIB.T6G(SCH_1):CPU1_SP5R4   I390 @T6G_MB_LIB.T6G(SCH_1):PAGE54

R514 Q_RES_0402LF-2.2K,5%,1/16W,CHIP,CS22202JB07
     1 P3V3_AUX @T6G_MB_LIB.T6G(SCH_1):P3V3_AUX   I401 @T6G_MB_LIB.T6G(SCH_1):PAGE54
     2 CPU1_CORETYPE1 @T6G_MB_LIB.T6G(SCH_1):CPU1_CORETYPE1   I401 @T6G_MB_LIB.T6G(SCH_1):PAGE54

R515 Q_RES_0402LF-2.2K,5%,1/16W,CHIP,CS22202JB07
     1 P3V3_AUX @T6G_MB_LIB.T6G(SCH_1):P3V3_AUX   I391 @T6G_MB_LIB.T6G(SCH_1):PAGE54
     2 CPU1_SP5R3 @T6G_MB_LIB.T6G(SCH_1):CPU1_SP5R3   I391 @T6G_MB_LIB.T6G(SCH_1):PAGE54

R516 Q_RES_0402LF-2.2K,5%,1/16W,CHIP,CS22202JB07
     1 P3V3_AUX @T6G_MB_LIB.T6G(SCH_1):P3V3_AUX   I402 @T6G_MB_LIB.T6G(SCH_1):PAGE54
     2 CPU1_CORETYPE0 @T6G_MB_LIB.T6G(SCH_1):CPU1_CORETYPE0   I402 @T6G_MB_LIB.T6G(SCH_1):PAGE54

R517 Q_RES_0402LF-2.2K,5%,1/16W,CHIP,CS22202JB07
     1 P3V3_AUX @T6G_MB_LIB.T6G(SCH_1):P3V3_AUX   I387 @T6G_MB_LIB.T6G(SCH_1):PAGE54
     2 CPU1_SP5R2 @T6G_MB_LIB.T6G(SCH_1):CPU1_SP5R2   I387 @T6G_MB_LIB.T6G(SCH_1):PAGE54

R518 Q_RES_0402LF-2.2K,5%,1/16W,CHIP,CS22202JB07
     1 PVDD18_S5_P1 @T6G_MB_LIB.T6G(SCH_1):PVDD18_S5_P1   I403 @T6G_MB_LIB.T6G(SCH_1):PAGE54
     2 CPU1_SA0 @T6G_MB_LIB.T6G(SCH_1):CPU1_SA0   I403 @T6G_MB_LIB.T6G(SCH_1):PAGE54

R519 Q_RES_0402LF-2.2K,5%,1/16W,EMPTY,CS22202JB07
     1 CPU1_SA0 @T6G_MB_LIB.T6G(SCH_1):CPU1_SA0   I404 @T6G_MB_LIB.T6G(SCH_1):PAGE54
     2    GND @T6G_MB_LIB.T6G(SCH_1):GND   I404 @T6G_MB_LIB.T6G(SCH_1):PAGE54

R520 Q_RES_0402LF-2.2K,5%,1/16W,CHIP,CS22202JB07
     1 CPU1_PROCHOT_N @T6G_MB_LIB.T6G(SCH_1):CPU1_PROCHOT_N   I396 @T6G_MB_LIB.T6G(SCH_1):PAGE54
     2 PVDD18_S5_P1 @T6G_MB_LIB.T6G(SCH_1):PVDD18_S5_P1   I396 @T6G_MB_LIB.T6G(SCH_1):PAGE54

R521 Q_RES_0402LF-2.2K,5%,1/16W,CHIP,CS22202JB07
     1 CPU1_SA1 @T6G_MB_LIB.T6G(SCH_1):CPU1_SA1   I405 @T6G_MB_LIB.T6G(SCH_1):PAGE54
     2    GND @T6G_MB_LIB.T6G(SCH_1):GND   I405 @T6G_MB_LIB.T6G(SCH_1):PAGE54

R522 Q_RES_0402LF-2.2K,5%,1/16W,CHIP,CS22202JB07
     1 P3V3_AUX @T6G_MB_LIB.T6G(SCH_1):P3V3_AUX   I388 @T6G_MB_LIB.T6G(SCH_1):PAGE54
     2 CPU1_SP5R1 @T6G_MB_LIB.T6G(SCH_1):CPU1_SP5R1   I388 @T6G_MB_LIB.T6G(SCH_1):PAGE54

R523 Q_RES_0402LF-1K,1%,1/16W,CHIP,CS21002FB06
     1 PVDD18_S5_P1 @T6G_MB_LIB.T6G(SCH_1):PVDD18_S5_P1   I324 @T6G_MB_LIB.T6G(SCH_1):PAGE54
     2 JTAG_CPU1_TDO @T6G_MB_LIB.T6G(SCH_1):JTAG_CPU1_TDO   I324 @T6G_MB_LIB.T6G(SCH_1):PAGE54

R524 Q_RES_0402LF-1K,1%,1/16W,CHIP,CS21002FB06
     1 PVDD18_S5_P1 @T6G_MB_LIB.T6G(SCH_1):PVDD18_S5_P1   I317 @T6G_MB_LIB.T6G(SCH_1):PAGE54
     2 JTAG_CPU1_TDI @T6G_MB_LIB.T6G(SCH_1):JTAG_CPU1_TDI   I317 @T6G_MB_LIB.T6G(SCH_1):PAGE54

R525 Q_RES_0402LF-1K,1%,1/16W,CHIP,CS21002FB06
     1 PVDD18_S5_P1 @T6G_MB_LIB.T6G(SCH_1):PVDD18_S5_P1   I316 @T6G_MB_LIB.T6G(SCH_1):PAGE54
     2 JTAG_CPU1_TRST_N @T6G_MB_LIB.T6G(SCH_1):JTAG_CPU1_TRST_N   I316 @T6G_MB_LIB.T6G(SCH_1):PAGE54

R526 Q_RES_0402LF-1K,1%,1/16W,CHIP,CS21002FB06
     1 PVDD18_S5_P1 @T6G_MB_LIB.T6G(SCH_1):PVDD18_S5_P1   I314 @T6G_MB_LIB.T6G(SCH_1):PAGE54
     2 JTAG_CPU1_TCK @T6G_MB_LIB.T6G(SCH_1):JTAG_CPU1_TCK   I314 @T6G_MB_LIB.T6G(SCH_1):PAGE54

R527 Q_RES_0402LF-1K,1%,1/16W,CHIP,CS21002FB06
     1 PVDD18_S5_P1 @T6G_MB_LIB.T6G(SCH_1):PVDD18_S5_P1   I309 @T6G_MB_LIB.T6G(SCH_1):PAGE54
     2 JTAG_CPU1_TMS @T6G_MB_LIB.T6G(SCH_1):JTAG_CPU1_TMS   I309 @T6G_MB_LIB.T6G(SCH_1):PAGE54

R528 Q_RES_0402LF-1K,1%,1/16W,CHIP,CS21002FB06
     1 PVDD18_S5_P1 @T6G_MB_LIB.T6G(SCH_1):PVDD18_S5_P1   I308 @T6G_MB_LIB.T6G(SCH_1):PAGE54
     2 JTAG_CPU1_DBREQ_N @T6G_MB_LIB.T6G(SCH_1):JTAG_CPU1_DBREQ_N   I308 @T6G_MB_LIB.T6G(SCH_1):PAGE54

R529 Q_RES_0402LF-0,5%,1/16W,CHIP,CS00002JB13
     1 JTAG_CPU1_R_TDO @T6G_MB_LIB.T6G(SCH_1):JTAG_CPU1_R_TDO   I203 @T6G_MB_LIB.T6G(SCH_1):PAGE54
     2 JTAG_CPU1_TDO @T6G_MB_LIB.T6G(SCH_1):JTAG_CPU1_TDO   I203 @T6G_MB_LIB.T6G(SCH_1):PAGE54

R530 Q_RES_0402LF-0,5%,1/16W,CHIP,CS00002JB13
     1 RST_CPU0_RESETL_N @T6G_MB_LIB.T6G(SCH_1):RST_CPU0_RESETL_N    I27 @T6G_MB_LIB.T6G(SCH_1):PAGE84
     2 RST_CPU1_RESETL_N @T6G_MB_LIB.T6G(SCH_1):RST_CPU1_RESETL_N    I27 @T6G_MB_LIB.T6G(SCH_1):PAGE84

R531 Q_RES_0402LF-2.2K,5%,1/16W,CHIP,CS22202JB07
     1 CPU1_BP0 @T6G_MB_LIB.T6G(SCH_1):CPU1_BP0   I406 @T6G_MB_LIB.T6G(SCH_1):PAGE54
     2 PVDD18_S5_P1 @T6G_MB_LIB.T6G(SCH_1):PVDD18_S5_P1   I406 @T6G_MB_LIB.T6G(SCH_1):PAGE54

R532 Q_RES_0402LF-2.2K,5%,1/16W,CHIP,CS22202JB07
     1 CPU1_BP1 @T6G_MB_LIB.T6G(SCH_1):CPU1_BP1   I407 @T6G_MB_LIB.T6G(SCH_1):PAGE54
     2 PVDD18_S5_P1 @T6G_MB_LIB.T6G(SCH_1):PVDD18_S5_P1   I407 @T6G_MB_LIB.T6G(SCH_1):PAGE54

R533 Q_RES_0402LF-2.2K,5%,1/16W,CHIP,CS22202JB07
     1 CPU1_BP2 @T6G_MB_LIB.T6G(SCH_1):CPU1_BP2   I408 @T6G_MB_LIB.T6G(SCH_1):PAGE54
     2 PVDD18_S5_P1 @T6G_MB_LIB.T6G(SCH_1):PVDD18_S5_P1   I408 @T6G_MB_LIB.T6G(SCH_1):PAGE54

R534 Q_RES_0402LF-2.2K,5%,1/16W,CHIP,CS22202JB07
     1 CPU1_BP3 @T6G_MB_LIB.T6G(SCH_1):CPU1_BP3   I409 @T6G_MB_LIB.T6G(SCH_1):PAGE54
     2 PVDD18_S5_P1 @T6G_MB_LIB.T6G(SCH_1):PVDD18_S5_P1   I409 @T6G_MB_LIB.T6G(SCH_1):PAGE54

R535 Q_RES_0402LF-2.2K,5%,1/16W,CHIP,CS22202JB07
     1 APML_CPU1_ALERT_N @T6G_MB_LIB.T6G(SCH_1):APML_CPU1_ALERT_N   I398 @T6G_MB_LIB.T6G(SCH_1):PAGE54
     2 PVDD18_S5_P1 @T6G_MB_LIB.T6G(SCH_1):PVDD18_S5_P1   I398 @T6G_MB_LIB.T6G(SCH_1):PAGE54

R536 Q_RES_0402LF-2.2K,5%,1/16W,EMPTY,CS22202JB07
     1 CPU1_THERMTRIP_N @T6G_MB_LIB.T6G(SCH_1):CPU1_THERMTRIP_N   I421 @T6G_MB_LIB.T6G(SCH_1):PAGE54
     2 PVDD18_S5_P1 @T6G_MB_LIB.T6G(SCH_1):PVDD18_S5_P1   I421 @T6G_MB_LIB.T6G(SCH_1):PAGE54

R537 Q_RES_0402LF-2.2K,5%,1/16W,CHIP,CS22202JB07
     1 CPU1_XTRIG_L4 @T6G_MB_LIB.T6G(SCH_1):CPU1_XTRIG_L4   I410 @T6G_MB_LIB.T6G(SCH_1):PAGE54
     2 PVDD18_S5_P1 @T6G_MB_LIB.T6G(SCH_1):PVDD18_S5_P1   I410 @T6G_MB_LIB.T6G(SCH_1):PAGE54

R538 Q_RES_0402LF-2.2K,5%,1/16W,CHIP,CS22202JB07
     1 CPU1_XTRIG_L5 @T6G_MB_LIB.T6G(SCH_1):CPU1_XTRIG_L5   I411 @T6G_MB_LIB.T6G(SCH_1):PAGE54
     2 PVDD18_S5_P1 @T6G_MB_LIB.T6G(SCH_1):PVDD18_S5_P1   I411 @T6G_MB_LIB.T6G(SCH_1):PAGE54

R539 Q_RES_0402LF-2.2K,5%,1/16W,CHIP,CS22202JB07
     1 CPU1_XTRIG_L6 @T6G_MB_LIB.T6G(SCH_1):CPU1_XTRIG_L6   I412 @T6G_MB_LIB.T6G(SCH_1):PAGE54
     2 PVDD18_S5_P1 @T6G_MB_LIB.T6G(SCH_1):PVDD18_S5_P1   I412 @T6G_MB_LIB.T6G(SCH_1):PAGE54

R540 Q_RES_0402LF-2.2K,5%,1/16W,CHIP,CS22202JB07
     1 CPU1_XTRIG_L7 @T6G_MB_LIB.T6G(SCH_1):CPU1_XTRIG_L7   I413 @T6G_MB_LIB.T6G(SCH_1):PAGE54
     2 PVDD18_S5_P1 @T6G_MB_LIB.T6G(SCH_1):PVDD18_S5_P1   I413 @T6G_MB_LIB.T6G(SCH_1):PAGE54

R541 Q_RES_0402LF-1K,1%,1/16W,EMPTY,CS21002FB06
     1 PVDD11_S3_P1 @T6G_MB_LIB.T6G(SCH_1):PVDD11_S3_P1   I365 @T6G_MB_LIB.T6G(SCH_1):PAGE55
     2 I3C_1_SPD_DDRGL_CPU1_R_SDA @T6G_MB_LIB.T6G(SCH_1):I3C_1_SPD_DDRGL_CPU1_R_SDA   I365 @T6G_MB_LIB.T6G(SCH_1):PAGE55

R542 Q_RES_0402LF-1K,1%,1/16W,EMPTY,CS21002FB06
     1 PVDD11_S3_P1 @T6G_MB_LIB.T6G(SCH_1):PVDD11_S3_P1   I366 @T6G_MB_LIB.T6G(SCH_1):PAGE55
     2 I3C_1_SPD_DDRGL_CPU1_R_SCL @T6G_MB_LIB.T6G(SCH_1):I3C_1_SPD_DDRGL_CPU1_R_SCL   I366 @T6G_MB_LIB.T6G(SCH_1):PAGE55

R543 Q_RES_0402LF-1K,1%,1/16W,EMPTY,CS21002FB06
     1 PVDD11_S3_P1 @T6G_MB_LIB.T6G(SCH_1):PVDD11_S3_P1   I367 @T6G_MB_LIB.T6G(SCH_1):PAGE55
     2 I3C_0_SPD_DDRAF_CPU1_R_SDA @T6G_MB_LIB.T6G(SCH_1):I3C_0_SPD_DDRAF_CPU1_R_SDA   I367 @T6G_MB_LIB.T6G(SCH_1):PAGE55

R544 Q_RES_0402LF-4.7K,5%,1/16W,CHIP,CS24702JB10
     1 IRQ_CPU_BMC_NMI_N @T6G_MB_LIB.T6G(SCH_1):IRQ_CPU_BMC_NMI_N   I336 @T6G_MB_LIB.T6G(SCH_1):PAGE55
     2 PVDD18_S5_P1 @T6G_MB_LIB.T6G(SCH_1):PVDD18_S5_P1   I336 @T6G_MB_LIB.T6G(SCH_1):PAGE55

R545 Q_RES_0402LF-4.7K,5%,1/16W,CHIP,CS24702JB10
     1 FM_BMC_READY_N @T6G_MB_LIB.T6G(SCH_1):FM_BMC_READY_N   I337 @T6G_MB_LIB.T6G(SCH_1):PAGE55
     2 PVDD18_S5_P1 @T6G_MB_LIB.T6G(SCH_1):PVDD18_S5_P1   I337 @T6G_MB_LIB.T6G(SCH_1):PAGE55

R546 Q_RES_0402LF-4.7K,5%,1/16W,CHIP,CS24702JB10
     1 FM_BMC_TPM_PRES_N @T6G_MB_LIB.T6G(SCH_1):FM_BMC_TPM_PRES_N   I338 @T6G_MB_LIB.T6G(SCH_1):PAGE55
     2 PVDD18_S5_P1 @T6G_MB_LIB.T6G(SCH_1):PVDD18_S5_P1   I338 @T6G_MB_LIB.T6G(SCH_1):PAGE55

R547 Q_RES_0402LF-4.7K,5%,1/16W,CHIP,CS24702JB10
     1 FM_CPU1_BMC_RST_N @T6G_MB_LIB.T6G(SCH_1):FM_CPU1_BMC_RST_N   I362 @T6G_MB_LIB.T6G(SCH_1):PAGE55
     2 PVDD18_S5_P1 @T6G_MB_LIB.T6G(SCH_1):PVDD18_S5_P1   I362 @T6G_MB_LIB.T6G(SCH_1):PAGE55

R548 Q_RES_0402LF-4.7K,5%,1/16W,EMPTY,CS24702JB10
     1 CPU1_SLP_S5_N @T6G_MB_LIB.T6G(SCH_1):CPU1_SLP_S5_N   I352 @T6G_MB_LIB.T6G(SCH_1):PAGE55
     2 PVDD18_S5_P1 @T6G_MB_LIB.T6G(SCH_1):PVDD18_S5_P1   I352 @T6G_MB_LIB.T6G(SCH_1):PAGE55

R549 Q_RES_0402LF-4.7K,5%,1/16W,EMPTY,CS24702JB10
     1 CPU1_SLP_S3_N @T6G_MB_LIB.T6G(SCH_1):CPU1_SLP_S3_N   I353 @T6G_MB_LIB.T6G(SCH_1):PAGE55
     2 PVDD18_S5_P1 @T6G_MB_LIB.T6G(SCH_1):PVDD18_S5_P1   I353 @T6G_MB_LIB.T6G(SCH_1):PAGE55

R550 Q_RES_0402LF-4.7K,5%,1/16W,CHIP,CS24702JB10
     1 CPU1_SMERR_N @T6G_MB_LIB.T6G(SCH_1):CPU1_SMERR_N   I363 @T6G_MB_LIB.T6G(SCH_1):PAGE55
     2 PVDD18_S5_P1 @T6G_MB_LIB.T6G(SCH_1):PVDD18_S5_P1   I363 @T6G_MB_LIB.T6G(SCH_1):PAGE55

R551 Q_RES_0402LF-4.7K,5%,1/16W,CHIP,CS24702JB10
     1 CPU1_SPD_HOST_CTRL_N @T6G_MB_LIB.T6G(SCH_1):CPU1_SPD_HOST_CTRL_N   I360 @T6G_MB_LIB.T6G(SCH_1):PAGE55
     2 PVDD18_S5_P1 @T6G_MB_LIB.T6G(SCH_1):PVDD18_S5_P1   I360 @T6G_MB_LIB.T6G(SCH_1):PAGE55

R552 Q_RES_0402LF-4.7K,5%,1/16W,CHIP,CS24702JB10
     1 P3V3_AUX @T6G_MB_LIB.T6G(SCH_1):P3V3_AUX   I104 @T6G_MB_LIB.T6G(SCH_1):PAGE273
     2 PWRGD_P5V_R2 @T6G_MB_LIB.T6G(SCH_1):PWRGD_P5V_R2   I104 @T6G_MB_LIB.T6G(SCH_1):PAGE273

R553 Q_RES_0402LF-4.7K,5%,1/16W,CHIP,CS24702JB10
     1 CPU1_NV_SAVE_N @T6G_MB_LIB.T6G(SCH_1):CPU1_NV_SAVE_N   I359 @T6G_MB_LIB.T6G(SCH_1):PAGE55
     2 PVDD18_S5_P1 @T6G_MB_LIB.T6G(SCH_1):PVDD18_S5_P1   I359 @T6G_MB_LIB.T6G(SCH_1):PAGE55

R554 Q_RES_0402LF-100K,1%,1/16W,CHIP,CS41002FB09
     1 P12V_AUX @T6G_MB_LIB.T6G(SCH_1):P12V_AUX   I111 @T6G_MB_LIB.T6G(SCH_1):PAGE273
     2 SW_P3V3_EN_N @T6G_MB_LIB.T6G(SCH_1):SW_P3V3_EN_N   I111 @T6G_MB_LIB.T6G(SCH_1):PAGE273

R555 Q_RES_0603LF-1,1%,1/10W,CHIP,CS-1003F900
     1 P3V3_9ZXL045_P1 @T6G_MB_LIB.T6G(SCH_1):P3V3_9ZXL045_P1    I20 @T6G_MB_LIB.T6G(SCH_1):PAGE379
     2 P3V3_9ZXL045_P1_VDDR @T6G_MB_LIB.T6G(SCH_1):P3V3_9ZXL045_P1_VDDR    I20 @T6G_MB_LIB.T6G(SCH_1):PAGE379

R556 Q_RES_0402LF-1K,1%,1/16W,EMPTY,CS21002FB06
     1 PVDD18_S5_P1 @T6G_MB_LIB.T6G(SCH_1):PVDD18_S5_P1   I357 @T6G_MB_LIB.T6G(SCH_1):PAGE55
     2 RST_CPU1_RESETL_N @T6G_MB_LIB.T6G(SCH_1):RST_CPU1_RESETL_N   I357 @T6G_MB_LIB.T6G(SCH_1):PAGE55

R557 Q_RES_0402LF-1K,1%,1/16W,EMPTY,CS21002FB06
     1 PVDD18_S5_P1 @T6G_MB_LIB.T6G(SCH_1):PVDD18_S5_P1   I364 @T6G_MB_LIB.T6G(SCH_1):PAGE55
     2 PWRGD_CPU1_PWROK @T6G_MB_LIB.T6G(SCH_1):PWRGD_CPU1_PWROK   I364 @T6G_MB_LIB.T6G(SCH_1):PAGE55

R558 Q_RES_0402LF-4.7K,5%,1/16W,EMPTY,CS24702JB10
     1 CPU1_FORCE_SELFREFRESH @T6G_MB_LIB.T6G(SCH_1):CPU1_FORCE_SELFREFRESH   I390 @T6G_MB_LIB.T6G(SCH_1):PAGE55
     2 PVDD18_S5_P1 @T6G_MB_LIB.T6G(SCH_1):PVDD18_S5_P1   I390 @T6G_MB_LIB.T6G(SCH_1):PAGE55

R559 Q_RES_0402LF-2.2K,5%,1/16W,CHIP,CS22202JB07
     1 PVDD18_S5_P1 @T6G_MB_LIB.T6G(SCH_1):PVDD18_S5_P1   I356 @T6G_MB_LIB.T6G(SCH_1):PAGE55
     2 RST_CPU1_SYS_N @T6G_MB_LIB.T6G(SCH_1):RST_CPU1_SYS_N   I356 @T6G_MB_LIB.T6G(SCH_1):PAGE55

R560 Q_RES_0402LF-10K,1%,1/16W,CHIP,CS31002FB08
     1 P3V3_AUX @T6G_MB_LIB.T6G(SCH_1):P3V3_AUX    I81 @T6G_MB_LIB.T6G(SCH_1):PAGE379
     2 FM_9ZXL045_P1_DEV_EN @T6G_MB_LIB.T6G(SCH_1):FM_9ZXL045_P1_DEV_EN    I81 @T6G_MB_LIB.T6G(SCH_1):PAGE379

R561 Q_RES_0402LF-0,5%,1/16W,CHIP,CS00002JB13
     1 P12V_OCP_SFF_BUF_EN_R @T6G_MB_LIB.T6G(SCH_1):P12V_OCP_SFF_BUF_EN_R   I125 @T6G_MB_LIB.T6G(SCH_1):PAGE338
     2 P12V_OCP_EN_1_R @T6G_MB_LIB.T6G(SCH_1):P12V_OCP_EN_1_R   I125 @T6G_MB_LIB.T6G(SCH_1):PAGE338

R562 Q_RES_0402LF-2.2K,5%,1/16W,CHIP,CS22202JB07
     1 PVDD18_S5_P1 @T6G_MB_LIB.T6G(SCH_1):PVDD18_S5_P1   I355 @T6G_MB_LIB.T6G(SCH_1):PAGE55
     2 CPU1_NMI_SYNC_FLOOD_N @T6G_MB_LIB.T6G(SCH_1):CPU1_NMI_SYNC_FLOOD_N   I355 @T6G_MB_LIB.T6G(SCH_1):PAGE55

R563 Q_RES_0402LF-1K,1%,1/16W,EMPTY,CS21002FB06
     1 PVDD11_S3_P1 @T6G_MB_LIB.T6G(SCH_1):PVDD11_S3_P1   I368 @T6G_MB_LIB.T6G(SCH_1):PAGE55
     2 I3C_0_SPD_DDRAF_CPU1_R_SCL @T6G_MB_LIB.T6G(SCH_1):I3C_0_SPD_DDRAF_CPU1_R_SCL   I368 @T6G_MB_LIB.T6G(SCH_1):PAGE55

R564 Q_RES_0402LF-0,5%,1/16W,CHIP,CS00002JB13
     1 I3C_0_SPD_DDRAF_CPU1_SCL @T6G_MB_LIB.T6G(SCH_1):I3C_0_SPD_DDRAF_CPU1_SCL   I108 @T6G_MB_LIB.T6G(SCH_1):PAGE136
     2 I3C_0_SPD_DDRAF_CPU1_R_SCL @T6G_MB_LIB.T6G(SCH_1):I3C_0_SPD_DDRAF_CPU1_R_SCL   I108 @T6G_MB_LIB.T6G(SCH_1):PAGE136

R565 Q_RES_0402LF-0,5%,1/16W,CHIP,CS00002JB13
     1 I3C_0_SPD_DDRAF_CPU1_SDA @T6G_MB_LIB.T6G(SCH_1):I3C_0_SPD_DDRAF_CPU1_SDA   I107 @T6G_MB_LIB.T6G(SCH_1):PAGE136
     2 I3C_0_SPD_DDRAF_CPU1_R_SDA @T6G_MB_LIB.T6G(SCH_1):I3C_0_SPD_DDRAF_CPU1_R_SDA   I107 @T6G_MB_LIB.T6G(SCH_1):PAGE136

R566 Q_RES_0402LF-0,5%,1/16W,CHIP,CS00002JB13
     1 I3C_1_SPD_DDRGL_CPU1_SCL @T6G_MB_LIB.T6G(SCH_1):I3C_1_SPD_DDRGL_CPU1_SCL   I111 @T6G_MB_LIB.T6G(SCH_1):PAGE136
     2 I3C_1_SPD_DDRGL_CPU1_R_SCL @T6G_MB_LIB.T6G(SCH_1):I3C_1_SPD_DDRGL_CPU1_R_SCL   I111 @T6G_MB_LIB.T6G(SCH_1):PAGE136

R567 Q_RES_0402LF-0,5%,1/16W,CHIP,CS00002JB13
     1 I3C_1_SPD_DDRGL_CPU1_SDA @T6G_MB_LIB.T6G(SCH_1):I3C_1_SPD_DDRGL_CPU1_SDA   I112 @T6G_MB_LIB.T6G(SCH_1):PAGE136
     2 I3C_1_SPD_DDRGL_CPU1_R_SDA @T6G_MB_LIB.T6G(SCH_1):I3C_1_SPD_DDRGL_CPU1_R_SDA   I112 @T6G_MB_LIB.T6G(SCH_1):PAGE136

R568 Q_RES_0402LF-10K,1%,1/16W,CHIP,CS31002FB08
     1 P12V_AUX @T6G_MB_LIB.T6G(SCH_1):P12V_AUX   I114 @T6G_MB_LIB.T6G(SCH_1):PAGE273
     2 SW_P3V3_EN_ISO_R @T6G_MB_LIB.T6G(SCH_1):SW_P3V3_EN_ISO_R   I114 @T6G_MB_LIB.T6G(SCH_1):PAGE273

R569 Q_RES_0402LF-1K,1%,1/16W,CHIP,CS21002FB06
     1 SW_P3V3_EN_ISO_R @T6G_MB_LIB.T6G(SCH_1):SW_P3V3_EN_ISO_R   I113 @T6G_MB_LIB.T6G(SCH_1):PAGE273
     2 SW_P3V3_EN_ISO @T6G_MB_LIB.T6G(SCH_1):SW_P3V3_EN_ISO   I113 @T6G_MB_LIB.T6G(SCH_1):PAGE273

R570 Q_RES_0402LF-0,5%,1/16W,CHIP,CS00002JB13
     1 CPU1_SPD_HOST_CTRL_N @T6G_MB_LIB.T6G(SCH_1):CPU1_SPD_HOST_CTRL_N   I236 @T6G_MB_LIB.T6G(SCH_1):PAGE55
     2 CPU1_SPD_HOST_CTRL_R_N @T6G_MB_LIB.T6G(SCH_1):CPU1_SPD_HOST_CTRL_R_N   I236 @T6G_MB_LIB.T6G(SCH_1):PAGE55

R571 Q_RES_0402LF-10M,1%,1/16W,CHIP,CS61002FB02
     1 XTAL_CPU1_X48M_X1 @T6G_MB_LIB.T6G(SCH_1):XTAL_CPU1_X48M_X1    I10 @T6G_MB_LIB.T6G(SCH_1):PAGE55
     2 XTAL_CPU1_X48M_X2_R @T6G_MB_LIB.T6G(SCH_1):XTAL_CPU1_X48M_X2_R    I10 @T6G_MB_LIB.T6G(SCH_1):PAGE55

R572 Q_RES_0402LF-20M,1%,1/16W,CHIP,CS62002FB01
     1 XTAL_CPU1_R_X32K_X1 @T6G_MB_LIB.T6G(SCH_1):XTAL_CPU1_R_X32K_X1   I389 @T6G_MB_LIB.T6G(SCH_1):PAGE55
     2 XTAL_CPU1_R_X32K_X2 @T6G_MB_LIB.T6G(SCH_1):XTAL_CPU1_R_X32K_X2   I389 @T6G_MB_LIB.T6G(SCH_1):PAGE55

R573 Q_RES_0402LF-0,5%,1/16W,CHIP,CS00002JB13
     1 CLK_CPU0_RTCCLK @T6G_MB_LIB.T6G(SCH_1):CLK_CPU0_RTCCLK    I26 @T6G_MB_LIB.T6G(SCH_1):PAGE55
     2 XTAL_CPU1_X32K_X1 @T6G_MB_LIB.T6G(SCH_1):XTAL_CPU1_X32K_X1    I26 @T6G_MB_LIB.T6G(SCH_1):PAGE55

R574 Q_RES_0402LF-0,5%,1/16W,EMPTY,CS00002JB13
     1 XTAL_CPU1_R_X32K_X1 @T6G_MB_LIB.T6G(SCH_1):XTAL_CPU1_R_X32K_X1    I24 @T6G_MB_LIB.T6G(SCH_1):PAGE55
     2 XTAL_CPU1_X32K_X1 @T6G_MB_LIB.T6G(SCH_1):XTAL_CPU1_X32K_X1    I24 @T6G_MB_LIB.T6G(SCH_1):PAGE55

R575 Q_RES_0402LF-0,5%,1/16W,EMPTY,CS00002JB13
     1 XTAL_CPU1_R_X32K_X2 @T6G_MB_LIB.T6G(SCH_1):XTAL_CPU1_R_X32K_X2   I296 @T6G_MB_LIB.T6G(SCH_1):PAGE55
     2 XTAL_CPU1_X32K_X2 @T6G_MB_LIB.T6G(SCH_1):XTAL_CPU1_X32K_X2   I296 @T6G_MB_LIB.T6G(SCH_1):PAGE55

R576 Q_RES_0402LF-0,5%,1/16W,CHIP,CS00002JB13
     1 HP_LVC3_OCP_V3_1_PRSNT2_N_R @T6G_MB_LIB.T6G(SCH_1):HP_LVC3_OCP_V3_1_PRSNT2_N_R   I116 @T6G_MB_LIB.T6G(SCH_1):PAGE338
     2 HP_LVC3_OCP_SFF_PRSNT2_N @T6G_MB_LIB.T6G(SCH_1):HP_LVC3_OCP_SFF_PRSNT2_N   I116 @T6G_MB_LIB.T6G(SCH_1):PAGE338

R577 Q_RES_0402LF-10K,1%,1/16W,CHIP,CS31002FB08
     1 P3V3_AUX @T6G_MB_LIB.T6G(SCH_1):P3V3_AUX   I118 @T6G_MB_LIB.T6G(SCH_1):PAGE338
     2 HP_LVC3_OCP_SFF_PRSNT2_N @T6G_MB_LIB.T6G(SCH_1):HP_LVC3_OCP_SFF_PRSNT2_N   I118 @T6G_MB_LIB.T6G(SCH_1):PAGE338

R578 Q_RES_0402LF-4.75K,1%,1/16W,EMPTY,CS24752FB03
     1 P3V3_AUX @T6G_MB_LIB.T6G(SCH_1):P3V3_AUX    I65 @T6G_MB_LIB.T6G(SCH_1):PAGE379
     2 CLK_9ZXL045_P1_SADR0 @T6G_MB_LIB.T6G(SCH_1):CLK_9ZXL045_P1_SADR0    I65 @T6G_MB_LIB.T6G(SCH_1):PAGE379

R579 Q_RES_0402LF-4.75K,1%,1/16W,CHIP,CS24752FB03
     1 CLK_9ZXL045_P1_SADR0 @T6G_MB_LIB.T6G(SCH_1):CLK_9ZXL045_P1_SADR0    I64 @T6G_MB_LIB.T6G(SCH_1):PAGE379
     2    GND @T6G_MB_LIB.T6G(SCH_1):GND    I64 @T6G_MB_LIB.T6G(SCH_1):PAGE379

R580 Q_RES_0402LF-10K,1%,1/16W,CHIP,CS31002FB08
     1 P3V3_AUX @T6G_MB_LIB.T6G(SCH_1):P3V3_AUX    I17 @T6G_MB_LIB.T6G(SCH_1):PAGE379
     2 CLK_9ZXL045_P1_HIBW @T6G_MB_LIB.T6G(SCH_1):CLK_9ZXL045_P1_HIBW    I17 @T6G_MB_LIB.T6G(SCH_1):PAGE379

R581 Q_RES_0402LF-4.7K,5%,1/16W,EMPTY,CS24702JB10
     1 RST_CPU0_RSMRST_N @T6G_MB_LIB.T6G(SCH_1):RST_CPU0_RSMRST_N    I34 @T6G_MB_LIB.T6G(SCH_1):PAGE28
     2 PVDD18_S5_P0 @T6G_MB_LIB.T6G(SCH_1):PVDD18_S5_P0    I34 @T6G_MB_LIB.T6G(SCH_1):PAGE28

R582 Q_RES_0402LF-4.7K,5%,1/16W,EMPTY,CS24702JB10
     1    GND @T6G_MB_LIB.T6G(SCH_1):GND    I33 @T6G_MB_LIB.T6G(SCH_1):PAGE28
     2 RST_CPU0_RSMRST_N @T6G_MB_LIB.T6G(SCH_1):RST_CPU0_RSMRST_N    I33 @T6G_MB_LIB.T6G(SCH_1):PAGE28

R583 Q_RES_0402LF-4.7K,5%,1/16W,EMPTY,CS24702JB10
     1 RST_CPU1_RSMRST_N @T6G_MB_LIB.T6G(SCH_1):RST_CPU1_RSMRST_N   I342 @T6G_MB_LIB.T6G(SCH_1):PAGE55
     2 PVDD18_S5_P1 @T6G_MB_LIB.T6G(SCH_1):PVDD18_S5_P1   I342 @T6G_MB_LIB.T6G(SCH_1):PAGE55

R584 Q_RES_0402LF-4.7K,5%,1/16W,EMPTY,CS24702JB10
     1    GND @T6G_MB_LIB.T6G(SCH_1):GND   I341 @T6G_MB_LIB.T6G(SCH_1):PAGE55
     2 RST_CPU1_RSMRST_N @T6G_MB_LIB.T6G(SCH_1):RST_CPU1_RSMRST_N   I341 @T6G_MB_LIB.T6G(SCH_1):PAGE55

R585 Q_RES_0402LF-10K,1%,1/16W,CHIP,CS31002FB08
     1 CLK_9ZXL045_P1_HIBW @T6G_MB_LIB.T6G(SCH_1):CLK_9ZXL045_P1_HIBW    I15 @T6G_MB_LIB.T6G(SCH_1):PAGE379
     2    GND @T6G_MB_LIB.T6G(SCH_1):GND    I15 @T6G_MB_LIB.T6G(SCH_1):PAGE379

R586 Q_RES_0603LF-1,1%,1/10W,CHIP,CS-1003F900
     1 P3V3_9ZXL045_P1 @T6G_MB_LIB.T6G(SCH_1):P3V3_9ZXL045_P1    I21 @T6G_MB_LIB.T6G(SCH_1):PAGE379
     2 P3V3_9ZXL045_P1_VDDA @T6G_MB_LIB.T6G(SCH_1):P3V3_9ZXL045_P1_VDDA    I21 @T6G_MB_LIB.T6G(SCH_1):PAGE379

R587 Q_RES_0402LF-1K,1%,1/16W,CHIP,CS21002FB06
     1 PCA9548_PCIE3_ADDR0 @T6G_MB_LIB.T6G(SCH_1):PCA9548_PCIE3_ADDR0     I6 @T6G_MB_LIB.T6G(SCH_1):PAGE252
     2    GND @T6G_MB_LIB.T6G(SCH_1):GND     I6 @T6G_MB_LIB.T6G(SCH_1):PAGE252

R588 Q_RES_0402LF-33,5%,1/16W,CHIP,CS03302JB10
     1 SCM_USB_OC_R_N @T6G_MB_LIB.T6G(SCH_1):SCM_USB_OC_R_N   I164 @T6G_MB_LIB.T6G(SCH_1):PAGE80
     2 SCM_USB_OC_N @T6G_MB_LIB.T6G(SCH_1):SCM_USB_OC_N   I164 @T6G_MB_LIB.T6G(SCH_1):PAGE80

R589 Q_RES_0402LF-0,5%,1/16W,CHIP,CS00002JB13
     1 SCM_USB_OC_BU_R_N @T6G_MB_LIB.T6G(SCH_1):SCM_USB_OC_BU_R_N   I377 @T6G_MB_LIB.T6G(SCH_1):PAGE29
     2 SCM_USB_OC_BUF_N @T6G_MB_LIB.T6G(SCH_1):SCM_USB_OC_BUF_N   I377 @T6G_MB_LIB.T6G(SCH_1):PAGE29

R590 Q_RES_0402LF-4.7K,5%,1/16W,CHIP,CS24702JB10
     1 P3V3_AUX @T6G_MB_LIB.T6G(SCH_1):P3V3_AUX     I5 @T6G_MB_LIB.T6G(SCH_1):PAGE34
     2 SMB_CPU0_4_XLTR_SDA @T6G_MB_LIB.T6G(SCH_1):SMB_CPU0_4_XLTR_SDA     I5 @T6G_MB_LIB.T6G(SCH_1):PAGE34

R591 Q_RES_0402LF-0,5%,1/16W,CHIP,CS00002JB13
     1 P12V_OCP_SFF_BUF_EN_R @T6G_MB_LIB.T6G(SCH_1):P12V_OCP_SFF_BUF_EN_R   I130 @T6G_MB_LIB.T6G(SCH_1):PAGE339
     2 P12V_OCP_EN_1_R2 @T6G_MB_LIB.T6G(SCH_1):P12V_OCP_EN_1_R2   I130 @T6G_MB_LIB.T6G(SCH_1):PAGE339

R592 Q_RES_0402LF-10K,1%,1/16W,CHIP,CS31002FB08
     1 FM_9ZXL045_P1_2_OE_N @T6G_MB_LIB.T6G(SCH_1):FM_9ZXL045_P1_2_OE_N    I49 @T6G_MB_LIB.T6G(SCH_1):PAGE379
     2    GND @T6G_MB_LIB.T6G(SCH_1):GND    I49 @T6G_MB_LIB.T6G(SCH_1):PAGE379

R593 Q_RES_0402LF-10K,1%,1/16W,CHIP,CS31002FB08
     1 FM_9ZXL045_P1_1_OE_N @T6G_MB_LIB.T6G(SCH_1):FM_9ZXL045_P1_1_OE_N    I50 @T6G_MB_LIB.T6G(SCH_1):PAGE379
     2    GND @T6G_MB_LIB.T6G(SCH_1):GND    I50 @T6G_MB_LIB.T6G(SCH_1):PAGE379

R594 Q_RES_0402LF-10K,1%,1/16W,CHIP,CS31002FB08
     1 FM_9ZXL045_P1_0_OE_N @T6G_MB_LIB.T6G(SCH_1):FM_9ZXL045_P1_0_OE_N    I51 @T6G_MB_LIB.T6G(SCH_1):PAGE379
     2    GND @T6G_MB_LIB.T6G(SCH_1):GND    I51 @T6G_MB_LIB.T6G(SCH_1):PAGE379

R595 Q_RES_0201LF-0,5%,1/20W,CHIP,CS00001JE10
     1 CLK_100M_RETIMER_CPU0_P0_R_DP @T6G_MB_LIB.T6G(SCH_1):CLK_100M_RETIMER_CPU0_P0_R_DP    I39 @T6G_MB_LIB.T6G(SCH_1):PAGE385
     2 CLK_100M_RETIMER_CPU0_P0_DP @T6G_MB_LIB.T6G(SCH_1):CLK_100M_RETIMER_CPU0_P0_DP    I39 @T6G_MB_LIB.T6G(SCH_1):PAGE385

R596 Q_RES_0201LF-0,5%,1/20W,CHIP,CS00001JE10
     1 CLK_100M_RETIMER_CPU0_P0_R_DN @T6G_MB_LIB.T6G(SCH_1):CLK_100M_RETIMER_CPU0_P0_R_DN    I40 @T6G_MB_LIB.T6G(SCH_1):PAGE385
     2 CLK_100M_RETIMER_CPU0_P0_DN @T6G_MB_LIB.T6G(SCH_1):CLK_100M_RETIMER_CPU0_P0_DN    I40 @T6G_MB_LIB.T6G(SCH_1):PAGE385

R597 Q_RES_0201LF-0,5%,1/20W,CHIP,CS00001JE10
     1 CLK_100M_RETIMER_CPU1_P1_R_DP @T6G_MB_LIB.T6G(SCH_1):CLK_100M_RETIMER_CPU1_P1_R_DP    I33 @T6G_MB_LIB.T6G(SCH_1):PAGE392
     2 CLK_100M_RETIMER_CPU1_P1_DP @T6G_MB_LIB.T6G(SCH_1):CLK_100M_RETIMER_CPU1_P1_DP    I33 @T6G_MB_LIB.T6G(SCH_1):PAGE392

R598 Q_RES_0201LF-0,5%,1/20W,CHIP,CS00001JE10
     1 CLK_100M_RETIMER_CPU1_P1_R_DN @T6G_MB_LIB.T6G(SCH_1):CLK_100M_RETIMER_CPU1_P1_R_DN    I34 @T6G_MB_LIB.T6G(SCH_1):PAGE392
     2 CLK_100M_RETIMER_CPU1_P1_DN @T6G_MB_LIB.T6G(SCH_1):CLK_100M_RETIMER_CPU1_P1_DN    I34 @T6G_MB_LIB.T6G(SCH_1):PAGE392

R599 Q_RES_0201LF-0,5%,1/20W,CHIP,CS00001JE10
     1 CLK_100M_RETIMER_CPU1_P0_R_DP @T6G_MB_LIB.T6G(SCH_1):CLK_100M_RETIMER_CPU1_P0_R_DP     I9 @T6G_MB_LIB.T6G(SCH_1):PAGE401
     2 CLK_100M_RETIMER_CPU1_P0_DP @T6G_MB_LIB.T6G(SCH_1):CLK_100M_RETIMER_CPU1_P0_DP     I9 @T6G_MB_LIB.T6G(SCH_1):PAGE401

R600 Q_RES_0402LF-0,5%,1/16W,CHIP,CS00002JB13
     1 SPI_CPU0_LVC3_CS1_N @T6G_MB_LIB.T6G(SCH_1):SPI_CPU0_LVC3_CS1_N   I180 @T6G_MB_LIB.T6G(SCH_1):PAGE76
     2 SPI_CPU0_LVC3_SCM_CS1_N @T6G_MB_LIB.T6G(SCH_1):SPI_CPU0_LVC3_SCM_CS1_N   I180 @T6G_MB_LIB.T6G(SCH_1):PAGE76

R601 Q_RES_0402LF-1K,1%,1/16W,CHIP,CS21002FB06
     1 PVDD18_S5_P0 @T6G_MB_LIB.T6G(SCH_1):PVDD18_S5_P0   I108 @T6G_MB_LIB.T6G(SCH_1):PAGE76
     2 SPI_CPU0_CS1_N @T6G_MB_LIB.T6G(SCH_1):SPI_CPU0_CS1_N   I108 @T6G_MB_LIB.T6G(SCH_1):PAGE76

R602 Q_RES_0402LF-33,5%,1/16W,CHIP,CS03302JB10
     1 SPI_CPU0_LVC3_CLK @T6G_MB_LIB.T6G(SCH_1):SPI_CPU0_LVC3_CLK   I230 @T6G_MB_LIB.T6G(SCH_1):PAGE76
     2 SPI_CPU0_LVC3_SCM_CLK @T6G_MB_LIB.T6G(SCH_1):SPI_CPU0_LVC3_SCM_CLK   I230 @T6G_MB_LIB.T6G(SCH_1):PAGE76

R603 Q_RES_0402LF-0,5%,1/16W,CHIP,CS00002JB13
     1 SPI_CPU0_LVC3_CS0_N @T6G_MB_LIB.T6G(SCH_1):SPI_CPU0_LVC3_CS0_N   I228 @T6G_MB_LIB.T6G(SCH_1):PAGE76
     2 SPI_CPU0_LVC3_SCM_CS0_N @T6G_MB_LIB.T6G(SCH_1):SPI_CPU0_LVC3_SCM_CS0_N   I228 @T6G_MB_LIB.T6G(SCH_1):PAGE76

R604 Q_RES_0402LF-33.2,1%,1/16W,CHIP,CS03322FB03
     1 SPI_CPU0_LVC3_D0 @T6G_MB_LIB.T6G(SCH_1):SPI_CPU0_LVC3_D0   I221 @T6G_MB_LIB.T6G(SCH_1):PAGE76
     2 SPI_CPU0_LVC3_SCM_D0 @T6G_MB_LIB.T6G(SCH_1):SPI_CPU0_LVC3_SCM_D0   I221 @T6G_MB_LIB.T6G(SCH_1):PAGE76

R605 Q_RES_0402LF-49.9,1%,1/16W,CHIP,CS04992FB07
     1 SPI_CPU0_LVC3_D1 @T6G_MB_LIB.T6G(SCH_1):SPI_CPU0_LVC3_D1   I219 @T6G_MB_LIB.T6G(SCH_1):PAGE76
     2 SPI_CPU0_LVC3_SCM_D1 @T6G_MB_LIB.T6G(SCH_1):SPI_CPU0_LVC3_SCM_D1   I219 @T6G_MB_LIB.T6G(SCH_1):PAGE76

R606 Q_RES_0402LF-0,5%,1/16W,CHIP,CS00002JB13
     1 SPI_CPU0_LVC3_D2 @T6G_MB_LIB.T6G(SCH_1):SPI_CPU0_LVC3_D2   I205 @T6G_MB_LIB.T6G(SCH_1):PAGE76
     2 SPI_CPU0_LVC3_SCM_D2 @T6G_MB_LIB.T6G(SCH_1):SPI_CPU0_LVC3_SCM_D2   I205 @T6G_MB_LIB.T6G(SCH_1):PAGE76

R607 Q_RES_0402LF-0,5%,1/16W,CHIP,CS00002JB13
     1 SPI_CPU0_LVC3_D3 @T6G_MB_LIB.T6G(SCH_1):SPI_CPU0_LVC3_D3   I207 @T6G_MB_LIB.T6G(SCH_1):PAGE76
     2 SPI_CPU0_LVC3_SCM_D3 @T6G_MB_LIB.T6G(SCH_1):SPI_CPU0_LVC3_SCM_D3   I207 @T6G_MB_LIB.T6G(SCH_1):PAGE76

R608 Q_RES_0402LF-33,5%,1/16W,CHIP,CS03302JB10
     1 SPI_CPU0_LVC3_R_TPM_CS_N @T6G_MB_LIB.T6G(SCH_1):SPI_CPU0_LVC3_R_TPM_CS_N   I242 @T6G_MB_LIB.T6G(SCH_1):PAGE76
     2 SPI_CPU0_LVC3_TPM_CS_N @T6G_MB_LIB.T6G(SCH_1):SPI_CPU0_LVC3_TPM_CS_N   I242 @T6G_MB_LIB.T6G(SCH_1):PAGE76

R609 Q_RES_0201LF-0,5%,1/20W,CHIP,CS00001JE10
     1 CLK_100M_RETIMER_CPU1_P0_R_DN @T6G_MB_LIB.T6G(SCH_1):CLK_100M_RETIMER_CPU1_P0_R_DN     I8 @T6G_MB_LIB.T6G(SCH_1):PAGE401
     2 CLK_100M_RETIMER_CPU1_P0_DN @T6G_MB_LIB.T6G(SCH_1):CLK_100M_RETIMER_CPU1_P0_DN     I8 @T6G_MB_LIB.T6G(SCH_1):PAGE401

R610 Q_RES_0402LF-1K,1%,1/16W,EMPTY,CS21002FB06
     1 P3V3_AUX @T6G_MB_LIB.T6G(SCH_1):P3V3_AUX    I97 @T6G_MB_LIB.T6G(SCH_1):PAGE76
     2 SPI_CPU0_LVC3_SCM_CS0_N @T6G_MB_LIB.T6G(SCH_1):SPI_CPU0_LVC3_SCM_CS0_N    I97 @T6G_MB_LIB.T6G(SCH_1):PAGE76

R611 Q_RES_0201LF-0,5%,1/20W,CHIP,CS00001JE10
     1 CLK_100M_RETIMER_CPU0_P1_R_DP @T6G_MB_LIB.T6G(SCH_1):CLK_100M_RETIMER_CPU0_P1_R_DP    I20 @T6G_MB_LIB.T6G(SCH_1):PAGE408
     2 CLK_100M_RETIMER_CPU0_P1_DP @T6G_MB_LIB.T6G(SCH_1):CLK_100M_RETIMER_CPU0_P1_DP    I20 @T6G_MB_LIB.T6G(SCH_1):PAGE408

R612 Q_RES_0201LF-0,5%,1/20W,CHIP,CS00001JE10
     1 CLK_100M_RETIMER_CPU0_P1_R_DN @T6G_MB_LIB.T6G(SCH_1):CLK_100M_RETIMER_CPU0_P1_R_DN    I15 @T6G_MB_LIB.T6G(SCH_1):PAGE408
     2 CLK_100M_RETIMER_CPU0_P1_DN @T6G_MB_LIB.T6G(SCH_1):CLK_100M_RETIMER_CPU0_P1_DN    I15 @T6G_MB_LIB.T6G(SCH_1):PAGE408

R613 Q_RES_0201LF-0,5%,1/20W,CHIP,CS00001JE10
     1 CLK_100M_RETIMER_CPU0_P2_R_DP @T6G_MB_LIB.T6G(SCH_1):CLK_100M_RETIMER_CPU0_P2_R_DP    I19 @T6G_MB_LIB.T6G(SCH_1):PAGE419
     2 CLK_100M_RETIMER_CPU0_P2_DP @T6G_MB_LIB.T6G(SCH_1):CLK_100M_RETIMER_CPU0_P2_DP    I19 @T6G_MB_LIB.T6G(SCH_1):PAGE419

R614 Q_RES_0201LF-0,5%,1/20W,CHIP,CS00001JE10
     1 CLK_100M_RETIMER_CPU0_P2_R_DN @T6G_MB_LIB.T6G(SCH_1):CLK_100M_RETIMER_CPU0_P2_R_DN    I20 @T6G_MB_LIB.T6G(SCH_1):PAGE419
     2 CLK_100M_RETIMER_CPU0_P2_DN @T6G_MB_LIB.T6G(SCH_1):CLK_100M_RETIMER_CPU0_P2_DN    I20 @T6G_MB_LIB.T6G(SCH_1):PAGE419

R615 Q_RES_0201LF-0,5%,1/20W,CHIP,CS00001JE10
     1 CLK_100M_RETIMER_CPU0_P3_R_DP @T6G_MB_LIB.T6G(SCH_1):CLK_100M_RETIMER_CPU0_P3_R_DP    I20 @T6G_MB_LIB.T6G(SCH_1):PAGE430
     2 CLK_100M_RETIMER_CPU0_P3_DP @T6G_MB_LIB.T6G(SCH_1):CLK_100M_RETIMER_CPU0_P3_DP    I20 @T6G_MB_LIB.T6G(SCH_1):PAGE430

R616 Q_RES_0201LF-0,5%,1/20W,CHIP,CS00001JE10
     1 CLK_100M_RETIMER_CPU0_P3_R_DN @T6G_MB_LIB.T6G(SCH_1):CLK_100M_RETIMER_CPU0_P3_R_DN    I15 @T6G_MB_LIB.T6G(SCH_1):PAGE430
     2 CLK_100M_RETIMER_CPU0_P3_DN @T6G_MB_LIB.T6G(SCH_1):CLK_100M_RETIMER_CPU0_P3_DN    I15 @T6G_MB_LIB.T6G(SCH_1):PAGE430

R617 Q_RES_0402LF-4.7K,5%,1/16W,CHIP,CS24702JB10
     1 PVDD18_S5_P0 @T6G_MB_LIB.T6G(SCH_1):PVDD18_S5_P0   I101 @T6G_MB_LIB.T6G(SCH_1):PAGE149
     2 JTAG_BMC_R_D_OE @T6G_MB_LIB.T6G(SCH_1):JTAG_BMC_R_D_OE   I101 @T6G_MB_LIB.T6G(SCH_1):PAGE149

R618 Q_RES_0402LF-0,5%,1/16W,CHIP,CS00002JB13
     1 CPU1_XTRIG_R2_L5 @T6G_MB_LIB.T6G(SCH_1):CPU1_XTRIG_R2_L5   I361 @T6G_MB_LIB.T6G(SCH_1):PAGE54
     2 CPU1_XTRIG_L5 @T6G_MB_LIB.T6G(SCH_1):CPU1_XTRIG_L5   I361 @T6G_MB_LIB.T6G(SCH_1):PAGE54

R619 Q_RES_0201LF-0,5%,1/20W,CHIP,CS00001JE10
     1 CLK_100M_RETIMER_CPU1_P2_R_DP @T6G_MB_LIB.T6G(SCH_1):CLK_100M_RETIMER_CPU1_P2_R_DP    I28 @T6G_MB_LIB.T6G(SCH_1):PAGE451
     2 CLK_100M_RETIMER_CPU1_P2_DP @T6G_MB_LIB.T6G(SCH_1):CLK_100M_RETIMER_CPU1_P2_DP    I28 @T6G_MB_LIB.T6G(SCH_1):PAGE451

R620 Q_RES_0201LF-0,5%,1/20W,CHIP,CS00001JE10
     1 CLK_100M_RETIMER_CPU1_P2_R_DN @T6G_MB_LIB.T6G(SCH_1):CLK_100M_RETIMER_CPU1_P2_R_DN    I27 @T6G_MB_LIB.T6G(SCH_1):PAGE451
     2 CLK_100M_RETIMER_CPU1_P2_DN @T6G_MB_LIB.T6G(SCH_1):CLK_100M_RETIMER_CPU1_P2_DN    I27 @T6G_MB_LIB.T6G(SCH_1):PAGE451

R621 Q_RES_0201LF-0,5%,1/20W,CHIP,CS00001JE10
     1 CLK_100M_RETIMER_CPU1_P3_R_DP @T6G_MB_LIB.T6G(SCH_1):CLK_100M_RETIMER_CPU1_P3_R_DP    I32 @T6G_MB_LIB.T6G(SCH_1):PAGE462
     2 CLK_100M_RETIMER_CPU1_P3_DP @T6G_MB_LIB.T6G(SCH_1):CLK_100M_RETIMER_CPU1_P3_DP    I32 @T6G_MB_LIB.T6G(SCH_1):PAGE462

R622 Q_RES_0201LF-0,5%,1/20W,CHIP,CS00001JE10
     1 CLK_100M_RETIMER_CPU1_P3_R_DN @T6G_MB_LIB.T6G(SCH_1):CLK_100M_RETIMER_CPU1_P3_R_DN    I31 @T6G_MB_LIB.T6G(SCH_1):PAGE462
     2 CLK_100M_RETIMER_CPU1_P3_DN @T6G_MB_LIB.T6G(SCH_1):CLK_100M_RETIMER_CPU1_P3_DN    I31 @T6G_MB_LIB.T6G(SCH_1):PAGE462

R623 Q_RES_0201LF-51.1,1%,1/20W,EMPTY,CS05111FE00
     1 CLK_100M_RETIMER_CPU0_P0_DN @T6G_MB_LIB.T6G(SCH_1):CLK_100M_RETIMER_CPU0_P0_DN    I37 @T6G_MB_LIB.T6G(SCH_1):PAGE385
     2    GND @T6G_MB_LIB.T6G(SCH_1):GND    I37 @T6G_MB_LIB.T6G(SCH_1):PAGE385

R624 Q_RES_0201LF-51.1,1%,1/20W,EMPTY,CS05111FE00
     1 CLK_100M_RETIMER_CPU0_P0_DP @T6G_MB_LIB.T6G(SCH_1):CLK_100M_RETIMER_CPU0_P0_DP    I38 @T6G_MB_LIB.T6G(SCH_1):PAGE385
     2    GND @T6G_MB_LIB.T6G(SCH_1):GND    I38 @T6G_MB_LIB.T6G(SCH_1):PAGE385

R625 Q_RES_0201LF-51.1,1%,1/20W,EMPTY,CS05111FE00
     1 CLK_100M_RETIMER_CPU1_P1_DN @T6G_MB_LIB.T6G(SCH_1):CLK_100M_RETIMER_CPU1_P1_DN    I31 @T6G_MB_LIB.T6G(SCH_1):PAGE392
     2    GND @T6G_MB_LIB.T6G(SCH_1):GND    I31 @T6G_MB_LIB.T6G(SCH_1):PAGE392

R626 Q_RES_0201LF-51.1,1%,1/20W,EMPTY,CS05111FE00
     1 CLK_100M_RETIMER_CPU1_P1_DP @T6G_MB_LIB.T6G(SCH_1):CLK_100M_RETIMER_CPU1_P1_DP    I32 @T6G_MB_LIB.T6G(SCH_1):PAGE392
     2    GND @T6G_MB_LIB.T6G(SCH_1):GND    I32 @T6G_MB_LIB.T6G(SCH_1):PAGE392

R627 Q_RES_0201LF-51.1,1%,1/20W,EMPTY,CS05111FE00
     1 CLK_100M_RETIMER_CPU1_P0_DN @T6G_MB_LIB.T6G(SCH_1):CLK_100M_RETIMER_CPU1_P0_DN    I23 @T6G_MB_LIB.T6G(SCH_1):PAGE401
     2    GND @T6G_MB_LIB.T6G(SCH_1):GND    I23 @T6G_MB_LIB.T6G(SCH_1):PAGE401

R628 Q_RES_0201LF-51.1,1%,1/20W,EMPTY,CS05111FE00
     1 CLK_100M_RETIMER_CPU1_P0_DP @T6G_MB_LIB.T6G(SCH_1):CLK_100M_RETIMER_CPU1_P0_DP    I24 @T6G_MB_LIB.T6G(SCH_1):PAGE401
     2    GND @T6G_MB_LIB.T6G(SCH_1):GND    I24 @T6G_MB_LIB.T6G(SCH_1):PAGE401

R629 Q_RES_0201LF-51.1,1%,1/20W,EMPTY,CS05111FE00
     1 CLK_100M_RETIMER_CPU0_P1_DN @T6G_MB_LIB.T6G(SCH_1):CLK_100M_RETIMER_CPU0_P1_DN    I18 @T6G_MB_LIB.T6G(SCH_1):PAGE408
     2    GND @T6G_MB_LIB.T6G(SCH_1):GND    I18 @T6G_MB_LIB.T6G(SCH_1):PAGE408

R630 Q_RES_0201LF-51.1,1%,1/20W,EMPTY,CS05111FE00
     1 CLK_100M_RETIMER_CPU0_P1_DP @T6G_MB_LIB.T6G(SCH_1):CLK_100M_RETIMER_CPU0_P1_DP    I19 @T6G_MB_LIB.T6G(SCH_1):PAGE408
     2    GND @T6G_MB_LIB.T6G(SCH_1):GND    I19 @T6G_MB_LIB.T6G(SCH_1):PAGE408

R631 Q_RES_0201LF-51.1,1%,1/20W,EMPTY,CS05111FE00
     1 CLK_100M_RETIMER_CPU0_P2_DN @T6G_MB_LIB.T6G(SCH_1):CLK_100M_RETIMER_CPU0_P2_DN    I17 @T6G_MB_LIB.T6G(SCH_1):PAGE419
     2    GND @T6G_MB_LIB.T6G(SCH_1):GND    I17 @T6G_MB_LIB.T6G(SCH_1):PAGE419

R632 Q_RES_0402LF-2.2K,5%,1/16W,CHIP,CS22202JB07
     1 PVDD18_S5_P0 @T6G_MB_LIB.T6G(SCH_1):PVDD18_S5_P0    I18 @T6G_MB_LIB.T6G(SCH_1):PAGE349
     2 SMB_CPU_5_SCL @T6G_MB_LIB.T6G(SCH_1):SMB_CPU_5_SCL    I18 @T6G_MB_LIB.T6G(SCH_1):PAGE349

R633 Q_RES_0402LF-2.2K,5%,1/16W,CHIP,CS22202JB07
     1 PVDD18_S5_P0 @T6G_MB_LIB.T6G(SCH_1):PVDD18_S5_P0    I17 @T6G_MB_LIB.T6G(SCH_1):PAGE349
     2 SMB_CPU_5_SDA @T6G_MB_LIB.T6G(SCH_1):SMB_CPU_5_SDA    I17 @T6G_MB_LIB.T6G(SCH_1):PAGE349

R634 Q_RES_0201LF-51.1,1%,1/20W,EMPTY,CS05111FE00
     1 CLK_100M_RETIMER_CPU0_P2_DP @T6G_MB_LIB.T6G(SCH_1):CLK_100M_RETIMER_CPU0_P2_DP    I18 @T6G_MB_LIB.T6G(SCH_1):PAGE419
     2    GND @T6G_MB_LIB.T6G(SCH_1):GND    I18 @T6G_MB_LIB.T6G(SCH_1):PAGE419

R635 Q_RES_0201LF-51.1,1%,1/20W,EMPTY,CS05111FE00
     1 CLK_100M_RETIMER_CPU0_P3_DN @T6G_MB_LIB.T6G(SCH_1):CLK_100M_RETIMER_CPU0_P3_DN    I18 @T6G_MB_LIB.T6G(SCH_1):PAGE430
     2    GND @T6G_MB_LIB.T6G(SCH_1):GND    I18 @T6G_MB_LIB.T6G(SCH_1):PAGE430

R636 Q_RES_0201LF-51.1,1%,1/20W,EMPTY,CS05111FE00
     1 CLK_100M_RETIMER_CPU0_P3_DP @T6G_MB_LIB.T6G(SCH_1):CLK_100M_RETIMER_CPU0_P3_DP    I19 @T6G_MB_LIB.T6G(SCH_1):PAGE430
     2    GND @T6G_MB_LIB.T6G(SCH_1):GND    I19 @T6G_MB_LIB.T6G(SCH_1):PAGE430

R637 Q_RES_0201LF-51.1,1%,1/20W,EMPTY,CS05111FE00
     1 CLK_100M_RETIMER_CPU1_P2_DN @T6G_MB_LIB.T6G(SCH_1):CLK_100M_RETIMER_CPU1_P2_DN    I92 @T6G_MB_LIB.T6G(SCH_1):PAGE451
     2    GND @T6G_MB_LIB.T6G(SCH_1):GND    I92 @T6G_MB_LIB.T6G(SCH_1):PAGE451

R638 Q_RES_0402LF-1K,1%,1/16W,CHIP,CS21002FB06
     1 CPLD_JTAG_EN @T6G_MB_LIB.T6G(SCH_1):CPLD_JTAG_EN    I35 @T6G_MB_LIB.T6G(SCH_1):PAGE82
     2 P3V3_AUX @T6G_MB_LIB.T6G(SCH_1):P3V3_AUX    I35 @T6G_MB_LIB.T6G(SCH_1):PAGE82

R639 Q_RES_0402LF-1K,1%,1/16W,CHIP,CS21002FB06
     1 CPLD_PROGRAMN @T6G_MB_LIB.T6G(SCH_1):CPLD_PROGRAMN    I33 @T6G_MB_LIB.T6G(SCH_1):PAGE82
     2 P3V3_AUX @T6G_MB_LIB.T6G(SCH_1):P3V3_AUX    I33 @T6G_MB_LIB.T6G(SCH_1):PAGE82

R640 Q_RES_0201LF-51.1,1%,1/20W,EMPTY,CS05111FE00
     1 CLK_100M_RETIMER_CPU1_P2_DP @T6G_MB_LIB.T6G(SCH_1):CLK_100M_RETIMER_CPU1_P2_DP    I36 @T6G_MB_LIB.T6G(SCH_1):PAGE451
     2    GND @T6G_MB_LIB.T6G(SCH_1):GND    I36 @T6G_MB_LIB.T6G(SCH_1):PAGE451

R641 Q_RES_0201LF-51.1,1%,1/20W,EMPTY,CS05111FE00
     1 CLK_100M_RETIMER_CPU1_P3_DN @T6G_MB_LIB.T6G(SCH_1):CLK_100M_RETIMER_CPU1_P3_DN    I30 @T6G_MB_LIB.T6G(SCH_1):PAGE462
     2    GND @T6G_MB_LIB.T6G(SCH_1):GND    I30 @T6G_MB_LIB.T6G(SCH_1):PAGE462

R642 Q_RES_0201LF-51.1,1%,1/20W,EMPTY,CS05111FE00
     1 CLK_100M_RETIMER_CPU1_P3_DP @T6G_MB_LIB.T6G(SCH_1):CLK_100M_RETIMER_CPU1_P3_DP    I46 @T6G_MB_LIB.T6G(SCH_1):PAGE462
     2    GND @T6G_MB_LIB.T6G(SCH_1):GND    I46 @T6G_MB_LIB.T6G(SCH_1):PAGE462

R643 Q_RES_0402LF-1K,1%,1/16W,EMPTY,CS21002FB06
     1 P3V3_AUX @T6G_MB_LIB.T6G(SCH_1):P3V3_AUX   I212 @T6G_MB_LIB.T6G(SCH_1):PAGE475
     2 PWRGD_P0V9_RETIMER_CPU0_R @T6G_MB_LIB.T6G(SCH_1):PWRGD_P0V9_RETIMER_CPU0_R   I212 @T6G_MB_LIB.T6G(SCH_1):PAGE475

R644 Q_RES_0402LF-10K,5%,1/16W,CHIP,CS31002JB08
     1 P3V3_AUX @T6G_MB_LIB.T6G(SCH_1):P3V3_AUX    I29 @T6G_MB_LIB.T6G(SCH_1):PAGE470
     2 PWRGD_P1V8_RETIMER_CPU1 @T6G_MB_LIB.T6G(SCH_1):PWRGD_P1V8_RETIMER_CPU1    I29 @T6G_MB_LIB.T6G(SCH_1):PAGE470

R645 Q_RES_0402LF-33,5%,1/16W,CHIP,CS03302JB10
     1 PWRGD_P1V8_RETIMER_CPU1 @T6G_MB_LIB.T6G(SCH_1):PWRGD_P1V8_RETIMER_CPU1    I36 @T6G_MB_LIB.T6G(SCH_1):PAGE470
     2 FM_PWRGD_P1V8_RETIMER_CPU1 @T6G_MB_LIB.T6G(SCH_1):FM_PWRGD_P1V8_RETIMER_CPU1    I36 @T6G_MB_LIB.T6G(SCH_1):PAGE470

R646 Q_RES_0402LF-0,5%,1/16W,CHIP,CS00002JB13
     1 P0V9_RETIMER_CPU0_PMSCL @T6G_MB_LIB.T6G(SCH_1):P0V9_RETIMER_CPU0_PMSCL    I94 @T6G_MB_LIB.T6G(SCH_1):PAGE475
     2 P0V9_RETIMER_CPU0_PMSCL_R @T6G_MB_LIB.T6G(SCH_1):P0V9_RETIMER_CPU0_PMSCL_R    I94 @T6G_MB_LIB.T6G(SCH_1):PAGE475

R647 Q_RES_0402LF-0,5%,1/16W,CHIP,CS00002JB13
     1 P0V9_RETIMER_CPU0_PMSDA @T6G_MB_LIB.T6G(SCH_1):P0V9_RETIMER_CPU0_PMSDA    I95 @T6G_MB_LIB.T6G(SCH_1):PAGE475
     2 P0V9_RETIMER_CPU0_PMSDA_R @T6G_MB_LIB.T6G(SCH_1):P0V9_RETIMER_CPU0_PMSDA_R    I95 @T6G_MB_LIB.T6G(SCH_1):PAGE475

R648 Q_RES_0402LF-33,5%,1/16W,CHIP,CS03302JB10
     1 E1S_0_P3V3_EN @T6G_MB_LIB.T6G(SCH_1):E1S_0_P3V3_EN    I25 @T6G_MB_LIB.T6G(SCH_1):PAGE80
     2 P3V3_E1S_0_EN_R @T6G_MB_LIB.T6G(SCH_1):P3V3_E1S_0_EN_R    I25 @T6G_MB_LIB.T6G(SCH_1):PAGE80

R649 Q_RES_0402LF-4.7K,1%,1/16W,EMPTY,CS24702FB06
     1 P3V3_AUX @T6G_MB_LIB.T6G(SCH_1):P3V3_AUX   I207 @T6G_MB_LIB.T6G(SCH_1):PAGE475
     2 TP_P0V9_RETIMER_CPU0_PMALERT @T6G_MB_LIB.T6G(SCH_1):TP_P0V9_RETIMER_CPU0_PMALERT   I207 @T6G_MB_LIB.T6G(SCH_1):PAGE475

R650 Q_RES_0402LF-0,5%,1/16W,CHIP,CS00002JB13
     1 PWRGD_P0V9_RETIMER_CPU0 @T6G_MB_LIB.T6G(SCH_1):PWRGD_P0V9_RETIMER_CPU0   I119 @T6G_MB_LIB.T6G(SCH_1):PAGE475
     2 PWRGD_P0V9_RETIMER_CPU0_R @T6G_MB_LIB.T6G(SCH_1):PWRGD_P0V9_RETIMER_CPU0_R   I119 @T6G_MB_LIB.T6G(SCH_1):PAGE475

R651 Q_RES_0402LF-0,5%,1/16W,CHIP,CS00002JB13
     1 P0V9_RETIMER_CPU0_EN @T6G_MB_LIB.T6G(SCH_1):P0V9_RETIMER_CPU0_EN   I120 @T6G_MB_LIB.T6G(SCH_1):PAGE475
     2 P0V9_RETIMER_CPU0_EN0_R @T6G_MB_LIB.T6G(SCH_1):P0V9_RETIMER_CPU0_EN0_R   I120 @T6G_MB_LIB.T6G(SCH_1):PAGE475

R652 Q_RES_0402LF-1K,1%,1/16W,CHIP,CS21002FB06
     1 P3V3_AUX @T6G_MB_LIB.T6G(SCH_1):P3V3_AUX   I128 @T6G_MB_LIB.T6G(SCH_1):PAGE475
     2 P0V9_RETIMER_CPU0_CFP @T6G_MB_LIB.T6G(SCH_1):P0V9_RETIMER_CPU0_CFP   I128 @T6G_MB_LIB.T6G(SCH_1):PAGE475

R653 Q_RES_0402LF-0,5%,1/16W,EMPTY,CS00002JB13
     1 P1V8_CPU1_RT1_1A_1D @T6G_MB_LIB.T6G(SCH_1):P1V8_CPU1_RT1_1A_1D     I5 @T6G_MB_LIB.T6G(SCH_1):PAGE443
     2 P1V8_CPU1_RT1_1A @T6G_MB_LIB.T6G(SCH_1):P1V8_CPU1_RT1_1A     I5 @T6G_MB_LIB.T6G(SCH_1):PAGE443

R654 Q_RES_0402LF-4.7K,5%,1/16W,CHIP,CS24702JB10
     1 SCM_USB_OC_N @T6G_MB_LIB.T6G(SCH_1):SCM_USB_OC_N    I64 @T6G_MB_LIB.T6G(SCH_1):PAGE82
     2 P1V8_AUX @T6G_MB_LIB.T6G(SCH_1):P1V8_AUX    I64 @T6G_MB_LIB.T6G(SCH_1):PAGE82

R655 Q_RES_0402LF-1K,1%,1/16W,CHIP,CS21002FB06
     1 P3V3_AUX @T6G_MB_LIB.T6G(SCH_1):P3V3_AUX   I127 @T6G_MB_LIB.T6G(SCH_1):PAGE475
     2 P0V9_RETIMER_CPU0_INALERT @T6G_MB_LIB.T6G(SCH_1):P0V9_RETIMER_CPU0_INALERT   I127 @T6G_MB_LIB.T6G(SCH_1):PAGE475

R656 Q_RES_0402LF-1K,1%,1/16W,EMPTY,CS21002FB06
     1 P3V3_AUX @T6G_MB_LIB.T6G(SCH_1):P3V3_AUX    I92 @T6G_MB_LIB.T6G(SCH_1):PAGE477
     2 PWRGD_P0V9_RETIMER_CPU1_R @T6G_MB_LIB.T6G(SCH_1):PWRGD_P0V9_RETIMER_CPU1_R    I92 @T6G_MB_LIB.T6G(SCH_1):PAGE477

R657 Q_RES_0402LF-0,5%,1/16W,CHIP,CS00002JB13
     1 P0V9_RETIMER_CPU1_PMSCL @T6G_MB_LIB.T6G(SCH_1):P0V9_RETIMER_CPU1_PMSCL    I33 @T6G_MB_LIB.T6G(SCH_1):PAGE477
     2 P0V9_RETIMER_CPU1_PMSCL_R @T6G_MB_LIB.T6G(SCH_1):P0V9_RETIMER_CPU1_PMSCL_R    I33 @T6G_MB_LIB.T6G(SCH_1):PAGE477

R658 Q_RES_0402LF-0,5%,1/16W,CHIP,CS00002JB13
     1 P0V9_RETIMER_CPU1_PMSDA @T6G_MB_LIB.T6G(SCH_1):P0V9_RETIMER_CPU1_PMSDA    I31 @T6G_MB_LIB.T6G(SCH_1):PAGE477
     2 P0V9_RETIMER_CPU1_PMSDA_R @T6G_MB_LIB.T6G(SCH_1):P0V9_RETIMER_CPU1_PMSDA_R    I31 @T6G_MB_LIB.T6G(SCH_1):PAGE477

R659 Q_RES_0402LF-1K,1%,1/16W,CHIP,CS21002FB06
     1 PVDD18_S5_P0 @T6G_MB_LIB.T6G(SCH_1):PVDD18_S5_P0   I107 @T6G_MB_LIB.T6G(SCH_1):PAGE76
     2 SPI_CPU0_TPM_CS_N @T6G_MB_LIB.T6G(SCH_1):SPI_CPU0_TPM_CS_N   I107 @T6G_MB_LIB.T6G(SCH_1):PAGE76

R660 Q_RES_0402LF-4.7K,1%,1/16W,EMPTY,CS24702FB06
     1 P3V3_AUX @T6G_MB_LIB.T6G(SCH_1):P3V3_AUX    I89 @T6G_MB_LIB.T6G(SCH_1):PAGE477
     2 TP_P0V9_RETIMER_CPU1_PMALERT @T6G_MB_LIB.T6G(SCH_1):TP_P0V9_RETIMER_CPU1_PMALERT    I89 @T6G_MB_LIB.T6G(SCH_1):PAGE477

R661 Q_RES_0402LF-0,5%,1/16W,CHIP,CS00002JB13
     1 PWRGD_P0V9_RETIMER_CPU1 @T6G_MB_LIB.T6G(SCH_1):PWRGD_P0V9_RETIMER_CPU1    I39 @T6G_MB_LIB.T6G(SCH_1):PAGE477
     2 PWRGD_P0V9_RETIMER_CPU1_R @T6G_MB_LIB.T6G(SCH_1):PWRGD_P0V9_RETIMER_CPU1_R    I39 @T6G_MB_LIB.T6G(SCH_1):PAGE477

R662 Q_RES_0402LF-0,5%,1/16W,CHIP,CS00002JB13
     1 P0V9_RETIMER_CPU1_EN @T6G_MB_LIB.T6G(SCH_1):P0V9_RETIMER_CPU1_EN    I38 @T6G_MB_LIB.T6G(SCH_1):PAGE477
     2 P0V9_RETIMER_CPU1_EN0_R @T6G_MB_LIB.T6G(SCH_1):P0V9_RETIMER_CPU1_EN0_R    I38 @T6G_MB_LIB.T6G(SCH_1):PAGE477

R663 Q_RES_0402LF-1K,1%,1/16W,CHIP,CS21002FB06
     1 P3V3_AUX @T6G_MB_LIB.T6G(SCH_1):P3V3_AUX    I15 @T6G_MB_LIB.T6G(SCH_1):PAGE477
     2 P0V9_RETIMER_CPU1_CFP @T6G_MB_LIB.T6G(SCH_1):P0V9_RETIMER_CPU1_CFP    I15 @T6G_MB_LIB.T6G(SCH_1):PAGE477

R664 Q_RES_0402LF-0,5%,1/16W,EMPTY,CS00002JB13
     1 P1V8_CPU1_RT1_1A_1D @T6G_MB_LIB.T6G(SCH_1):P1V8_CPU1_RT1_1A_1D     I4 @T6G_MB_LIB.T6G(SCH_1):PAGE443
     2 P1V8_CPU1_RT1_1A @T6G_MB_LIB.T6G(SCH_1):P1V8_CPU1_RT1_1A     I4 @T6G_MB_LIB.T6G(SCH_1):PAGE443

R665 Q_RES_0402LF-1K,1%,1/16W,CHIP,CS21002FB06
     1 P3V3_AUX @T6G_MB_LIB.T6G(SCH_1):P3V3_AUX    I14 @T6G_MB_LIB.T6G(SCH_1):PAGE477
     2 P0V9_RETIMER_CPU1_INALERT @T6G_MB_LIB.T6G(SCH_1):P0V9_RETIMER_CPU1_INALERT    I14 @T6G_MB_LIB.T6G(SCH_1):PAGE477

R666 Q_RES_0201LF-49.9,1%,1/20W,CHIP,CS04991FE06
     1 SMB_RT_CPU0_P0_ROM_MUX_1D_SCL @T6G_MB_LIB.T6G(SCH_1):SMB_RT_CPU0_P0_ROM_MUX_1D_SCL    I42 @T6G_MB_LIB.T6G(SCH_1):PAGE385
     2 SMB_RT_CPU0_P0_ROM_MUX_1D_R_SCL @T6G_MB_LIB.T6G(SCH_1):SMB_RT_CPU0_P0_ROM_MUX_1D_R_SCL    I42 @T6G_MB_LIB.T6G(SCH_1):PAGE385

R667 Q_RES_0201LF-49.9,1%,1/20W,CHIP,CS04991FE06
     1 SMB_RT_CPU0_P0_ROM_MUX_1D_SDA @T6G_MB_LIB.T6G(SCH_1):SMB_RT_CPU0_P0_ROM_MUX_1D_SDA    I41 @T6G_MB_LIB.T6G(SCH_1):PAGE385
     2 SMB_RT_CPU0_P0_ROM_MUX_1D_R_SDA @T6G_MB_LIB.T6G(SCH_1):SMB_RT_CPU0_P0_ROM_MUX_1D_R_SDA    I41 @T6G_MB_LIB.T6G(SCH_1):PAGE385

R668 Q_RES_0201LF-33.2,1%,1/20W,CHIP,CS03321FE09
     1 SMB_RT_CPU0_P0_ROM_R_SCL @T6G_MB_LIB.T6G(SCH_1):SMB_RT_CPU0_P0_ROM_R_SCL     I6 @T6G_MB_LIB.T6G(SCH_1):PAGE387
     2 SMB_RT_CPU0_P0_ROM_SCL @T6G_MB_LIB.T6G(SCH_1):SMB_RT_CPU0_P0_ROM_SCL     I6 @T6G_MB_LIB.T6G(SCH_1):PAGE387

R669 Q_RES_0201LF-33.2,1%,1/20W,CHIP,CS03321FE09
     1 SMB_RT_CPU0_P0_ROM_R_SDA @T6G_MB_LIB.T6G(SCH_1):SMB_RT_CPU0_P0_ROM_R_SDA     I7 @T6G_MB_LIB.T6G(SCH_1):PAGE387
     2 SMB_RT_CPU0_P0_ROM_SDA @T6G_MB_LIB.T6G(SCH_1):SMB_RT_CPU0_P0_ROM_SDA     I7 @T6G_MB_LIB.T6G(SCH_1):PAGE387

R670 Q_RES_0201LF-49.9,1%,1/20W,CHIP,CS04991FE06
     1 SMB_RT_CPU1_P1_ROM_MUX_1D_SCL @T6G_MB_LIB.T6G(SCH_1):SMB_RT_CPU1_P1_ROM_MUX_1D_SCL    I36 @T6G_MB_LIB.T6G(SCH_1):PAGE392
     2 SMB_RT_CPU1_P1_ROM_MUX_1D_R_SCL @T6G_MB_LIB.T6G(SCH_1):SMB_RT_CPU1_P1_ROM_MUX_1D_R_SCL    I36 @T6G_MB_LIB.T6G(SCH_1):PAGE392

R671 Q_RES_0201LF-49.9,1%,1/20W,CHIP,CS04991FE06
     1 SMB_RT_CPU1_P1_ROM_MUX_1D_SDA @T6G_MB_LIB.T6G(SCH_1):SMB_RT_CPU1_P1_ROM_MUX_1D_SDA    I35 @T6G_MB_LIB.T6G(SCH_1):PAGE392
     2 SMB_RT_CPU1_P1_ROM_MUX_1D_R_SDA @T6G_MB_LIB.T6G(SCH_1):SMB_RT_CPU1_P1_ROM_MUX_1D_R_SDA    I35 @T6G_MB_LIB.T6G(SCH_1):PAGE392

R672 Q_RES_0201LF-33.2,1%,1/20W,CHIP,CS03321FE09
     1 SMB_RT_CPU1_P0_ROM_R_SCL @T6G_MB_LIB.T6G(SCH_1):SMB_RT_CPU1_P0_ROM_R_SCL     I3 @T6G_MB_LIB.T6G(SCH_1):PAGE399
     2 SMB_RT_CPU1_P0_ROM_SCL @T6G_MB_LIB.T6G(SCH_1):SMB_RT_CPU1_P0_ROM_SCL     I3 @T6G_MB_LIB.T6G(SCH_1):PAGE399

R673 Q_RES_0201LF-33.2,1%,1/20W,CHIP,CS03321FE09
     1 SMB_RT_CPU1_P0_ROM_R_SDA @T6G_MB_LIB.T6G(SCH_1):SMB_RT_CPU1_P0_ROM_R_SDA     I4 @T6G_MB_LIB.T6G(SCH_1):PAGE399
     2 SMB_RT_CPU1_P0_ROM_SDA @T6G_MB_LIB.T6G(SCH_1):SMB_RT_CPU1_P0_ROM_SDA     I4 @T6G_MB_LIB.T6G(SCH_1):PAGE399

R674 Q_RES_0201LF-22,1%,1/20W,CHIP,CS02201FE11
     1 SMB_RT_CPU1_P0_ROM_MUX_1D_SCL @T6G_MB_LIB.T6G(SCH_1):SMB_RT_CPU1_P0_ROM_MUX_1D_SCL   I155 @T6G_MB_LIB.T6G(SCH_1):PAGE401
     2 SMB_RT_CPU1_P0_ROM_MUX_1D_R_SCL @T6G_MB_LIB.T6G(SCH_1):SMB_RT_CPU1_P0_ROM_MUX_1D_R_SCL   I155 @T6G_MB_LIB.T6G(SCH_1):PAGE401

R675 Q_RES_0201LF-49.9,1%,1/20W,CHIP,CS04991FE06
     1 SMB_RT_CPU1_P0_ROM_MUX_1D_SDA @T6G_MB_LIB.T6G(SCH_1):SMB_RT_CPU1_P0_ROM_MUX_1D_SDA    I13 @T6G_MB_LIB.T6G(SCH_1):PAGE401
     2 SMB_RT_CPU1_P0_ROM_MUX_1D_R_SDA @T6G_MB_LIB.T6G(SCH_1):SMB_RT_CPU1_P0_ROM_MUX_1D_R_SDA    I13 @T6G_MB_LIB.T6G(SCH_1):PAGE401

R676 Q_RES_0201LF-49.9,1%,1/20W,CHIP,CS04991FE06
     1 SMB_RT_CPU0_P1_ROM_MUX_1D_SCL @T6G_MB_LIB.T6G(SCH_1):SMB_RT_CPU0_P1_ROM_MUX_1D_SCL    I22 @T6G_MB_LIB.T6G(SCH_1):PAGE408
     2 SMB_RT_CPU0_P1_ROM_MUX_1D_R_SCL @T6G_MB_LIB.T6G(SCH_1):SMB_RT_CPU0_P1_ROM_MUX_1D_R_SCL    I22 @T6G_MB_LIB.T6G(SCH_1):PAGE408

R677 Q_RES_0201LF-49.9,1%,1/20W,CHIP,CS04991FE06
     1 SMB_RT_CPU0_P1_ROM_MUX_1D_SDA @T6G_MB_LIB.T6G(SCH_1):SMB_RT_CPU0_P1_ROM_MUX_1D_SDA    I21 @T6G_MB_LIB.T6G(SCH_1):PAGE408
     2 SMB_RT_CPU0_P1_ROM_MUX_1D_R_SDA @T6G_MB_LIB.T6G(SCH_1):SMB_RT_CPU0_P1_ROM_MUX_1D_R_SDA    I21 @T6G_MB_LIB.T6G(SCH_1):PAGE408

R678 Q_RES_0201LF-33.2,1%,1/20W,CHIP,CS03321FE09
     1 SMB_RT_CPU0_P1_ROM_R_SCL @T6G_MB_LIB.T6G(SCH_1):SMB_RT_CPU0_P1_ROM_R_SCL     I6 @T6G_MB_LIB.T6G(SCH_1):PAGE410
     2 SMB_RT_CPU0_P1_ROM_SCL @T6G_MB_LIB.T6G(SCH_1):SMB_RT_CPU0_P1_ROM_SCL     I6 @T6G_MB_LIB.T6G(SCH_1):PAGE410

R679 Q_RES_0201LF-33.2,1%,1/20W,CHIP,CS03321FE09
     1 SMB_RT_CPU0_P1_ROM_R_SDA @T6G_MB_LIB.T6G(SCH_1):SMB_RT_CPU0_P1_ROM_R_SDA     I7 @T6G_MB_LIB.T6G(SCH_1):PAGE410
     2 SMB_RT_CPU0_P1_ROM_SDA @T6G_MB_LIB.T6G(SCH_1):SMB_RT_CPU0_P1_ROM_SDA     I7 @T6G_MB_LIB.T6G(SCH_1):PAGE410

R680 Q_RES_0201LF-49.9,1%,1/20W,CHIP,CS04991FE06
     1 SMB_RT_CPU0_P2_ROM_MUX_1D_SCL @T6G_MB_LIB.T6G(SCH_1):SMB_RT_CPU0_P2_ROM_MUX_1D_SCL    I22 @T6G_MB_LIB.T6G(SCH_1):PAGE419
     2 SMB_RT_CPU0_P2_ROM_MUX_1D_R_SCL @T6G_MB_LIB.T6G(SCH_1):SMB_RT_CPU0_P2_ROM_MUX_1D_R_SCL    I22 @T6G_MB_LIB.T6G(SCH_1):PAGE419

R681 Q_RES_0201LF-49.9,1%,1/20W,CHIP,CS04991FE06
     1 SMB_RT_CPU0_P2_ROM_MUX_1D_SDA @T6G_MB_LIB.T6G(SCH_1):SMB_RT_CPU0_P2_ROM_MUX_1D_SDA    I21 @T6G_MB_LIB.T6G(SCH_1):PAGE419
     2 SMB_RT_CPU0_P2_ROM_MUX_1D_R_SDA @T6G_MB_LIB.T6G(SCH_1):SMB_RT_CPU0_P2_ROM_MUX_1D_R_SDA    I21 @T6G_MB_LIB.T6G(SCH_1):PAGE419

R682 Q_RES_0201LF-33.2,1%,1/20W,CHIP,CS03321FE09
     1 SMB_RT_CPU0_P2_ROM_R_SCL @T6G_MB_LIB.T6G(SCH_1):SMB_RT_CPU0_P2_ROM_R_SCL     I3 @T6G_MB_LIB.T6G(SCH_1):PAGE421
     2 SMB_RT_CPU0_P2_ROM_SCL @T6G_MB_LIB.T6G(SCH_1):SMB_RT_CPU0_P2_ROM_SCL     I3 @T6G_MB_LIB.T6G(SCH_1):PAGE421

R683 Q_RES_0201LF-33.2,1%,1/20W,CHIP,CS03321FE09
     1 SMB_RT_CPU0_P2_ROM_R_SDA @T6G_MB_LIB.T6G(SCH_1):SMB_RT_CPU0_P2_ROM_R_SDA     I4 @T6G_MB_LIB.T6G(SCH_1):PAGE421
     2 SMB_RT_CPU0_P2_ROM_SDA @T6G_MB_LIB.T6G(SCH_1):SMB_RT_CPU0_P2_ROM_SDA     I4 @T6G_MB_LIB.T6G(SCH_1):PAGE421

R684 Q_RES_0201LF-49.9,1%,1/20W,CHIP,CS04991FE06
     1 SMB_RT_CPU0_P3_ROM_MUX_1D_SCL @T6G_MB_LIB.T6G(SCH_1):SMB_RT_CPU0_P3_ROM_MUX_1D_SCL    I22 @T6G_MB_LIB.T6G(SCH_1):PAGE430
     2 SMB_RT_CPU0_P3_ROM_MUX_1D_R_SCL @T6G_MB_LIB.T6G(SCH_1):SMB_RT_CPU0_P3_ROM_MUX_1D_R_SCL    I22 @T6G_MB_LIB.T6G(SCH_1):PAGE430

R685 Q_RES_0402LF-33,5%,1/16W,CHIP,CS03302JB10
     1 RST_PERST_E1S_0_R_N @T6G_MB_LIB.T6G(SCH_1):RST_PERST_E1S_0_R_N   I131 @T6G_MB_LIB.T6G(SCH_1):PAGE80
     2 RST_PERST_E1S_0_N @T6G_MB_LIB.T6G(SCH_1):RST_PERST_E1S_0_N   I131 @T6G_MB_LIB.T6G(SCH_1):PAGE80

R686 Q_RES_0201LF-49.9,1%,1/20W,CHIP,CS04991FE06
     1 SMB_RT_CPU0_P3_ROM_MUX_1D_SDA @T6G_MB_LIB.T6G(SCH_1):SMB_RT_CPU0_P3_ROM_MUX_1D_SDA    I21 @T6G_MB_LIB.T6G(SCH_1):PAGE430
     2 SMB_RT_CPU0_P3_ROM_MUX_1D_R_SDA @T6G_MB_LIB.T6G(SCH_1):SMB_RT_CPU0_P3_ROM_MUX_1D_R_SDA    I21 @T6G_MB_LIB.T6G(SCH_1):PAGE430

R687 Q_RES_0201LF-33.2,1%,1/20W,CHIP,CS03321FE09
     1 SMB_RT_CPU0_P3_ROM_R_SCL @T6G_MB_LIB.T6G(SCH_1):SMB_RT_CPU0_P3_ROM_R_SCL     I3 @T6G_MB_LIB.T6G(SCH_1):PAGE432
     2 SMB_RT_CPU0_P3_ROM_SCL @T6G_MB_LIB.T6G(SCH_1):SMB_RT_CPU0_P3_ROM_SCL     I3 @T6G_MB_LIB.T6G(SCH_1):PAGE432

R688 Q_RES_0201LF-33.2,1%,1/20W,CHIP,CS03321FE09
     1 SMB_RT_CPU0_P3_ROM_R_SDA @T6G_MB_LIB.T6G(SCH_1):SMB_RT_CPU0_P3_ROM_R_SDA     I4 @T6G_MB_LIB.T6G(SCH_1):PAGE432
     2 SMB_RT_CPU0_P3_ROM_SDA @T6G_MB_LIB.T6G(SCH_1):SMB_RT_CPU0_P3_ROM_SDA     I4 @T6G_MB_LIB.T6G(SCH_1):PAGE432

R689 Q_RES_0201LF-33.2,1%,1/20W,CHIP,CS03321FE09
     1 SMB_RT_CPU1_P1_ROM_R_SCL @T6G_MB_LIB.T6G(SCH_1):SMB_RT_CPU1_P1_ROM_R_SCL     I4 @T6G_MB_LIB.T6G(SCH_1):PAGE442
     2 SMB_RT_CPU1_P1_ROM_SCL @T6G_MB_LIB.T6G(SCH_1):SMB_RT_CPU1_P1_ROM_SCL     I4 @T6G_MB_LIB.T6G(SCH_1):PAGE442

R690 Q_RES_0201LF-33.2,1%,1/20W,CHIP,CS03321FE09
     1 SMB_RT_CPU1_P1_ROM_R_SDA @T6G_MB_LIB.T6G(SCH_1):SMB_RT_CPU1_P1_ROM_R_SDA     I3 @T6G_MB_LIB.T6G(SCH_1):PAGE442
     2 SMB_RT_CPU1_P1_ROM_SDA @T6G_MB_LIB.T6G(SCH_1):SMB_RT_CPU1_P1_ROM_SDA     I3 @T6G_MB_LIB.T6G(SCH_1):PAGE442

R691 Q_RES_0201LF-49.9,1%,1/20W,CHIP,CS04991FE06
     1 SMB_RT_CPU1_P2_ROM_MUX_1D_SCL @T6G_MB_LIB.T6G(SCH_1):SMB_RT_CPU1_P2_ROM_MUX_1D_SCL    I30 @T6G_MB_LIB.T6G(SCH_1):PAGE451
     2 SMB_RT_CPU1_P2_ROM_MUX_1D_R_SCL @T6G_MB_LIB.T6G(SCH_1):SMB_RT_CPU1_P2_ROM_MUX_1D_R_SCL    I30 @T6G_MB_LIB.T6G(SCH_1):PAGE451

R692 Q_RES_0201LF-49.9,1%,1/20W,CHIP,CS04991FE06
     1 SMB_RT_CPU1_P2_ROM_MUX_1D_SDA @T6G_MB_LIB.T6G(SCH_1):SMB_RT_CPU1_P2_ROM_MUX_1D_SDA    I29 @T6G_MB_LIB.T6G(SCH_1):PAGE451
     2 SMB_RT_CPU1_P2_ROM_MUX_1D_R_SDA @T6G_MB_LIB.T6G(SCH_1):SMB_RT_CPU1_P2_ROM_MUX_1D_R_SDA    I29 @T6G_MB_LIB.T6G(SCH_1):PAGE451

R693 Q_RES_0201LF-33.2,1%,1/20W,CHIP,CS03321FE09
     1 SMB_RT_CPU1_P2_ROM_R_SCL @T6G_MB_LIB.T6G(SCH_1):SMB_RT_CPU1_P2_ROM_R_SCL     I4 @T6G_MB_LIB.T6G(SCH_1):PAGE453
     2 SMB_RT_CPU1_P2_ROM_SCL @T6G_MB_LIB.T6G(SCH_1):SMB_RT_CPU1_P2_ROM_SCL     I4 @T6G_MB_LIB.T6G(SCH_1):PAGE453

R694 Q_RES_0201LF-33.2,1%,1/20W,CHIP,CS03321FE09
     1 SMB_RT_CPU1_P2_ROM_R_SDA @T6G_MB_LIB.T6G(SCH_1):SMB_RT_CPU1_P2_ROM_R_SDA     I3 @T6G_MB_LIB.T6G(SCH_1):PAGE453
     2 SMB_RT_CPU1_P2_ROM_SDA @T6G_MB_LIB.T6G(SCH_1):SMB_RT_CPU1_P2_ROM_SDA     I3 @T6G_MB_LIB.T6G(SCH_1):PAGE453

R695 Q_RES_0201LF-22,1%,1/20W,CHIP,CS02201FE11
     1 SMB_RT_CPU1_P3_ROM_MUX_1D_SCL @T6G_MB_LIB.T6G(SCH_1):SMB_RT_CPU1_P3_ROM_MUX_1D_SCL   I146 @T6G_MB_LIB.T6G(SCH_1):PAGE462
     2 SMB_RT_CPU1_P3_ROM_MUX_1D_R_SCL @T6G_MB_LIB.T6G(SCH_1):SMB_RT_CPU1_P3_ROM_MUX_1D_R_SCL   I146 @T6G_MB_LIB.T6G(SCH_1):PAGE462

R696 Q_RES_0201LF-49.9,1%,1/20W,CHIP,CS04991FE06
     1 SMB_RT_CPU1_P3_ROM_MUX_1D_SDA @T6G_MB_LIB.T6G(SCH_1):SMB_RT_CPU1_P3_ROM_MUX_1D_SDA    I33 @T6G_MB_LIB.T6G(SCH_1):PAGE462
     2 SMB_RT_CPU1_P3_ROM_MUX_1D_R_SDA @T6G_MB_LIB.T6G(SCH_1):SMB_RT_CPU1_P3_ROM_MUX_1D_R_SDA    I33 @T6G_MB_LIB.T6G(SCH_1):PAGE462

R697 Q_RES_0201LF-0,5%,1/20W,CHIP,CS00001JE10
     1 SMB_RT_CPU1_P3_ROM_R_SCL @T6G_MB_LIB.T6G(SCH_1):SMB_RT_CPU1_P3_ROM_R_SCL    I25 @T6G_MB_LIB.T6G(SCH_1):PAGE464
     2 SMB_RT_CPU1_P3_ROM_SCL @T6G_MB_LIB.T6G(SCH_1):SMB_RT_CPU1_P3_ROM_SCL    I25 @T6G_MB_LIB.T6G(SCH_1):PAGE464

R698 Q_RES_0201LF-33.2,1%,1/20W,CHIP,CS03321FE09
     1 SMB_RT_CPU1_P3_ROM_R_SDA @T6G_MB_LIB.T6G(SCH_1):SMB_RT_CPU1_P3_ROM_R_SDA     I4 @T6G_MB_LIB.T6G(SCH_1):PAGE464
     2 SMB_RT_CPU1_P3_ROM_SDA @T6G_MB_LIB.T6G(SCH_1):SMB_RT_CPU1_P3_ROM_SDA     I4 @T6G_MB_LIB.T6G(SCH_1):PAGE464

R699 Q_RES_0201LF-1K,1%,1/20W,EMPTY,CS21001FE07
     1 P1V8_CPU1_RT_1D @T6G_MB_LIB.T6G(SCH_1):P1V8_CPU1_RT_1D   I106 @T6G_MB_LIB.T6G(SCH_1):PAGE400
     2 RT_CPU1_P0_VQPS @T6G_MB_LIB.T6G(SCH_1):RT_CPU1_P0_VQPS   I106 @T6G_MB_LIB.T6G(SCH_1):PAGE400

R700 Q_RES_0402LF-30K,1%,1/16W,EMPTY,CS33002FB02
     1 P12V_AUX @T6G_MB_LIB.T6G(SCH_1):P12V_AUX     I2 @T6G_MB_LIB.T6G(SCH_1):PAGE146
     2 P12V_AUX_DSC_VOL @T6G_MB_LIB.T6G(SCH_1):P12V_AUX_DSC_VOL     I2 @T6G_MB_LIB.T6G(SCH_1):PAGE146

R701 Q_RES_0201LF-200,1%,1/20W,CHIP,CS12001FE12
     1 RT_CPU1_P0_VQPS @T6G_MB_LIB.T6G(SCH_1):RT_CPU1_P0_VQPS   I105 @T6G_MB_LIB.T6G(SCH_1):PAGE400
     2    GND @T6G_MB_LIB.T6G(SCH_1):GND   I105 @T6G_MB_LIB.T6G(SCH_1):PAGE400

R702 Q_RES_0402LF-10K,5%,1/16W,EMPTY,CS31002JB08
     1 PWRGD_CPU0_PWROK @T6G_MB_LIB.T6G(SCH_1):PWRGD_CPU0_PWROK     I1 @T6G_MB_LIB.T6G(SCH_1):PAGE77
     2    GND @T6G_MB_LIB.T6G(SCH_1):GND     I1 @T6G_MB_LIB.T6G(SCH_1):PAGE77

R703 Q_RES_0402LF-10K,5%,1/16W,EMPTY,CS31002JB08
     1 PWRGD_CPU1_PWROK @T6G_MB_LIB.T6G(SCH_1):PWRGD_CPU1_PWROK     I5 @T6G_MB_LIB.T6G(SCH_1):PAGE77
     2    GND @T6G_MB_LIB.T6G(SCH_1):GND     I5 @T6G_MB_LIB.T6G(SCH_1):PAGE77

R704 Q_RES_0402LF-0,5%,1/16W,EMPTY,CS00002JB13
     1 P1V8_CPU1_RT_1D @T6G_MB_LIB.T6G(SCH_1):P1V8_CPU1_RT_1D    I89 @T6G_MB_LIB.T6G(SCH_1):PAGE443
     2 P1V8_CPU1_RT1_1A_1D @T6G_MB_LIB.T6G(SCH_1):P1V8_CPU1_RT1_1A_1D    I89 @T6G_MB_LIB.T6G(SCH_1):PAGE443

R705 Q_RES_0603LF-0,5%,1/4W,EMPTY,CS00006J900
     1 P0V9_CPU1_RT_2D @T6G_MB_LIB.T6G(SCH_1):P0V9_CPU1_RT_2D    I10 @T6G_MB_LIB.T6G(SCH_1):PAGE443
     2 P0V9_CPU1_RT1_2A_2D @T6G_MB_LIB.T6G(SCH_1):P0V9_CPU1_RT1_2A_2D    I10 @T6G_MB_LIB.T6G(SCH_1):PAGE443

R706 Q_RES_0201LF-4.7K,5%,1/20W,EMPTY,CS24701JE04
     1 P1V8_CPU1_RT_1D @T6G_MB_LIB.T6G(SCH_1):P1V8_CPU1_RT_1D    I29 @T6G_MB_LIB.T6G(SCH_1):PAGE401
     2 GPIO2_RT_CPU1_P0 @T6G_MB_LIB.T6G(SCH_1):GPIO2_RT_CPU1_P0    I29 @T6G_MB_LIB.T6G(SCH_1):PAGE401

R707 Q_RES_0201LF-10K,1%,1/20W,CHIP,CS31001FE17
     1 GPIO2_RT_CPU1_P0 @T6G_MB_LIB.T6G(SCH_1):GPIO2_RT_CPU1_P0    I36 @T6G_MB_LIB.T6G(SCH_1):PAGE401
     2    GND @T6G_MB_LIB.T6G(SCH_1):GND    I36 @T6G_MB_LIB.T6G(SCH_1):PAGE401

R708 Q_RES_0402LF-33,5%,1/16W,CHIP,CS03302JB10
     1 FM_HDT_HDR_PWROK @T6G_MB_LIB.T6G(SCH_1):FM_HDT_HDR_PWROK   I168 @T6G_MB_LIB.T6G(SCH_1):PAGE80
     2 HDT_HDR_PWROK @T6G_MB_LIB.T6G(SCH_1):HDT_HDR_PWROK   I168 @T6G_MB_LIB.T6G(SCH_1):PAGE80

R709 Q_RES_0201LF-0,5%,1/20W,CHIP,CS00001JE10
     1 NCF_CPU1_P0_GND @T6G_MB_LIB.T6G(SCH_1):NCF_CPU1_P0_GND   I103 @T6G_MB_LIB.T6G(SCH_1):PAGE400
     2    GND @T6G_MB_LIB.T6G(SCH_1):GND   I103 @T6G_MB_LIB.T6G(SCH_1):PAGE400

R710 Q_RES_0402LF-1K,1%,1/16W,CHIP,CS21002FB06
     1 PD_MB_FRU_WP @T6G_MB_LIB.T6G(SCH_1):PD_MB_FRU_WP    I57 @T6G_MB_LIB.T6G(SCH_1):PAGE361
     2    GND @T6G_MB_LIB.T6G(SCH_1):GND    I57 @T6G_MB_LIB.T6G(SCH_1):PAGE361

R711 Q_RES_0201LF-0,5%,1/20W,CHIP,CS00001JE10
     1 NCF_A1_CPU1_P0_GND @T6G_MB_LIB.T6G(SCH_1):NCF_A1_CPU1_P0_GND   I102 @T6G_MB_LIB.T6G(SCH_1):PAGE400
     2    GND @T6G_MB_LIB.T6G(SCH_1):GND   I102 @T6G_MB_LIB.T6G(SCH_1):PAGE400

R712 Q_RES_0603LF-0,5%,1/4W,CHIP,CS00006J900
     1 P0V9_CPU1_RT1_2A_2D @T6G_MB_LIB.T6G(SCH_1):P0V9_CPU1_RT1_2A_2D    I11 @T6G_MB_LIB.T6G(SCH_1):PAGE443
     2 P0V9_CPU1_RT1_2A @T6G_MB_LIB.T6G(SCH_1):P0V9_CPU1_RT1_2A    I11 @T6G_MB_LIB.T6G(SCH_1):PAGE443

R713 Q_RES_0402LF-10K,1%,1/16W,EMPTY,CS31002FB08
     1 P3V3_AUX @T6G_MB_LIB.T6G(SCH_1):P3V3_AUX    I47 @T6G_MB_LIB.T6G(SCH_1):PAGE361
     2 MB_FRU_ADDR2 @T6G_MB_LIB.T6G(SCH_1):MB_FRU_ADDR2    I47 @T6G_MB_LIB.T6G(SCH_1):PAGE361

R714 Q_RES_0402LF-1K,1%,1/16W,CHIP,CS21002FB06
     1 MB_FRU_ADDR2 @T6G_MB_LIB.T6G(SCH_1):MB_FRU_ADDR2    I52 @T6G_MB_LIB.T6G(SCH_1):PAGE361
     2    GND @T6G_MB_LIB.T6G(SCH_1):GND    I52 @T6G_MB_LIB.T6G(SCH_1):PAGE361

R715 Q_RES_0201LF-10K,1%,1/20W,CHIP,CS31001FE17
     1 GPIO3_RT_CPU1_P0 @T6G_MB_LIB.T6G(SCH_1):GPIO3_RT_CPU1_P0    I35 @T6G_MB_LIB.T6G(SCH_1):PAGE401
     2    GND @T6G_MB_LIB.T6G(SCH_1):GND    I35 @T6G_MB_LIB.T6G(SCH_1):PAGE401

R716 Q_RES_0201LF-4.7K,5%,1/20W,EMPTY,CS24701JE04
     1 P1V8_CPU1_RT_1D @T6G_MB_LIB.T6G(SCH_1):P1V8_CPU1_RT_1D    I27 @T6G_MB_LIB.T6G(SCH_1):PAGE401
     2 TEST0_RT_CPU1_P0 @T6G_MB_LIB.T6G(SCH_1):TEST0_RT_CPU1_P0    I27 @T6G_MB_LIB.T6G(SCH_1):PAGE401

R717 Q_RES_0402LF-10K,1%,1/16W,EMPTY,CS31002FB08
     1 P3V3_AUX @T6G_MB_LIB.T6G(SCH_1):P3V3_AUX    I45 @T6G_MB_LIB.T6G(SCH_1):PAGE361
     2 MB_FRU_ADDR1 @T6G_MB_LIB.T6G(SCH_1):MB_FRU_ADDR1    I45 @T6G_MB_LIB.T6G(SCH_1):PAGE361

R718 Q_RES_0402LF-1K,1%,1/16W,CHIP,CS21002FB06
     1 MB_FRU_ADDR1 @T6G_MB_LIB.T6G(SCH_1):MB_FRU_ADDR1    I50 @T6G_MB_LIB.T6G(SCH_1):PAGE361
     2    GND @T6G_MB_LIB.T6G(SCH_1):GND    I50 @T6G_MB_LIB.T6G(SCH_1):PAGE361

R719 Q_RES_0201LF-4.7K,5%,1/20W,CHIP,CS24701JE04
     1 TEST0_RT_CPU1_P0 @T6G_MB_LIB.T6G(SCH_1):TEST0_RT_CPU1_P0    I34 @T6G_MB_LIB.T6G(SCH_1):PAGE401
     2    GND @T6G_MB_LIB.T6G(SCH_1):GND    I34 @T6G_MB_LIB.T6G(SCH_1):PAGE401

R720 Q_RES_0201LF-4.7K,5%,1/20W,EMPTY,CS24701JE04
     1 P1V8_CPU1_RT_1D @T6G_MB_LIB.T6G(SCH_1):P1V8_CPU1_RT_1D    I26 @T6G_MB_LIB.T6G(SCH_1):PAGE401
     2 TEST1_RT_CPU1_P0 @T6G_MB_LIB.T6G(SCH_1):TEST1_RT_CPU1_P0    I26 @T6G_MB_LIB.T6G(SCH_1):PAGE401

R721 Q_RES_0402LF-10K,1%,1/16W,CHIP,CS31002FB08
     1 P3V3_AUX @T6G_MB_LIB.T6G(SCH_1):P3V3_AUX    I62 @T6G_MB_LIB.T6G(SCH_1):PAGE361
     2 MB_FRU_ADDR0 @T6G_MB_LIB.T6G(SCH_1):MB_FRU_ADDR0    I62 @T6G_MB_LIB.T6G(SCH_1):PAGE361

R722 Q_RES_0402LF-1K,1%,1/16W,EMPTY,CS21002FB06
     1 MB_FRU_ADDR0 @T6G_MB_LIB.T6G(SCH_1):MB_FRU_ADDR0    I61 @T6G_MB_LIB.T6G(SCH_1):PAGE361
     2    GND @T6G_MB_LIB.T6G(SCH_1):GND    I61 @T6G_MB_LIB.T6G(SCH_1):PAGE361

R723 Q_RES_0201LF-4.7K,5%,1/20W,CHIP,CS24701JE04
     1 TEST1_RT_CPU1_P0 @T6G_MB_LIB.T6G(SCH_1):TEST1_RT_CPU1_P0    I33 @T6G_MB_LIB.T6G(SCH_1):PAGE401
     2    GND @T6G_MB_LIB.T6G(SCH_1):GND    I33 @T6G_MB_LIB.T6G(SCH_1):PAGE401

R724 Q_RES_0201LF-4.7K,5%,1/20W,EMPTY,CS24701JE04
     1 P1V8_CPU1_RT_1D @T6G_MB_LIB.T6G(SCH_1):P1V8_CPU1_RT_1D    I25 @T6G_MB_LIB.T6G(SCH_1):PAGE401
     2 TEST2_RT_CPU1_P0 @T6G_MB_LIB.T6G(SCH_1):TEST2_RT_CPU1_P0    I25 @T6G_MB_LIB.T6G(SCH_1):PAGE401

R725 Q_RES_0201LF-4.7K,5%,1/20W,CHIP,CS24701JE04
     1 TEST2_RT_CPU1_P0 @T6G_MB_LIB.T6G(SCH_1):TEST2_RT_CPU1_P0    I32 @T6G_MB_LIB.T6G(SCH_1):PAGE401
     2    GND @T6G_MB_LIB.T6G(SCH_1):GND    I32 @T6G_MB_LIB.T6G(SCH_1):PAGE401

R726 Q_RES_0201LF-4.7K,5%,1/20W,CHIP,CS24701JE04
     1 JTAG_TEST_MODE_RT_CPU1_P0 @T6G_MB_LIB.T6G(SCH_1):JTAG_TEST_MODE_RT_CPU1_P0    I90 @T6G_MB_LIB.T6G(SCH_1):PAGE401
     2    GND @T6G_MB_LIB.T6G(SCH_1):GND    I90 @T6G_MB_LIB.T6G(SCH_1):PAGE401

R727 Q_RES_0201LF-4.7K,5%,1/20W,CHIP,CS24701JE04
     1 P1V8_CPU1_RT_1D @T6G_MB_LIB.T6G(SCH_1):P1V8_CPU1_RT_1D    I54 @T6G_MB_LIB.T6G(SCH_1):PAGE401
     2 MODE_RT_CPU1_P0 @T6G_MB_LIB.T6G(SCH_1):MODE_RT_CPU1_P0    I54 @T6G_MB_LIB.T6G(SCH_1):PAGE401

R728 Q_RES_0201LF-4.7K,5%,1/20W,EMPTY,CS24701JE04
     1 MODE_RT_CPU1_P0 @T6G_MB_LIB.T6G(SCH_1):MODE_RT_CPU1_P0    I55 @T6G_MB_LIB.T6G(SCH_1):PAGE401
     2    GND @T6G_MB_LIB.T6G(SCH_1):GND    I55 @T6G_MB_LIB.T6G(SCH_1):PAGE401

R729 Q_RES_0402LF-10K,5%,1/16W,EMPTY,CS31002JB08
     1 PVDD18_S5_P0 @T6G_MB_LIB.T6G(SCH_1):PVDD18_S5_P0    I41 @T6G_MB_LIB.T6G(SCH_1):PAGE75
     2 UART_CPU0_SCM_UART1_TX @T6G_MB_LIB.T6G(SCH_1):UART_CPU0_SCM_UART1_TX    I41 @T6G_MB_LIB.T6G(SCH_1):PAGE75

R730 Q_RES_0402LF-10K,5%,1/16W,CHIP,CS31002JB08
     1 PVDD18_S5_P1 @T6G_MB_LIB.T6G(SCH_1):PVDD18_S5_P1    I87 @T6G_MB_LIB.T6G(SCH_1):PAGE75
     2 SPI_CPU1_CLK @T6G_MB_LIB.T6G(SCH_1):SPI_CPU1_CLK    I87 @T6G_MB_LIB.T6G(SCH_1):PAGE75

R731 Q_RES_0201LF-0,5%,1/20W,CHIP,CS00001JE10
     1 RST_RT_CPU1_P1_PERST_N @T6G_MB_LIB.T6G(SCH_1):RST_RT_CPU1_P1_PERST_N    I70 @T6G_MB_LIB.T6G(SCH_1):PAGE392
     2 RST_RT_CPU1_P1_PERST_R_N @T6G_MB_LIB.T6G(SCH_1):RST_RT_CPU1_P1_PERST_R_N    I70 @T6G_MB_LIB.T6G(SCH_1):PAGE392

R732 Q_RES_0201LF-0,5%,1/20W,CHIP,CS00001JE10
     1 RST_RT_CPU1_P1_RESET_N @T6G_MB_LIB.T6G(SCH_1):RST_RT_CPU1_P1_RESET_N    I71 @T6G_MB_LIB.T6G(SCH_1):PAGE392
     2 RST_RT_CPU1_P1_RESET_R_N @T6G_MB_LIB.T6G(SCH_1):RST_RT_CPU1_P1_RESET_R_N    I71 @T6G_MB_LIB.T6G(SCH_1):PAGE392

R733 Q_RES_0402LF-100,1%,1/16W,EMPTY,CS11002FB07
     1 P1V8_AUX @T6G_MB_LIB.T6G(SCH_1):P1V8_AUX    I50 @T6G_MB_LIB.T6G(SCH_1):PAGE144
     2 FM_JTAG_BMC_R_OE @T6G_MB_LIB.T6G(SCH_1):FM_JTAG_BMC_R_OE    I50 @T6G_MB_LIB.T6G(SCH_1):PAGE144

R734 Q_RES_0402LF-0,5%,1/16W,CHIP,CS00002JB13
     1 PRSNT_CPU0_N @T6G_MB_LIB.T6G(SCH_1):PRSNT_CPU0_N    I19 @T6G_MB_LIB.T6G(SCH_1):PAGE144
     2 FM_PRSNT_CPU0_N @T6G_MB_LIB.T6G(SCH_1):FM_PRSNT_CPU0_N    I19 @T6G_MB_LIB.T6G(SCH_1):PAGE144

R735 Q_RES_0201LF-1K,1%,1/20W,CHIP,CS21001FE07
     1 P1V8_CPU1_RT_1D @T6G_MB_LIB.T6G(SCH_1):P1V8_CPU1_RT_1D   I103 @T6G_MB_LIB.T6G(SCH_1):PAGE392
     2 RT_CPU1_P1_ADDR3 @T6G_MB_LIB.T6G(SCH_1):RT_CPU1_P1_ADDR3   I103 @T6G_MB_LIB.T6G(SCH_1):PAGE392

R736 Q_RES_0402LF-10K,5%,1/16W,EMPTY,CS31002JB08
     1 PVDD18_S5_P1 @T6G_MB_LIB.T6G(SCH_1):PVDD18_S5_P1    I89 @T6G_MB_LIB.T6G(SCH_1):PAGE75
     2 PD_ESPI_CPU1_CLK2 @T6G_MB_LIB.T6G(SCH_1):PD_ESPI_CPU1_CLK2    I89 @T6G_MB_LIB.T6G(SCH_1):PAGE75

R737 Q_RES_0402LF-10K,5%,1/16W,CHIP,CS31002JB08
     1 PVDD18_S5_P0 @T6G_MB_LIB.T6G(SCH_1):PVDD18_S5_P0    I43 @T6G_MB_LIB.T6G(SCH_1):PAGE75
     2 CPU0_ROM_TYPE_SELECT @T6G_MB_LIB.T6G(SCH_1):CPU0_ROM_TYPE_SELECT    I43 @T6G_MB_LIB.T6G(SCH_1):PAGE75

R738 Q_RES_0402LF-33,5%,1/16W,CHIP,CS03302JB10
     1 SPI_CPU1_CLK @T6G_MB_LIB.T6G(SCH_1):SPI_CPU1_CLK    I11 @T6G_MB_LIB.T6G(SCH_1):PAGE56
     2 SPI_CPU1_R_CLK @T6G_MB_LIB.T6G(SCH_1):SPI_CPU1_R_CLK    I11 @T6G_MB_LIB.T6G(SCH_1):PAGE56

R739 Q_RES_0402LF-10K,5%,1/16W,EMPTY,CS31002JB08
     1 PVDD18_S5_P0 @T6G_MB_LIB.T6G(SCH_1):PVDD18_S5_P0    I45 @T6G_MB_LIB.T6G(SCH_1):PAGE75
     2 CLK_ESPI_CPU0_CLK1 @T6G_MB_LIB.T6G(SCH_1):CLK_ESPI_CPU0_CLK1    I45 @T6G_MB_LIB.T6G(SCH_1):PAGE75

R740 Q_RES_0402LF-10K,5%,1/16W,EMPTY,CS31002JB08
     1 PVDD18_S5_P0 @T6G_MB_LIB.T6G(SCH_1):PVDD18_S5_P0    I44 @T6G_MB_LIB.T6G(SCH_1):PAGE75
     2 CLK_CPU0_RTCCLK @T6G_MB_LIB.T6G(SCH_1):CLK_CPU0_RTCCLK    I44 @T6G_MB_LIB.T6G(SCH_1):PAGE75

R741 Q_RES_0201LF-1K,1%,1/20W,EMPTY,CS21001FE07
     1 RT_CPU1_P1_ADDR3 @T6G_MB_LIB.T6G(SCH_1):RT_CPU1_P1_ADDR3   I101 @T6G_MB_LIB.T6G(SCH_1):PAGE392
     2    GND @T6G_MB_LIB.T6G(SCH_1):GND   I101 @T6G_MB_LIB.T6G(SCH_1):PAGE392

R742 Q_RES_0402LF-10K,5%,1/16W,EMPTY,CS31002JB08
     1 PVDD18_S5_P0 @T6G_MB_LIB.T6G(SCH_1):PVDD18_S5_P0    I46 @T6G_MB_LIB.T6G(SCH_1):PAGE75
     2 PD_ESPI_CPU0_CLK2 @T6G_MB_LIB.T6G(SCH_1):PD_ESPI_CPU0_CLK2    I46 @T6G_MB_LIB.T6G(SCH_1):PAGE75

R743 Q_RES_0402LF-10K,5%,1/16W,CHIP,CS31002JB08
     1 PVDD18_S5_P0 @T6G_MB_LIB.T6G(SCH_1):PVDD18_S5_P0    I97 @T6G_MB_LIB.T6G(SCH_1):PAGE75
     2 SPI_CPU0_CLK @T6G_MB_LIB.T6G(SCH_1):SPI_CPU0_CLK    I97 @T6G_MB_LIB.T6G(SCH_1):PAGE75

R744 Q_RES_0402LF-0,5%,1/16W,CHIP,CS00002JB13
     1 PRSNT_CPU1_N @T6G_MB_LIB.T6G(SCH_1):PRSNT_CPU1_N    I17 @T6G_MB_LIB.T6G(SCH_1):PAGE144
     2 FM_PRSNT_CPU1_N @T6G_MB_LIB.T6G(SCH_1):FM_PRSNT_CPU1_N    I17 @T6G_MB_LIB.T6G(SCH_1):PAGE144

R745 Q_RES_0201LF-1K,1%,1/20W,EMPTY,CS21001FE07
     1 P1V8_CPU1_RT_1D @T6G_MB_LIB.T6G(SCH_1):P1V8_CPU1_RT_1D   I104 @T6G_MB_LIB.T6G(SCH_1):PAGE392
     2 RT_CPU1_P1_ADDR2 @T6G_MB_LIB.T6G(SCH_1):RT_CPU1_P1_ADDR2   I104 @T6G_MB_LIB.T6G(SCH_1):PAGE392

R746 Q_RES_0201LF-20K,1%,1/20W,CHIP,CS32001FE00
     1 RT_CPU1_P1_ADDR2 @T6G_MB_LIB.T6G(SCH_1):RT_CPU1_P1_ADDR2   I102 @T6G_MB_LIB.T6G(SCH_1):PAGE392
     2    GND @T6G_MB_LIB.T6G(SCH_1):GND   I102 @T6G_MB_LIB.T6G(SCH_1):PAGE392

R747 Q_RES_0402LF-1K,1%,1/16W,CHIP,CS21002FB06
     1    GND @T6G_MB_LIB.T6G(SCH_1):GND     I8 @T6G_MB_LIB.T6G(SCH_1):PAGE75
     2 UART_CPU0_SCM_UART1_TX @T6G_MB_LIB.T6G(SCH_1):UART_CPU0_SCM_UART1_TX     I8 @T6G_MB_LIB.T6G(SCH_1):PAGE75

R748 Q_RES_0402LF-10K,5%,1/16W,EMPTY,CS31002JB08
     1    GND @T6G_MB_LIB.T6G(SCH_1):GND     I9 @T6G_MB_LIB.T6G(SCH_1):PAGE75
     2 CPU0_ROM_TYPE_SELECT @T6G_MB_LIB.T6G(SCH_1):CPU0_ROM_TYPE_SELECT     I9 @T6G_MB_LIB.T6G(SCH_1):PAGE75

R749 Q_RES_0201LF-10K,1%,1/20W,CHIP,CS31001FE17
     1 RST_RT_CPU1_P1_PERST_R_N @T6G_MB_LIB.T6G(SCH_1):RST_RT_CPU1_P1_PERST_R_N    I93 @T6G_MB_LIB.T6G(SCH_1):PAGE392
     2    GND @T6G_MB_LIB.T6G(SCH_1):GND    I93 @T6G_MB_LIB.T6G(SCH_1):PAGE392

R750 Q_RES_0402LF-30K,1%,1/16W,CHIP,CS33002FB02
     1    GND @T6G_MB_LIB.T6G(SCH_1):GND    I74 @T6G_MB_LIB.T6G(SCH_1):PAGE75
     2 CLK_ESPI_CPU0_CLK1 @T6G_MB_LIB.T6G(SCH_1):CLK_ESPI_CPU0_CLK1    I74 @T6G_MB_LIB.T6G(SCH_1):PAGE75

R751 Q_RES_0402LF-10K,5%,1/16W,CHIP,CS31002JB08
     1    GND @T6G_MB_LIB.T6G(SCH_1):GND    I12 @T6G_MB_LIB.T6G(SCH_1):PAGE75
     2 CLK_CPU0_RTCCLK @T6G_MB_LIB.T6G(SCH_1):CLK_CPU0_RTCCLK    I12 @T6G_MB_LIB.T6G(SCH_1):PAGE75

R752 Q_RES_0201LF-10K,1%,1/20W,CHIP,CS31001FE17
     1 RST_RT_CPU1_P1_RESET_R_N @T6G_MB_LIB.T6G(SCH_1):RST_RT_CPU1_P1_RESET_R_N    I92 @T6G_MB_LIB.T6G(SCH_1):PAGE392
     2    GND @T6G_MB_LIB.T6G(SCH_1):GND    I92 @T6G_MB_LIB.T6G(SCH_1):PAGE392

R753 Q_RES_0402LF-10K,5%,1/16W,CHIP,CS31002JB08
     1    GND @T6G_MB_LIB.T6G(SCH_1):GND    I75 @T6G_MB_LIB.T6G(SCH_1):PAGE75
     2 PD_ESPI_CPU0_CLK2 @T6G_MB_LIB.T6G(SCH_1):PD_ESPI_CPU0_CLK2    I75 @T6G_MB_LIB.T6G(SCH_1):PAGE75

R754 Q_RES_0402LF-10K,5%,1/16W,EMPTY,CS31002JB08
     1    GND @T6G_MB_LIB.T6G(SCH_1):GND    I91 @T6G_MB_LIB.T6G(SCH_1):PAGE75
     2 SPI_CPU1_CLK @T6G_MB_LIB.T6G(SCH_1):SPI_CPU1_CLK    I91 @T6G_MB_LIB.T6G(SCH_1):PAGE75

R755 Q_RES_0201LF-4.7K,5%,1/20W,EMPTY,CS24701JE04
     1 P1V8_CPU1_RT_1D @T6G_MB_LIB.T6G(SCH_1):P1V8_CPU1_RT_1D    I19 @T6G_MB_LIB.T6G(SCH_1):PAGE392
     2 RT_CPU1_P1_SCAN_MODE @T6G_MB_LIB.T6G(SCH_1):RT_CPU1_P1_SCAN_MODE    I19 @T6G_MB_LIB.T6G(SCH_1):PAGE392

R756 Q_RES_0201LF-200,1%,1/20W,CHIP,CS12001FE12
     1 RT_CPU1_P1_SCAN_MODE @T6G_MB_LIB.T6G(SCH_1):RT_CPU1_P1_SCAN_MODE   I132 @T6G_MB_LIB.T6G(SCH_1):PAGE392
     2    GND @T6G_MB_LIB.T6G(SCH_1):GND   I132 @T6G_MB_LIB.T6G(SCH_1):PAGE392

R757 Q_RES_0402LF-4.7K,5%,1/16W,EMPTY,CS24702JB10
     1 E1S_0_P3V3_EN @T6G_MB_LIB.T6G(SCH_1):E1S_0_P3V3_EN    I41 @T6G_MB_LIB.T6G(SCH_1):PAGE82
     2 P3V3_AUX @T6G_MB_LIB.T6G(SCH_1):P3V3_AUX    I41 @T6G_MB_LIB.T6G(SCH_1):PAGE82

R758 Q_RES_0201LF-4.7K,5%,1/20W,EMPTY,CS24701JE04
     1 P1V8_CPU1_RT_1D @T6G_MB_LIB.T6G(SCH_1):P1V8_CPU1_RT_1D    I94 @T6G_MB_LIB.T6G(SCH_1):PAGE392
     2 RST_RT_CPU1_P1_RESET_R_N @T6G_MB_LIB.T6G(SCH_1):RST_RT_CPU1_P1_RESET_R_N    I94 @T6G_MB_LIB.T6G(SCH_1):PAGE392

R759 Q_RES_0201LF-4.7K,5%,1/20W,EMPTY,CS24701JE04
     1 P1V8_CPU1_RT_1D @T6G_MB_LIB.T6G(SCH_1):P1V8_CPU1_RT_1D    I57 @T6G_MB_LIB.T6G(SCH_1):PAGE392
     2 JTAG_TEST_MODE_RT_CPU1_P1 @T6G_MB_LIB.T6G(SCH_1):JTAG_TEST_MODE_RT_CPU1_P1    I57 @T6G_MB_LIB.T6G(SCH_1):PAGE392

R760 Q_RES_0402LF-10K,5%,1/16W,CHIP,CS31002JB08
     1    GND @T6G_MB_LIB.T6G(SCH_1):GND    I92 @T6G_MB_LIB.T6G(SCH_1):PAGE75
     2 PD_ESPI_CPU1_CLK2 @T6G_MB_LIB.T6G(SCH_1):PD_ESPI_CPU1_CLK2    I92 @T6G_MB_LIB.T6G(SCH_1):PAGE75

R761 Q_RES_0402LF-15.4K,1%,1/16W,CHIP,CS31542FB02
     1 PD_CHB_CPU0_DIMM_SAA @T6G_MB_LIB.T6G(SCH_1):PD_CHB_CPU0_DIMM_SAA   I349 @T6G_MB_LIB.T6G(SCH_1):PAGE86
     2    GND @T6G_MB_LIB.T6G(SCH_1):GND   I349 @T6G_MB_LIB.T6G(SCH_1):PAGE86

R762 Q_RES_0402LF-23.2K,1%,1/16W,CHIP,CS32322FB03
     1 PD_CHC_CPU0_DIMM_SAA @T6G_MB_LIB.T6G(SCH_1):PD_CHC_CPU0_DIMM_SAA   I349 @T6G_MB_LIB.T6G(SCH_1):PAGE87
     2    GND @T6G_MB_LIB.T6G(SCH_1):GND   I349 @T6G_MB_LIB.T6G(SCH_1):PAGE87

R763 Q_RES_0402LF-35.7K,1%,1/16W,CHIP,CS33572FB01
     1 PD_CHD_CPU0_DIMM_SAA @T6G_MB_LIB.T6G(SCH_1):PD_CHD_CPU0_DIMM_SAA   I349 @T6G_MB_LIB.T6G(SCH_1):PAGE88
     2    GND @T6G_MB_LIB.T6G(SCH_1):GND   I349 @T6G_MB_LIB.T6G(SCH_1):PAGE88

R764 Q_RES_0402LF-84.5K,1%,1/16W,CHIP,CS38452FB05
     1 PD_CHF_CPU0_DIMM_SAA @T6G_MB_LIB.T6G(SCH_1):PD_CHF_CPU0_DIMM_SAA   I349 @T6G_MB_LIB.T6G(SCH_1):PAGE90
     2    GND @T6G_MB_LIB.T6G(SCH_1):GND   I349 @T6G_MB_LIB.T6G(SCH_1):PAGE90

R765 Q_RES_0402LF-15.4K,1%,1/16W,CHIP,CS31542FB02
     1 PD_CHH_CPU0_DIMM_SAA @T6G_MB_LIB.T6G(SCH_1):PD_CHH_CPU0_DIMM_SAA   I129 @T6G_MB_LIB.T6G(SCH_1):PAGE92
     2    GND @T6G_MB_LIB.T6G(SCH_1):GND   I129 @T6G_MB_LIB.T6G(SCH_1):PAGE92

R766 Q_RES_0402LF-23.2K,1%,1/16W,CHIP,CS32322FB03
     1 PD_CHI_CPU0_DIMM_SAA @T6G_MB_LIB.T6G(SCH_1):PD_CHI_CPU0_DIMM_SAA   I128 @T6G_MB_LIB.T6G(SCH_1):PAGE93
     2    GND @T6G_MB_LIB.T6G(SCH_1):GND   I128 @T6G_MB_LIB.T6G(SCH_1):PAGE93

R767 Q_RES_0402LF-35.7K,1%,1/16W,CHIP,CS33572FB01
     1 PD_CHJ_CPU0_DIMM_SAA @T6G_MB_LIB.T6G(SCH_1):PD_CHJ_CPU0_DIMM_SAA   I129 @T6G_MB_LIB.T6G(SCH_1):PAGE94
     2    GND @T6G_MB_LIB.T6G(SCH_1):GND   I129 @T6G_MB_LIB.T6G(SCH_1):PAGE94

R768 Q_RES_0402LF-54.9K,1%,1/16W,CHIP,CS35492FB03
     1 PD_CHK_CPU0_DIMM_SAA @T6G_MB_LIB.T6G(SCH_1):PD_CHK_CPU0_DIMM_SAA   I129 @T6G_MB_LIB.T6G(SCH_1):PAGE95
     2    GND @T6G_MB_LIB.T6G(SCH_1):GND   I129 @T6G_MB_LIB.T6G(SCH_1):PAGE95

R769 Q_RES_0402LF-84.5K,1%,1/16W,CHIP,CS38452FB05
     1 PD_CHL_CPU0_DIMM_SAA @T6G_MB_LIB.T6G(SCH_1):PD_CHL_CPU0_DIMM_SAA   I127 @T6G_MB_LIB.T6G(SCH_1):PAGE96
     2    GND @T6G_MB_LIB.T6G(SCH_1):GND   I127 @T6G_MB_LIB.T6G(SCH_1):PAGE96

R770 Q_RES_0402LF-15.4K,1%,1/16W,CHIP,CS31542FB02
     1 PD_CHB_CPU1_DIMM_SAA @T6G_MB_LIB.T6G(SCH_1):PD_CHB_CPU1_DIMM_SAA   I127 @T6G_MB_LIB.T6G(SCH_1):PAGE98
     2    GND @T6G_MB_LIB.T6G(SCH_1):GND   I127 @T6G_MB_LIB.T6G(SCH_1):PAGE98

R771 Q_RES_0402LF-23.2K,1%,1/16W,CHIP,CS32322FB03
     1 PD_CHC_CPU1_DIMM_SAA @T6G_MB_LIB.T6G(SCH_1):PD_CHC_CPU1_DIMM_SAA   I148 @T6G_MB_LIB.T6G(SCH_1):PAGE99
     2    GND @T6G_MB_LIB.T6G(SCH_1):GND   I148 @T6G_MB_LIB.T6G(SCH_1):PAGE99

R772 Q_RES_0402LF-35.7K,1%,1/16W,CHIP,CS33572FB01
     1 PD_CHD_CPU1_DIMM_SAA @T6G_MB_LIB.T6G(SCH_1):PD_CHD_CPU1_DIMM_SAA   I146 @T6G_MB_LIB.T6G(SCH_1):PAGE100
     2    GND @T6G_MB_LIB.T6G(SCH_1):GND   I146 @T6G_MB_LIB.T6G(SCH_1):PAGE100

R773 Q_RES_0402LF-84.5K,1%,1/16W,CHIP,CS38452FB05
     1 PD_CHF_CPU1_DIMM_SAA @T6G_MB_LIB.T6G(SCH_1):PD_CHF_CPU1_DIMM_SAA   I129 @T6G_MB_LIB.T6G(SCH_1):PAGE102
     2    GND @T6G_MB_LIB.T6G(SCH_1):GND   I129 @T6G_MB_LIB.T6G(SCH_1):PAGE102

R774 Q_RES_0402LF-15.4K,1%,1/16W,CHIP,CS31542FB02
     1 PD_CHH_CPU1_DIMM_SAA @T6G_MB_LIB.T6G(SCH_1):PD_CHH_CPU1_DIMM_SAA   I128 @T6G_MB_LIB.T6G(SCH_1):PAGE104
     2    GND @T6G_MB_LIB.T6G(SCH_1):GND   I128 @T6G_MB_LIB.T6G(SCH_1):PAGE104

R775 Q_RES_0402LF-23.2K,1%,1/16W,CHIP,CS32322FB03
     1 PD_CHI_CPU1_DIMM_SAA @T6G_MB_LIB.T6G(SCH_1):PD_CHI_CPU1_DIMM_SAA   I128 @T6G_MB_LIB.T6G(SCH_1):PAGE105
     2    GND @T6G_MB_LIB.T6G(SCH_1):GND   I128 @T6G_MB_LIB.T6G(SCH_1):PAGE105

R776 Q_RES_0402LF-35.7K,1%,1/16W,CHIP,CS33572FB01
     1 PD_CHJ_CPU1_DIMM_SAA @T6G_MB_LIB.T6G(SCH_1):PD_CHJ_CPU1_DIMM_SAA   I127 @T6G_MB_LIB.T6G(SCH_1):PAGE106
     2    GND @T6G_MB_LIB.T6G(SCH_1):GND   I127 @T6G_MB_LIB.T6G(SCH_1):PAGE106

R777 Q_RES_0402LF-54.9K,1%,1/16W,CHIP,CS35492FB03
     1 PD_CHK_CPU1_DIMM_SAA @T6G_MB_LIB.T6G(SCH_1):PD_CHK_CPU1_DIMM_SAA   I136 @T6G_MB_LIB.T6G(SCH_1):PAGE107
     2    GND @T6G_MB_LIB.T6G(SCH_1):GND   I136 @T6G_MB_LIB.T6G(SCH_1):PAGE107

R778 Q_RES_0402LF-84.5K,1%,1/16W,CHIP,CS38452FB05
     1 PD_CHL_CPU1_DIMM_SAA @T6G_MB_LIB.T6G(SCH_1):PD_CHL_CPU1_DIMM_SAA   I136 @T6G_MB_LIB.T6G(SCH_1):PAGE108
     2    GND @T6G_MB_LIB.T6G(SCH_1):GND   I136 @T6G_MB_LIB.T6G(SCH_1):PAGE108

R779 Q_RES_0201LF-0,5%,1/20W,CHIP,CS00001JE10
     1 SMB_RT_CPU1_P1_R_SCL @T6G_MB_LIB.T6G(SCH_1):SMB_RT_CPU1_P1_R_SCL    I44 @T6G_MB_LIB.T6G(SCH_1):PAGE392
     2 SMB_RT_CPU1_P1_R2_SCL @T6G_MB_LIB.T6G(SCH_1):SMB_RT_CPU1_P1_R2_SCL    I44 @T6G_MB_LIB.T6G(SCH_1):PAGE392

R780 Q_RES_0201LF-0,5%,1/20W,CHIP,CS00001JE10
     1 SMB_RT_CPU1_P1_R_SDA @T6G_MB_LIB.T6G(SCH_1):SMB_RT_CPU1_P1_R_SDA    I43 @T6G_MB_LIB.T6G(SCH_1):PAGE392
     2 SMB_RT_CPU1_P1_R2_SDA @T6G_MB_LIB.T6G(SCH_1):SMB_RT_CPU1_P1_R2_SDA    I43 @T6G_MB_LIB.T6G(SCH_1):PAGE392

R781 Q_RES_0201LF-4.7K,5%,1/20W,EMPTY,CS24701JE04
     1 P1V8_CPU1_RT_1D @T6G_MB_LIB.T6G(SCH_1):P1V8_CPU1_RT_1D    I24 @T6G_MB_LIB.T6G(SCH_1):PAGE392
     2 GPIO2_RT_CPU1_P1 @T6G_MB_LIB.T6G(SCH_1):GPIO2_RT_CPU1_P1    I24 @T6G_MB_LIB.T6G(SCH_1):PAGE392

R782 Q_RES_0201LF-10K,1%,1/20W,CHIP,CS31001FE17
     1 GPIO2_RT_CPU1_P1 @T6G_MB_LIB.T6G(SCH_1):GPIO2_RT_CPU1_P1    I21 @T6G_MB_LIB.T6G(SCH_1):PAGE392
     2    GND @T6G_MB_LIB.T6G(SCH_1):GND    I21 @T6G_MB_LIB.T6G(SCH_1):PAGE392

R783 Q_RES_0201LF-10K,1%,1/20W,CHIP,CS31001FE17
     1 GPIO3_RT_CPU1_P1 @T6G_MB_LIB.T6G(SCH_1):GPIO3_RT_CPU1_P1    I22 @T6G_MB_LIB.T6G(SCH_1):PAGE392
     2    GND @T6G_MB_LIB.T6G(SCH_1):GND    I22 @T6G_MB_LIB.T6G(SCH_1):PAGE392

R784 Q_RES_0201LF-4.7K,5%,1/20W,EMPTY,CS24701JE04
     1 P1V8_CPU1_RT_1D @T6G_MB_LIB.T6G(SCH_1):P1V8_CPU1_RT_1D    I25 @T6G_MB_LIB.T6G(SCH_1):PAGE392
     2 TEST0_RT_CPU1_P1 @T6G_MB_LIB.T6G(SCH_1):TEST0_RT_CPU1_P1    I25 @T6G_MB_LIB.T6G(SCH_1):PAGE392

R785 Q_RES_0201LF-4.7K,5%,1/20W,CHIP,CS24701JE04
     1 TEST0_RT_CPU1_P1 @T6G_MB_LIB.T6G(SCH_1):TEST0_RT_CPU1_P1    I23 @T6G_MB_LIB.T6G(SCH_1):PAGE392
     2    GND @T6G_MB_LIB.T6G(SCH_1):GND    I23 @T6G_MB_LIB.T6G(SCH_1):PAGE392

R786 Q_RES_0201LF-4.7K,5%,1/20W,EMPTY,CS24701JE04
     1 P1V8_CPU1_RT_1D @T6G_MB_LIB.T6G(SCH_1):P1V8_CPU1_RT_1D    I55 @T6G_MB_LIB.T6G(SCH_1):PAGE392
     2 TEST1_RT_CPU1_P1 @T6G_MB_LIB.T6G(SCH_1):TEST1_RT_CPU1_P1    I55 @T6G_MB_LIB.T6G(SCH_1):PAGE392

R787 Q_RES_0201LF-4.7K,5%,1/20W,CHIP,CS24701JE04
     1 TEST1_RT_CPU1_P1 @T6G_MB_LIB.T6G(SCH_1):TEST1_RT_CPU1_P1    I51 @T6G_MB_LIB.T6G(SCH_1):PAGE392
     2    GND @T6G_MB_LIB.T6G(SCH_1):GND    I51 @T6G_MB_LIB.T6G(SCH_1):PAGE392

R788 Q_RES_0201LF-4.7K,5%,1/20W,EMPTY,CS24701JE04
     1 P1V8_CPU1_RT_1D @T6G_MB_LIB.T6G(SCH_1):P1V8_CPU1_RT_1D    I56 @T6G_MB_LIB.T6G(SCH_1):PAGE392
     2 TEST2_RT_CPU1_P1 @T6G_MB_LIB.T6G(SCH_1):TEST2_RT_CPU1_P1    I56 @T6G_MB_LIB.T6G(SCH_1):PAGE392

R789 Q_RES_0402LF-0,5%,1/16W,EMPTY,CS00002JB13
     1 SMB_CPU0_CPU1_APML_BUF1_SCL @T6G_MB_LIB.T6G(SCH_1):SMB_CPU0_CPU1_APML_BUF1_SCL    I96 @T6G_MB_LIB.T6G(SCH_1):PAGE137
     2 SMB_CPU0_CPU1_APML_BUF1_SCL_R1 @T6G_MB_LIB.T6G(SCH_1):SMB_CPU0_CPU1_APML_BUF1_SCL_R1    I96 @T6G_MB_LIB.T6G(SCH_1):PAGE137

R790 Q_RES_0402LF-0,5%,1/16W,EMPTY,CS00002JB13
     1 SMB_CPU0_CPU1_APML_BUF1_SDA @T6G_MB_LIB.T6G(SCH_1):SMB_CPU0_CPU1_APML_BUF1_SDA    I95 @T6G_MB_LIB.T6G(SCH_1):PAGE137
     2 SMB_CPU0_CPU1_APML_BUF1_SDA_R1 @T6G_MB_LIB.T6G(SCH_1):SMB_CPU0_CPU1_APML_BUF1_SDA_R1    I95 @T6G_MB_LIB.T6G(SCH_1):PAGE137

R791 Q_RES_0201LF-4.7K,5%,1/20W,CHIP,CS24701JE04
     1 TEST2_RT_CPU1_P1 @T6G_MB_LIB.T6G(SCH_1):TEST2_RT_CPU1_P1    I52 @T6G_MB_LIB.T6G(SCH_1):PAGE392
     2    GND @T6G_MB_LIB.T6G(SCH_1):GND    I52 @T6G_MB_LIB.T6G(SCH_1):PAGE392

R792 Q_RES_0201LF-4.7K,5%,1/20W,CHIP,CS24701JE04
     1 JTAG_TEST_MODE_RT_CPU1_P1 @T6G_MB_LIB.T6G(SCH_1):JTAG_TEST_MODE_RT_CPU1_P1    I54 @T6G_MB_LIB.T6G(SCH_1):PAGE392
     2    GND @T6G_MB_LIB.T6G(SCH_1):GND    I54 @T6G_MB_LIB.T6G(SCH_1):PAGE392

R793 Q_RES_0201LF-4.7K,5%,1/20W,CHIP,CS24701JE04
     1 P1V8_CPU1_RT_1D @T6G_MB_LIB.T6G(SCH_1):P1V8_CPU1_RT_1D    I66 @T6G_MB_LIB.T6G(SCH_1):PAGE392
     2 MODE_RT_CPU1_P1 @T6G_MB_LIB.T6G(SCH_1):MODE_RT_CPU1_P1    I66 @T6G_MB_LIB.T6G(SCH_1):PAGE392

R794 Q_RES_0201LF-4.7K,5%,1/20W,EMPTY,CS24701JE04
     1 MODE_RT_CPU1_P1 @T6G_MB_LIB.T6G(SCH_1):MODE_RT_CPU1_P1    I65 @T6G_MB_LIB.T6G(SCH_1):PAGE392
     2    GND @T6G_MB_LIB.T6G(SCH_1):GND    I65 @T6G_MB_LIB.T6G(SCH_1):PAGE392

R795 Q_RES_0201LF-1K,1%,1/20W,EMPTY,CS21001FE07
     1 P1V8_CPU1_RT_1D @T6G_MB_LIB.T6G(SCH_1):P1V8_CPU1_RT_1D   I110 @T6G_MB_LIB.T6G(SCH_1):PAGE392
     2 RT_CPU1_P1_ADDR1 @T6G_MB_LIB.T6G(SCH_1):RT_CPU1_P1_ADDR1   I110 @T6G_MB_LIB.T6G(SCH_1):PAGE392

R796 Q_RES_0201LF-1K,1%,1/20W,CHIP,CS21001FE07
     1 RT_CPU1_P1_ADDR1 @T6G_MB_LIB.T6G(SCH_1):RT_CPU1_P1_ADDR1   I105 @T6G_MB_LIB.T6G(SCH_1):PAGE392
     2    GND @T6G_MB_LIB.T6G(SCH_1):GND   I105 @T6G_MB_LIB.T6G(SCH_1):PAGE392

R797 Q_RES_0201LF-0,5%,1/20W,CHIP,CS00001JE10
     1 SMB_RT_CPU0_P0_ROM_MUX_2D_R_SDA @T6G_MB_LIB.T6G(SCH_1):SMB_RT_CPU0_P0_ROM_MUX_2D_R_SDA    I80 @T6G_MB_LIB.T6G(SCH_1):PAGE377
     2 SMB_RT_CPU0_P0_ROM_MUX_2D_SDA @T6G_MB_LIB.T6G(SCH_1):SMB_RT_CPU0_P0_ROM_MUX_2D_SDA    I80 @T6G_MB_LIB.T6G(SCH_1):PAGE377

R798 Q_RES_0402LF-33,5%,1/16W,CHIP,CS03302JB10
     1 RST_PERST_M2_0_R_N @T6G_MB_LIB.T6G(SCH_1):RST_PERST_M2_0_R_N   I125 @T6G_MB_LIB.T6G(SCH_1):PAGE80
     2 RST_PERST_M2_0_N @T6G_MB_LIB.T6G(SCH_1):RST_PERST_M2_0_N   I125 @T6G_MB_LIB.T6G(SCH_1):PAGE80

R799 Q_RES_0201LF-0,5%,1/20W,CHIP,CS00001JE10
     1 SMB_RT_CPU0_P0_ROM_MUX_2D_R_SCL @T6G_MB_LIB.T6G(SCH_1):SMB_RT_CPU0_P0_ROM_MUX_2D_R_SCL    I79 @T6G_MB_LIB.T6G(SCH_1):PAGE377
     2 SMB_RT_CPU0_P0_ROM_MUX_2D_SCL @T6G_MB_LIB.T6G(SCH_1):SMB_RT_CPU0_P0_ROM_MUX_2D_SCL    I79 @T6G_MB_LIB.T6G(SCH_1):PAGE377

R800 Q_RES_0402LF-10K,1%,1/16W,CHIP,CS31002FB08
     1 RST_PERST_E1S_0_N @T6G_MB_LIB.T6G(SCH_1):RST_PERST_E1S_0_N   I118 @T6G_MB_LIB.T6G(SCH_1):PAGE82
     2    GND @T6G_MB_LIB.T6G(SCH_1):GND   I118 @T6G_MB_LIB.T6G(SCH_1):PAGE82

R801 Q_RES_0201LF-0,5%,1/20W,CHIP,CS00001JE10
     1 SMB_RT_CPU1_P0_ROM_MUX_2D_SDA @T6G_MB_LIB.T6G(SCH_1):SMB_RT_CPU1_P0_ROM_MUX_2D_SDA    I49 @T6G_MB_LIB.T6G(SCH_1):PAGE377
     2 SMB_RT_CPU1_P0_ROM_MUX_2D_R_SDA @T6G_MB_LIB.T6G(SCH_1):SMB_RT_CPU1_P0_ROM_MUX_2D_R_SDA    I49 @T6G_MB_LIB.T6G(SCH_1):PAGE377

R802 Q_RES_0201LF-0,5%,1/20W,CHIP,CS00001JE10
     1 SMB_RT_CPU1_P0_ROM_MUX_2D_SCL @T6G_MB_LIB.T6G(SCH_1):SMB_RT_CPU1_P0_ROM_MUX_2D_SCL    I50 @T6G_MB_LIB.T6G(SCH_1):PAGE377
     2 SMB_RT_CPU1_P0_ROM_MUX_2D_R_SCL @T6G_MB_LIB.T6G(SCH_1):SMB_RT_CPU1_P0_ROM_MUX_2D_R_SCL    I50 @T6G_MB_LIB.T6G(SCH_1):PAGE377

R803 Q_RES_0201LF-0,5%,1/20W,CHIP,CS00001JE10
     1 SMB_RT_CPU1_P1_ROM_MUX_2D_SDA @T6G_MB_LIB.T6G(SCH_1):SMB_RT_CPU1_P1_ROM_MUX_2D_SDA    I48 @T6G_MB_LIB.T6G(SCH_1):PAGE377
     2 SMB_RT_CPU1_P1_ROM_MUX_2D_R_SDA @T6G_MB_LIB.T6G(SCH_1):SMB_RT_CPU1_P1_ROM_MUX_2D_R_SDA    I48 @T6G_MB_LIB.T6G(SCH_1):PAGE377

R804 Q_RES_0402LF-10K,1%,1/16W,CHIP,CS31002FB08
     1 RST_PERST_M2_0_N @T6G_MB_LIB.T6G(SCH_1):RST_PERST_M2_0_N   I120 @T6G_MB_LIB.T6G(SCH_1):PAGE82
     2    GND @T6G_MB_LIB.T6G(SCH_1):GND   I120 @T6G_MB_LIB.T6G(SCH_1):PAGE82

R805 Q_RES_0201LF-0,5%,1/20W,CHIP,CS00001JE10
     1 SMB_RT_CPU1_P1_ROM_MUX_2D_SCL @T6G_MB_LIB.T6G(SCH_1):SMB_RT_CPU1_P1_ROM_MUX_2D_SCL    I46 @T6G_MB_LIB.T6G(SCH_1):PAGE377
     2 SMB_RT_CPU1_P1_ROM_MUX_2D_R_SCL @T6G_MB_LIB.T6G(SCH_1):SMB_RT_CPU1_P1_ROM_MUX_2D_R_SCL    I46 @T6G_MB_LIB.T6G(SCH_1):PAGE377

R806 Q_RES_0201LF-0,5%,1/20W,CHIP,CS00001JE10
     1 SMB_RT_CPU1_P3_ROM_MUX_2D_SDA @T6G_MB_LIB.T6G(SCH_1):SMB_RT_CPU1_P3_ROM_MUX_2D_SDA    I47 @T6G_MB_LIB.T6G(SCH_1):PAGE377
     2 SMB_RT_CPU1_P3_ROM_MUX_2D_R_SDA @T6G_MB_LIB.T6G(SCH_1):SMB_RT_CPU1_P3_ROM_MUX_2D_R_SDA    I47 @T6G_MB_LIB.T6G(SCH_1):PAGE377

R807 Q_RES_0201LF-0,5%,1/20W,CHIP,CS00001JE10
     1 SMB_RT_CPU1_P3_ROM_MUX_2D_SCL @T6G_MB_LIB.T6G(SCH_1):SMB_RT_CPU1_P3_ROM_MUX_2D_SCL    I43 @T6G_MB_LIB.T6G(SCH_1):PAGE377
     2 SMB_RT_CPU1_P3_ROM_MUX_2D_R_SCL @T6G_MB_LIB.T6G(SCH_1):SMB_RT_CPU1_P3_ROM_MUX_2D_R_SCL    I43 @T6G_MB_LIB.T6G(SCH_1):PAGE377

R808 Q_RES_0201LF-0,5%,1/20W,CHIP,CS00001JE10
     1 SMB_RT_CPU1_P2_ROM_MUX_2D_SDA @T6G_MB_LIB.T6G(SCH_1):SMB_RT_CPU1_P2_ROM_MUX_2D_SDA    I45 @T6G_MB_LIB.T6G(SCH_1):PAGE377
     2 SMB_RT_CPU1_P2_ROM_MUX_2D_R_SDA @T6G_MB_LIB.T6G(SCH_1):SMB_RT_CPU1_P2_ROM_MUX_2D_R_SDA    I45 @T6G_MB_LIB.T6G(SCH_1):PAGE377

R809 Q_RES_0201LF-0,5%,1/20W,CHIP,CS00001JE10
     1 SMB_RT_CPU1_P2_ROM_MUX_2D_SCL @T6G_MB_LIB.T6G(SCH_1):SMB_RT_CPU1_P2_ROM_MUX_2D_SCL    I44 @T6G_MB_LIB.T6G(SCH_1):PAGE377
     2 SMB_RT_CPU1_P2_ROM_MUX_2D_R_SCL @T6G_MB_LIB.T6G(SCH_1):SMB_RT_CPU1_P2_ROM_MUX_2D_R_SCL    I44 @T6G_MB_LIB.T6G(SCH_1):PAGE377

R810 Q_RES_0201LF-1K,1%,1/20W,CHIP,CS21001FE07
     1 P1V8_CPU1_RT_1D @T6G_MB_LIB.T6G(SCH_1):P1V8_CPU1_RT_1D    I61 @T6G_MB_LIB.T6G(SCH_1):PAGE377
     2 SMB_RT_CPU1_P3_ROM_R_SDA @T6G_MB_LIB.T6G(SCH_1):SMB_RT_CPU1_P3_ROM_R_SDA    I61 @T6G_MB_LIB.T6G(SCH_1):PAGE377

R811 Q_RES_0402LF-1K,1%,1/16W,CHIP,CS21002FB06
     1 PVDD18_S5_P0 @T6G_MB_LIB.T6G(SCH_1):PVDD18_S5_P0   I106 @T6G_MB_LIB.T6G(SCH_1):PAGE76
     2 SPI_CPU0_CS0_N @T6G_MB_LIB.T6G(SCH_1):SPI_CPU0_CS0_N   I106 @T6G_MB_LIB.T6G(SCH_1):PAGE76

R812 Q_RES_0201LF-1K,1%,1/20W,CHIP,CS21001FE07
     1 P1V8_CPU1_RT_1D @T6G_MB_LIB.T6G(SCH_1):P1V8_CPU1_RT_1D    I60 @T6G_MB_LIB.T6G(SCH_1):PAGE377
     2 SMB_RT_CPU1_P3_ROM_R_SCL @T6G_MB_LIB.T6G(SCH_1):SMB_RT_CPU1_P3_ROM_R_SCL    I60 @T6G_MB_LIB.T6G(SCH_1):PAGE377

R813 Q_RES_0402LF-10K,5%,1/16W,CHIP,CS31002JB08
     1 PVDD18_S5_P0 @T6G_MB_LIB.T6G(SCH_1):PVDD18_S5_P0   I199 @T6G_MB_LIB.T6G(SCH_1):PAGE141
     2 UART_CPU0_UART0_RX @T6G_MB_LIB.T6G(SCH_1):UART_CPU0_UART0_RX   I199 @T6G_MB_LIB.T6G(SCH_1):PAGE141

R814 Q_RES_0402LF-10K,5%,1/16W,EMPTY,CS31002JB08
     1 PVDD18_S5_P0 @T6G_MB_LIB.T6G(SCH_1):PVDD18_S5_P0   I198 @T6G_MB_LIB.T6G(SCH_1):PAGE141
     2 UART_CPU0_UART0_TX @T6G_MB_LIB.T6G(SCH_1):UART_CPU0_UART0_TX   I198 @T6G_MB_LIB.T6G(SCH_1):PAGE141

R815 Q_RES_0402LF-10K,5%,1/16W,EMPTY,CS31002JB08
     1 PVDD18_S5_P0 @T6G_MB_LIB.T6G(SCH_1):PVDD18_S5_P0   I197 @T6G_MB_LIB.T6G(SCH_1):PAGE141
     2 UART_CPU0_SCM_UART1_TX @T6G_MB_LIB.T6G(SCH_1):UART_CPU0_SCM_UART1_TX   I197 @T6G_MB_LIB.T6G(SCH_1):PAGE141

R816 Q_RES_0402LF-10K,5%,1/16W,CHIP,CS31002JB08
     1 PVDD18_S5_P0 @T6G_MB_LIB.T6G(SCH_1):PVDD18_S5_P0   I196 @T6G_MB_LIB.T6G(SCH_1):PAGE141
     2 UART_CPU0_SCM_UART1_RX @T6G_MB_LIB.T6G(SCH_1):UART_CPU0_SCM_UART1_RX   I196 @T6G_MB_LIB.T6G(SCH_1):PAGE141

R817 Q_RES_0402LF-0,5%,1/16W,CHIP,CS00002JB13
     1 UART_CPU0_UART0_RX @T6G_MB_LIB.T6G(SCH_1):UART_CPU0_UART0_RX   I231 @T6G_MB_LIB.T6G(SCH_1):PAGE141
     2 UART_CPU0_UART0_R_RX @T6G_MB_LIB.T6G(SCH_1):UART_CPU0_UART0_R_RX   I231 @T6G_MB_LIB.T6G(SCH_1):PAGE141

R818 Q_RES_0402LF-0,5%,1/16W,CHIP,CS00002JB13
     1 UART_CPU0_LVC3_UART0_R_TX @T6G_MB_LIB.T6G(SCH_1):UART_CPU0_LVC3_UART0_R_TX   I220 @T6G_MB_LIB.T6G(SCH_1):PAGE141
     2 UART_CPU0_LVC3_UART0_TX @T6G_MB_LIB.T6G(SCH_1):UART_CPU0_LVC3_UART0_TX   I220 @T6G_MB_LIB.T6G(SCH_1):PAGE141

R819 Q_RES_0402LF-0,5%,1/16W,CHIP,CS00002JB13
     1 UART_CPU0_LVC3_UART0_R_RX @T6G_MB_LIB.T6G(SCH_1):UART_CPU0_LVC3_UART0_R_RX   I212 @T6G_MB_LIB.T6G(SCH_1):PAGE141
     2 UART_CPU0_LVC3_UART0_RX @T6G_MB_LIB.T6G(SCH_1):UART_CPU0_LVC3_UART0_RX   I212 @T6G_MB_LIB.T6G(SCH_1):PAGE141

R820 Q_RES_0402LF-10K,5%,1/16W,EMPTY,CS31002JB08
     1 UART_VCC_J13 @T6G_MB_LIB.T6G(SCH_1):UART_VCC_J13   I186 @T6G_MB_LIB.T6G(SCH_1):PAGE141
     2 P5V_AUX @T6G_MB_LIB.T6G(SCH_1):P5V_AUX   I186 @T6G_MB_LIB.T6G(SCH_1):PAGE141

R821 Q_RES_0402LF-10K,5%,1/16W,CHIP,CS31002JB08
     1 P3V3_AUX @T6G_MB_LIB.T6G(SCH_1):P3V3_AUX   I185 @T6G_MB_LIB.T6G(SCH_1):PAGE141
     2 UART_VCC_J13 @T6G_MB_LIB.T6G(SCH_1):UART_VCC_J13   I185 @T6G_MB_LIB.T6G(SCH_1):PAGE141

R822 Q_RES_0402LF-10K,5%,1/16W,CHIP,CS31002JB08
     1 P3V3_AUX @T6G_MB_LIB.T6G(SCH_1):P3V3_AUX   I206 @T6G_MB_LIB.T6G(SCH_1):PAGE141
     2 UART_CPU0_SCM_LVC3_UART1_TX @T6G_MB_LIB.T6G(SCH_1):UART_CPU0_SCM_LVC3_UART1_TX   I206 @T6G_MB_LIB.T6G(SCH_1):PAGE141

R823 Q_RES_0402LF-10K,5%,1/16W,EMPTY,CS31002JB08
     1 P3V3_AUX @T6G_MB_LIB.T6G(SCH_1):P3V3_AUX   I205 @T6G_MB_LIB.T6G(SCH_1):PAGE141
     2 UART_CPU0_SCM_LVC3_UART1_R_RX @T6G_MB_LIB.T6G(SCH_1):UART_CPU0_SCM_LVC3_UART1_R_RX   I205 @T6G_MB_LIB.T6G(SCH_1):PAGE141

R824 Q_RES_0402LF-10K,5%,1/16W,CHIP,CS31002JB08
     1 P3V3_AUX @T6G_MB_LIB.T6G(SCH_1):P3V3_AUX   I204 @T6G_MB_LIB.T6G(SCH_1):PAGE141
     2 UART_CPU0_LVC3_UART0_TX @T6G_MB_LIB.T6G(SCH_1):UART_CPU0_LVC3_UART0_TX   I204 @T6G_MB_LIB.T6G(SCH_1):PAGE141

R825 Q_RES_0402LF-10K,5%,1/16W,EMPTY,CS31002JB08
     1 P3V3_AUX @T6G_MB_LIB.T6G(SCH_1):P3V3_AUX   I203 @T6G_MB_LIB.T6G(SCH_1):PAGE141
     2 UART_CPU0_LVC3_UART0_RX @T6G_MB_LIB.T6G(SCH_1):UART_CPU0_LVC3_UART0_RX   I203 @T6G_MB_LIB.T6G(SCH_1):PAGE141

R826 Q_RES_0201LF-1K,1%,1/20W,CHIP,CS21001FE07
     1 P1V8_CPU1_RT_1D @T6G_MB_LIB.T6G(SCH_1):P1V8_CPU1_RT_1D    I59 @T6G_MB_LIB.T6G(SCH_1):PAGE377
     2 SMB_RT_CPU1_P2_ROM_R_SDA @T6G_MB_LIB.T6G(SCH_1):SMB_RT_CPU1_P2_ROM_R_SDA    I59 @T6G_MB_LIB.T6G(SCH_1):PAGE377

R827 Q_RES_0201LF-1K,1%,1/20W,CHIP,CS21001FE07
     1 P1V8_CPU1_RT_1D @T6G_MB_LIB.T6G(SCH_1):P1V8_CPU1_RT_1D    I58 @T6G_MB_LIB.T6G(SCH_1):PAGE377
     2 SMB_RT_CPU1_P2_ROM_R_SCL @T6G_MB_LIB.T6G(SCH_1):SMB_RT_CPU1_P2_ROM_R_SCL    I58 @T6G_MB_LIB.T6G(SCH_1):PAGE377

R828 Q_RES_0201LF-0,5%,1/20W,CHIP,CS00001JE10
     1 SMB_RT_CPU0_P1_ROM_MUX_2D_R_SDA @T6G_MB_LIB.T6G(SCH_1):SMB_RT_CPU0_P1_ROM_MUX_2D_R_SDA    I76 @T6G_MB_LIB.T6G(SCH_1):PAGE377
     2 SMB_RT_CPU0_P1_ROM_MUX_2D_SDA @T6G_MB_LIB.T6G(SCH_1):SMB_RT_CPU0_P1_ROM_MUX_2D_SDA    I76 @T6G_MB_LIB.T6G(SCH_1):PAGE377

R829 Q_RES_0201LF-0,5%,1/20W,CHIP,CS00001JE10
     1 SMB_RT_CPU0_P1_ROM_MUX_2D_R_SCL @T6G_MB_LIB.T6G(SCH_1):SMB_RT_CPU0_P1_ROM_MUX_2D_R_SCL    I77 @T6G_MB_LIB.T6G(SCH_1):PAGE377
     2 SMB_RT_CPU0_P1_ROM_MUX_2D_SCL @T6G_MB_LIB.T6G(SCH_1):SMB_RT_CPU0_P1_ROM_MUX_2D_SCL    I77 @T6G_MB_LIB.T6G(SCH_1):PAGE377

R830 Q_RES_0201LF-0,5%,1/20W,CHIP,CS00001JE10
     1 SMB_RT_CPU0_P3_ROM_MUX_2D_R_SDA @T6G_MB_LIB.T6G(SCH_1):SMB_RT_CPU0_P3_ROM_MUX_2D_R_SDA    I78 @T6G_MB_LIB.T6G(SCH_1):PAGE377
     2 SMB_RT_CPU0_P3_ROM_MUX_2D_SDA @T6G_MB_LIB.T6G(SCH_1):SMB_RT_CPU0_P3_ROM_MUX_2D_SDA    I78 @T6G_MB_LIB.T6G(SCH_1):PAGE377

R831 Q_RES_0201LF-0,5%,1/20W,CHIP,CS00001JE10
     1 SMB_RT_CPU0_P3_ROM_MUX_2D_R_SCL @T6G_MB_LIB.T6G(SCH_1):SMB_RT_CPU0_P3_ROM_MUX_2D_R_SCL    I74 @T6G_MB_LIB.T6G(SCH_1):PAGE377
     2 SMB_RT_CPU0_P3_ROM_MUX_2D_SCL @T6G_MB_LIB.T6G(SCH_1):SMB_RT_CPU0_P3_ROM_MUX_2D_SCL    I74 @T6G_MB_LIB.T6G(SCH_1):PAGE377

R832 Q_RES_0201LF-0,5%,1/20W,CHIP,CS00001JE10
     1 SMB_RT_CPU0_P2_ROM_MUX_2D_R_SDA @T6G_MB_LIB.T6G(SCH_1):SMB_RT_CPU0_P2_ROM_MUX_2D_R_SDA    I75 @T6G_MB_LIB.T6G(SCH_1):PAGE377
     2 SMB_RT_CPU0_P2_ROM_MUX_2D_SDA @T6G_MB_LIB.T6G(SCH_1):SMB_RT_CPU0_P2_ROM_MUX_2D_SDA    I75 @T6G_MB_LIB.T6G(SCH_1):PAGE377

R833 Q_RES_0201LF-0,5%,1/20W,CHIP,CS00001JE10
     1 SMB_RT_CPU0_P2_ROM_MUX_2D_R_SCL @T6G_MB_LIB.T6G(SCH_1):SMB_RT_CPU0_P2_ROM_MUX_2D_R_SCL    I73 @T6G_MB_LIB.T6G(SCH_1):PAGE377
     2 SMB_RT_CPU0_P2_ROM_MUX_2D_SCL @T6G_MB_LIB.T6G(SCH_1):SMB_RT_CPU0_P2_ROM_MUX_2D_SCL    I73 @T6G_MB_LIB.T6G(SCH_1):PAGE377

R834 Q_RES_0201LF-1K,1%,1/20W,CHIP,CS21001FE07
     1 P1V8_CPU0_RT_1D @T6G_MB_LIB.T6G(SCH_1):P1V8_CPU0_RT_1D    I24 @T6G_MB_LIB.T6G(SCH_1):PAGE377
     2 SMB_RT_CPU0_P0_ROM_R_SDA @T6G_MB_LIB.T6G(SCH_1):SMB_RT_CPU0_P0_ROM_R_SDA    I24 @T6G_MB_LIB.T6G(SCH_1):PAGE377

R835 Q_RES_0201LF-1K,1%,1/20W,CHIP,CS21001FE07
     1 P1V8_CPU0_RT_1D @T6G_MB_LIB.T6G(SCH_1):P1V8_CPU0_RT_1D    I23 @T6G_MB_LIB.T6G(SCH_1):PAGE377
     2 SMB_RT_CPU0_P0_ROM_R_SCL @T6G_MB_LIB.T6G(SCH_1):SMB_RT_CPU0_P0_ROM_R_SCL    I23 @T6G_MB_LIB.T6G(SCH_1):PAGE377

R836 Q_RES_0201LF-1K,1%,1/20W,CHIP,CS21001FE07
     1 P1V8_CPU0_RT_1D @T6G_MB_LIB.T6G(SCH_1):P1V8_CPU0_RT_1D    I22 @T6G_MB_LIB.T6G(SCH_1):PAGE377
     2 SMB_RT_CPU0_P1_ROM_R_SDA @T6G_MB_LIB.T6G(SCH_1):SMB_RT_CPU0_P1_ROM_R_SDA    I22 @T6G_MB_LIB.T6G(SCH_1):PAGE377

R837 Q_RES_0201LF-1K,1%,1/20W,CHIP,CS21001FE07
     1 P1V8_CPU0_RT_1D @T6G_MB_LIB.T6G(SCH_1):P1V8_CPU0_RT_1D    I21 @T6G_MB_LIB.T6G(SCH_1):PAGE377
     2 SMB_RT_CPU0_P1_ROM_R_SCL @T6G_MB_LIB.T6G(SCH_1):SMB_RT_CPU0_P1_ROM_R_SCL    I21 @T6G_MB_LIB.T6G(SCH_1):PAGE377

R838 Q_RES_0201LF-1K,1%,1/20W,CHIP,CS21001FE07
     1 P1V8_CPU0_RT_1D @T6G_MB_LIB.T6G(SCH_1):P1V8_CPU0_RT_1D    I19 @T6G_MB_LIB.T6G(SCH_1):PAGE377
     2 SMB_RT_CPU0_P3_ROM_R_SDA @T6G_MB_LIB.T6G(SCH_1):SMB_RT_CPU0_P3_ROM_R_SDA    I19 @T6G_MB_LIB.T6G(SCH_1):PAGE377

R839 Q_RES_0201LF-1K,1%,1/20W,CHIP,CS21001FE07
     1 P1V8_CPU0_RT_1D @T6G_MB_LIB.T6G(SCH_1):P1V8_CPU0_RT_1D    I20 @T6G_MB_LIB.T6G(SCH_1):PAGE377
     2 SMB_RT_CPU0_P3_ROM_R_SCL @T6G_MB_LIB.T6G(SCH_1):SMB_RT_CPU0_P3_ROM_R_SCL    I20 @T6G_MB_LIB.T6G(SCH_1):PAGE377

R840 Q_RES_0201LF-1K,1%,1/20W,CHIP,CS21001FE07
     1 P1V8_CPU0_RT_1D @T6G_MB_LIB.T6G(SCH_1):P1V8_CPU0_RT_1D    I18 @T6G_MB_LIB.T6G(SCH_1):PAGE377
     2 SMB_RT_CPU0_P2_ROM_R_SDA @T6G_MB_LIB.T6G(SCH_1):SMB_RT_CPU0_P2_ROM_R_SDA    I18 @T6G_MB_LIB.T6G(SCH_1):PAGE377

R841 Q_RES_0201LF-1K,1%,1/20W,CHIP,CS21001FE07
     1 P1V8_CPU0_RT_1D @T6G_MB_LIB.T6G(SCH_1):P1V8_CPU0_RT_1D    I17 @T6G_MB_LIB.T6G(SCH_1):PAGE377
     2 SMB_RT_CPU0_P2_ROM_R_SCL @T6G_MB_LIB.T6G(SCH_1):SMB_RT_CPU0_P2_ROM_R_SCL    I17 @T6G_MB_LIB.T6G(SCH_1):PAGE377

R842 Q_RES_0201LF-4.7K,5%,1/20W,EMPTY,CS24701JE04
     1 P1V8_AUX @T6G_MB_LIB.T6G(SCH_1):P1V8_AUX     I4 @T6G_MB_LIB.T6G(SCH_1):PAGE377
     2 RT_ROM_SMB_MUX_ADDR2 @T6G_MB_LIB.T6G(SCH_1):RT_ROM_SMB_MUX_ADDR2     I4 @T6G_MB_LIB.T6G(SCH_1):PAGE377

R843 Q_RES_0201LF-4.7K,5%,1/20W,EMPTY,CS24701JE04
     1 P1V8_AUX @T6G_MB_LIB.T6G(SCH_1):P1V8_AUX     I5 @T6G_MB_LIB.T6G(SCH_1):PAGE377
     2 RT_ROM_SMB_MUX_ADDR1 @T6G_MB_LIB.T6G(SCH_1):RT_ROM_SMB_MUX_ADDR1     I5 @T6G_MB_LIB.T6G(SCH_1):PAGE377

R844 Q_RES_0201LF-4.7K,5%,1/20W,EMPTY,CS24701JE04
     1 P1V8_AUX @T6G_MB_LIB.T6G(SCH_1):P1V8_AUX     I9 @T6G_MB_LIB.T6G(SCH_1):PAGE377
     2 RT_ROM_SMB_MUX_ADDR0 @T6G_MB_LIB.T6G(SCH_1):RT_ROM_SMB_MUX_ADDR0     I9 @T6G_MB_LIB.T6G(SCH_1):PAGE377

R845 Q_RES_0201LF-4.7K,5%,1/20W,CHIP,CS24701JE04
     1 RT_ROM_SMB_MUX_ADDR2 @T6G_MB_LIB.T6G(SCH_1):RT_ROM_SMB_MUX_ADDR2     I2 @T6G_MB_LIB.T6G(SCH_1):PAGE377
     2    GND @T6G_MB_LIB.T6G(SCH_1):GND     I2 @T6G_MB_LIB.T6G(SCH_1):PAGE377

R846 Q_RES_0201LF-4.7K,5%,1/20W,CHIP,CS24701JE04
     1 RT_ROM_SMB_MUX_ADDR1 @T6G_MB_LIB.T6G(SCH_1):RT_ROM_SMB_MUX_ADDR1     I3 @T6G_MB_LIB.T6G(SCH_1):PAGE377
     2    GND @T6G_MB_LIB.T6G(SCH_1):GND     I3 @T6G_MB_LIB.T6G(SCH_1):PAGE377

R847 Q_RES_0201LF-4.7K,5%,1/20W,CHIP,CS24701JE04
     1 RT_ROM_SMB_MUX_ADDR0 @T6G_MB_LIB.T6G(SCH_1):RT_ROM_SMB_MUX_ADDR0     I8 @T6G_MB_LIB.T6G(SCH_1):PAGE377
     2    GND @T6G_MB_LIB.T6G(SCH_1):GND     I8 @T6G_MB_LIB.T6G(SCH_1):PAGE377

R848 Q_RES_0201LF-0,5%,1/20W,CHIP,CS00001JE10
     1 RST_SMB_RT_ROM_R1_N @T6G_MB_LIB.T6G(SCH_1):RST_SMB_RT_ROM_R1_N    I42 @T6G_MB_LIB.T6G(SCH_1):PAGE377
     2 RST_SMB_RT_ROM_N @T6G_MB_LIB.T6G(SCH_1):RST_SMB_RT_ROM_N    I42 @T6G_MB_LIB.T6G(SCH_1):PAGE377

R849 Q_RES_0201LF-10K,1%,1/20W,CHIP,CS31001FE17
     1 RST_SMB_RT_ROM_R1_N @T6G_MB_LIB.T6G(SCH_1):RST_SMB_RT_ROM_R1_N    I16 @T6G_MB_LIB.T6G(SCH_1):PAGE377
     2    GND @T6G_MB_LIB.T6G(SCH_1):GND    I16 @T6G_MB_LIB.T6G(SCH_1):PAGE377

R850 Q_RES_0201LF-0,5%,1/20W,CHIP,CS00001JE10
     1 SMB_MUX_RT_ROM_SDA @T6G_MB_LIB.T6G(SCH_1):SMB_MUX_RT_ROM_SDA    I81 @T6G_MB_LIB.T6G(SCH_1):PAGE377
     2 SMB_MUX_RT_ROM_R1_SDA @T6G_MB_LIB.T6G(SCH_1):SMB_MUX_RT_ROM_R1_SDA    I81 @T6G_MB_LIB.T6G(SCH_1):PAGE377

R851 Q_RES_0201LF-0,5%,1/20W,CHIP,CS00001JE10
     1 SMB_MUX_RT_ROM_SCL @T6G_MB_LIB.T6G(SCH_1):SMB_MUX_RT_ROM_SCL    I82 @T6G_MB_LIB.T6G(SCH_1):PAGE377
     2 SMB_MUX_RT_ROM_R1_SCL @T6G_MB_LIB.T6G(SCH_1):SMB_MUX_RT_ROM_R1_SCL    I82 @T6G_MB_LIB.T6G(SCH_1):PAGE377

R852 Q_RES_0402LF-0,5%,1/16W,EMPTY,CS00002JB13
     1 P1V8_CPU1_RT2_1A_1D @T6G_MB_LIB.T6G(SCH_1):P1V8_CPU1_RT2_1A_1D     I2 @T6G_MB_LIB.T6G(SCH_1):PAGE454
     2 P1V8_CPU1_RT2_1A @T6G_MB_LIB.T6G(SCH_1):P1V8_CPU1_RT2_1A     I2 @T6G_MB_LIB.T6G(SCH_1):PAGE454

R853 Q_RES_0402LF-0,5%,1/16W,EMPTY,CS00002JB13
     1 P1V8_CPU1_RT2_1A_1D @T6G_MB_LIB.T6G(SCH_1):P1V8_CPU1_RT2_1A_1D     I3 @T6G_MB_LIB.T6G(SCH_1):PAGE454
     2 P1V8_CPU1_RT2_1A @T6G_MB_LIB.T6G(SCH_1):P1V8_CPU1_RT2_1A     I3 @T6G_MB_LIB.T6G(SCH_1):PAGE454

R854 Q_RES_0201LF-0,5%,1/20W,CHIP,CS00001JE10
     1 RST_RT_CPU1_P2_PERST_N @T6G_MB_LIB.T6G(SCH_1):RST_RT_CPU1_P2_PERST_N    I63 @T6G_MB_LIB.T6G(SCH_1):PAGE451
     2 RST_RT_CPU1_P2_PERST_R_N @T6G_MB_LIB.T6G(SCH_1):RST_RT_CPU1_P2_PERST_R_N    I63 @T6G_MB_LIB.T6G(SCH_1):PAGE451

R855 Q_RES_0402LF-11.5K,1%,1/16W,EMPTY,CS31152FB03
     1 P12V_AUX_DSC_VOL @T6G_MB_LIB.T6G(SCH_1):P12V_AUX_DSC_VOL     I3 @T6G_MB_LIB.T6G(SCH_1):PAGE146
     2    GND @T6G_MB_LIB.T6G(SCH_1):GND     I3 @T6G_MB_LIB.T6G(SCH_1):PAGE146

R856 Q_RES_0402LF-0,5%,1/16W,CHIP,CS00002JB13
     1 FM_HDT_HDR_RESET_N @T6G_MB_LIB.T6G(SCH_1):FM_HDT_HDR_RESET_N   I167 @T6G_MB_LIB.T6G(SCH_1):PAGE80
     2 HDT_HDR_RESET_N @T6G_MB_LIB.T6G(SCH_1):HDT_HDR_RESET_N   I167 @T6G_MB_LIB.T6G(SCH_1):PAGE80

R857 Q_RES_0402LF-0,5%,1/16W,EMPTY,CS00002JB13
     1 P1V8_CPU1_RT_1D @T6G_MB_LIB.T6G(SCH_1):P1V8_CPU1_RT_1D    I89 @T6G_MB_LIB.T6G(SCH_1):PAGE454
     2 P1V8_CPU1_RT2_1A_1D @T6G_MB_LIB.T6G(SCH_1):P1V8_CPU1_RT2_1A_1D    I89 @T6G_MB_LIB.T6G(SCH_1):PAGE454

R858 Q_RES_0603LF-0,5%,1/4W,EMPTY,CS00006J900
     1 P0V9_CPU1_RT_2D @T6G_MB_LIB.T6G(SCH_1):P0V9_CPU1_RT_2D    I20 @T6G_MB_LIB.T6G(SCH_1):PAGE454
     2 P0V9_CPU1_RT2_2A_2D @T6G_MB_LIB.T6G(SCH_1):P0V9_CPU1_RT2_2A_2D    I20 @T6G_MB_LIB.T6G(SCH_1):PAGE454

R859 Q_RES_0603LF-0,5%,1/4W,CHIP,CS00006J900
     1 P0V9_CPU1_RT2_2A_2D @T6G_MB_LIB.T6G(SCH_1):P0V9_CPU1_RT2_2A_2D    I41 @T6G_MB_LIB.T6G(SCH_1):PAGE454
     2 P0V9_CPU1_RT2_2A @T6G_MB_LIB.T6G(SCH_1):P0V9_CPU1_RT2_2A    I41 @T6G_MB_LIB.T6G(SCH_1):PAGE454

R860 Q_RES_0201LF-0,5%,1/20W,CHIP,CS00001JE10
     1 RST_RT_CPU1_P2_RESET_N @T6G_MB_LIB.T6G(SCH_1):RST_RT_CPU1_P2_RESET_N    I62 @T6G_MB_LIB.T6G(SCH_1):PAGE451
     2 RST_RT_CPU1_P2_RESET_R_N @T6G_MB_LIB.T6G(SCH_1):RST_RT_CPU1_P2_RESET_R_N    I62 @T6G_MB_LIB.T6G(SCH_1):PAGE451

R861 Q_RES_0201LF-1K,1%,1/20W,CHIP,CS21001FE07
     1 P1V8_CPU1_RT_1D @T6G_MB_LIB.T6G(SCH_1):P1V8_CPU1_RT_1D    I74 @T6G_MB_LIB.T6G(SCH_1):PAGE451
     2 RT_CPU1_P2_ADDR3 @T6G_MB_LIB.T6G(SCH_1):RT_CPU1_P2_ADDR3    I74 @T6G_MB_LIB.T6G(SCH_1):PAGE451

R862 Q_RES_0402LF-0,5%,1/16W,CHIP,CS00002JB13
     1 CPU1_XTRIG_R2_L6 @T6G_MB_LIB.T6G(SCH_1):CPU1_XTRIG_R2_L6   I364 @T6G_MB_LIB.T6G(SCH_1):PAGE54
     2 CPU1_XTRIG_L6 @T6G_MB_LIB.T6G(SCH_1):CPU1_XTRIG_L6   I364 @T6G_MB_LIB.T6G(SCH_1):PAGE54

R863 Q_RES_0201LF-1K,1%,1/20W,EMPTY,CS21001FE07
     1 RT_CPU1_P2_ADDR3 @T6G_MB_LIB.T6G(SCH_1):RT_CPU1_P2_ADDR3    I71 @T6G_MB_LIB.T6G(SCH_1):PAGE451
     2    GND @T6G_MB_LIB.T6G(SCH_1):GND    I71 @T6G_MB_LIB.T6G(SCH_1):PAGE451

R864 Q_RES_0201LF-1K,1%,1/20W,EMPTY,CS21001FE07
     1 P1V8_CPU1_RT_1D @T6G_MB_LIB.T6G(SCH_1):P1V8_CPU1_RT_1D    I75 @T6G_MB_LIB.T6G(SCH_1):PAGE451
     2 RT_CPU1_P2_ADDR2 @T6G_MB_LIB.T6G(SCH_1):RT_CPU1_P2_ADDR2    I75 @T6G_MB_LIB.T6G(SCH_1):PAGE451

R865 Q_RES_0201LF-20K,1%,1/20W,CHIP,CS32001FE00
     1 RT_CPU1_P2_ADDR2 @T6G_MB_LIB.T6G(SCH_1):RT_CPU1_P2_ADDR2    I72 @T6G_MB_LIB.T6G(SCH_1):PAGE451
     2    GND @T6G_MB_LIB.T6G(SCH_1):GND    I72 @T6G_MB_LIB.T6G(SCH_1):PAGE451

R866 Q_RES_0201LF-10K,1%,1/20W,CHIP,CS31001FE17
     1 RST_RT_CPU1_P2_PERST_R_N @T6G_MB_LIB.T6G(SCH_1):RST_RT_CPU1_P2_PERST_R_N    I82 @T6G_MB_LIB.T6G(SCH_1):PAGE451
     2    GND @T6G_MB_LIB.T6G(SCH_1):GND    I82 @T6G_MB_LIB.T6G(SCH_1):PAGE451

R867 Q_RES_0201LF-10K,1%,1/20W,CHIP,CS31001FE17
     1 RST_RT_CPU1_P2_RESET_R_N @T6G_MB_LIB.T6G(SCH_1):RST_RT_CPU1_P2_RESET_R_N    I80 @T6G_MB_LIB.T6G(SCH_1):PAGE451
     2    GND @T6G_MB_LIB.T6G(SCH_1):GND    I80 @T6G_MB_LIB.T6G(SCH_1):PAGE451

R868 Q_RES_0201LF-4.7K,5%,1/20W,EMPTY,CS24701JE04
     1 P1V8_CPU1_RT_1D @T6G_MB_LIB.T6G(SCH_1):P1V8_CPU1_RT_1D    I17 @T6G_MB_LIB.T6G(SCH_1):PAGE451
     2 RT_CPU1_P2_SCAN_MODE @T6G_MB_LIB.T6G(SCH_1):RT_CPU1_P2_SCAN_MODE    I17 @T6G_MB_LIB.T6G(SCH_1):PAGE451

R869 Q_RES_0201LF-200,1%,1/20W,CHIP,CS12001FE12
     1 RT_CPU1_P2_SCAN_MODE @T6G_MB_LIB.T6G(SCH_1):RT_CPU1_P2_SCAN_MODE   I119 @T6G_MB_LIB.T6G(SCH_1):PAGE451
     2    GND @T6G_MB_LIB.T6G(SCH_1):GND   I119 @T6G_MB_LIB.T6G(SCH_1):PAGE451

R870 Q_RES_0201LF-4.7K,5%,1/20W,EMPTY,CS24701JE04
     1 P1V8_CPU1_RT_1D @T6G_MB_LIB.T6G(SCH_1):P1V8_CPU1_RT_1D    I86 @T6G_MB_LIB.T6G(SCH_1):PAGE451
     2 RST_RT_CPU1_P2_RESET_R_N @T6G_MB_LIB.T6G(SCH_1):RST_RT_CPU1_P2_RESET_R_N    I86 @T6G_MB_LIB.T6G(SCH_1):PAGE451

R871 Q_RES_0201LF-4.7K,5%,1/20W,EMPTY,CS24701JE04
     1 P1V8_CPU1_RT_1D @T6G_MB_LIB.T6G(SCH_1):P1V8_CPU1_RT_1D    I50 @T6G_MB_LIB.T6G(SCH_1):PAGE451
     2 JTAG_TEST_MODE_RT_CPU1_P2 @T6G_MB_LIB.T6G(SCH_1):JTAG_TEST_MODE_RT_CPU1_P2    I50 @T6G_MB_LIB.T6G(SCH_1):PAGE451

R872 Q_RES_0201LF-0,5%,1/20W,CHIP,CS00001JE10
     1 SMB_RT_CPU1_P2_R_SCL @T6G_MB_LIB.T6G(SCH_1):SMB_RT_CPU1_P2_R_SCL    I34 @T6G_MB_LIB.T6G(SCH_1):PAGE451
     2 SMB_RT_CPU1_P2_R2_SCL @T6G_MB_LIB.T6G(SCH_1):SMB_RT_CPU1_P2_R2_SCL    I34 @T6G_MB_LIB.T6G(SCH_1):PAGE451

R873 Q_RES_0201LF-0,5%,1/20W,CHIP,CS00001JE10
     1 SMB_RT_CPU1_P2_R_SDA @T6G_MB_LIB.T6G(SCH_1):SMB_RT_CPU1_P2_R_SDA    I35 @T6G_MB_LIB.T6G(SCH_1):PAGE451
     2 SMB_RT_CPU1_P2_R2_SDA @T6G_MB_LIB.T6G(SCH_1):SMB_RT_CPU1_P2_R2_SDA    I35 @T6G_MB_LIB.T6G(SCH_1):PAGE451

R874 Q_RES_0201LF-4.7K,5%,1/20W,EMPTY,CS24701JE04
     1 P1V8_CPU1_RT_1D @T6G_MB_LIB.T6G(SCH_1):P1V8_CPU1_RT_1D    I21 @T6G_MB_LIB.T6G(SCH_1):PAGE451
     2 GPIO2_RT_CPU1_P2 @T6G_MB_LIB.T6G(SCH_1):GPIO2_RT_CPU1_P2    I21 @T6G_MB_LIB.T6G(SCH_1):PAGE451

R875 Q_RES_0201LF-10K,1%,1/20W,CHIP,CS31001FE17
     1 GPIO2_RT_CPU1_P2 @T6G_MB_LIB.T6G(SCH_1):GPIO2_RT_CPU1_P2    I19 @T6G_MB_LIB.T6G(SCH_1):PAGE451
     2    GND @T6G_MB_LIB.T6G(SCH_1):GND    I19 @T6G_MB_LIB.T6G(SCH_1):PAGE451

R876 Q_RES_0201LF-10K,1%,1/20W,CHIP,CS31001FE17
     1 GPIO3_RT_CPU1_P2 @T6G_MB_LIB.T6G(SCH_1):GPIO3_RT_CPU1_P2    I20 @T6G_MB_LIB.T6G(SCH_1):PAGE451
     2    GND @T6G_MB_LIB.T6G(SCH_1):GND    I20 @T6G_MB_LIB.T6G(SCH_1):PAGE451

R877 Q_RES_0402LF-0,5%,1/16W,CHIP,CS00002JB13
     1 RST_PERST_OCP_SFF_BUF2_N @T6G_MB_LIB.T6G(SCH_1):RST_PERST_OCP_SFF_BUF2_N    I79 @T6G_MB_LIB.T6G(SCH_1):PAGE337
     2 RST_PERST0_OCP_SFF_N @T6G_MB_LIB.T6G(SCH_1):RST_PERST0_OCP_SFF_N    I79 @T6G_MB_LIB.T6G(SCH_1):PAGE337

R878 Q_RES_0201LF-4.7K,5%,1/20W,EMPTY,CS24701JE04
     1 P1V8_CPU1_RT_1D @T6G_MB_LIB.T6G(SCH_1):P1V8_CPU1_RT_1D    I47 @T6G_MB_LIB.T6G(SCH_1):PAGE451
     2 TEST0_RT_CPU1_P2 @T6G_MB_LIB.T6G(SCH_1):TEST0_RT_CPU1_P2    I47 @T6G_MB_LIB.T6G(SCH_1):PAGE451

R879 Q_RES_0201LF-4.7K,5%,1/20W,CHIP,CS24701JE04
     1 TEST0_RT_CPU1_P2 @T6G_MB_LIB.T6G(SCH_1):TEST0_RT_CPU1_P2    I42 @T6G_MB_LIB.T6G(SCH_1):PAGE451
     2    GND @T6G_MB_LIB.T6G(SCH_1):GND    I42 @T6G_MB_LIB.T6G(SCH_1):PAGE451

R880 Q_RES_0201LF-4.7K,5%,1/20W,EMPTY,CS24701JE04
     1 P1V8_CPU1_RT_1D @T6G_MB_LIB.T6G(SCH_1):P1V8_CPU1_RT_1D    I48 @T6G_MB_LIB.T6G(SCH_1):PAGE451
     2 TEST1_RT_CPU1_P2 @T6G_MB_LIB.T6G(SCH_1):TEST1_RT_CPU1_P2    I48 @T6G_MB_LIB.T6G(SCH_1):PAGE451

R881 Q_RES_0201LF-4.7K,5%,1/20W,CHIP,CS24701JE04
     1 TEST1_RT_CPU1_P2 @T6G_MB_LIB.T6G(SCH_1):TEST1_RT_CPU1_P2    I43 @T6G_MB_LIB.T6G(SCH_1):PAGE451
     2    GND @T6G_MB_LIB.T6G(SCH_1):GND    I43 @T6G_MB_LIB.T6G(SCH_1):PAGE451

R882 Q_RES_0201LF-4.7K,5%,1/20W,EMPTY,CS24701JE04
     1 P1V8_CPU1_RT_1D @T6G_MB_LIB.T6G(SCH_1):P1V8_CPU1_RT_1D    I49 @T6G_MB_LIB.T6G(SCH_1):PAGE451
     2 TEST2_RT_CPU1_P2 @T6G_MB_LIB.T6G(SCH_1):TEST2_RT_CPU1_P2    I49 @T6G_MB_LIB.T6G(SCH_1):PAGE451

R883 Q_RES_0201LF-4.7K,5%,1/20W,CHIP,CS24701JE04
     1 TEST2_RT_CPU1_P2 @T6G_MB_LIB.T6G(SCH_1):TEST2_RT_CPU1_P2    I45 @T6G_MB_LIB.T6G(SCH_1):PAGE451
     2    GND @T6G_MB_LIB.T6G(SCH_1):GND    I45 @T6G_MB_LIB.T6G(SCH_1):PAGE451

R884 Q_RES_0201LF-4.7K,5%,1/20W,CHIP,CS24701JE04
     1 JTAG_TEST_MODE_RT_CPU1_P2 @T6G_MB_LIB.T6G(SCH_1):JTAG_TEST_MODE_RT_CPU1_P2    I46 @T6G_MB_LIB.T6G(SCH_1):PAGE451
     2    GND @T6G_MB_LIB.T6G(SCH_1):GND    I46 @T6G_MB_LIB.T6G(SCH_1):PAGE451

R885 Q_RES_0201LF-4.7K,5%,1/20W,CHIP,CS24701JE04
     1 P1V8_CPU1_RT_1D @T6G_MB_LIB.T6G(SCH_1):P1V8_CPU1_RT_1D    I59 @T6G_MB_LIB.T6G(SCH_1):PAGE451
     2 MODE_RT_CPU1_P2 @T6G_MB_LIB.T6G(SCH_1):MODE_RT_CPU1_P2    I59 @T6G_MB_LIB.T6G(SCH_1):PAGE451

R886 Q_RES_0201LF-4.7K,5%,1/20W,EMPTY,CS24701JE04
     1 MODE_RT_CPU1_P2 @T6G_MB_LIB.T6G(SCH_1):MODE_RT_CPU1_P2    I58 @T6G_MB_LIB.T6G(SCH_1):PAGE451
     2    GND @T6G_MB_LIB.T6G(SCH_1):GND    I58 @T6G_MB_LIB.T6G(SCH_1):PAGE451

R887 Q_RES_0201LF-1K,1%,1/20W,EMPTY,CS21001FE07
     1 P1V8_CPU1_RT_1D @T6G_MB_LIB.T6G(SCH_1):P1V8_CPU1_RT_1D    I77 @T6G_MB_LIB.T6G(SCH_1):PAGE451
     2 RT_CPU1_P2_ADDR1 @T6G_MB_LIB.T6G(SCH_1):RT_CPU1_P2_ADDR1    I77 @T6G_MB_LIB.T6G(SCH_1):PAGE451

R888 Q_RES_0402LF-10K,5%,1/16W,EMPTY,CS31002JB08
     1 P3V3_AUX @T6G_MB_LIB.T6G(SCH_1):P3V3_AUX   I145 @T6G_MB_LIB.T6G(SCH_1):PAGE349
     2 SCM_SPARE_0 @T6G_MB_LIB.T6G(SCH_1):SCM_SPARE_0   I145 @T6G_MB_LIB.T6G(SCH_1):PAGE349

R889 Q_RES_0402LF-10K,5%,1/16W,EMPTY,CS31002JB08
     1 SCM_SPARE_0 @T6G_MB_LIB.T6G(SCH_1):SCM_SPARE_0   I142 @T6G_MB_LIB.T6G(SCH_1):PAGE349
     2    GND @T6G_MB_LIB.T6G(SCH_1):GND   I142 @T6G_MB_LIB.T6G(SCH_1):PAGE349

R890 Q_RES_0402LF-10K,5%,1/16W,EMPTY,CS31002JB08
     1 P3V3_AUX @T6G_MB_LIB.T6G(SCH_1):P3V3_AUX   I147 @T6G_MB_LIB.T6G(SCH_1):PAGE349
     2 SCM_SPARE_1 @T6G_MB_LIB.T6G(SCH_1):SCM_SPARE_1   I147 @T6G_MB_LIB.T6G(SCH_1):PAGE349

R891 Q_RES_0402LF-10K,5%,1/16W,EMPTY,CS31002JB08
     1 SCM_SPARE_1 @T6G_MB_LIB.T6G(SCH_1):SCM_SPARE_1   I144 @T6G_MB_LIB.T6G(SCH_1):PAGE349
     2    GND @T6G_MB_LIB.T6G(SCH_1):GND   I144 @T6G_MB_LIB.T6G(SCH_1):PAGE349

R892 Q_RES_0201LF-1K,1%,1/20W,CHIP,CS21001FE07
     1 RT_CPU1_P2_ADDR1 @T6G_MB_LIB.T6G(SCH_1):RT_CPU1_P2_ADDR1    I76 @T6G_MB_LIB.T6G(SCH_1):PAGE451
     2    GND @T6G_MB_LIB.T6G(SCH_1):GND    I76 @T6G_MB_LIB.T6G(SCH_1):PAGE451

R893 Q_RES_0402LF-0,5%,1/16W,EMPTY,CS00002JB13
     1 P1V8_CPU1_RT3_1A_1D @T6G_MB_LIB.T6G(SCH_1):P1V8_CPU1_RT3_1A_1D     I2 @T6G_MB_LIB.T6G(SCH_1):PAGE465
     2 P1V8_CPU1_RT3_1A @T6G_MB_LIB.T6G(SCH_1):P1V8_CPU1_RT3_1A     I2 @T6G_MB_LIB.T6G(SCH_1):PAGE465

R894 Q_RES_0402LF-0,5%,1/16W,EMPTY,CS00002JB13
     1 P1V8_CPU1_RT3_1A_1D @T6G_MB_LIB.T6G(SCH_1):P1V8_CPU1_RT3_1A_1D     I1 @T6G_MB_LIB.T6G(SCH_1):PAGE465
     2 P1V8_CPU1_RT3_1A @T6G_MB_LIB.T6G(SCH_1):P1V8_CPU1_RT3_1A     I1 @T6G_MB_LIB.T6G(SCH_1):PAGE465

R895 Q_RES_0201LF-0,5%,1/20W,CHIP,CS00001JE10
     1 RST_RT_CPU1_P3_PERST_N @T6G_MB_LIB.T6G(SCH_1):RST_RT_CPU1_P3_PERST_N    I69 @T6G_MB_LIB.T6G(SCH_1):PAGE462
     2 RST_RT_CPU1_P3_PERST_R_N @T6G_MB_LIB.T6G(SCH_1):RST_RT_CPU1_P3_PERST_R_N    I69 @T6G_MB_LIB.T6G(SCH_1):PAGE462

R896 Q_RES_0402LF-30K,1%,1/16W,EMPTY,CS33002FB02
     1 P12V_AUX @T6G_MB_LIB.T6G(SCH_1):P12V_AUX    I35 @T6G_MB_LIB.T6G(SCH_1):PAGE146
     2 P3V3_AUX_DSC_VOL @T6G_MB_LIB.T6G(SCH_1):P3V3_AUX_DSC_VOL    I35 @T6G_MB_LIB.T6G(SCH_1):PAGE146

R897 Q_RES_0402LF-0,5%,1/16W,EMPTY,CS00002JB13
     1 P1V8_CPU1_RT_1D @T6G_MB_LIB.T6G(SCH_1):P1V8_CPU1_RT_1D    I89 @T6G_MB_LIB.T6G(SCH_1):PAGE465
     2 P1V8_CPU1_RT3_1A_1D @T6G_MB_LIB.T6G(SCH_1):P1V8_CPU1_RT3_1A_1D    I89 @T6G_MB_LIB.T6G(SCH_1):PAGE465

R898 Q_RES_0603LF-0,5%,1/4W,EMPTY,CS00006J900
     1 P0V9_CPU1_RT_2D @T6G_MB_LIB.T6G(SCH_1):P0V9_CPU1_RT_2D     I8 @T6G_MB_LIB.T6G(SCH_1):PAGE465
     2 P0V9_CPU1_RT3_2A_2D @T6G_MB_LIB.T6G(SCH_1):P0V9_CPU1_RT3_2A_2D     I8 @T6G_MB_LIB.T6G(SCH_1):PAGE465

R899 Q_RES_0402LF-0,5%,1/16W,CHIP,CS00002JB13
     1 RST_PERST_OCP_SFF_BUF2_N @T6G_MB_LIB.T6G(SCH_1):RST_PERST_OCP_SFF_BUF2_N    I78 @T6G_MB_LIB.T6G(SCH_1):PAGE337
     2 RST_PERST1_OCP_SFF_N @T6G_MB_LIB.T6G(SCH_1):RST_PERST1_OCP_SFF_N    I78 @T6G_MB_LIB.T6G(SCH_1):PAGE337

R900 Q_RES_0603LF-0,5%,1/4W,CHIP,CS00006J900
     1 P0V9_CPU1_RT3_2A_2D @T6G_MB_LIB.T6G(SCH_1):P0V9_CPU1_RT3_2A_2D    I36 @T6G_MB_LIB.T6G(SCH_1):PAGE465
     2 P0V9_CPU1_RT3_2A @T6G_MB_LIB.T6G(SCH_1):P0V9_CPU1_RT3_2A    I36 @T6G_MB_LIB.T6G(SCH_1):PAGE465

R901 Q_RES_0201LF-0,5%,1/20W,CHIP,CS00001JE10
     1 RST_RT_CPU1_P3_RESET_N @T6G_MB_LIB.T6G(SCH_1):RST_RT_CPU1_P3_RESET_N    I70 @T6G_MB_LIB.T6G(SCH_1):PAGE462
     2 RST_RT_CPU1_P3_RESET_R_N @T6G_MB_LIB.T6G(SCH_1):RST_RT_CPU1_P3_RESET_R_N    I70 @T6G_MB_LIB.T6G(SCH_1):PAGE462

R902 Q_RES_0201LF-1K,1%,1/20W,CHIP,CS21001FE07
     1 P1V8_CPU1_RT_1D @T6G_MB_LIB.T6G(SCH_1):P1V8_CPU1_RT_1D    I80 @T6G_MB_LIB.T6G(SCH_1):PAGE462
     2 RT_CPU1_P3_ADDR3 @T6G_MB_LIB.T6G(SCH_1):RT_CPU1_P3_ADDR3    I80 @T6G_MB_LIB.T6G(SCH_1):PAGE462

R903 Q_RES_0201LF-1K,1%,1/20W,EMPTY,CS21001FE07
     1 RT_CPU1_P3_ADDR3 @T6G_MB_LIB.T6G(SCH_1):RT_CPU1_P3_ADDR3    I79 @T6G_MB_LIB.T6G(SCH_1):PAGE462
     2    GND @T6G_MB_LIB.T6G(SCH_1):GND    I79 @T6G_MB_LIB.T6G(SCH_1):PAGE462

R904 Q_RES_0201LF-1K,1%,1/20W,EMPTY,CS21001FE07
     1 P1V8_CPU1_RT_1D @T6G_MB_LIB.T6G(SCH_1):P1V8_CPU1_RT_1D    I82 @T6G_MB_LIB.T6G(SCH_1):PAGE462
     2 RT_CPU1_P3_ADDR2 @T6G_MB_LIB.T6G(SCH_1):RT_CPU1_P3_ADDR2    I82 @T6G_MB_LIB.T6G(SCH_1):PAGE462

R905 Q_RES_0402LF-0,5%,1/16W,CHIP,CS00002JB13
     1 RST_PERST_OCP_SFF_BUF2_N @T6G_MB_LIB.T6G(SCH_1):RST_PERST_OCP_SFF_BUF2_N    I80 @T6G_MB_LIB.T6G(SCH_1):PAGE337
     2 RST_PERST2_OCP_SFF_N @T6G_MB_LIB.T6G(SCH_1):RST_PERST2_OCP_SFF_N    I80 @T6G_MB_LIB.T6G(SCH_1):PAGE337

R906 Q_RES_0201LF-20K,1%,1/20W,CHIP,CS32001FE00
     1 RT_CPU1_P3_ADDR2 @T6G_MB_LIB.T6G(SCH_1):RT_CPU1_P3_ADDR2    I81 @T6G_MB_LIB.T6G(SCH_1):PAGE462
     2    GND @T6G_MB_LIB.T6G(SCH_1):GND    I81 @T6G_MB_LIB.T6G(SCH_1):PAGE462

R907 Q_RES_0201LF-10K,1%,1/20W,CHIP,CS31001FE17
     1 RST_RT_CPU1_P3_PERST_R_N @T6G_MB_LIB.T6G(SCH_1):RST_RT_CPU1_P3_PERST_R_N    I92 @T6G_MB_LIB.T6G(SCH_1):PAGE462
     2    GND @T6G_MB_LIB.T6G(SCH_1):GND    I92 @T6G_MB_LIB.T6G(SCH_1):PAGE462

R908 Q_RES_0201LF-10K,1%,1/20W,CHIP,CS31001FE17
     1 RST_RT_CPU1_P3_RESET_R_N @T6G_MB_LIB.T6G(SCH_1):RST_RT_CPU1_P3_RESET_R_N    I90 @T6G_MB_LIB.T6G(SCH_1):PAGE462
     2    GND @T6G_MB_LIB.T6G(SCH_1):GND    I90 @T6G_MB_LIB.T6G(SCH_1):PAGE462

R909 Q_RES_0201LF-4.7K,5%,1/20W,EMPTY,CS24701JE04
     1 P1V8_CPU1_RT_1D @T6G_MB_LIB.T6G(SCH_1):P1V8_CPU1_RT_1D    I17 @T6G_MB_LIB.T6G(SCH_1):PAGE462
     2 RT_CPU1_P3_SCAN_MODE @T6G_MB_LIB.T6G(SCH_1):RT_CPU1_P3_SCAN_MODE    I17 @T6G_MB_LIB.T6G(SCH_1):PAGE462

R910 Q_RES_0201LF-200,1%,1/20W,CHIP,CS12001FE12
     1 RT_CPU1_P3_SCAN_MODE @T6G_MB_LIB.T6G(SCH_1):RT_CPU1_P3_SCAN_MODE   I119 @T6G_MB_LIB.T6G(SCH_1):PAGE462
     2    GND @T6G_MB_LIB.T6G(SCH_1):GND   I119 @T6G_MB_LIB.T6G(SCH_1):PAGE462

R911 Q_RES_0201LF-4.7K,5%,1/20W,EMPTY,CS24701JE04
     1 P1V8_CPU1_RT_1D @T6G_MB_LIB.T6G(SCH_1):P1V8_CPU1_RT_1D    I93 @T6G_MB_LIB.T6G(SCH_1):PAGE462
     2 RST_RT_CPU1_P3_RESET_R_N @T6G_MB_LIB.T6G(SCH_1):RST_RT_CPU1_P3_RESET_R_N    I93 @T6G_MB_LIB.T6G(SCH_1):PAGE462

R912 Q_RES_0201LF-4.7K,5%,1/20W,EMPTY,CS24701JE04
     1 P1V8_CPU1_RT_1D @T6G_MB_LIB.T6G(SCH_1):P1V8_CPU1_RT_1D    I56 @T6G_MB_LIB.T6G(SCH_1):PAGE462
     2 JTAG_TEST_MODE_RT_CPU1_P3 @T6G_MB_LIB.T6G(SCH_1):JTAG_TEST_MODE_RT_CPU1_P3    I56 @T6G_MB_LIB.T6G(SCH_1):PAGE462

R913 Q_RES_0201LF-0,5%,1/20W,CHIP,CS00001JE10
     1 SMB_RT_CPU1_P3_R_SCL @T6G_MB_LIB.T6G(SCH_1):SMB_RT_CPU1_P3_R_SCL    I42 @T6G_MB_LIB.T6G(SCH_1):PAGE462
     2 SMB_RT_CPU1_P3_R2_SCL @T6G_MB_LIB.T6G(SCH_1):SMB_RT_CPU1_P3_R2_SCL    I42 @T6G_MB_LIB.T6G(SCH_1):PAGE462

R914 Q_RES_0201LF-0,5%,1/20W,CHIP,CS00001JE10
     1 SMB_RT_CPU1_P3_R_SDA @T6G_MB_LIB.T6G(SCH_1):SMB_RT_CPU1_P3_R_SDA    I41 @T6G_MB_LIB.T6G(SCH_1):PAGE462
     2 SMB_RT_CPU1_P3_R2_SDA @T6G_MB_LIB.T6G(SCH_1):SMB_RT_CPU1_P3_R2_SDA    I41 @T6G_MB_LIB.T6G(SCH_1):PAGE462

R915 Q_RES_0201LF-4.7K,5%,1/20W,EMPTY,CS24701JE04
     1 P1V8_CPU1_RT_1D @T6G_MB_LIB.T6G(SCH_1):P1V8_CPU1_RT_1D    I22 @T6G_MB_LIB.T6G(SCH_1):PAGE462
     2 GPIO2_RT_CPU1_P3 @T6G_MB_LIB.T6G(SCH_1):GPIO2_RT_CPU1_P3    I22 @T6G_MB_LIB.T6G(SCH_1):PAGE462

R916 Q_RES_0201LF-10K,1%,1/20W,CHIP,CS31001FE17
     1 GPIO2_RT_CPU1_P3 @T6G_MB_LIB.T6G(SCH_1):GPIO2_RT_CPU1_P3    I19 @T6G_MB_LIB.T6G(SCH_1):PAGE462
     2    GND @T6G_MB_LIB.T6G(SCH_1):GND    I19 @T6G_MB_LIB.T6G(SCH_1):PAGE462

R917 Q_RES_0201LF-10K,1%,1/20W,CHIP,CS31001FE17
     1 GPIO3_RT_CPU1_P3 @T6G_MB_LIB.T6G(SCH_1):GPIO3_RT_CPU1_P3    I20 @T6G_MB_LIB.T6G(SCH_1):PAGE462
     2    GND @T6G_MB_LIB.T6G(SCH_1):GND    I20 @T6G_MB_LIB.T6G(SCH_1):PAGE462

R918 Q_RES_0201LF-4.7K,5%,1/20W,EMPTY,CS24701JE04
     1 P1V8_CPU1_RT_1D @T6G_MB_LIB.T6G(SCH_1):P1V8_CPU1_RT_1D    I23 @T6G_MB_LIB.T6G(SCH_1):PAGE462
     2 TEST0_RT_CPU1_P3 @T6G_MB_LIB.T6G(SCH_1):TEST0_RT_CPU1_P3    I23 @T6G_MB_LIB.T6G(SCH_1):PAGE462

R919 Q_RES_0201LF-4.7K,5%,1/20W,CHIP,CS24701JE04
     1 TEST0_RT_CPU1_P3 @T6G_MB_LIB.T6G(SCH_1):TEST0_RT_CPU1_P3    I21 @T6G_MB_LIB.T6G(SCH_1):PAGE462
     2    GND @T6G_MB_LIB.T6G(SCH_1):GND    I21 @T6G_MB_LIB.T6G(SCH_1):PAGE462

R920 Q_RES_0201LF-4.7K,5%,1/20W,EMPTY,CS24701JE04
     1 P1V8_CPU1_RT_1D @T6G_MB_LIB.T6G(SCH_1):P1V8_CPU1_RT_1D    I54 @T6G_MB_LIB.T6G(SCH_1):PAGE462
     2 TEST1_RT_CPU1_P3 @T6G_MB_LIB.T6G(SCH_1):TEST1_RT_CPU1_P3    I54 @T6G_MB_LIB.T6G(SCH_1):PAGE462

R921 Q_RES_0201LF-4.7K,5%,1/20W,CHIP,CS24701JE04
     1 TEST1_RT_CPU1_P3 @T6G_MB_LIB.T6G(SCH_1):TEST1_RT_CPU1_P3    I50 @T6G_MB_LIB.T6G(SCH_1):PAGE462
     2    GND @T6G_MB_LIB.T6G(SCH_1):GND    I50 @T6G_MB_LIB.T6G(SCH_1):PAGE462

R922 Q_RES_0201LF-4.7K,5%,1/20W,EMPTY,CS24701JE04
     1 P1V8_CPU1_RT_1D @T6G_MB_LIB.T6G(SCH_1):P1V8_CPU1_RT_1D    I55 @T6G_MB_LIB.T6G(SCH_1):PAGE462
     2 TEST2_RT_CPU1_P3 @T6G_MB_LIB.T6G(SCH_1):TEST2_RT_CPU1_P3    I55 @T6G_MB_LIB.T6G(SCH_1):PAGE462

R923 Q_RES_0201LF-4.7K,5%,1/20W,CHIP,CS24701JE04
     1 TEST2_RT_CPU1_P3 @T6G_MB_LIB.T6G(SCH_1):TEST2_RT_CPU1_P3    I51 @T6G_MB_LIB.T6G(SCH_1):PAGE462
     2    GND @T6G_MB_LIB.T6G(SCH_1):GND    I51 @T6G_MB_LIB.T6G(SCH_1):PAGE462

R924 Q_RES_0201LF-4.7K,5%,1/20W,CHIP,CS24701JE04
     1 JTAG_TEST_MODE_RT_CPU1_P3 @T6G_MB_LIB.T6G(SCH_1):JTAG_TEST_MODE_RT_CPU1_P3    I53 @T6G_MB_LIB.T6G(SCH_1):PAGE462
     2    GND @T6G_MB_LIB.T6G(SCH_1):GND    I53 @T6G_MB_LIB.T6G(SCH_1):PAGE462

R925 Q_RES_0201LF-4.7K,5%,1/20W,CHIP,CS24701JE04
     1 P1V8_CPU1_RT_1D @T6G_MB_LIB.T6G(SCH_1):P1V8_CPU1_RT_1D    I65 @T6G_MB_LIB.T6G(SCH_1):PAGE462
     2 MODE_RT_CPU1_P3 @T6G_MB_LIB.T6G(SCH_1):MODE_RT_CPU1_P3    I65 @T6G_MB_LIB.T6G(SCH_1):PAGE462

R926 Q_RES_0201LF-4.7K,5%,1/20W,EMPTY,CS24701JE04
     1 MODE_RT_CPU1_P3 @T6G_MB_LIB.T6G(SCH_1):MODE_RT_CPU1_P3    I64 @T6G_MB_LIB.T6G(SCH_1):PAGE462
     2    GND @T6G_MB_LIB.T6G(SCH_1):GND    I64 @T6G_MB_LIB.T6G(SCH_1):PAGE462

R927 Q_RES_0201LF-1K,1%,1/20W,EMPTY,CS21001FE07
     1 P1V8_CPU1_RT_1D @T6G_MB_LIB.T6G(SCH_1):P1V8_CPU1_RT_1D    I84 @T6G_MB_LIB.T6G(SCH_1):PAGE462
     2 RT_CPU1_P3_ADDR1 @T6G_MB_LIB.T6G(SCH_1):RT_CPU1_P3_ADDR1    I84 @T6G_MB_LIB.T6G(SCH_1):PAGE462

R928 Q_RES_0402LF-0,5%,1/16W,CHIP,CS00002JB13
     1 CPU1_XTRIG_R2_L7 @T6G_MB_LIB.T6G(SCH_1):CPU1_XTRIG_R2_L7   I363 @T6G_MB_LIB.T6G(SCH_1):PAGE54
     2 CPU1_XTRIG_L7 @T6G_MB_LIB.T6G(SCH_1):CPU1_XTRIG_L7   I363 @T6G_MB_LIB.T6G(SCH_1):PAGE54

R929 Q_RES_0402LF-0,5%,1/16W,CHIP,CS00002JB13
     1 CPU1_XTRIG_L4 @T6G_MB_LIB.T6G(SCH_1):CPU1_XTRIG_L4   I371 @T6G_MB_LIB.T6G(SCH_1):PAGE54
     2 CPU1_XTRIG_R1_L4 @T6G_MB_LIB.T6G(SCH_1):CPU1_XTRIG_R1_L4   I371 @T6G_MB_LIB.T6G(SCH_1):PAGE54

R930 Q_RES_0402LF-0,5%,1/16W,CHIP,CS00002JB13
     1 CPU1_XTRIG_L5 @T6G_MB_LIB.T6G(SCH_1):CPU1_XTRIG_L5   I372 @T6G_MB_LIB.T6G(SCH_1):PAGE54
     2 CPU1_XTRIG_R1_L5 @T6G_MB_LIB.T6G(SCH_1):CPU1_XTRIG_R1_L5   I372 @T6G_MB_LIB.T6G(SCH_1):PAGE54

R931 Q_RES_0402LF-0,5%,1/16W,CHIP,CS00002JB13
     1 CPU1_XTRIG_L6 @T6G_MB_LIB.T6G(SCH_1):CPU1_XTRIG_L6   I374 @T6G_MB_LIB.T6G(SCH_1):PAGE54
     2 CPU1_XTRIG_R1_L6 @T6G_MB_LIB.T6G(SCH_1):CPU1_XTRIG_R1_L6   I374 @T6G_MB_LIB.T6G(SCH_1):PAGE54

R932 Q_RES_0402LF-0,5%,1/16W,CHIP,CS00002JB13
     1 CPU1_XTRIG_L7 @T6G_MB_LIB.T6G(SCH_1):CPU1_XTRIG_L7   I373 @T6G_MB_LIB.T6G(SCH_1):PAGE54
     2 CPU1_XTRIG_R1_L7 @T6G_MB_LIB.T6G(SCH_1):CPU1_XTRIG_R1_L7   I373 @T6G_MB_LIB.T6G(SCH_1):PAGE54

R933 Q_RES_0402LF-33,5%,1/16W,CHIP,CS03302JB10
     1 FM_SMERR_LED_R_N @T6G_MB_LIB.T6G(SCH_1):FM_SMERR_LED_R_N   I215 @T6G_MB_LIB.T6G(SCH_1):PAGE80
     2 FM_SMERR_LED_N @T6G_MB_LIB.T6G(SCH_1):FM_SMERR_LED_N   I215 @T6G_MB_LIB.T6G(SCH_1):PAGE80

R934 Q_RES_0402LF-0,5%,1/16W,CHIP,CS00002JB13
     1 FM_BIOS_POST_CMPLT_N @T6G_MB_LIB.T6G(SCH_1):FM_BIOS_POST_CMPLT_N    I33 @T6G_MB_LIB.T6G(SCH_1):PAGE143
     2 BOOT_RDY_R1_N @T6G_MB_LIB.T6G(SCH_1):BOOT_RDY_R1_N    I33 @T6G_MB_LIB.T6G(SCH_1):PAGE143

R935 Q_RES_0402LF-0,5%,1/16W,CHIP,CS00002JB13
     1 BOOT_RDY_BUF_R_LED @T6G_MB_LIB.T6G(SCH_1):BOOT_RDY_BUF_R_LED    I21 @T6G_MB_LIB.T6G(SCH_1):PAGE143
     2 BOOT_RDY_BUF_LED @T6G_MB_LIB.T6G(SCH_1):BOOT_RDY_BUF_LED    I21 @T6G_MB_LIB.T6G(SCH_1):PAGE143

R936 Q_RES_0402LF-0,5%,1/16W,CHIP,CS00002JB13
     1 FM_SMERR_BUF_LED_N @T6G_MB_LIB.T6G(SCH_1):FM_SMERR_BUF_LED_N    I22 @T6G_MB_LIB.T6G(SCH_1):PAGE143
     2 FM_SMERR_BUF_R_LED_N @T6G_MB_LIB.T6G(SCH_1):FM_SMERR_BUF_R_LED_N    I22 @T6G_MB_LIB.T6G(SCH_1):PAGE143

R937 Q_RES_0402LF-0,5%,1/16W,CHIP,CS00002JB13
     1 FM_BIOS_POST_CMPLT_BUF_R_N @T6G_MB_LIB.T6G(SCH_1):FM_BIOS_POST_CMPLT_BUF_R_N   I166 @T6G_MB_LIB.T6G(SCH_1):PAGE80
     2 FM_BIOS_POST_CMPLT_BUF_N @T6G_MB_LIB.T6G(SCH_1):FM_BIOS_POST_CMPLT_BUF_N   I166 @T6G_MB_LIB.T6G(SCH_1):PAGE80

R938 Q_RES_0402LF-4.7K,5%,1/16W,CHIP,CS24702JB10
     1 BOOT_RDY_H @T6G_MB_LIB.T6G(SCH_1):BOOT_RDY_H    I69 @T6G_MB_LIB.T6G(SCH_1):PAGE28
     2 PVDD18_S5_P0 @T6G_MB_LIB.T6G(SCH_1):PVDD18_S5_P0    I69 @T6G_MB_LIB.T6G(SCH_1):PAGE28

R939 Q_RES_0402LF-0,5%,1/16W,CHIP,CS00002JB13
     1 FM_BIOS_POST_CMPLT_R_N @T6G_MB_LIB.T6G(SCH_1):FM_BIOS_POST_CMPLT_R_N    I93 @T6G_MB_LIB.T6G(SCH_1):PAGE28
     2 FM_BIOS_POST_CMPLT_N @T6G_MB_LIB.T6G(SCH_1):FM_BIOS_POST_CMPLT_N    I93 @T6G_MB_LIB.T6G(SCH_1):PAGE28

R940 Q_RES_0402LF-0,5%,1/16W,CHIP,CS00002JB13
     1 BOOT_RDY_R_H @T6G_MB_LIB.T6G(SCH_1):BOOT_RDY_R_H    I94 @T6G_MB_LIB.T6G(SCH_1):PAGE28
     2 BOOT_RDY_H @T6G_MB_LIB.T6G(SCH_1):BOOT_RDY_H    I94 @T6G_MB_LIB.T6G(SCH_1):PAGE28

R941 Q_RES_0402LF-0,5%,1/16W,EMPTY,CS00002JB13
     1 BOOT_RDY_H @T6G_MB_LIB.T6G(SCH_1):BOOT_RDY_H    I34 @T6G_MB_LIB.T6G(SCH_1):PAGE143
     2 BOOT_RDY_R1_N @T6G_MB_LIB.T6G(SCH_1):BOOT_RDY_R1_N    I34 @T6G_MB_LIB.T6G(SCH_1):PAGE143

R942 Q_RES_0402LF-4.7K,5%,1/16W,CHIP,CS24702JB10
     1 PVDD18_S5_P0 @T6G_MB_LIB.T6G(SCH_1):PVDD18_S5_P0    I60 @T6G_MB_LIB.T6G(SCH_1):PAGE34
     2 FM_BIOS_POST_CMPLT_N @T6G_MB_LIB.T6G(SCH_1):FM_BIOS_POST_CMPLT_N    I60 @T6G_MB_LIB.T6G(SCH_1):PAGE34

R943 Q_RES_0402LF-4.7K,5%,1/16W,CHIP,CS24702JB10
     1 P1V8_AUX @T6G_MB_LIB.T6G(SCH_1):P1V8_AUX    I53 @T6G_MB_LIB.T6G(SCH_1):PAGE34
     2 FM_BIOS_POST_CMPLT_BUF_R1_N @T6G_MB_LIB.T6G(SCH_1):FM_BIOS_POST_CMPLT_BUF_R1_N    I53 @T6G_MB_LIB.T6G(SCH_1):PAGE34

R944 Q_RES_0402LF-4.7K,5%,1/16W,CHIP,CS24702JB10
     1 P3V3_AUX @T6G_MB_LIB.T6G(SCH_1):P3V3_AUX    I15 @T6G_MB_LIB.T6G(SCH_1):PAGE143
     2 BOOT_RDY_BUF_LED @T6G_MB_LIB.T6G(SCH_1):BOOT_RDY_BUF_LED    I15 @T6G_MB_LIB.T6G(SCH_1):PAGE143

R945 Q_RES_0402LF-4.7K,5%,1/16W,CHIP,CS24702JB10
     1 P3V3_AUX @T6G_MB_LIB.T6G(SCH_1):P3V3_AUX    I18 @T6G_MB_LIB.T6G(SCH_1):PAGE143
     2 FM_SMERR_BUF_R_LED_N @T6G_MB_LIB.T6G(SCH_1):FM_SMERR_BUF_R_LED_N    I18 @T6G_MB_LIB.T6G(SCH_1):PAGE143

R946 Q_RES_0402LF-4.7K,5%,1/16W,CHIP,CS24702JB10
     1 P3V3_AUX @T6G_MB_LIB.T6G(SCH_1):P3V3_AUX     I5 @T6G_MB_LIB.T6G(SCH_1):PAGE143
     2 BOOT_RDY_LED @T6G_MB_LIB.T6G(SCH_1):BOOT_RDY_LED     I5 @T6G_MB_LIB.T6G(SCH_1):PAGE143

R947 Q_RES_0402LF-4.7K,5%,1/16W,CHIP,CS24702JB10
     1 P3V3_AUX @T6G_MB_LIB.T6G(SCH_1):P3V3_AUX    I11 @T6G_MB_LIB.T6G(SCH_1):PAGE143
     2 SMERR_LED @T6G_MB_LIB.T6G(SCH_1):SMERR_LED    I11 @T6G_MB_LIB.T6G(SCH_1):PAGE143

R948 Q_RES_0402LF-130,1%,1/16W,CHIP,CS11302FB03
     1 PU_BOOT_RDY_LED @T6G_MB_LIB.T6G(SCH_1):PU_BOOT_RDY_LED     I7 @T6G_MB_LIB.T6G(SCH_1):PAGE143
     2 P3V3_AUX @T6G_MB_LIB.T6G(SCH_1):P3V3_AUX     I7 @T6G_MB_LIB.T6G(SCH_1):PAGE143

R949 Q_RES_0201LF-1K,1%,1/20W,CHIP,CS21001FE07
     1 RT_CPU1_P3_ADDR1 @T6G_MB_LIB.T6G(SCH_1):RT_CPU1_P3_ADDR1    I83 @T6G_MB_LIB.T6G(SCH_1):PAGE462
     2    GND @T6G_MB_LIB.T6G(SCH_1):GND    I83 @T6G_MB_LIB.T6G(SCH_1):PAGE462

R950 Q_RES_0402LF-249,1%,1/16W,CHIP,CS12492FB02
     1 PU_SMERR_LED @T6G_MB_LIB.T6G(SCH_1):PU_SMERR_LED     I3 @T6G_MB_LIB.T6G(SCH_1):PAGE143
     2 P3V3_AUX @T6G_MB_LIB.T6G(SCH_1):P3V3_AUX     I3 @T6G_MB_LIB.T6G(SCH_1):PAGE143

R951 Q_RES_0402LF-0,5%,1/16W,EMPTY,CS00002JB13
     1 P1V8_CPU0_RT0_1A_1D @T6G_MB_LIB.T6G(SCH_1):P1V8_CPU0_RT0_1A_1D     I5 @T6G_MB_LIB.T6G(SCH_1):PAGE388
     2 P1V8_CPU0_RT0_1A @T6G_MB_LIB.T6G(SCH_1):P1V8_CPU0_RT0_1A     I5 @T6G_MB_LIB.T6G(SCH_1):PAGE388

R952 Q_RES_0402LF-0,5%,1/16W,EMPTY,CS00002JB13
     1 P1V8_CPU0_RT0_1A_1D @T6G_MB_LIB.T6G(SCH_1):P1V8_CPU0_RT0_1A_1D     I4 @T6G_MB_LIB.T6G(SCH_1):PAGE388
     2 P1V8_CPU0_RT0_1A @T6G_MB_LIB.T6G(SCH_1):P1V8_CPU0_RT0_1A     I4 @T6G_MB_LIB.T6G(SCH_1):PAGE388

R953 Q_RES_0201LF-0,5%,1/20W,CHIP,CS00001JE10
     1 RST_RT_CPU0_P0_PERST_N @T6G_MB_LIB.T6G(SCH_1):RST_RT_CPU0_P0_PERST_N    I76 @T6G_MB_LIB.T6G(SCH_1):PAGE385
     2 RST_RT_CPU0_P0_PERST_R_N @T6G_MB_LIB.T6G(SCH_1):RST_RT_CPU0_P0_PERST_R_N    I76 @T6G_MB_LIB.T6G(SCH_1):PAGE385

R954 Q_RES_0402LF-11.5K,1%,1/16W,EMPTY,CS31152FB03
     1 P3V3_AUX_DSC_VOL @T6G_MB_LIB.T6G(SCH_1):P3V3_AUX_DSC_VOL    I36 @T6G_MB_LIB.T6G(SCH_1):PAGE146
     2    GND @T6G_MB_LIB.T6G(SCH_1):GND    I36 @T6G_MB_LIB.T6G(SCH_1):PAGE146

R955 Q_RES_0402LF-0,5%,1/16W,CHIP,CS00002JB13
     1 FM_LED_ACTIVE_E1S_0 @T6G_MB_LIB.T6G(SCH_1):FM_LED_ACTIVE_E1S_0    I94 @T6G_MB_LIB.T6G(SCH_1):PAGE297
     2 FM_LED_ACTIVE_E1S_0_R @T6G_MB_LIB.T6G(SCH_1):FM_LED_ACTIVE_E1S_0_R    I94 @T6G_MB_LIB.T6G(SCH_1):PAGE297

R956 Q_RES_0402LF-0,5%,1/16W,CHIP,CS00002JB13
     1 RST_PERST_OCP_SFF_BUF2_N @T6G_MB_LIB.T6G(SCH_1):RST_PERST_OCP_SFF_BUF2_N    I81 @T6G_MB_LIB.T6G(SCH_1):PAGE337
     2 RST_PERST3_OCP_SFF_N @T6G_MB_LIB.T6G(SCH_1):RST_PERST3_OCP_SFF_N    I81 @T6G_MB_LIB.T6G(SCH_1):PAGE337

R957 Q_RES_0402LF-33,5%,1/16W,CHIP,CS03302JB10
     1 FM_RST_PERST_SCM_R_N @T6G_MB_LIB.T6G(SCH_1):FM_RST_PERST_SCM_R_N   I130 @T6G_MB_LIB.T6G(SCH_1):PAGE80
     2 FM_RST_PERST_SCM_N @T6G_MB_LIB.T6G(SCH_1):FM_RST_PERST_SCM_N   I130 @T6G_MB_LIB.T6G(SCH_1):PAGE80

R958 Q_RES_0402LF-33,5%,1/16W,CHIP,CS03302JB10
     1 FM_PLD_OCP_SFF_AUX_PWR_EN @T6G_MB_LIB.T6G(SCH_1):FM_PLD_OCP_SFF_AUX_PWR_EN    I86 @T6G_MB_LIB.T6G(SCH_1):PAGE81
     2 FM_PLD_OCP_SFF_AUX_PWR_R_EN @T6G_MB_LIB.T6G(SCH_1):FM_PLD_OCP_SFF_AUX_PWR_R_EN    I86 @T6G_MB_LIB.T6G(SCH_1):PAGE81

R959 Q_RES_0402LF-33,5%,1/16W,CHIP,CS03302JB10
     1 OCP_SFF_MAIN_PWR_EN @T6G_MB_LIB.T6G(SCH_1):OCP_SFF_MAIN_PWR_EN    I81 @T6G_MB_LIB.T6G(SCH_1):PAGE81
     2 FM_PLD_OCP_SFF_MAIN_PWR_EN_R @T6G_MB_LIB.T6G(SCH_1):FM_PLD_OCP_SFF_MAIN_PWR_EN_R    I81 @T6G_MB_LIB.T6G(SCH_1):PAGE81

R960 Q_RES_0402LF-0,5%,1/16W,EMPTY,CS00002JB13
     1 P1V8_CPU0_RT_1D @T6G_MB_LIB.T6G(SCH_1):P1V8_CPU0_RT_1D    I89 @T6G_MB_LIB.T6G(SCH_1):PAGE388
     2 P1V8_CPU0_RT0_1A_1D @T6G_MB_LIB.T6G(SCH_1):P1V8_CPU0_RT0_1A_1D    I89 @T6G_MB_LIB.T6G(SCH_1):PAGE388

R961 Q_RES_0603LF-0,5%,1/4W,EMPTY,CS00006J900
     1 P0V9_CPU0_RT_2D @T6G_MB_LIB.T6G(SCH_1):P0V9_CPU0_RT_2D    I10 @T6G_MB_LIB.T6G(SCH_1):PAGE388
     2 P0V9_CPU0_RT0_2A_2D @T6G_MB_LIB.T6G(SCH_1):P0V9_CPU0_RT0_2A_2D    I10 @T6G_MB_LIB.T6G(SCH_1):PAGE388

R962 Q_RES_0603LF-0,5%,1/4W,CHIP,CS00006J900
     1 P0V9_CPU0_RT0_2A_2D @T6G_MB_LIB.T6G(SCH_1):P0V9_CPU0_RT0_2A_2D    I11 @T6G_MB_LIB.T6G(SCH_1):PAGE388
     2 P0V9_CPU0_RT0_2A @T6G_MB_LIB.T6G(SCH_1):P0V9_CPU0_RT0_2A    I11 @T6G_MB_LIB.T6G(SCH_1):PAGE388

R963 Q_RES_0201LF-0,5%,1/20W,CHIP,CS00001JE10
     1 RST_RT_CPU0_P0_RESET_N @T6G_MB_LIB.T6G(SCH_1):RST_RT_CPU0_P0_RESET_N    I77 @T6G_MB_LIB.T6G(SCH_1):PAGE385
     2 RST_RT_CPU0_P0_RESET_R_N @T6G_MB_LIB.T6G(SCH_1):RST_RT_CPU0_P0_RESET_R_N    I77 @T6G_MB_LIB.T6G(SCH_1):PAGE385

R964 Q_RES_0201LF-1K,1%,1/20W,CHIP,CS21001FE07
     1 P1V8_CPU0_RT_1D @T6G_MB_LIB.T6G(SCH_1):P1V8_CPU0_RT_1D    I88 @T6G_MB_LIB.T6G(SCH_1):PAGE385
     2 RT_CPU0_P0_ADDR3 @T6G_MB_LIB.T6G(SCH_1):RT_CPU0_P0_ADDR3    I88 @T6G_MB_LIB.T6G(SCH_1):PAGE385

R965 Q_RES_0201LF-1K,1%,1/20W,EMPTY,CS21001FE07
     1 RT_CPU0_P0_ADDR3 @T6G_MB_LIB.T6G(SCH_1):RT_CPU0_P0_ADDR3    I86 @T6G_MB_LIB.T6G(SCH_1):PAGE385
     2    GND @T6G_MB_LIB.T6G(SCH_1):GND    I86 @T6G_MB_LIB.T6G(SCH_1):PAGE385

R966 Q_RES_0201LF-1K,1%,1/20W,EMPTY,CS21001FE07
     1 P1V8_CPU0_RT_1D @T6G_MB_LIB.T6G(SCH_1):P1V8_CPU0_RT_1D    I89 @T6G_MB_LIB.T6G(SCH_1):PAGE385
     2 RT_CPU0_P0_ADDR2 @T6G_MB_LIB.T6G(SCH_1):RT_CPU0_P0_ADDR2    I89 @T6G_MB_LIB.T6G(SCH_1):PAGE385

R967 Q_RES_0201LF-20K,1%,1/20W,CHIP,CS32001FE00
     1 RT_CPU0_P0_ADDR2 @T6G_MB_LIB.T6G(SCH_1):RT_CPU0_P0_ADDR2    I87 @T6G_MB_LIB.T6G(SCH_1):PAGE385
     2    GND @T6G_MB_LIB.T6G(SCH_1):GND    I87 @T6G_MB_LIB.T6G(SCH_1):PAGE385

R968 Q_RES_0201LF-1K,1%,1/20W,EMPTY,CS21001FE07
     1 P1V8_CPU0_RT_1D @T6G_MB_LIB.T6G(SCH_1):P1V8_CPU0_RT_1D    I91 @T6G_MB_LIB.T6G(SCH_1):PAGE385
     2 RT_CPU0_P0_ADDR1 @T6G_MB_LIB.T6G(SCH_1):RT_CPU0_P0_ADDR1    I91 @T6G_MB_LIB.T6G(SCH_1):PAGE385

R969 Q_RES_0201LF-1K,1%,1/20W,CHIP,CS21001FE07
     1 RT_CPU0_P0_ADDR1 @T6G_MB_LIB.T6G(SCH_1):RT_CPU0_P0_ADDR1    I90 @T6G_MB_LIB.T6G(SCH_1):PAGE385
     2    GND @T6G_MB_LIB.T6G(SCH_1):GND    I90 @T6G_MB_LIB.T6G(SCH_1):PAGE385

R970 Q_RES_0201LF-10K,1%,1/20W,CHIP,CS31001FE17
     1 RST_RT_CPU0_P0_PERST_R_N @T6G_MB_LIB.T6G(SCH_1):RST_RT_CPU0_P0_PERST_R_N    I97 @T6G_MB_LIB.T6G(SCH_1):PAGE385
     2    GND @T6G_MB_LIB.T6G(SCH_1):GND    I97 @T6G_MB_LIB.T6G(SCH_1):PAGE385

R971 Q_RES_0201LF-10K,1%,1/20W,CHIP,CS31001FE17
     1 RST_RT_CPU0_P0_RESET_R_N @T6G_MB_LIB.T6G(SCH_1):RST_RT_CPU0_P0_RESET_R_N    I96 @T6G_MB_LIB.T6G(SCH_1):PAGE385
     2    GND @T6G_MB_LIB.T6G(SCH_1):GND    I96 @T6G_MB_LIB.T6G(SCH_1):PAGE385

R972 Q_RES_0201LF-4.7K,5%,1/20W,EMPTY,CS24701JE04
     1 P1V8_CPU0_RT_1D @T6G_MB_LIB.T6G(SCH_1):P1V8_CPU0_RT_1D    I25 @T6G_MB_LIB.T6G(SCH_1):PAGE385
     2 RT_CPU0_P0_SCAN_MODE @T6G_MB_LIB.T6G(SCH_1):RT_CPU0_P0_SCAN_MODE    I25 @T6G_MB_LIB.T6G(SCH_1):PAGE385

R973 Q_RES_0201LF-200,1%,1/20W,CHIP,CS12001FE12
     1 RT_CPU0_P0_SCAN_MODE @T6G_MB_LIB.T6G(SCH_1):RT_CPU0_P0_SCAN_MODE   I121 @T6G_MB_LIB.T6G(SCH_1):PAGE385
     2    GND @T6G_MB_LIB.T6G(SCH_1):GND   I121 @T6G_MB_LIB.T6G(SCH_1):PAGE385

R974 Q_RES_0201LF-4.7K,5%,1/20W,EMPTY,CS24701JE04
     1 P1V8_CPU0_RT_1D @T6G_MB_LIB.T6G(SCH_1):P1V8_CPU0_RT_1D    I98 @T6G_MB_LIB.T6G(SCH_1):PAGE385
     2 RST_RT_CPU0_P0_RESET_R_N @T6G_MB_LIB.T6G(SCH_1):RST_RT_CPU0_P0_RESET_R_N    I98 @T6G_MB_LIB.T6G(SCH_1):PAGE385

R975 Q_RES_0201LF-4.7K,5%,1/20W,EMPTY,CS24701JE04
     1 P1V8_CPU0_RT_1D @T6G_MB_LIB.T6G(SCH_1):P1V8_CPU0_RT_1D    I63 @T6G_MB_LIB.T6G(SCH_1):PAGE385
     2 JTAG_TEST_MODE_RT_CPU0_P0 @T6G_MB_LIB.T6G(SCH_1):JTAG_TEST_MODE_RT_CPU0_P0    I63 @T6G_MB_LIB.T6G(SCH_1):PAGE385

R976 Q_RES_0201LF-0,5%,1/20W,CHIP,CS00001JE10
     1 SMB_RT_CPU0_P0_R_SCL @T6G_MB_LIB.T6G(SCH_1):SMB_RT_CPU0_P0_R_SCL    I50 @T6G_MB_LIB.T6G(SCH_1):PAGE385
     2 SMB_RT_CPU0_P0_R2_SCL @T6G_MB_LIB.T6G(SCH_1):SMB_RT_CPU0_P0_R2_SCL    I50 @T6G_MB_LIB.T6G(SCH_1):PAGE385

R977 Q_RES_0201LF-0,5%,1/20W,CHIP,CS00001JE10
     1 SMB_RT_CPU0_P0_R_SDA @T6G_MB_LIB.T6G(SCH_1):SMB_RT_CPU0_P0_R_SDA    I49 @T6G_MB_LIB.T6G(SCH_1):PAGE385
     2 SMB_RT_CPU0_P0_R2_SDA @T6G_MB_LIB.T6G(SCH_1):SMB_RT_CPU0_P0_R2_SDA    I49 @T6G_MB_LIB.T6G(SCH_1):PAGE385

R978 Q_RES_0201LF-4.7K,5%,1/20W,EMPTY,CS24701JE04
     1 P1V8_CPU0_RT_1D @T6G_MB_LIB.T6G(SCH_1):P1V8_CPU0_RT_1D    I30 @T6G_MB_LIB.T6G(SCH_1):PAGE385
     2 GPIO2_RT_CPU0_P0 @T6G_MB_LIB.T6G(SCH_1):GPIO2_RT_CPU0_P0    I30 @T6G_MB_LIB.T6G(SCH_1):PAGE385

R979 Q_RES_0201LF-10K,1%,1/20W,CHIP,CS31001FE17
     1 GPIO2_RT_CPU0_P0 @T6G_MB_LIB.T6G(SCH_1):GPIO2_RT_CPU0_P0    I27 @T6G_MB_LIB.T6G(SCH_1):PAGE385
     2    GND @T6G_MB_LIB.T6G(SCH_1):GND    I27 @T6G_MB_LIB.T6G(SCH_1):PAGE385

R980 Q_RES_0201LF-10K,1%,1/20W,CHIP,CS31001FE17
     1 GPIO3_RT_CPU0_P0 @T6G_MB_LIB.T6G(SCH_1):GPIO3_RT_CPU0_P0    I28 @T6G_MB_LIB.T6G(SCH_1):PAGE385
     2    GND @T6G_MB_LIB.T6G(SCH_1):GND    I28 @T6G_MB_LIB.T6G(SCH_1):PAGE385

R981 Q_RES_0201LF-4.7K,5%,1/20W,EMPTY,CS24701JE04
     1 P1V8_CPU0_RT_1D @T6G_MB_LIB.T6G(SCH_1):P1V8_CPU0_RT_1D    I31 @T6G_MB_LIB.T6G(SCH_1):PAGE385
     2 TEST0_RT_CPU0_P0 @T6G_MB_LIB.T6G(SCH_1):TEST0_RT_CPU0_P0    I31 @T6G_MB_LIB.T6G(SCH_1):PAGE385

R982 Q_RES_0201LF-4.7K,5%,1/20W,CHIP,CS24701JE04
     1 TEST0_RT_CPU0_P0 @T6G_MB_LIB.T6G(SCH_1):TEST0_RT_CPU0_P0    I29 @T6G_MB_LIB.T6G(SCH_1):PAGE385
     2    GND @T6G_MB_LIB.T6G(SCH_1):GND    I29 @T6G_MB_LIB.T6G(SCH_1):PAGE385

R983 Q_RES_0201LF-4.7K,5%,1/20W,EMPTY,CS24701JE04
     1 P1V8_CPU0_RT_1D @T6G_MB_LIB.T6G(SCH_1):P1V8_CPU0_RT_1D    I61 @T6G_MB_LIB.T6G(SCH_1):PAGE385
     2 TEST1_RT_CPU0_P0 @T6G_MB_LIB.T6G(SCH_1):TEST1_RT_CPU0_P0    I61 @T6G_MB_LIB.T6G(SCH_1):PAGE385

R984 Q_RES_0201LF-4.7K,5%,1/20W,CHIP,CS24701JE04
     1 TEST1_RT_CPU0_P0 @T6G_MB_LIB.T6G(SCH_1):TEST1_RT_CPU0_P0    I57 @T6G_MB_LIB.T6G(SCH_1):PAGE385
     2    GND @T6G_MB_LIB.T6G(SCH_1):GND    I57 @T6G_MB_LIB.T6G(SCH_1):PAGE385

R985 Q_RES_0201LF-4.7K,5%,1/20W,EMPTY,CS24701JE04
     1 P1V8_CPU0_RT_1D @T6G_MB_LIB.T6G(SCH_1):P1V8_CPU0_RT_1D    I62 @T6G_MB_LIB.T6G(SCH_1):PAGE385
     2 TEST2_RT_CPU0_P0 @T6G_MB_LIB.T6G(SCH_1):TEST2_RT_CPU0_P0    I62 @T6G_MB_LIB.T6G(SCH_1):PAGE385

R986 Q_RES_0402LF-0,5%,1/16W,EMPTY,CS00002JB13
     1 I3C_1_SPD_DDRGL_CPU0_R_SCL @T6G_MB_LIB.T6G(SCH_1):I3C_1_SPD_DDRGL_CPU0_R_SCL   I135 @T6G_MB_LIB.T6G(SCH_1):PAGE136
     2 I3C_SPD_DDRGL_CPU0_BYPASS_SCL @T6G_MB_LIB.T6G(SCH_1):I3C_SPD_DDRGL_CPU0_BYPASS_SCL   I135 @T6G_MB_LIB.T6G(SCH_1):PAGE136

R987 Q_RES_0402LF-0,5%,1/16W,EMPTY,CS00002JB13
     1 I3C_1_SPD_DDRGL_CPU0_R_SDA @T6G_MB_LIB.T6G(SCH_1):I3C_1_SPD_DDRGL_CPU0_R_SDA   I136 @T6G_MB_LIB.T6G(SCH_1):PAGE136
     2 I3C_SPD_DDRGL_CPU0_BYPASS_SDA @T6G_MB_LIB.T6G(SCH_1):I3C_SPD_DDRGL_CPU0_BYPASS_SDA   I136 @T6G_MB_LIB.T6G(SCH_1):PAGE136

R988 Q_RES_0402LF-0,5%,1/16W,EMPTY,CS00002JB13
     1 I3C_0_SPD_DDRAF_CPU1_R_SCL @T6G_MB_LIB.T6G(SCH_1):I3C_0_SPD_DDRAF_CPU1_R_SCL   I138 @T6G_MB_LIB.T6G(SCH_1):PAGE136
     2 I3C_SPD_DDRAF_CPU1_BYPASS_SCL @T6G_MB_LIB.T6G(SCH_1):I3C_SPD_DDRAF_CPU1_BYPASS_SCL   I138 @T6G_MB_LIB.T6G(SCH_1):PAGE136

R989 Q_RES_0402LF-0,5%,1/16W,EMPTY,CS00002JB13
     1 I3C_0_SPD_DDRAF_CPU1_R_SDA @T6G_MB_LIB.T6G(SCH_1):I3C_0_SPD_DDRAF_CPU1_R_SDA   I137 @T6G_MB_LIB.T6G(SCH_1):PAGE136
     2 I3C_SPD_DDRAF_CPU1_BYPASS_SDA @T6G_MB_LIB.T6G(SCH_1):I3C_SPD_DDRAF_CPU1_BYPASS_SDA   I137 @T6G_MB_LIB.T6G(SCH_1):PAGE136

R990 Q_RES_0402LF-0,5%,1/16W,EMPTY,CS00002JB13
     1 I3C_1_SPD_DDRGL_CPU1_R_SCL @T6G_MB_LIB.T6G(SCH_1):I3C_1_SPD_DDRGL_CPU1_R_SCL   I142 @T6G_MB_LIB.T6G(SCH_1):PAGE136
     2 I3C_SPD_DDRGL_CPU1_BYPASS_SCL @T6G_MB_LIB.T6G(SCH_1):I3C_SPD_DDRGL_CPU1_BYPASS_SCL   I142 @T6G_MB_LIB.T6G(SCH_1):PAGE136

R991 Q_RES_0402LF-0,5%,1/16W,EMPTY,CS00002JB13
     1 I3C_1_SPD_DDRGL_CPU1_R_SDA @T6G_MB_LIB.T6G(SCH_1):I3C_1_SPD_DDRGL_CPU1_R_SDA   I141 @T6G_MB_LIB.T6G(SCH_1):PAGE136
     2 I3C_SPD_DDRGL_CPU1_BYPASS_SDA @T6G_MB_LIB.T6G(SCH_1):I3C_SPD_DDRGL_CPU1_BYPASS_SDA   I141 @T6G_MB_LIB.T6G(SCH_1):PAGE136

R992 Q_RES_0402LF-33,5%,1/16W,CHIP,CS03302JB10
     1 FM_SYS_THROTTLE_R_N @T6G_MB_LIB.T6G(SCH_1):FM_SYS_THROTTLE_R_N    I17 @T6G_MB_LIB.T6G(SCH_1):PAGE79
     2 FM_SYS_THROTTLE_N @T6G_MB_LIB.T6G(SCH_1):FM_SYS_THROTTLE_N    I17 @T6G_MB_LIB.T6G(SCH_1):PAGE79

R993 Q_RES_0402LF-1K,1%,1/16W,CHIP,CS21002FB06
     1 FM_SYS_THROTTLE_N @T6G_MB_LIB.T6G(SCH_1):FM_SYS_THROTTLE_N    I53 @T6G_MB_LIB.T6G(SCH_1):PAGE82
     2 P3V3_AUX @T6G_MB_LIB.T6G(SCH_1):P3V3_AUX    I53 @T6G_MB_LIB.T6G(SCH_1):PAGE82

R994 Q_RES_0402LF-10K,1%,1/16W,CHIP,CS31002FB08
     1 P3V3_AUX @T6G_MB_LIB.T6G(SCH_1):P3V3_AUX     I7 @T6G_MB_LIB.T6G(SCH_1):PAGE132
     2 IRQ_LVC3_WAKE_N @T6G_MB_LIB.T6G(SCH_1):IRQ_LVC3_WAKE_N     I7 @T6G_MB_LIB.T6G(SCH_1):PAGE132

R995 Q_RES_0201LF-4.7K,5%,1/20W,CHIP,CS24701JE04
     1 TEST2_RT_CPU0_P0 @T6G_MB_LIB.T6G(SCH_1):TEST2_RT_CPU0_P0    I58 @T6G_MB_LIB.T6G(SCH_1):PAGE385
     2    GND @T6G_MB_LIB.T6G(SCH_1):GND    I58 @T6G_MB_LIB.T6G(SCH_1):PAGE385

R996 Q_RES_0402LF-4.7K,5%,1/16W,CHIP,CS24702JB10
     1 P1V8_AUX @T6G_MB_LIB.T6G(SCH_1):P1V8_AUX    I22 @T6G_MB_LIB.T6G(SCH_1):PAGE83
     2 SCM_IRQ_1V8_N @T6G_MB_LIB.T6G(SCH_1):SCM_IRQ_1V8_N    I22 @T6G_MB_LIB.T6G(SCH_1):PAGE83

R997 Q_RES_0201LF-4.7K,5%,1/20W,CHIP,CS24701JE04
     1 JTAG_TEST_MODE_RT_CPU0_P0 @T6G_MB_LIB.T6G(SCH_1):JTAG_TEST_MODE_RT_CPU0_P0    I60 @T6G_MB_LIB.T6G(SCH_1):PAGE385
     2    GND @T6G_MB_LIB.T6G(SCH_1):GND    I60 @T6G_MB_LIB.T6G(SCH_1):PAGE385

R998 Q_RES_0201LF-4.7K,5%,1/20W,CHIP,CS24701JE04
     1 P1V8_CPU0_RT_1D @T6G_MB_LIB.T6G(SCH_1):P1V8_CPU0_RT_1D    I72 @T6G_MB_LIB.T6G(SCH_1):PAGE385
     2 MODE_RT_CPU0_P0 @T6G_MB_LIB.T6G(SCH_1):MODE_RT_CPU0_P0    I72 @T6G_MB_LIB.T6G(SCH_1):PAGE385

R999 Q_RES_0402LF-4.7K,5%,1/16W,CHIP,CS24702JB10
     1 FM_LED_ACTIVE_E1S_0_R @T6G_MB_LIB.T6G(SCH_1):FM_LED_ACTIVE_E1S_0_R    I95 @T6G_MB_LIB.T6G(SCH_1):PAGE297
     2    GND @T6G_MB_LIB.T6G(SCH_1):GND    I95 @T6G_MB_LIB.T6G(SCH_1):PAGE297

R1000 Q_RES_0402LF-4.7K,5%,1/16W,CHIP,CS24702JB10
     1 FM_LED_ACTIVE_E1S_0_BUF @T6G_MB_LIB.T6G(SCH_1):FM_LED_ACTIVE_E1S_0_BUF   I102 @T6G_MB_LIB.T6G(SCH_1):PAGE297
     2    GND @T6G_MB_LIB.T6G(SCH_1):GND   I102 @T6G_MB_LIB.T6G(SCH_1):PAGE297

R1001 Q_RES_0201LF-4.7K,5%,1/20W,EMPTY,CS24701JE04
     1 MODE_RT_CPU0_P0 @T6G_MB_LIB.T6G(SCH_1):MODE_RT_CPU0_P0    I71 @T6G_MB_LIB.T6G(SCH_1):PAGE385
     2    GND @T6G_MB_LIB.T6G(SCH_1):GND    I71 @T6G_MB_LIB.T6G(SCH_1):PAGE385

R1002 Q_RES_0402LF-0,5%,1/16W,EMPTY,CS00002JB13
     1 P1V8_CPU0_RT1_1A_1D @T6G_MB_LIB.T6G(SCH_1):P1V8_CPU0_RT1_1A_1D     I4 @T6G_MB_LIB.T6G(SCH_1):PAGE411
     2 P1V8_CPU0_RT1_1A @T6G_MB_LIB.T6G(SCH_1):P1V8_CPU0_RT1_1A     I4 @T6G_MB_LIB.T6G(SCH_1):PAGE411

R1003 Q_RES_0402LF-0,5%,1/16W,EMPTY,CS00002JB13
     1 P1V8_CPU0_RT1_1A_1D @T6G_MB_LIB.T6G(SCH_1):P1V8_CPU0_RT1_1A_1D     I2 @T6G_MB_LIB.T6G(SCH_1):PAGE411
     2 P1V8_CPU0_RT1_1A @T6G_MB_LIB.T6G(SCH_1):P1V8_CPU0_RT1_1A     I2 @T6G_MB_LIB.T6G(SCH_1):PAGE411

R1004 Q_RES_0201LF-0,5%,1/20W,CHIP,CS00001JE10
     1 RST_RT_CPU0_P1_PERST_N @T6G_MB_LIB.T6G(SCH_1):RST_RT_CPU0_P1_PERST_N    I56 @T6G_MB_LIB.T6G(SCH_1):PAGE408
     2 RST_RT_CPU0_P1_PERST_R_N @T6G_MB_LIB.T6G(SCH_1):RST_RT_CPU0_P1_PERST_R_N    I56 @T6G_MB_LIB.T6G(SCH_1):PAGE408

R1005 Q_RES_0402LF-33,5%,1/16W,CHIP,CS03302JB10
     1 M2_0_PEWAKE_R_N @T6G_MB_LIB.T6G(SCH_1):M2_0_PEWAKE_R_N     I4 @T6G_MB_LIB.T6G(SCH_1):PAGE132
     2 IRQ_LVC3_WAKE_N @T6G_MB_LIB.T6G(SCH_1):IRQ_LVC3_WAKE_N     I4 @T6G_MB_LIB.T6G(SCH_1):PAGE132

R1006 Q_RES_0201LF-4.7K,5%,1/20W,EMPTY,CS24701JE04
     1 MODE_RT_CPU0_P1 @T6G_MB_LIB.T6G(SCH_1):MODE_RT_CPU0_P1    I50 @T6G_MB_LIB.T6G(SCH_1):PAGE408
     2    GND @T6G_MB_LIB.T6G(SCH_1):GND    I50 @T6G_MB_LIB.T6G(SCH_1):PAGE408

R1007 Q_RES_0402LF-2K,1%,1/16W,EMPTY,CS22002FB07
     1 P12V_AUX @T6G_MB_LIB.T6G(SCH_1):P12V_AUX    I11 @T6G_MB_LIB.T6G(SCH_1):PAGE146
     2 P12V_AUX_DSC_G1 @T6G_MB_LIB.T6G(SCH_1):P12V_AUX_DSC_G1    I11 @T6G_MB_LIB.T6G(SCH_1):PAGE146

R1008 Q_RES_0402LF-0,5%,1/16W,EMPTY,CS00002JB13
     1 P1V8_CPU0_RT_1D @T6G_MB_LIB.T6G(SCH_1):P1V8_CPU0_RT_1D    I89 @T6G_MB_LIB.T6G(SCH_1):PAGE411
     2 P1V8_CPU0_RT1_1A_1D @T6G_MB_LIB.T6G(SCH_1):P1V8_CPU0_RT1_1A_1D    I89 @T6G_MB_LIB.T6G(SCH_1):PAGE411

R1009 Q_RES_0402LF-10K,1%,1/16W,CHIP,CS31002FB08
     1 P3V3_AUX @T6G_MB_LIB.T6G(SCH_1):P3V3_AUX    I10 @T6G_MB_LIB.T6G(SCH_1):PAGE132
     2 IRQ_LVC3_WAKE @T6G_MB_LIB.T6G(SCH_1):IRQ_LVC3_WAKE    I10 @T6G_MB_LIB.T6G(SCH_1):PAGE132

R1010 Q_RES_0603LF-0,5%,1/4W,EMPTY,CS00006J900
     1 P0V9_CPU0_RT_2D @T6G_MB_LIB.T6G(SCH_1):P0V9_CPU0_RT_2D    I10 @T6G_MB_LIB.T6G(SCH_1):PAGE411
     2 P0V9_CPU0_RT1_2A_2D @T6G_MB_LIB.T6G(SCH_1):P0V9_CPU0_RT1_2A_2D    I10 @T6G_MB_LIB.T6G(SCH_1):PAGE411

R1011 Q_RES_0603LF-0,5%,1/4W,CHIP,CS00006J900
     1 P0V9_CPU0_RT1_2A_2D @T6G_MB_LIB.T6G(SCH_1):P0V9_CPU0_RT1_2A_2D    I36 @T6G_MB_LIB.T6G(SCH_1):PAGE411
     2 P0V9_CPU0_RT1_2A @T6G_MB_LIB.T6G(SCH_1):P0V9_CPU0_RT1_2A    I36 @T6G_MB_LIB.T6G(SCH_1):PAGE411

R1012 Q_RES_0201LF-0,5%,1/20W,CHIP,CS00001JE10
     1 RST_RT_CPU0_P1_RESET_N @T6G_MB_LIB.T6G(SCH_1):RST_RT_CPU0_P1_RESET_N    I55 @T6G_MB_LIB.T6G(SCH_1):PAGE408
     2 RST_RT_CPU0_P1_RESET_R_N @T6G_MB_LIB.T6G(SCH_1):RST_RT_CPU0_P1_RESET_R_N    I55 @T6G_MB_LIB.T6G(SCH_1):PAGE408

R1013 Q_RES_0201LF-1K,1%,1/20W,CHIP,CS21001FE07
     1 P1V8_CPU0_RT_1D @T6G_MB_LIB.T6G(SCH_1):P1V8_CPU0_RT_1D    I66 @T6G_MB_LIB.T6G(SCH_1):PAGE408
     2 RT_CPU0_P1_ADDR3 @T6G_MB_LIB.T6G(SCH_1):RT_CPU0_P1_ADDR3    I66 @T6G_MB_LIB.T6G(SCH_1):PAGE408

R1014 Q_RES_0201LF-1K,1%,1/20W,EMPTY,CS21001FE07
     1 RT_CPU0_P1_ADDR3 @T6G_MB_LIB.T6G(SCH_1):RT_CPU0_P1_ADDR3    I64 @T6G_MB_LIB.T6G(SCH_1):PAGE408
     2    GND @T6G_MB_LIB.T6G(SCH_1):GND    I64 @T6G_MB_LIB.T6G(SCH_1):PAGE408

R1015 Q_RES_0201LF-1K,1%,1/20W,EMPTY,CS21001FE07
     1 P1V8_CPU0_RT_1D @T6G_MB_LIB.T6G(SCH_1):P1V8_CPU0_RT_1D    I67 @T6G_MB_LIB.T6G(SCH_1):PAGE408
     2 RT_CPU0_P1_ADDR2 @T6G_MB_LIB.T6G(SCH_1):RT_CPU0_P1_ADDR2    I67 @T6G_MB_LIB.T6G(SCH_1):PAGE408

R1016 Q_RES_0201LF-20K,1%,1/20W,CHIP,CS32001FE00
     1 RT_CPU0_P1_ADDR2 @T6G_MB_LIB.T6G(SCH_1):RT_CPU0_P1_ADDR2    I65 @T6G_MB_LIB.T6G(SCH_1):PAGE408
     2    GND @T6G_MB_LIB.T6G(SCH_1):GND    I65 @T6G_MB_LIB.T6G(SCH_1):PAGE408

R1017 Q_RES_0201LF-1K,1%,1/20W,EMPTY,CS21001FE07
     1 P1V8_CPU0_RT_1D @T6G_MB_LIB.T6G(SCH_1):P1V8_CPU0_RT_1D    I69 @T6G_MB_LIB.T6G(SCH_1):PAGE408
     2 RT_CPU0_P1_ADDR1 @T6G_MB_LIB.T6G(SCH_1):RT_CPU0_P1_ADDR1    I69 @T6G_MB_LIB.T6G(SCH_1):PAGE408

R1018 Q_RES_0201LF-1K,1%,1/20W,CHIP,CS21001FE07
     1 RT_CPU0_P1_ADDR1 @T6G_MB_LIB.T6G(SCH_1):RT_CPU0_P1_ADDR1    I68 @T6G_MB_LIB.T6G(SCH_1):PAGE408
     2    GND @T6G_MB_LIB.T6G(SCH_1):GND    I68 @T6G_MB_LIB.T6G(SCH_1):PAGE408

R1019 Q_RES_0201LF-10K,1%,1/20W,CHIP,CS31001FE17
     1 RST_RT_CPU0_P1_PERST_R_N @T6G_MB_LIB.T6G(SCH_1):RST_RT_CPU0_P1_PERST_R_N    I73 @T6G_MB_LIB.T6G(SCH_1):PAGE408
     2    GND @T6G_MB_LIB.T6G(SCH_1):GND    I73 @T6G_MB_LIB.T6G(SCH_1):PAGE408

R1020 Q_RES_0201LF-10K,1%,1/20W,CHIP,CS31001FE17
     1 RST_RT_CPU0_P1_RESET_R_N @T6G_MB_LIB.T6G(SCH_1):RST_RT_CPU0_P1_RESET_R_N    I74 @T6G_MB_LIB.T6G(SCH_1):PAGE408
     2    GND @T6G_MB_LIB.T6G(SCH_1):GND    I74 @T6G_MB_LIB.T6G(SCH_1):PAGE408

R1021 Q_RES_0201LF-4.7K,5%,1/20W,EMPTY,CS24701JE04
     1 P1V8_CPU0_RT_1D @T6G_MB_LIB.T6G(SCH_1):P1V8_CPU0_RT_1D     I5 @T6G_MB_LIB.T6G(SCH_1):PAGE408
     2 RT_CPU0_P1_SCAN_MODE @T6G_MB_LIB.T6G(SCH_1):RT_CPU0_P1_SCAN_MODE     I5 @T6G_MB_LIB.T6G(SCH_1):PAGE408

R1022 Q_RES_0201LF-200,1%,1/20W,CHIP,CS12001FE12
     1 RT_CPU0_P1_SCAN_MODE @T6G_MB_LIB.T6G(SCH_1):RT_CPU0_P1_SCAN_MODE   I102 @T6G_MB_LIB.T6G(SCH_1):PAGE408
     2    GND @T6G_MB_LIB.T6G(SCH_1):GND   I102 @T6G_MB_LIB.T6G(SCH_1):PAGE408

R1023 Q_RES_0201LF-4.7K,5%,1/20W,EMPTY,CS24701JE04
     1 P1V8_CPU0_RT_1D @T6G_MB_LIB.T6G(SCH_1):P1V8_CPU0_RT_1D    I78 @T6G_MB_LIB.T6G(SCH_1):PAGE408
     2 RST_RT_CPU0_P1_RESET_R_N @T6G_MB_LIB.T6G(SCH_1):RST_RT_CPU0_P1_RESET_R_N    I78 @T6G_MB_LIB.T6G(SCH_1):PAGE408

R1024 Q_RES_0201LF-4.7K,5%,1/20W,EMPTY,CS24701JE04
     1 P1V8_CPU0_RT_1D @T6G_MB_LIB.T6G(SCH_1):P1V8_CPU0_RT_1D    I42 @T6G_MB_LIB.T6G(SCH_1):PAGE408
     2 JTAG_TEST_MODE_RT_CPU0_P1 @T6G_MB_LIB.T6G(SCH_1):JTAG_TEST_MODE_RT_CPU0_P1    I42 @T6G_MB_LIB.T6G(SCH_1):PAGE408

R1025 Q_RES_0201LF-0,5%,1/20W,CHIP,CS00001JE10
     1 SMB_RT_CPU0_P1_R_SCL @T6G_MB_LIB.T6G(SCH_1):SMB_RT_CPU0_P1_R_SCL    I30 @T6G_MB_LIB.T6G(SCH_1):PAGE408
     2 SMB_RT_CPU0_P1_R2_SCL @T6G_MB_LIB.T6G(SCH_1):SMB_RT_CPU0_P1_R2_SCL    I30 @T6G_MB_LIB.T6G(SCH_1):PAGE408

R1026 Q_RES_0201LF-0,5%,1/20W,CHIP,CS00001JE10
     1 SMB_RT_CPU0_P1_R_SDA @T6G_MB_LIB.T6G(SCH_1):SMB_RT_CPU0_P1_R_SDA    I29 @T6G_MB_LIB.T6G(SCH_1):PAGE408
     2 SMB_RT_CPU0_P1_R2_SDA @T6G_MB_LIB.T6G(SCH_1):SMB_RT_CPU0_P1_R2_SDA    I29 @T6G_MB_LIB.T6G(SCH_1):PAGE408

R1027 Q_RES_0201LF-4.7K,5%,1/20W,EMPTY,CS24701JE04
     1 P1V8_CPU0_RT_1D @T6G_MB_LIB.T6G(SCH_1):P1V8_CPU0_RT_1D    I10 @T6G_MB_LIB.T6G(SCH_1):PAGE408
     2 GPIO2_RT_CPU0_P1 @T6G_MB_LIB.T6G(SCH_1):GPIO2_RT_CPU0_P1    I10 @T6G_MB_LIB.T6G(SCH_1):PAGE408

R1028 Q_RES_0201LF-10K,1%,1/20W,CHIP,CS31001FE17
     1 GPIO2_RT_CPU0_P1 @T6G_MB_LIB.T6G(SCH_1):GPIO2_RT_CPU0_P1     I7 @T6G_MB_LIB.T6G(SCH_1):PAGE408
     2    GND @T6G_MB_LIB.T6G(SCH_1):GND     I7 @T6G_MB_LIB.T6G(SCH_1):PAGE408

R1029 Q_RES_0201LF-10K,1%,1/20W,CHIP,CS31001FE17
     1 GPIO3_RT_CPU0_P1 @T6G_MB_LIB.T6G(SCH_1):GPIO3_RT_CPU0_P1     I8 @T6G_MB_LIB.T6G(SCH_1):PAGE408
     2    GND @T6G_MB_LIB.T6G(SCH_1):GND     I8 @T6G_MB_LIB.T6G(SCH_1):PAGE408

R1030 Q_RES_0201LF-4.7K,5%,1/20W,EMPTY,CS24701JE04
     1 P1V8_CPU0_RT_1D @T6G_MB_LIB.T6G(SCH_1):P1V8_CPU0_RT_1D    I11 @T6G_MB_LIB.T6G(SCH_1):PAGE408
     2 TEST0_RT_CPU0_P1 @T6G_MB_LIB.T6G(SCH_1):TEST0_RT_CPU0_P1    I11 @T6G_MB_LIB.T6G(SCH_1):PAGE408

R1031 Q_RES_0201LF-4.7K,5%,1/20W,CHIP,CS24701JE04
     1 TEST0_RT_CPU0_P1 @T6G_MB_LIB.T6G(SCH_1):TEST0_RT_CPU0_P1     I9 @T6G_MB_LIB.T6G(SCH_1):PAGE408
     2    GND @T6G_MB_LIB.T6G(SCH_1):GND     I9 @T6G_MB_LIB.T6G(SCH_1):PAGE408

R1032 Q_RES_0201LF-4.7K,5%,1/20W,EMPTY,CS24701JE04
     1 P1V8_CPU0_RT_1D @T6G_MB_LIB.T6G(SCH_1):P1V8_CPU0_RT_1D    I40 @T6G_MB_LIB.T6G(SCH_1):PAGE408
     2 TEST1_RT_CPU0_P1 @T6G_MB_LIB.T6G(SCH_1):TEST1_RT_CPU0_P1    I40 @T6G_MB_LIB.T6G(SCH_1):PAGE408

R1033 Q_RES_0201LF-4.7K,5%,1/20W,CHIP,CS24701JE04
     1 TEST1_RT_CPU0_P1 @T6G_MB_LIB.T6G(SCH_1):TEST1_RT_CPU0_P1    I36 @T6G_MB_LIB.T6G(SCH_1):PAGE408
     2    GND @T6G_MB_LIB.T6G(SCH_1):GND    I36 @T6G_MB_LIB.T6G(SCH_1):PAGE408

R1034 Q_RES_0201LF-4.7K,5%,1/20W,EMPTY,CS24701JE04
     1 P1V8_CPU0_RT_1D @T6G_MB_LIB.T6G(SCH_1):P1V8_CPU0_RT_1D    I41 @T6G_MB_LIB.T6G(SCH_1):PAGE408
     2 TEST2_RT_CPU0_P1 @T6G_MB_LIB.T6G(SCH_1):TEST2_RT_CPU0_P1    I41 @T6G_MB_LIB.T6G(SCH_1):PAGE408

R1035 Q_RES_0201LF-4.7K,5%,1/20W,CHIP,CS24701JE04
     1 TEST2_RT_CPU0_P1 @T6G_MB_LIB.T6G(SCH_1):TEST2_RT_CPU0_P1    I37 @T6G_MB_LIB.T6G(SCH_1):PAGE408
     2    GND @T6G_MB_LIB.T6G(SCH_1):GND    I37 @T6G_MB_LIB.T6G(SCH_1):PAGE408

R1036 Q_RES_0402LF-0,5%,1/16W,CHIP,CS00002JB13
     1 FM_SMB_RST_E1S_0_N @T6G_MB_LIB.T6G(SCH_1):FM_SMB_RST_E1S_0_N     I6 @T6G_MB_LIB.T6G(SCH_1):PAGE84
     2 FM_SMB_RST_E1S_0_R_N @T6G_MB_LIB.T6G(SCH_1):FM_SMB_RST_E1S_0_R_N     I6 @T6G_MB_LIB.T6G(SCH_1):PAGE84

R1037 Q_RES_0201LF-4.7K,5%,1/20W,CHIP,CS24701JE04
     1 JTAG_TEST_MODE_RT_CPU0_P1 @T6G_MB_LIB.T6G(SCH_1):JTAG_TEST_MODE_RT_CPU0_P1    I39 @T6G_MB_LIB.T6G(SCH_1):PAGE408
     2    GND @T6G_MB_LIB.T6G(SCH_1):GND    I39 @T6G_MB_LIB.T6G(SCH_1):PAGE408

R1038 Q_RES_0402LF-0,5%,1/16W,CHIP,CS00002JB13
     1 FM_LED_ACTIVE_E1S_0_R_BUF @T6G_MB_LIB.T6G(SCH_1):FM_LED_ACTIVE_E1S_0_R_BUF   I101 @T6G_MB_LIB.T6G(SCH_1):PAGE297
     2 FM_LED_ACTIVE_E1S_0_BUF @T6G_MB_LIB.T6G(SCH_1):FM_LED_ACTIVE_E1S_0_BUF   I101 @T6G_MB_LIB.T6G(SCH_1):PAGE297

R1039 Q_RES_0201LF-4.7K,5%,1/20W,CHIP,CS24701JE04
     1 P1V8_CPU0_RT_1D @T6G_MB_LIB.T6G(SCH_1):P1V8_CPU0_RT_1D    I51 @T6G_MB_LIB.T6G(SCH_1):PAGE408
     2 MODE_RT_CPU0_P1 @T6G_MB_LIB.T6G(SCH_1):MODE_RT_CPU0_P1    I51 @T6G_MB_LIB.T6G(SCH_1):PAGE408

R1040 Q_RES_0201LF-1K,1%,1/20W,EMPTY,CS21001FE07
     1 P1V8_CPU0_RT_1D @T6G_MB_LIB.T6G(SCH_1):P1V8_CPU0_RT_1D    I19 @T6G_MB_LIB.T6G(SCH_1):PAGE409
     2 RT_CPU0_P1_VQPS @T6G_MB_LIB.T6G(SCH_1):RT_CPU0_P1_VQPS    I19 @T6G_MB_LIB.T6G(SCH_1):PAGE409

R1041 Q_RES_0201LF-200,1%,1/20W,CHIP,CS12001FE12
     1 RT_CPU0_P1_VQPS @T6G_MB_LIB.T6G(SCH_1):RT_CPU0_P1_VQPS    I18 @T6G_MB_LIB.T6G(SCH_1):PAGE409
     2    GND @T6G_MB_LIB.T6G(SCH_1):GND    I18 @T6G_MB_LIB.T6G(SCH_1):PAGE409

R1042 Q_RES_0201LF-0,5%,1/20W,CHIP,CS00001JE10
     1 NCF_CPU0_P1_GND @T6G_MB_LIB.T6G(SCH_1):NCF_CPU0_P1_GND    I13 @T6G_MB_LIB.T6G(SCH_1):PAGE409
     2    GND @T6G_MB_LIB.T6G(SCH_1):GND    I13 @T6G_MB_LIB.T6G(SCH_1):PAGE409

R1043 Q_RES_0201LF-0,5%,1/20W,CHIP,CS00001JE10
     1 NCF_A1_CPU0_P1_GND @T6G_MB_LIB.T6G(SCH_1):NCF_A1_CPU0_P1_GND    I15 @T6G_MB_LIB.T6G(SCH_1):PAGE409
     2    GND @T6G_MB_LIB.T6G(SCH_1):GND    I15 @T6G_MB_LIB.T6G(SCH_1):PAGE409

R1044 Q_RES_0201LF-1K,1%,1/20W,CHIP,CS21001FE07
     1 U15_E2 @T6G_MB_LIB.T6G(SCH_1):U15_E2    I20 @T6G_MB_LIB.T6G(SCH_1):PAGE410
     2    GND @T6G_MB_LIB.T6G(SCH_1):GND    I20 @T6G_MB_LIB.T6G(SCH_1):PAGE410

R1045 Q_RES_0402LF-0,5%,1/16W,EMPTY,CS00002JB13
     1 P1V8_CPU0_RT2_1A_1D @T6G_MB_LIB.T6G(SCH_1):P1V8_CPU0_RT2_1A_1D     I5 @T6G_MB_LIB.T6G(SCH_1):PAGE422
     2 P1V8_CPU0_RT2_1A @T6G_MB_LIB.T6G(SCH_1):P1V8_CPU0_RT2_1A     I5 @T6G_MB_LIB.T6G(SCH_1):PAGE422

R1046 Q_RES_0402LF-0,5%,1/16W,EMPTY,CS00002JB13
     1 P1V8_CPU0_RT2_1A_1D @T6G_MB_LIB.T6G(SCH_1):P1V8_CPU0_RT2_1A_1D     I4 @T6G_MB_LIB.T6G(SCH_1):PAGE422
     2 P1V8_CPU0_RT2_1A @T6G_MB_LIB.T6G(SCH_1):P1V8_CPU0_RT2_1A     I4 @T6G_MB_LIB.T6G(SCH_1):PAGE422

R1047 Q_RES_0201LF-0,5%,1/20W,CHIP,CS00001JE10
     1 RST_RT_CPU0_P2_PERST_N @T6G_MB_LIB.T6G(SCH_1):RST_RT_CPU0_P2_PERST_N    I56 @T6G_MB_LIB.T6G(SCH_1):PAGE419
     2 RST_RT_CPU0_P2_PERST_R_N @T6G_MB_LIB.T6G(SCH_1):RST_RT_CPU0_P2_PERST_R_N    I56 @T6G_MB_LIB.T6G(SCH_1):PAGE419

R1048 Q_RES_0201LF-4.7K,5%,1/20W,EMPTY,CS24701JE04
     1 MODE_RT_CPU0_P2 @T6G_MB_LIB.T6G(SCH_1):MODE_RT_CPU0_P2    I50 @T6G_MB_LIB.T6G(SCH_1):PAGE419
     2    GND @T6G_MB_LIB.T6G(SCH_1):GND    I50 @T6G_MB_LIB.T6G(SCH_1):PAGE419

R1049 Q_RES_0402LF-1K,1%,1/16W,EMPTY,CS21002FB06
     1 P12V_AUX_DSC_G1 @T6G_MB_LIB.T6G(SCH_1):P12V_AUX_DSC_G1    I12 @T6G_MB_LIB.T6G(SCH_1):PAGE146
     2    GND @T6G_MB_LIB.T6G(SCH_1):GND    I12 @T6G_MB_LIB.T6G(SCH_1):PAGE146

R1050 Q_RES_0402LF-0,5%,1/16W,EMPTY,CS00002JB13
     1 P1V8_CPU0_RT_1D @T6G_MB_LIB.T6G(SCH_1):P1V8_CPU0_RT_1D    I89 @T6G_MB_LIB.T6G(SCH_1):PAGE422
     2 P1V8_CPU0_RT2_1A_1D @T6G_MB_LIB.T6G(SCH_1):P1V8_CPU0_RT2_1A_1D    I89 @T6G_MB_LIB.T6G(SCH_1):PAGE422

R1051 Q_RES_0603LF-0,5%,1/4W,EMPTY,CS00006J900
     1 P0V9_CPU0_RT_2D @T6G_MB_LIB.T6G(SCH_1):P0V9_CPU0_RT_2D    I21 @T6G_MB_LIB.T6G(SCH_1):PAGE422
     2 P0V9_CPU0_RT2_2A_2D @T6G_MB_LIB.T6G(SCH_1):P0V9_CPU0_RT2_2A_2D    I21 @T6G_MB_LIB.T6G(SCH_1):PAGE422

R1052 Q_RES_0402LF-1K,1%,1/16W,EMPTY,CS21002FB06
     1 P3V3_AUX @T6G_MB_LIB.T6G(SCH_1):P3V3_AUX    I38 @T6G_MB_LIB.T6G(SCH_1):PAGE146
     2 P3V3_AUX_DSC_G1 @T6G_MB_LIB.T6G(SCH_1):P3V3_AUX_DSC_G1    I38 @T6G_MB_LIB.T6G(SCH_1):PAGE146

R1053 Q_RES_0603LF-0,5%,1/4W,CHIP,CS00006J900
     1 P0V9_CPU0_RT2_2A_2D @T6G_MB_LIB.T6G(SCH_1):P0V9_CPU0_RT2_2A_2D    I22 @T6G_MB_LIB.T6G(SCH_1):PAGE422
     2 P0V9_CPU0_RT2_2A @T6G_MB_LIB.T6G(SCH_1):P0V9_CPU0_RT2_2A    I22 @T6G_MB_LIB.T6G(SCH_1):PAGE422

R1054 Q_RES_0201LF-0,5%,1/20W,CHIP,CS00001JE10
     1 RST_RT_CPU0_P2_RESET_N @T6G_MB_LIB.T6G(SCH_1):RST_RT_CPU0_P2_RESET_N    I55 @T6G_MB_LIB.T6G(SCH_1):PAGE419
     2 RST_RT_CPU0_P2_RESET_R_N @T6G_MB_LIB.T6G(SCH_1):RST_RT_CPU0_P2_RESET_R_N    I55 @T6G_MB_LIB.T6G(SCH_1):PAGE419

R1055 Q_RES_0201LF-1K,1%,1/20W,CHIP,CS21001FE07
     1 P1V8_CPU0_RT_1D @T6G_MB_LIB.T6G(SCH_1):P1V8_CPU0_RT_1D    I67 @T6G_MB_LIB.T6G(SCH_1):PAGE419
     2 RT_CPU0_P2_ADDR3 @T6G_MB_LIB.T6G(SCH_1):RT_CPU0_P2_ADDR3    I67 @T6G_MB_LIB.T6G(SCH_1):PAGE419

R1056 Q_RES_0201LF-1K,1%,1/20W,EMPTY,CS21001FE07
     1 RT_CPU0_P2_ADDR3 @T6G_MB_LIB.T6G(SCH_1):RT_CPU0_P2_ADDR3    I65 @T6G_MB_LIB.T6G(SCH_1):PAGE419
     2    GND @T6G_MB_LIB.T6G(SCH_1):GND    I65 @T6G_MB_LIB.T6G(SCH_1):PAGE419

R1057 Q_RES_0201LF-1K,1%,1/20W,EMPTY,CS21001FE07
     1 P1V8_CPU0_RT_1D @T6G_MB_LIB.T6G(SCH_1):P1V8_CPU0_RT_1D    I68 @T6G_MB_LIB.T6G(SCH_1):PAGE419
     2 RT_CPU0_P2_ADDR2 @T6G_MB_LIB.T6G(SCH_1):RT_CPU0_P2_ADDR2    I68 @T6G_MB_LIB.T6G(SCH_1):PAGE419

R1058 Q_RES_0201LF-20K,1%,1/20W,CHIP,CS32001FE00
     1 RT_CPU0_P2_ADDR2 @T6G_MB_LIB.T6G(SCH_1):RT_CPU0_P2_ADDR2    I66 @T6G_MB_LIB.T6G(SCH_1):PAGE419
     2    GND @T6G_MB_LIB.T6G(SCH_1):GND    I66 @T6G_MB_LIB.T6G(SCH_1):PAGE419

R1059 Q_RES_0201LF-1K,1%,1/20W,EMPTY,CS21001FE07
     1 P1V8_CPU0_RT_1D @T6G_MB_LIB.T6G(SCH_1):P1V8_CPU0_RT_1D    I70 @T6G_MB_LIB.T6G(SCH_1):PAGE419
     2 RT_CPU0_P2_ADDR1 @T6G_MB_LIB.T6G(SCH_1):RT_CPU0_P2_ADDR1    I70 @T6G_MB_LIB.T6G(SCH_1):PAGE419

R1060 Q_RES_0201LF-1K,1%,1/20W,CHIP,CS21001FE07
     1 RT_CPU0_P2_ADDR1 @T6G_MB_LIB.T6G(SCH_1):RT_CPU0_P2_ADDR1    I69 @T6G_MB_LIB.T6G(SCH_1):PAGE419
     2    GND @T6G_MB_LIB.T6G(SCH_1):GND    I69 @T6G_MB_LIB.T6G(SCH_1):PAGE419

R1061 Q_RES_0201LF-10K,1%,1/20W,CHIP,CS31001FE17
     1 RST_RT_CPU0_P2_PERST_R_N @T6G_MB_LIB.T6G(SCH_1):RST_RT_CPU0_P2_PERST_R_N    I77 @T6G_MB_LIB.T6G(SCH_1):PAGE419
     2    GND @T6G_MB_LIB.T6G(SCH_1):GND    I77 @T6G_MB_LIB.T6G(SCH_1):PAGE419

R1062 Q_RES_0201LF-10K,1%,1/20W,CHIP,CS31001FE17
     1 RST_RT_CPU0_P2_RESET_R_N @T6G_MB_LIB.T6G(SCH_1):RST_RT_CPU0_P2_RESET_R_N    I76 @T6G_MB_LIB.T6G(SCH_1):PAGE419
     2    GND @T6G_MB_LIB.T6G(SCH_1):GND    I76 @T6G_MB_LIB.T6G(SCH_1):PAGE419

R1063 Q_RES_0201LF-4.7K,5%,1/20W,EMPTY,CS24701JE04
     1 P1V8_CPU0_RT_1D @T6G_MB_LIB.T6G(SCH_1):P1V8_CPU0_RT_1D     I5 @T6G_MB_LIB.T6G(SCH_1):PAGE419
     2 RT_CPU0_P2_SCAN_MODE @T6G_MB_LIB.T6G(SCH_1):RT_CPU0_P2_SCAN_MODE     I5 @T6G_MB_LIB.T6G(SCH_1):PAGE419

R1064 Q_RES_0201LF-200,1%,1/20W,CHIP,CS12001FE12
     1 RT_CPU0_P2_SCAN_MODE @T6G_MB_LIB.T6G(SCH_1):RT_CPU0_P2_SCAN_MODE   I102 @T6G_MB_LIB.T6G(SCH_1):PAGE419
     2    GND @T6G_MB_LIB.T6G(SCH_1):GND   I102 @T6G_MB_LIB.T6G(SCH_1):PAGE419

R1065 Q_RES_0201LF-4.7K,5%,1/20W,EMPTY,CS24701JE04
     1 P1V8_CPU0_RT_1D @T6G_MB_LIB.T6G(SCH_1):P1V8_CPU0_RT_1D    I78 @T6G_MB_LIB.T6G(SCH_1):PAGE419
     2 RST_RT_CPU0_P2_RESET_R_N @T6G_MB_LIB.T6G(SCH_1):RST_RT_CPU0_P2_RESET_R_N    I78 @T6G_MB_LIB.T6G(SCH_1):PAGE419

R1066 Q_RES_0201LF-4.7K,5%,1/20W,EMPTY,CS24701JE04
     1 P1V8_CPU0_RT_1D @T6G_MB_LIB.T6G(SCH_1):P1V8_CPU0_RT_1D    I42 @T6G_MB_LIB.T6G(SCH_1):PAGE419
     2 JTAG_TEST_MODE_RT_CPU0_P2 @T6G_MB_LIB.T6G(SCH_1):JTAG_TEST_MODE_RT_CPU0_P2    I42 @T6G_MB_LIB.T6G(SCH_1):PAGE419

R1067 Q_RES_0201LF-0,5%,1/20W,CHIP,CS00001JE10
     1 SMB_RT_CPU0_P2_R_SCL @T6G_MB_LIB.T6G(SCH_1):SMB_RT_CPU0_P2_R_SCL    I29 @T6G_MB_LIB.T6G(SCH_1):PAGE419
     2 SMB_RT_CPU0_P2_R2_SCL @T6G_MB_LIB.T6G(SCH_1):SMB_RT_CPU0_P2_R2_SCL    I29 @T6G_MB_LIB.T6G(SCH_1):PAGE419

R1068 Q_RES_0201LF-0,5%,1/20W,CHIP,CS00001JE10
     1 SMB_RT_CPU0_P2_R_SDA @T6G_MB_LIB.T6G(SCH_1):SMB_RT_CPU0_P2_R_SDA    I30 @T6G_MB_LIB.T6G(SCH_1):PAGE419
     2 SMB_RT_CPU0_P2_R2_SDA @T6G_MB_LIB.T6G(SCH_1):SMB_RT_CPU0_P2_R2_SDA    I30 @T6G_MB_LIB.T6G(SCH_1):PAGE419

R1069 Q_RES_0201LF-4.7K,5%,1/20W,EMPTY,CS24701JE04
     1 P1V8_CPU0_RT_1D @T6G_MB_LIB.T6G(SCH_1):P1V8_CPU0_RT_1D    I10 @T6G_MB_LIB.T6G(SCH_1):PAGE419
     2 GPIO2_RT_CPU0_P2 @T6G_MB_LIB.T6G(SCH_1):GPIO2_RT_CPU0_P2    I10 @T6G_MB_LIB.T6G(SCH_1):PAGE419

R1070 Q_RES_0201LF-10K,1%,1/20W,CHIP,CS31001FE17
     1 GPIO2_RT_CPU0_P2 @T6G_MB_LIB.T6G(SCH_1):GPIO2_RT_CPU0_P2     I7 @T6G_MB_LIB.T6G(SCH_1):PAGE419
     2    GND @T6G_MB_LIB.T6G(SCH_1):GND     I7 @T6G_MB_LIB.T6G(SCH_1):PAGE419

R1071 Q_RES_0402LF-4.7K,5%,1/16W,EMPTY,CS24702JB10
     1 P3V3_OCP_SFF_EN_R @T6G_MB_LIB.T6G(SCH_1):P3V3_OCP_SFF_EN_R    I38 @T6G_MB_LIB.T6G(SCH_1):PAGE82
     2 P3V3_AUX @T6G_MB_LIB.T6G(SCH_1):P3V3_AUX    I38 @T6G_MB_LIB.T6G(SCH_1):PAGE82

R1072 Q_RES_0201LF-10K,1%,1/20W,CHIP,CS31001FE17
     1 GPIO3_RT_CPU0_P2 @T6G_MB_LIB.T6G(SCH_1):GPIO3_RT_CPU0_P2     I8 @T6G_MB_LIB.T6G(SCH_1):PAGE419
     2    GND @T6G_MB_LIB.T6G(SCH_1):GND     I8 @T6G_MB_LIB.T6G(SCH_1):PAGE419

R1073 Q_RES_0201LF-4.7K,5%,1/20W,EMPTY,CS24701JE04
     1 P1V8_CPU0_RT_1D @T6G_MB_LIB.T6G(SCH_1):P1V8_CPU0_RT_1D    I11 @T6G_MB_LIB.T6G(SCH_1):PAGE419
     2 TEST0_RT_CPU0_P2 @T6G_MB_LIB.T6G(SCH_1):TEST0_RT_CPU0_P2    I11 @T6G_MB_LIB.T6G(SCH_1):PAGE419

R1074 Q_RES_0201LF-4.7K,5%,1/20W,CHIP,CS24701JE04
     1 TEST0_RT_CPU0_P2 @T6G_MB_LIB.T6G(SCH_1):TEST0_RT_CPU0_P2     I9 @T6G_MB_LIB.T6G(SCH_1):PAGE419
     2    GND @T6G_MB_LIB.T6G(SCH_1):GND     I9 @T6G_MB_LIB.T6G(SCH_1):PAGE419

R1075 Q_RES_0201LF-4.7K,5%,1/20W,EMPTY,CS24701JE04
     1 P1V8_CPU0_RT_1D @T6G_MB_LIB.T6G(SCH_1):P1V8_CPU0_RT_1D    I40 @T6G_MB_LIB.T6G(SCH_1):PAGE419
     2 TEST1_RT_CPU0_P2 @T6G_MB_LIB.T6G(SCH_1):TEST1_RT_CPU0_P2    I40 @T6G_MB_LIB.T6G(SCH_1):PAGE419

R1076 Q_RES_0201LF-4.7K,5%,1/20W,CHIP,CS24701JE04
     1 TEST1_RT_CPU0_P2 @T6G_MB_LIB.T6G(SCH_1):TEST1_RT_CPU0_P2    I36 @T6G_MB_LIB.T6G(SCH_1):PAGE419
     2    GND @T6G_MB_LIB.T6G(SCH_1):GND    I36 @T6G_MB_LIB.T6G(SCH_1):PAGE419

R1077 Q_RES_0201LF-4.7K,5%,1/20W,EMPTY,CS24701JE04
     1 P1V8_CPU0_RT_1D @T6G_MB_LIB.T6G(SCH_1):P1V8_CPU0_RT_1D    I41 @T6G_MB_LIB.T6G(SCH_1):PAGE419
     2 TEST2_RT_CPU0_P2 @T6G_MB_LIB.T6G(SCH_1):TEST2_RT_CPU0_P2    I41 @T6G_MB_LIB.T6G(SCH_1):PAGE419

R1078 Q_RES_0201LF-4.7K,5%,1/20W,CHIP,CS24701JE04
     1 TEST2_RT_CPU0_P2 @T6G_MB_LIB.T6G(SCH_1):TEST2_RT_CPU0_P2    I37 @T6G_MB_LIB.T6G(SCH_1):PAGE419
     2    GND @T6G_MB_LIB.T6G(SCH_1):GND    I37 @T6G_MB_LIB.T6G(SCH_1):PAGE419

R1079 Q_RES_0201LF-4.7K,5%,1/20W,CHIP,CS24701JE04
     1 JTAG_TEST_MODE_RT_CPU0_P2 @T6G_MB_LIB.T6G(SCH_1):JTAG_TEST_MODE_RT_CPU0_P2    I39 @T6G_MB_LIB.T6G(SCH_1):PAGE419
     2    GND @T6G_MB_LIB.T6G(SCH_1):GND    I39 @T6G_MB_LIB.T6G(SCH_1):PAGE419

R1080 Q_RES_0201LF-4.7K,5%,1/20W,CHIP,CS24701JE04
     1 P1V8_CPU0_RT_1D @T6G_MB_LIB.T6G(SCH_1):P1V8_CPU0_RT_1D    I51 @T6G_MB_LIB.T6G(SCH_1):PAGE419
     2 MODE_RT_CPU0_P2 @T6G_MB_LIB.T6G(SCH_1):MODE_RT_CPU0_P2    I51 @T6G_MB_LIB.T6G(SCH_1):PAGE419

R1081 Q_RES_0201LF-1K,1%,1/20W,EMPTY,CS21001FE07
     1 P1V8_CPU0_RT_1D @T6G_MB_LIB.T6G(SCH_1):P1V8_CPU0_RT_1D    I19 @T6G_MB_LIB.T6G(SCH_1):PAGE420
     2 RT_CPU0_P2_VQPS @T6G_MB_LIB.T6G(SCH_1):RT_CPU0_P2_VQPS    I19 @T6G_MB_LIB.T6G(SCH_1):PAGE420

R1082 Q_RES_0201LF-200,1%,1/20W,CHIP,CS12001FE12
     1 RT_CPU0_P2_VQPS @T6G_MB_LIB.T6G(SCH_1):RT_CPU0_P2_VQPS    I18 @T6G_MB_LIB.T6G(SCH_1):PAGE420
     2    GND @T6G_MB_LIB.T6G(SCH_1):GND    I18 @T6G_MB_LIB.T6G(SCH_1):PAGE420

R1083 Q_RES_0201LF-0,5%,1/20W,CHIP,CS00001JE10
     1 NCF_CPU0_P2_GND @T6G_MB_LIB.T6G(SCH_1):NCF_CPU0_P2_GND    I13 @T6G_MB_LIB.T6G(SCH_1):PAGE420
     2    GND @T6G_MB_LIB.T6G(SCH_1):GND    I13 @T6G_MB_LIB.T6G(SCH_1):PAGE420

R1084 Q_RES_0201LF-0,5%,1/20W,CHIP,CS00001JE10
     1 NCF_A1_CPU0_P2_GND @T6G_MB_LIB.T6G(SCH_1):NCF_A1_CPU0_P2_GND    I14 @T6G_MB_LIB.T6G(SCH_1):PAGE420
     2    GND @T6G_MB_LIB.T6G(SCH_1):GND    I14 @T6G_MB_LIB.T6G(SCH_1):PAGE420

R1085 Q_RES_0201LF-1K,1%,1/20W,CHIP,CS21001FE07
     1 U16_E2 @T6G_MB_LIB.T6G(SCH_1):U16_E2    I18 @T6G_MB_LIB.T6G(SCH_1):PAGE421
     2    GND @T6G_MB_LIB.T6G(SCH_1):GND    I18 @T6G_MB_LIB.T6G(SCH_1):PAGE421

R1086 Q_RES_0402LF-0,5%,1/16W,EMPTY,CS00002JB13
     1 P1V8_CPU0_RT3_1A_1D @T6G_MB_LIB.T6G(SCH_1):P1V8_CPU0_RT3_1A_1D     I2 @T6G_MB_LIB.T6G(SCH_1):PAGE433
     2 P1V8_CPU0_RT3_1A @T6G_MB_LIB.T6G(SCH_1):P1V8_CPU0_RT3_1A     I2 @T6G_MB_LIB.T6G(SCH_1):PAGE433

R1087 Q_RES_0402LF-0,5%,1/16W,EMPTY,CS00002JB13
     1 P1V8_CPU0_RT3_1A_1D @T6G_MB_LIB.T6G(SCH_1):P1V8_CPU0_RT3_1A_1D     I1 @T6G_MB_LIB.T6G(SCH_1):PAGE433
     2 P1V8_CPU0_RT3_1A @T6G_MB_LIB.T6G(SCH_1):P1V8_CPU0_RT3_1A     I1 @T6G_MB_LIB.T6G(SCH_1):PAGE433

R1088 Q_RES_0201LF-0,5%,1/20W,CHIP,CS00001JE10
     1 RST_RT_CPU0_P3_PERST_N @T6G_MB_LIB.T6G(SCH_1):RST_RT_CPU0_P3_PERST_N    I56 @T6G_MB_LIB.T6G(SCH_1):PAGE430
     2 RST_RT_CPU0_P3_PERST_R_N @T6G_MB_LIB.T6G(SCH_1):RST_RT_CPU0_P3_PERST_R_N    I56 @T6G_MB_LIB.T6G(SCH_1):PAGE430

R1089 Q_RES_0402LF-2.2K,5%,1/16W,CHIP,CS22202JB07
     1 P3V3_AUX @T6G_MB_LIB.T6G(SCH_1):P3V3_AUX    I37 @T6G_MB_LIB.T6G(SCH_1):PAGE252
     2 SMB_SENSOR_M2_P1_3V3AUX_SCL @T6G_MB_LIB.T6G(SCH_1):SMB_SENSOR_M2_P1_3V3AUX_SCL    I37 @T6G_MB_LIB.T6G(SCH_1):PAGE252

R1090 Q_RES_0402LF-2.2K,5%,1/16W,CHIP,CS22202JB07
     1 P3V3_AUX @T6G_MB_LIB.T6G(SCH_1):P3V3_AUX    I38 @T6G_MB_LIB.T6G(SCH_1):PAGE252
     2 SMB_SENSOR_M2_P1_3V3AUX_SDA @T6G_MB_LIB.T6G(SCH_1):SMB_SENSOR_M2_P1_3V3AUX_SDA    I38 @T6G_MB_LIB.T6G(SCH_1):PAGE252

R1091 Q_RES_0201LF-4.7K,5%,1/20W,EMPTY,CS24701JE04
     1 MODE_RT_CPU0_P3 @T6G_MB_LIB.T6G(SCH_1):MODE_RT_CPU0_P3    I50 @T6G_MB_LIB.T6G(SCH_1):PAGE430
     2    GND @T6G_MB_LIB.T6G(SCH_1):GND    I50 @T6G_MB_LIB.T6G(SCH_1):PAGE430

R1092 Q_RES_0402LF-10M,1%,1/16W,EMPTY,CS61002FB02
     1 P3V3_AUX_DSC_G1 @T6G_MB_LIB.T6G(SCH_1):P3V3_AUX_DSC_G1    I39 @T6G_MB_LIB.T6G(SCH_1):PAGE146
     2    GND @T6G_MB_LIB.T6G(SCH_1):GND    I39 @T6G_MB_LIB.T6G(SCH_1):PAGE146

R1093 Q_RES_0402LF-0,5%,1/16W,EMPTY,CS00002JB13
     1 P1V8_CPU0_RT_1D @T6G_MB_LIB.T6G(SCH_1):P1V8_CPU0_RT_1D    I89 @T6G_MB_LIB.T6G(SCH_1):PAGE433
     2 P1V8_CPU0_RT3_1A_1D @T6G_MB_LIB.T6G(SCH_1):P1V8_CPU0_RT3_1A_1D    I89 @T6G_MB_LIB.T6G(SCH_1):PAGE433

R1094 Q_RES_0603LF-0,5%,1/4W,EMPTY,CS00006J900
     1 P0V9_CPU0_RT_2D @T6G_MB_LIB.T6G(SCH_1):P0V9_CPU0_RT_2D     I7 @T6G_MB_LIB.T6G(SCH_1):PAGE433
     2 P0V9_CPU0_RT3_2A_2D @T6G_MB_LIB.T6G(SCH_1):P0V9_CPU0_RT3_2A_2D     I7 @T6G_MB_LIB.T6G(SCH_1):PAGE433

R1095 Q_RES_0603LF-0,5%,1/4W,CHIP,CS00006J900
     1 P0V9_CPU0_RT3_2A_2D @T6G_MB_LIB.T6G(SCH_1):P0V9_CPU0_RT3_2A_2D    I36 @T6G_MB_LIB.T6G(SCH_1):PAGE433
     2 P0V9_CPU0_RT3_2A @T6G_MB_LIB.T6G(SCH_1):P0V9_CPU0_RT3_2A    I36 @T6G_MB_LIB.T6G(SCH_1):PAGE433

R1096 Q_RES_0201LF-0,5%,1/20W,CHIP,CS00001JE10
     1 RST_RT_CPU0_P3_RESET_N @T6G_MB_LIB.T6G(SCH_1):RST_RT_CPU0_P3_RESET_N    I55 @T6G_MB_LIB.T6G(SCH_1):PAGE430
     2 RST_RT_CPU0_P3_RESET_R_N @T6G_MB_LIB.T6G(SCH_1):RST_RT_CPU0_P3_RESET_R_N    I55 @T6G_MB_LIB.T6G(SCH_1):PAGE430

R1097 Q_RES_0201LF-1K,1%,1/20W,CHIP,CS21001FE07
     1 P1V8_CPU0_RT_1D @T6G_MB_LIB.T6G(SCH_1):P1V8_CPU0_RT_1D    I67 @T6G_MB_LIB.T6G(SCH_1):PAGE430
     2 RT_CPU0_P3_ADDR3 @T6G_MB_LIB.T6G(SCH_1):RT_CPU0_P3_ADDR3    I67 @T6G_MB_LIB.T6G(SCH_1):PAGE430

R1098 Q_RES_0201LF-1K,1%,1/20W,EMPTY,CS21001FE07
     1 RT_CPU0_P3_ADDR3 @T6G_MB_LIB.T6G(SCH_1):RT_CPU0_P3_ADDR3    I65 @T6G_MB_LIB.T6G(SCH_1):PAGE430
     2    GND @T6G_MB_LIB.T6G(SCH_1):GND    I65 @T6G_MB_LIB.T6G(SCH_1):PAGE430

R1099 Q_RES_0201LF-1K,1%,1/20W,EMPTY,CS21001FE07
     1 P1V8_CPU0_RT_1D @T6G_MB_LIB.T6G(SCH_1):P1V8_CPU0_RT_1D    I68 @T6G_MB_LIB.T6G(SCH_1):PAGE430
     2 RT_CPU0_P3_ADDR2 @T6G_MB_LIB.T6G(SCH_1):RT_CPU0_P3_ADDR2    I68 @T6G_MB_LIB.T6G(SCH_1):PAGE430

R1100 Q_RES_0201LF-20K,1%,1/20W,CHIP,CS32001FE00
     1 RT_CPU0_P3_ADDR2 @T6G_MB_LIB.T6G(SCH_1):RT_CPU0_P3_ADDR2    I66 @T6G_MB_LIB.T6G(SCH_1):PAGE430
     2    GND @T6G_MB_LIB.T6G(SCH_1):GND    I66 @T6G_MB_LIB.T6G(SCH_1):PAGE430

R1101 Q_RES_0201LF-1K,1%,1/20W,EMPTY,CS21001FE07
     1 P1V8_CPU0_RT_1D @T6G_MB_LIB.T6G(SCH_1):P1V8_CPU0_RT_1D    I70 @T6G_MB_LIB.T6G(SCH_1):PAGE430
     2 RT_CPU0_P3_ADDR1 @T6G_MB_LIB.T6G(SCH_1):RT_CPU0_P3_ADDR1    I70 @T6G_MB_LIB.T6G(SCH_1):PAGE430

R1102 Q_RES_0201LF-1K,1%,1/20W,CHIP,CS21001FE07
     1 RT_CPU0_P3_ADDR1 @T6G_MB_LIB.T6G(SCH_1):RT_CPU0_P3_ADDR1    I69 @T6G_MB_LIB.T6G(SCH_1):PAGE430
     2    GND @T6G_MB_LIB.T6G(SCH_1):GND    I69 @T6G_MB_LIB.T6G(SCH_1):PAGE430

R1103 Q_RES_0201LF-10K,1%,1/20W,CHIP,CS31001FE17
     1 RST_RT_CPU0_P3_PERST_R_N @T6G_MB_LIB.T6G(SCH_1):RST_RT_CPU0_P3_PERST_R_N    I74 @T6G_MB_LIB.T6G(SCH_1):PAGE430
     2    GND @T6G_MB_LIB.T6G(SCH_1):GND    I74 @T6G_MB_LIB.T6G(SCH_1):PAGE430

R1104 Q_RES_0201LF-10K,1%,1/20W,CHIP,CS31001FE17
     1 RST_RT_CPU0_P3_RESET_R_N @T6G_MB_LIB.T6G(SCH_1):RST_RT_CPU0_P3_RESET_R_N    I75 @T6G_MB_LIB.T6G(SCH_1):PAGE430
     2    GND @T6G_MB_LIB.T6G(SCH_1):GND    I75 @T6G_MB_LIB.T6G(SCH_1):PAGE430

R1105 Q_RES_0201LF-4.7K,5%,1/20W,EMPTY,CS24701JE04
     1 P1V8_CPU0_RT_1D @T6G_MB_LIB.T6G(SCH_1):P1V8_CPU0_RT_1D     I5 @T6G_MB_LIB.T6G(SCH_1):PAGE430
     2 RT_CPU0_P3_SCAN_MODE @T6G_MB_LIB.T6G(SCH_1):RT_CPU0_P3_SCAN_MODE     I5 @T6G_MB_LIB.T6G(SCH_1):PAGE430

R1106 Q_RES_0201LF-200,1%,1/20W,CHIP,CS12001FE12
     1 RT_CPU0_P3_SCAN_MODE @T6G_MB_LIB.T6G(SCH_1):RT_CPU0_P3_SCAN_MODE   I102 @T6G_MB_LIB.T6G(SCH_1):PAGE430
     2    GND @T6G_MB_LIB.T6G(SCH_1):GND   I102 @T6G_MB_LIB.T6G(SCH_1):PAGE430

R1107 Q_RES_0201LF-4.7K,5%,1/20W,EMPTY,CS24701JE04
     1 P1V8_CPU0_RT_1D @T6G_MB_LIB.T6G(SCH_1):P1V8_CPU0_RT_1D    I79 @T6G_MB_LIB.T6G(SCH_1):PAGE430
     2 RST_RT_CPU0_P3_RESET_R_N @T6G_MB_LIB.T6G(SCH_1):RST_RT_CPU0_P3_RESET_R_N    I79 @T6G_MB_LIB.T6G(SCH_1):PAGE430

R1108 Q_RES_0201LF-4.7K,5%,1/20W,EMPTY,CS24701JE04
     1 P1V8_CPU0_RT_1D @T6G_MB_LIB.T6G(SCH_1):P1V8_CPU0_RT_1D    I42 @T6G_MB_LIB.T6G(SCH_1):PAGE430
     2 JTAG_TEST_MODE_RT_CPU0_P3 @T6G_MB_LIB.T6G(SCH_1):JTAG_TEST_MODE_RT_CPU0_P3    I42 @T6G_MB_LIB.T6G(SCH_1):PAGE430

R1109 Q_RES_0201LF-0,5%,1/20W,CHIP,CS00001JE10
     1 SMB_RT_CPU0_P3_R_SCL @T6G_MB_LIB.T6G(SCH_1):SMB_RT_CPU0_P3_R_SCL    I32 @T6G_MB_LIB.T6G(SCH_1):PAGE430
     2 SMB_RT_CPU0_P3_R2_SCL @T6G_MB_LIB.T6G(SCH_1):SMB_RT_CPU0_P3_R2_SCL    I32 @T6G_MB_LIB.T6G(SCH_1):PAGE430

R1110 Q_RES_0201LF-0,5%,1/20W,CHIP,CS00001JE10
     1 SMB_RT_CPU0_P3_R_SDA @T6G_MB_LIB.T6G(SCH_1):SMB_RT_CPU0_P3_R_SDA    I33 @T6G_MB_LIB.T6G(SCH_1):PAGE430
     2 SMB_RT_CPU0_P3_R2_SDA @T6G_MB_LIB.T6G(SCH_1):SMB_RT_CPU0_P3_R2_SDA    I33 @T6G_MB_LIB.T6G(SCH_1):PAGE430

R1111 Q_RES_0201LF-4.7K,5%,1/20W,EMPTY,CS24701JE04
     1 P1V8_CPU0_RT_1D @T6G_MB_LIB.T6G(SCH_1):P1V8_CPU0_RT_1D    I10 @T6G_MB_LIB.T6G(SCH_1):PAGE430
     2 GPIO2_RT_CPU0_P3 @T6G_MB_LIB.T6G(SCH_1):GPIO2_RT_CPU0_P3    I10 @T6G_MB_LIB.T6G(SCH_1):PAGE430

R1112 Q_RES_0201LF-10K,1%,1/20W,CHIP,CS31001FE17
     1 GPIO2_RT_CPU0_P3 @T6G_MB_LIB.T6G(SCH_1):GPIO2_RT_CPU0_P3     I7 @T6G_MB_LIB.T6G(SCH_1):PAGE430
     2    GND @T6G_MB_LIB.T6G(SCH_1):GND     I7 @T6G_MB_LIB.T6G(SCH_1):PAGE430

R1113 Q_RES_0201LF-10K,1%,1/20W,CHIP,CS31001FE17
     1 GPIO3_RT_CPU0_P3 @T6G_MB_LIB.T6G(SCH_1):GPIO3_RT_CPU0_P3     I8 @T6G_MB_LIB.T6G(SCH_1):PAGE430
     2    GND @T6G_MB_LIB.T6G(SCH_1):GND     I8 @T6G_MB_LIB.T6G(SCH_1):PAGE430

R1114 Q_RES_0201LF-4.7K,5%,1/20W,EMPTY,CS24701JE04
     1 P1V8_CPU0_RT_1D @T6G_MB_LIB.T6G(SCH_1):P1V8_CPU0_RT_1D    I11 @T6G_MB_LIB.T6G(SCH_1):PAGE430
     2 TEST0_RT_CPU0_P3 @T6G_MB_LIB.T6G(SCH_1):TEST0_RT_CPU0_P3    I11 @T6G_MB_LIB.T6G(SCH_1):PAGE430

R1115 Q_RES_0201LF-4.7K,5%,1/20W,CHIP,CS24701JE04
     1 TEST0_RT_CPU0_P3 @T6G_MB_LIB.T6G(SCH_1):TEST0_RT_CPU0_P3     I9 @T6G_MB_LIB.T6G(SCH_1):PAGE430
     2    GND @T6G_MB_LIB.T6G(SCH_1):GND     I9 @T6G_MB_LIB.T6G(SCH_1):PAGE430

R1116 Q_RES_0201LF-4.7K,5%,1/20W,EMPTY,CS24701JE04
     1 P1V8_CPU0_RT_1D @T6G_MB_LIB.T6G(SCH_1):P1V8_CPU0_RT_1D    I40 @T6G_MB_LIB.T6G(SCH_1):PAGE430
     2 TEST1_RT_CPU0_P3 @T6G_MB_LIB.T6G(SCH_1):TEST1_RT_CPU0_P3    I40 @T6G_MB_LIB.T6G(SCH_1):PAGE430

R1117 Q_RES_0402LF-6.19K,1%,1/16W,CHIP,CS26192FB03
     1 MB0_P12V_STBY_PWRGD @T6G_MB_LIB.T6G(SCH_1):MB0_P12V_STBY_PWRGD    I22 @T6G_MB_LIB.T6G(SCH_1):PAGE267
     2 AGND_HSC @T6G_MB_LIB.T6G(SCH_1):AGND_HSC    I22 @T6G_MB_LIB.T6G(SCH_1):PAGE267

R1118 Q_RES_0201LF-4.7K,5%,1/20W,CHIP,CS24701JE04
     1 TEST1_RT_CPU0_P3 @T6G_MB_LIB.T6G(SCH_1):TEST1_RT_CPU0_P3    I36 @T6G_MB_LIB.T6G(SCH_1):PAGE430
     2    GND @T6G_MB_LIB.T6G(SCH_1):GND    I36 @T6G_MB_LIB.T6G(SCH_1):PAGE430

R1119 Q_RES_0201LF-4.7K,5%,1/20W,EMPTY,CS24701JE04
     1 P1V8_CPU0_RT_1D @T6G_MB_LIB.T6G(SCH_1):P1V8_CPU0_RT_1D    I41 @T6G_MB_LIB.T6G(SCH_1):PAGE430
     2 TEST2_RT_CPU0_P3 @T6G_MB_LIB.T6G(SCH_1):TEST2_RT_CPU0_P3    I41 @T6G_MB_LIB.T6G(SCH_1):PAGE430

R1120 Q_RES_0201LF-4.7K,5%,1/20W,CHIP,CS24701JE04
     1 TEST2_RT_CPU0_P3 @T6G_MB_LIB.T6G(SCH_1):TEST2_RT_CPU0_P3    I37 @T6G_MB_LIB.T6G(SCH_1):PAGE430
     2    GND @T6G_MB_LIB.T6G(SCH_1):GND    I37 @T6G_MB_LIB.T6G(SCH_1):PAGE430

R1121 Q_RES_0201LF-4.7K,5%,1/20W,CHIP,CS24701JE04
     1 JTAG_TEST_MODE_RT_CPU0_P3 @T6G_MB_LIB.T6G(SCH_1):JTAG_TEST_MODE_RT_CPU0_P3    I39 @T6G_MB_LIB.T6G(SCH_1):PAGE430
     2    GND @T6G_MB_LIB.T6G(SCH_1):GND    I39 @T6G_MB_LIB.T6G(SCH_1):PAGE430

R1122 Q_RES_0201LF-4.7K,5%,1/20W,CHIP,CS24701JE04
     1 P1V8_CPU0_RT_1D @T6G_MB_LIB.T6G(SCH_1):P1V8_CPU0_RT_1D    I51 @T6G_MB_LIB.T6G(SCH_1):PAGE430
     2 MODE_RT_CPU0_P3 @T6G_MB_LIB.T6G(SCH_1):MODE_RT_CPU0_P3    I51 @T6G_MB_LIB.T6G(SCH_1):PAGE430

R1123 Q_RES_0201LF-1K,1%,1/20W,EMPTY,CS21001FE07
     1 P1V8_CPU0_RT_1D @T6G_MB_LIB.T6G(SCH_1):P1V8_CPU0_RT_1D    I19 @T6G_MB_LIB.T6G(SCH_1):PAGE431
     2 RT_CPU0_P3_VQPS @T6G_MB_LIB.T6G(SCH_1):RT_CPU0_P3_VQPS    I19 @T6G_MB_LIB.T6G(SCH_1):PAGE431

R1124 Q_RES_0201LF-200,1%,1/20W,CHIP,CS12001FE12
     1 RT_CPU0_P3_VQPS @T6G_MB_LIB.T6G(SCH_1):RT_CPU0_P3_VQPS    I18 @T6G_MB_LIB.T6G(SCH_1):PAGE431
     2    GND @T6G_MB_LIB.T6G(SCH_1):GND    I18 @T6G_MB_LIB.T6G(SCH_1):PAGE431

R1125 Q_RES_0201LF-0,5%,1/20W,CHIP,CS00001JE10
     1 NCF_CPU0_P3_GND @T6G_MB_LIB.T6G(SCH_1):NCF_CPU0_P3_GND    I13 @T6G_MB_LIB.T6G(SCH_1):PAGE431
     2    GND @T6G_MB_LIB.T6G(SCH_1):GND    I13 @T6G_MB_LIB.T6G(SCH_1):PAGE431

R1126 Q_RES_0201LF-0,5%,1/20W,CHIP,CS00001JE10
     1 NCF_A1_CPU0_P3_GND @T6G_MB_LIB.T6G(SCH_1):NCF_A1_CPU0_P3_GND    I14 @T6G_MB_LIB.T6G(SCH_1):PAGE431
     2    GND @T6G_MB_LIB.T6G(SCH_1):GND    I14 @T6G_MB_LIB.T6G(SCH_1):PAGE431

R1127 Q_RES_0201LF-1K,1%,1/20W,CHIP,CS21001FE07
     1 U17_E2 @T6G_MB_LIB.T6G(SCH_1):U17_E2    I18 @T6G_MB_LIB.T6G(SCH_1):PAGE432
     2    GND @T6G_MB_LIB.T6G(SCH_1):GND    I18 @T6G_MB_LIB.T6G(SCH_1):PAGE432

R1128 Q_RES_0402LF-1K,1%,1/16W,CHIP,CS21002FB06
     1 P3V3_AUX @T6G_MB_LIB.T6G(SCH_1):P3V3_AUX    I34 @T6G_MB_LIB.T6G(SCH_1):PAGE340
     2 HP_LVC3_OCP_SFF_PRSNT2 @T6G_MB_LIB.T6G(SCH_1):HP_LVC3_OCP_SFF_PRSNT2    I34 @T6G_MB_LIB.T6G(SCH_1):PAGE340

R1129 Q_RES_0402LF-0,5%,1/16W,CHIP,CS00002JB13
     1 HP_LVC3_OCP_V3_1_P12V_PWRGD @T6G_MB_LIB.T6G(SCH_1):HP_LVC3_OCP_V3_1_P12V_PWRGD    I57 @T6G_MB_LIB.T6G(SCH_1):PAGE340
     2 HP_LVC3_OCP_V3_1_P12V_R_PWRGD @T6G_MB_LIB.T6G(SCH_1):HP_LVC3_OCP_V3_1_P12V_R_PWRGD    I57 @T6G_MB_LIB.T6G(SCH_1):PAGE340

R1130 Q_RES_0402LF-0,5%,1/16W,EMPTY,CS00002JB13
     1 P12V_OCP_SFF_EN_R @T6G_MB_LIB.T6G(SCH_1):P12V_OCP_SFF_EN_R    I49 @T6G_MB_LIB.T6G(SCH_1):PAGE340
     2 P12V_OCP_SFF_EN_R3 @T6G_MB_LIB.T6G(SCH_1):P12V_OCP_SFF_EN_R3    I49 @T6G_MB_LIB.T6G(SCH_1):PAGE340

R1131 Q_RES_0402LF-1K,1%,1/16W,CHIP,CS21002FB06
     1 P3V3_AUX @T6G_MB_LIB.T6G(SCH_1):P3V3_AUX    I44 @T6G_MB_LIB.T6G(SCH_1):PAGE340
     2 P12V_OCP_SFF_EN_R3 @T6G_MB_LIB.T6G(SCH_1):P12V_OCP_SFF_EN_R3    I44 @T6G_MB_LIB.T6G(SCH_1):PAGE340

R1132 Q_RES_0402LF-0,5%,1/16W,CHIP,CS00002JB13
     1 P12V_OCP_V3_1_PLD_R_PWRGD @T6G_MB_LIB.T6G(SCH_1):P12V_OCP_V3_1_PLD_R_PWRGD    I58 @T6G_MB_LIB.T6G(SCH_1):PAGE340
     2 P12V_OCP_V3_1_PLD_PWRGD @T6G_MB_LIB.T6G(SCH_1):P12V_OCP_V3_1_PLD_PWRGD    I58 @T6G_MB_LIB.T6G(SCH_1):PAGE340

R1133 Q_RES_0402LF-1K,1%,1/16W,CHIP,CS21002FB06
     1 P3V3_AUX @T6G_MB_LIB.T6G(SCH_1):P3V3_AUX    I61 @T6G_MB_LIB.T6G(SCH_1):PAGE340
     2 P12V_OCP_V3_1_PLD_PWRGD @T6G_MB_LIB.T6G(SCH_1):P12V_OCP_V3_1_PLD_PWRGD    I61 @T6G_MB_LIB.T6G(SCH_1):PAGE340

R1134 Q_RES_0402LF-0,5%,1/16W,CHIP,CS00002JB13
     1 P12V_OCP_SFF_BUF_EN @T6G_MB_LIB.T6G(SCH_1):P12V_OCP_SFF_BUF_EN    I47 @T6G_MB_LIB.T6G(SCH_1):PAGE340
     2 P12V_OCP_SFF_BUF_EN_R @T6G_MB_LIB.T6G(SCH_1):P12V_OCP_SFF_BUF_EN_R    I47 @T6G_MB_LIB.T6G(SCH_1):PAGE340

R1135 Q_RES_0402LF-0,5%,1/16W,EMPTY,CS00002JB13
     1 HP_LVC3_OCP_V3_1_R_EN @T6G_MB_LIB.T6G(SCH_1):HP_LVC3_OCP_V3_1_R_EN    I41 @T6G_MB_LIB.T6G(SCH_1):PAGE248
     2 HP_LVC3_OCP_V3_1_P12V_PWRGD @T6G_MB_LIB.T6G(SCH_1):HP_LVC3_OCP_V3_1_P12V_PWRGD    I41 @T6G_MB_LIB.T6G(SCH_1):PAGE248

R1136 Q_RES_0402LF-0,5%,1/16W,EMPTY,CS00002JB13
     1 HP_LVC3_OCP_V3_1_P12V_PWRGD @T6G_MB_LIB.T6G(SCH_1):HP_LVC3_OCP_V3_1_P12V_PWRGD   I133 @T6G_MB_LIB.T6G(SCH_1):PAGE338
     2 P3V3_OCP_EN_1_R @T6G_MB_LIB.T6G(SCH_1):P3V3_OCP_EN_1_R   I133 @T6G_MB_LIB.T6G(SCH_1):PAGE338

R1137 Q_RES_0402LF-0,5%,1/16W,EMPTY,CS00002JB13
     1 HP_LVC3_OCP_V3_1_P12V_PWRGD @T6G_MB_LIB.T6G(SCH_1):HP_LVC3_OCP_V3_1_P12V_PWRGD   I135 @T6G_MB_LIB.T6G(SCH_1):PAGE339
     2 P3V3_OCP_EN_1_R2 @T6G_MB_LIB.T6G(SCH_1):P3V3_OCP_EN_1_R2   I135 @T6G_MB_LIB.T6G(SCH_1):PAGE339

R1138 Q_RES_0402LF-10K,1%,1/16W,CHIP,CS31002FB08
     1 P3V3_AUX @T6G_MB_LIB.T6G(SCH_1):P3V3_AUX     I1 @T6G_MB_LIB.T6G(SCH_1):PAGE337
     2 CLK_50M_EN @T6G_MB_LIB.T6G(SCH_1):CLK_50M_EN     I1 @T6G_MB_LIB.T6G(SCH_1):PAGE337

R1139 Q_RES_0402LF-0,5%,1/16W,CHIP,CS00002JB13
     1 CLK_50M_RMII @T6G_MB_LIB.T6G(SCH_1):CLK_50M_RMII     I7 @T6G_MB_LIB.T6G(SCH_1):PAGE337
     2 CLK_50M_RMII_R @T6G_MB_LIB.T6G(SCH_1):CLK_50M_RMII_R     I7 @T6G_MB_LIB.T6G(SCH_1):PAGE337

R1140 Q_RES_0402LF-27.4,1%,1/16W,CHIP,CS02742FB03
     1 CLK_50M_BMC_MAC_R @T6G_MB_LIB.T6G(SCH_1):CLK_50M_BMC_MAC_R    I22 @T6G_MB_LIB.T6G(SCH_1):PAGE337
     2 CLK_50M_RMII_BMC_OCP @T6G_MB_LIB.T6G(SCH_1):CLK_50M_RMII_BMC_OCP    I22 @T6G_MB_LIB.T6G(SCH_1):PAGE337

R1141 Q_RES_0402LF-27.4,1%,1/16W,CHIP,CS02742FB03
     1 CLK_50M_NCSI_OCP_1 @T6G_MB_LIB.T6G(SCH_1):CLK_50M_NCSI_OCP_1    I21 @T6G_MB_LIB.T6G(SCH_1):PAGE337
     2 CLK_50M_NCSI_OCP_SFF @T6G_MB_LIB.T6G(SCH_1):CLK_50M_NCSI_OCP_SFF    I21 @T6G_MB_LIB.T6G(SCH_1):PAGE337

R1142 Q_RES_0402LF-0,5%,1/16W,CHIP,CS00002JB13
     1 OCP_V3_1_P3V3_PWRGD @T6G_MB_LIB.T6G(SCH_1):OCP_V3_1_P3V3_PWRGD    I71 @T6G_MB_LIB.T6G(SCH_1):PAGE340
     2 OCP_V3_1_P3V3_R2_PWRGD @T6G_MB_LIB.T6G(SCH_1):OCP_V3_1_P3V3_R2_PWRGD    I71 @T6G_MB_LIB.T6G(SCH_1):PAGE340

R1143 Q_RES_0402LF-0,5%,1/16W,CHIP,CS00002JB13
     1 OCP_V3_1_P3V3_PLD_PWRGD @T6G_MB_LIB.T6G(SCH_1):OCP_V3_1_P3V3_PLD_PWRGD    I65 @T6G_MB_LIB.T6G(SCH_1):PAGE340
     2 OCP_V3_1_P3V3_PLD_R_PWRGD @T6G_MB_LIB.T6G(SCH_1):OCP_V3_1_P3V3_PLD_R_PWRGD    I65 @T6G_MB_LIB.T6G(SCH_1):PAGE340

R1144 Q_RES_0402LF-1K,1%,1/16W,CHIP,CS21002FB06
     1 P3V3_AUX @T6G_MB_LIB.T6G(SCH_1):P3V3_AUX    I64 @T6G_MB_LIB.T6G(SCH_1):PAGE340
     2 OCP_V3_1_P3V3_PLD_R_PWRGD @T6G_MB_LIB.T6G(SCH_1):OCP_V3_1_P3V3_PLD_R_PWRGD    I64 @T6G_MB_LIB.T6G(SCH_1):PAGE340

R1145 Q_RES_0402LF-10K,5%,1/16W,EMPTY,CS31002JB08
     1 P3V3_AUX @T6G_MB_LIB.T6G(SCH_1):P3V3_AUX    I76 @T6G_MB_LIB.T6G(SCH_1):PAGE340
     2 OCP_SFF_AUX_PWR_EN @T6G_MB_LIB.T6G(SCH_1):OCP_SFF_AUX_PWR_EN    I76 @T6G_MB_LIB.T6G(SCH_1):PAGE340

R1146 Q_RES_0402LF-0,5%,1/16W,EMPTY,CS00002JB13
     1 OCP_V3_2_AUX_PWR_EN_R2 @T6G_MB_LIB.T6G(SCH_1):OCP_V3_2_AUX_PWR_EN_R2    I41 @T6G_MB_LIB.T6G(SCH_1):PAGE257
     2 HP_LVC3_OCP_V3_2_PWRGD_R1 @T6G_MB_LIB.T6G(SCH_1):HP_LVC3_OCP_V3_2_PWRGD_R1    I41 @T6G_MB_LIB.T6G(SCH_1):PAGE257

R1147 Q_RES_0402LF-0,5%,1/16W,EMPTY,CS00002JB13
     1 OCP_V3_2_AUX_PWR_EN_R2 @T6G_MB_LIB.T6G(SCH_1):OCP_V3_2_AUX_PWR_EN_R2    I39 @T6G_MB_LIB.T6G(SCH_1):PAGE257
     2 FM_OCP_V3_2_AUX_PWR_R_EN @T6G_MB_LIB.T6G(SCH_1):FM_OCP_V3_2_AUX_PWR_R_EN    I39 @T6G_MB_LIB.T6G(SCH_1):PAGE257

R1148 Q_RES_0402LF-0,5%,1/16W,CHIP,CS00002JB13
     1 HP_LVC3_OCP_V3_1_PRSNT2_N_R @T6G_MB_LIB.T6G(SCH_1):HP_LVC3_OCP_V3_1_PRSNT2_N_R    I46 @T6G_MB_LIB.T6G(SCH_1):PAGE338
     2 HP_LVC3_OCP_SFF_PRSNT2_PLD_N @T6G_MB_LIB.T6G(SCH_1):HP_LVC3_OCP_SFF_PRSNT2_PLD_N    I46 @T6G_MB_LIB.T6G(SCH_1):PAGE338

R1149 Q_RES_0402LF-1K,1%,1/16W,CHIP,CS21002FB06
     1 P3V3_AUX @T6G_MB_LIB.T6G(SCH_1):P3V3_AUX    I25 @T6G_MB_LIB.T6G(SCH_1):PAGE257
     2 HP_LVC3_OCP_V3_2_PRSNT2 @T6G_MB_LIB.T6G(SCH_1):HP_LVC3_OCP_V3_2_PRSNT2    I25 @T6G_MB_LIB.T6G(SCH_1):PAGE257

R1150 Q_RES_0402LF-10K,1%,1/16W,CHIP,CS31002FB08
     1 P3V3_AUX @T6G_MB_LIB.T6G(SCH_1):P3V3_AUX    I71 @T6G_MB_LIB.T6G(SCH_1):PAGE338
     2 HP_LVC3_OCP_SFF_PRSNT2_PLD_N @T6G_MB_LIB.T6G(SCH_1):HP_LVC3_OCP_SFF_PRSNT2_PLD_N    I71 @T6G_MB_LIB.T6G(SCH_1):PAGE338

R1151 Q_RES_0402LF-0,5%,1/16W,EMPTY,CS00002JB13
     1 SMB_CPU0_CPU1_APML_BUF1_SCL_R1 @T6G_MB_LIB.T6G(SCH_1):SMB_CPU0_CPU1_APML_BUF1_SCL_R1    I93 @T6G_MB_LIB.T6G(SCH_1):PAGE137
     2 SMB_CPU0_CPU1_APML_BUF1_SCL_R2 @T6G_MB_LIB.T6G(SCH_1):SMB_CPU0_CPU1_APML_BUF1_SCL_R2    I93 @T6G_MB_LIB.T6G(SCH_1):PAGE137

R1152 Q_RES_0402LF-0,5%,1/16W,EMPTY,CS00002JB13
     1 SMB_CPU0_CPU1_APML_BUF1_SDA_R1 @T6G_MB_LIB.T6G(SCH_1):SMB_CPU0_CPU1_APML_BUF1_SDA_R1    I94 @T6G_MB_LIB.T6G(SCH_1):PAGE137
     2 SMB_CPU0_CPU1_APML_BUF1_SDA_R2 @T6G_MB_LIB.T6G(SCH_1):SMB_CPU0_CPU1_APML_BUF1_SDA_R2    I94 @T6G_MB_LIB.T6G(SCH_1):PAGE137

R1153 Q_RES_0402LF-0,5%,1/16W,CHIP,CS00002JB13
     1 SMB_CPU0_CPU1_SEC_SCL_R1 @T6G_MB_LIB.T6G(SCH_1):SMB_CPU0_CPU1_SEC_SCL_R1    I16 @T6G_MB_LIB.T6G(SCH_1):PAGE137
     2 SMB_CPU0_CPU1_SEC_SCL_R2 @T6G_MB_LIB.T6G(SCH_1):SMB_CPU0_CPU1_SEC_SCL_R2    I16 @T6G_MB_LIB.T6G(SCH_1):PAGE137

R1154 Q_RES_0402LF-0,5%,1/16W,CHIP,CS00002JB13
     1 SMB_CPU0_CPU1_SEC_SDA_R1 @T6G_MB_LIB.T6G(SCH_1):SMB_CPU0_CPU1_SEC_SDA_R1    I15 @T6G_MB_LIB.T6G(SCH_1):PAGE137
     2 SMB_CPU0_CPU1_SEC_SDA_R2 @T6G_MB_LIB.T6G(SCH_1):SMB_CPU0_CPU1_SEC_SDA_R2    I15 @T6G_MB_LIB.T6G(SCH_1):PAGE137

R1155 Q_RES_0402LF-33,5%,1/16W,EMPTY,CS03302JB10
     1 SMB_APML_CPU0_R_SDA @T6G_MB_LIB.T6G(SCH_1):SMB_APML_CPU0_R_SDA    I39 @T6G_MB_LIB.T6G(SCH_1):PAGE138
     2 SMB_APML_CPU0_SDA @T6G_MB_LIB.T6G(SCH_1):SMB_APML_CPU0_SDA    I39 @T6G_MB_LIB.T6G(SCH_1):PAGE138

R1156 Q_RES_0402LF-33,5%,1/16W,EMPTY,CS03302JB10
     1 SMB_APML_CPU0_R_SCL @T6G_MB_LIB.T6G(SCH_1):SMB_APML_CPU0_R_SCL    I38 @T6G_MB_LIB.T6G(SCH_1):PAGE138
     2 SMB_APML_CPU0_SCL @T6G_MB_LIB.T6G(SCH_1):SMB_APML_CPU0_SCL    I38 @T6G_MB_LIB.T6G(SCH_1):PAGE138

R1157 Q_RES_0402LF-33,5%,1/16W,EMPTY,CS03302JB10
     1 SMB_APML_CPU1_R_SCL @T6G_MB_LIB.T6G(SCH_1):SMB_APML_CPU1_R_SCL    I74 @T6G_MB_LIB.T6G(SCH_1):PAGE138
     2 SMB_APML_CPU1_SCL @T6G_MB_LIB.T6G(SCH_1):SMB_APML_CPU1_SCL    I74 @T6G_MB_LIB.T6G(SCH_1):PAGE138

R1158 Q_RES_0402LF-33,5%,1/16W,EMPTY,CS03302JB10
     1 SMB_APML_CPU1_R_SDA @T6G_MB_LIB.T6G(SCH_1):SMB_APML_CPU1_R_SDA    I73 @T6G_MB_LIB.T6G(SCH_1):PAGE138
     2 SMB_APML_CPU1_SDA @T6G_MB_LIB.T6G(SCH_1):SMB_APML_CPU1_SDA    I73 @T6G_MB_LIB.T6G(SCH_1):PAGE138

R1159 Q_RES_0402LF-0,5%,1/16W,CHIP,CS00002JB13
     1 SMB_CPU0_SEC_R_SCL @T6G_MB_LIB.T6G(SCH_1):SMB_CPU0_SEC_R_SCL    I76 @T6G_MB_LIB.T6G(SCH_1):PAGE138
     2 SMB_CPU0_SEC_SCL @T6G_MB_LIB.T6G(SCH_1):SMB_CPU0_SEC_SCL    I76 @T6G_MB_LIB.T6G(SCH_1):PAGE138

R1160 Q_RES_0402LF-0,5%,1/16W,CHIP,CS00002JB13
     1 SMB_CPU0_SEC_R_SDA @T6G_MB_LIB.T6G(SCH_1):SMB_CPU0_SEC_R_SDA    I75 @T6G_MB_LIB.T6G(SCH_1):PAGE138
     2 SMB_CPU0_SEC_SDA @T6G_MB_LIB.T6G(SCH_1):SMB_CPU0_SEC_SDA    I75 @T6G_MB_LIB.T6G(SCH_1):PAGE138

R1161 Q_RES_0402LF-0,5%,1/16W,CHIP,CS00002JB13
     1 SMB_CPU1_SEC_R_SCL @T6G_MB_LIB.T6G(SCH_1):SMB_CPU1_SEC_R_SCL    I23 @T6G_MB_LIB.T6G(SCH_1):PAGE138
     2 SMB_CPU1_SEC_SCL @T6G_MB_LIB.T6G(SCH_1):SMB_CPU1_SEC_SCL    I23 @T6G_MB_LIB.T6G(SCH_1):PAGE138

R1162 Q_RES_0402LF-0,5%,1/16W,CHIP,CS00002JB13
     1 SMB_CPU1_SEC_R_SDA @T6G_MB_LIB.T6G(SCH_1):SMB_CPU1_SEC_R_SDA    I22 @T6G_MB_LIB.T6G(SCH_1):PAGE138
     2 SMB_CPU1_SEC_SDA @T6G_MB_LIB.T6G(SCH_1):SMB_CPU1_SEC_SDA    I22 @T6G_MB_LIB.T6G(SCH_1):PAGE138

R1163 Q_RES_0402LF-0,5%,1/16W,CHIP,CS00002JB13
     1 HP_LVC3_OCP_V3_2_P12V_PWRGD @T6G_MB_LIB.T6G(SCH_1):HP_LVC3_OCP_V3_2_P12V_PWRGD     I3 @T6G_MB_LIB.T6G(SCH_1):PAGE257
     2 HP_LVC3_OCP_V3_2_P12V_R_PWRGD @T6G_MB_LIB.T6G(SCH_1):HP_LVC3_OCP_V3_2_P12V_R_PWRGD     I3 @T6G_MB_LIB.T6G(SCH_1):PAGE257

R1164 Q_RES_0402LF-0,5%,1/16W,EMPTY,CS00002JB13
     1 P12V_OCP_V3_2_EN_R @T6G_MB_LIB.T6G(SCH_1):P12V_OCP_V3_2_EN_R    I28 @T6G_MB_LIB.T6G(SCH_1):PAGE257
     2 P12V_OCP_V3_2_EN_R3 @T6G_MB_LIB.T6G(SCH_1):P12V_OCP_V3_2_EN_R3    I28 @T6G_MB_LIB.T6G(SCH_1):PAGE257

R1165 Q_RES_0402LF-1K,1%,1/16W,CHIP,CS21002FB06
     1 P3V3_AUX @T6G_MB_LIB.T6G(SCH_1):P3V3_AUX    I32 @T6G_MB_LIB.T6G(SCH_1):PAGE257
     2 P12V_OCP_V3_2_EN_R3 @T6G_MB_LIB.T6G(SCH_1):P12V_OCP_V3_2_EN_R3    I32 @T6G_MB_LIB.T6G(SCH_1):PAGE257

R1166 Q_RES_0402LF-0,5%,1/16W,CHIP,CS00002JB13
     1 P12V_OCP_V3_2_PLD_R_PWRGD @T6G_MB_LIB.T6G(SCH_1):P12V_OCP_V3_2_PLD_R_PWRGD    I18 @T6G_MB_LIB.T6G(SCH_1):PAGE257
     2 P12V_OCP_V3_2_PLD_PWRGD @T6G_MB_LIB.T6G(SCH_1):P12V_OCP_V3_2_PLD_PWRGD    I18 @T6G_MB_LIB.T6G(SCH_1):PAGE257

R1167 Q_RES_0402LF-1K,1%,1/16W,CHIP,CS21002FB06
     1 P3V3_AUX @T6G_MB_LIB.T6G(SCH_1):P3V3_AUX    I19 @T6G_MB_LIB.T6G(SCH_1):PAGE257
     2 P12V_OCP_V3_2_PLD_PWRGD @T6G_MB_LIB.T6G(SCH_1):P12V_OCP_V3_2_PLD_PWRGD    I19 @T6G_MB_LIB.T6G(SCH_1):PAGE257

R1168 Q_RES_0402LF-0,5%,1/16W,CHIP,CS00002JB13
     1 P12V_OCP_V3_2_BUF_EN @T6G_MB_LIB.T6G(SCH_1):P12V_OCP_V3_2_BUF_EN    I57 @T6G_MB_LIB.T6G(SCH_1):PAGE257
     2 P12V_OCP_V3_2_BUF_EN_R @T6G_MB_LIB.T6G(SCH_1):P12V_OCP_V3_2_BUF_EN_R    I57 @T6G_MB_LIB.T6G(SCH_1):PAGE257

R1169 Q_RES_0402LF-0,5%,1/16W,CHIP,CS00002JB13
     1 OCP_V3_2_P3V3_PWRGD @T6G_MB_LIB.T6G(SCH_1):OCP_V3_2_P3V3_PWRGD    I34 @T6G_MB_LIB.T6G(SCH_1):PAGE257
     2 OCP_V3_2_P3V3_R2_PWRGD @T6G_MB_LIB.T6G(SCH_1):OCP_V3_2_P3V3_R2_PWRGD    I34 @T6G_MB_LIB.T6G(SCH_1):PAGE257

R1170 Q_RES_0402LF-0,5%,1/16W,CHIP,CS00002JB13
     1 OCP_V3_2_P3V3_PLD_PWRGD @T6G_MB_LIB.T6G(SCH_1):OCP_V3_2_P3V3_PLD_PWRGD    I58 @T6G_MB_LIB.T6G(SCH_1):PAGE257
     2 OCP_V3_2_P3V3_PLD_R_PWRGD @T6G_MB_LIB.T6G(SCH_1):OCP_V3_2_P3V3_PLD_R_PWRGD    I58 @T6G_MB_LIB.T6G(SCH_1):PAGE257

R1171 Q_RES_0402LF-1K,1%,1/16W,CHIP,CS21002FB06
     1 P3V3_AUX @T6G_MB_LIB.T6G(SCH_1):P3V3_AUX    I60 @T6G_MB_LIB.T6G(SCH_1):PAGE257
     2 OCP_V3_2_P3V3_PLD_R_PWRGD @T6G_MB_LIB.T6G(SCH_1):OCP_V3_2_P3V3_PLD_R_PWRGD    I60 @T6G_MB_LIB.T6G(SCH_1):PAGE257

R1172 Q_RES_0402LF-10K,5%,1/16W,EMPTY,CS31002JB08
     1 P3V3_AUX @T6G_MB_LIB.T6G(SCH_1):P3V3_AUX    I51 @T6G_MB_LIB.T6G(SCH_1):PAGE257
     2 OCP_V3_2_AUX_PWR_EN @T6G_MB_LIB.T6G(SCH_1):OCP_V3_2_AUX_PWR_EN    I51 @T6G_MB_LIB.T6G(SCH_1):PAGE257

R1173 Q_RES_0402LF-33.2,1%,1/16W,CHIP,CS03322FB03
     1 OCP_V3_2_P3V3_R3_PWRGD @T6G_MB_LIB.T6G(SCH_1):OCP_V3_2_P3V3_R3_PWRGD    I16 @T6G_MB_LIB.T6G(SCH_1):PAGE257
     2 HP_LVC3_OCP_V3_2_PWRGD @T6G_MB_LIB.T6G(SCH_1):HP_LVC3_OCP_V3_2_PWRGD    I16 @T6G_MB_LIB.T6G(SCH_1):PAGE257

R1174 Q_RES_0402LF-33.2,1%,1/16W,CHIP,CS03322FB03
     1 RST_PERST_OCP_V3_2_N @T6G_MB_LIB.T6G(SCH_1):RST_PERST_OCP_V3_2_N    I17 @T6G_MB_LIB.T6G(SCH_1):PAGE257
     2 RST_PERST_OCP_V3_2_R_N @T6G_MB_LIB.T6G(SCH_1):RST_PERST_OCP_V3_2_R_N    I17 @T6G_MB_LIB.T6G(SCH_1):PAGE257

R1175 Q_RES_0402LF-33.2,1%,1/16W,CHIP,CS03322FB03
     1 OCP_V3_2_AUX_PWR_EN_R2 @T6G_MB_LIB.T6G(SCH_1):OCP_V3_2_AUX_PWR_EN_R2    I42 @T6G_MB_LIB.T6G(SCH_1):PAGE257
     2 OCP_V3_2_AUX_PWR_EN @T6G_MB_LIB.T6G(SCH_1):OCP_V3_2_AUX_PWR_EN    I42 @T6G_MB_LIB.T6G(SCH_1):PAGE257

R1176 Q_RES_0402LF-10K,1%,1/16W,CHIP,CS31002FB08
     1 P3V3_AUX @T6G_MB_LIB.T6G(SCH_1):P3V3_AUX    I10 @T6G_MB_LIB.T6G(SCH_1):PAGE257
     2 FM_OCP_V3_2_AUX_PWR_R_EN @T6G_MB_LIB.T6G(SCH_1):FM_OCP_V3_2_AUX_PWR_R_EN    I10 @T6G_MB_LIB.T6G(SCH_1):PAGE257

R1177 Q_RES_0402LF-33.2,1%,1/16W,CHIP,CS03322FB03
     1 RST_PERST_OCP_V3_2_BUF_R_N @T6G_MB_LIB.T6G(SCH_1):RST_PERST_OCP_V3_2_BUF_R_N    I49 @T6G_MB_LIB.T6G(SCH_1):PAGE257
     2 RST_PERST_OCP_V3_2_BUF_N @T6G_MB_LIB.T6G(SCH_1):RST_PERST_OCP_V3_2_BUF_N    I49 @T6G_MB_LIB.T6G(SCH_1):PAGE257

R1178 Q_RES_0402LF-33.2,1%,1/16W,CHIP,CS03322FB03
     1 OCP_V3_2_P3V3_R3_PWRGD @T6G_MB_LIB.T6G(SCH_1):OCP_V3_2_P3V3_R3_PWRGD    I12 @T6G_MB_LIB.T6G(SCH_1):PAGE257
     2 HP_LVC3_OCP_V3_2_PWRGD_R1 @T6G_MB_LIB.T6G(SCH_1):HP_LVC3_OCP_V3_2_PWRGD_R1    I12 @T6G_MB_LIB.T6G(SCH_1):PAGE257

R1179 Q_RES_0402LF-0,5%,1/16W,CHIP,CS00002JB13
     1 FM_OCP_V3_2_AUX_PWR_R_EN @T6G_MB_LIB.T6G(SCH_1):FM_OCP_V3_2_AUX_PWR_R_EN   I155 @T6G_MB_LIB.T6G(SCH_1):PAGE79
     2 FM_OCP_V3_2_AUX_PWR_EN @T6G_MB_LIB.T6G(SCH_1):FM_OCP_V3_2_AUX_PWR_EN   I155 @T6G_MB_LIB.T6G(SCH_1):PAGE79

R1180 Q_RES_0402LF-0,5%,1/16W,EMPTY,CS00002JB13
     1 HP_LVC3_OCP_V3_2_R_EN @T6G_MB_LIB.T6G(SCH_1):HP_LVC3_OCP_V3_2_R_EN    I45 @T6G_MB_LIB.T6G(SCH_1):PAGE248
     2 HP_LVC3_OCP_V3_2_P12V_PWRGD @T6G_MB_LIB.T6G(SCH_1):HP_LVC3_OCP_V3_2_P12V_PWRGD    I45 @T6G_MB_LIB.T6G(SCH_1):PAGE248

R1181 Q_RES_0402LF-0,5%,1/16W,CHIP,CS00002JB13
     1 P12V_OCP_V3_2_BUF_EN_R @T6G_MB_LIB.T6G(SCH_1):P12V_OCP_V3_2_BUF_EN_R   I123 @T6G_MB_LIB.T6G(SCH_1):PAGE343
     2 P12V_OCP_EN_2_R @T6G_MB_LIB.T6G(SCH_1):P12V_OCP_EN_2_R   I123 @T6G_MB_LIB.T6G(SCH_1):PAGE343

R1182 Q_RES_0402LF-0,5%,1/16W,EMPTY,CS00002JB13
     1 HP_LVC3_OCP_V3_2_P12V_PWRGD @T6G_MB_LIB.T6G(SCH_1):HP_LVC3_OCP_V3_2_P12V_PWRGD   I129 @T6G_MB_LIB.T6G(SCH_1):PAGE343
     2 P3V3_OCP_EN_2_R @T6G_MB_LIB.T6G(SCH_1):P3V3_OCP_EN_2_R   I129 @T6G_MB_LIB.T6G(SCH_1):PAGE343

R1183 Q_RES_0402LF-1K,1%,1/16W,CHIP,CS21002FB06
     1 PWRGD_CHF_CPU1_DIMM @T6G_MB_LIB.T6G(SCH_1):PWRGD_CHF_CPU1_DIMM   I188 @T6G_MB_LIB.T6G(SCH_1):PAGE102
     2 PWRGD_CHAF_CPU1 @T6G_MB_LIB.T6G(SCH_1):PWRGD_CHAF_CPU1   I188 @T6G_MB_LIB.T6G(SCH_1):PAGE102

R1184 Q_RES_0402LF-1K,1%,1/16W,CHIP,CS21002FB06
     1 PWRGD_CHG_CPU1_DIMM0 @T6G_MB_LIB.T6G(SCH_1):PWRGD_CHG_CPU1_DIMM0   I188 @T6G_MB_LIB.T6G(SCH_1):PAGE103
     2 PWRGD_CHGL_CPU1 @T6G_MB_LIB.T6G(SCH_1):PWRGD_CHGL_CPU1   I188 @T6G_MB_LIB.T6G(SCH_1):PAGE103

R1185 Q_RES_0402LF-1K,1%,1/16W,CHIP,CS21002FB06
     1 PVDDCR_CPU0_P0_PMALERT @T6G_MB_LIB.T6G(SCH_1):PVDDCR_CPU0_P0_PMALERT    I62 @T6G_MB_LIB.T6G(SCH_1):PAGE82
     2 P3V3_AUX @T6G_MB_LIB.T6G(SCH_1):P3V3_AUX    I62 @T6G_MB_LIB.T6G(SCH_1):PAGE82

R1186 Q_RES_0402LF-1K,1%,1/16W,CHIP,CS21002FB06
     1 PVDDCR_CPU1_P0_SMB_ALERT @T6G_MB_LIB.T6G(SCH_1):PVDDCR_CPU1_P0_SMB_ALERT    I60 @T6G_MB_LIB.T6G(SCH_1):PAGE82
     2 P3V3_AUX @T6G_MB_LIB.T6G(SCH_1):P3V3_AUX    I60 @T6G_MB_LIB.T6G(SCH_1):PAGE82

R1187 Q_RES_0402LF-1K,1%,1/16W,CHIP,CS21002FB06
     1 PVDDCR_CPU0_P1_PMALERT @T6G_MB_LIB.T6G(SCH_1):PVDDCR_CPU0_P1_PMALERT    I59 @T6G_MB_LIB.T6G(SCH_1):PAGE82
     2 P3V3_AUX @T6G_MB_LIB.T6G(SCH_1):P3V3_AUX    I59 @T6G_MB_LIB.T6G(SCH_1):PAGE82

R1188 Q_RES_0402LF-1K,1%,1/16W,CHIP,CS21002FB06
     1 PVDDCR_CPU1_P1_SMB_ALERT @T6G_MB_LIB.T6G(SCH_1):PVDDCR_CPU1_P1_SMB_ALERT    I61 @T6G_MB_LIB.T6G(SCH_1):PAGE82
     2 P3V3_AUX @T6G_MB_LIB.T6G(SCH_1):P3V3_AUX    I61 @T6G_MB_LIB.T6G(SCH_1):PAGE82

R1189 Q_RES_0402LF-1K,1%,1/16W,CHIP,CS21002FB06
     1 PVDD11_S3_P0_PMALERT @T6G_MB_LIB.T6G(SCH_1):PVDD11_S3_P0_PMALERT    I57 @T6G_MB_LIB.T6G(SCH_1):PAGE82
     2 P3V3_AUX @T6G_MB_LIB.T6G(SCH_1):P3V3_AUX    I57 @T6G_MB_LIB.T6G(SCH_1):PAGE82

R1190 Q_RES_0402LF-1K,1%,1/16W,CHIP,CS21002FB06
     1 PVDD11_S3_P1_PMALERT @T6G_MB_LIB.T6G(SCH_1):PVDD11_S3_P1_PMALERT    I58 @T6G_MB_LIB.T6G(SCH_1):PAGE82
     2 P3V3_AUX @T6G_MB_LIB.T6G(SCH_1):P3V3_AUX    I58 @T6G_MB_LIB.T6G(SCH_1):PAGE82

R1191 Q_RES_0402LF-0,5%,1/16W,CHIP,CS00002JB13
     1 HP_LVC3_OCP_V3_2_PRSNT2_N_R @T6G_MB_LIB.T6G(SCH_1):HP_LVC3_OCP_V3_2_PRSNT2_N_R   I116 @T6G_MB_LIB.T6G(SCH_1):PAGE343
     2 HP_LVC3_OCP_V3_2_PRSNT2_N @T6G_MB_LIB.T6G(SCH_1):HP_LVC3_OCP_V3_2_PRSNT2_N   I116 @T6G_MB_LIB.T6G(SCH_1):PAGE343

R1192 Q_RES_0402LF-1K,1%,1/16W,CHIP,CS21002FB06
     1 P3V3_AUX @T6G_MB_LIB.T6G(SCH_1):P3V3_AUX   I118 @T6G_MB_LIB.T6G(SCH_1):PAGE343
     2 HP_LVC3_OCP_V3_2_PRSNT2_N @T6G_MB_LIB.T6G(SCH_1):HP_LVC3_OCP_V3_2_PRSNT2_N   I118 @T6G_MB_LIB.T6G(SCH_1):PAGE343

R1193 Q_RES_0402LF-0,5%,1/16W,CHIP,CS00002JB13
     1 P12V_OCP_V3_2_BUF_EN_R @T6G_MB_LIB.T6G(SCH_1):P12V_OCP_V3_2_BUF_EN_R    I76 @T6G_MB_LIB.T6G(SCH_1):PAGE344
     2 P12V_OCP_V3_2_EN_2_R3 @T6G_MB_LIB.T6G(SCH_1):P12V_OCP_V3_2_EN_2_R3    I76 @T6G_MB_LIB.T6G(SCH_1):PAGE344

R1194 Q_RES_0402LF-200,1%,1/16W,CHIP,CS12002FB06
     1 P3V3_AUX @T6G_MB_LIB.T6G(SCH_1):P3V3_AUX    I46 @T6G_MB_LIB.T6G(SCH_1):PAGE84
     2 BMC_FPGA_LED2_R_N @T6G_MB_LIB.T6G(SCH_1):BMC_FPGA_LED2_R_N    I46 @T6G_MB_LIB.T6G(SCH_1):PAGE84

R1195 Q_RES_0402LF-4.7K,5%,1/16W,EMPTY,CS24702JB10
     1 P12V_OCP_SFF_EN_R @T6G_MB_LIB.T6G(SCH_1):P12V_OCP_SFF_EN_R    I36 @T6G_MB_LIB.T6G(SCH_1):PAGE82
     2 P3V3_AUX @T6G_MB_LIB.T6G(SCH_1):P3V3_AUX    I36 @T6G_MB_LIB.T6G(SCH_1):PAGE82

R1196 Q_RES_0402LF-0,5%,1/16W,EMPTY,CS00002JB13
     1 HP_LVC3_OCP_V3_2_P12V_PWRGD @T6G_MB_LIB.T6G(SCH_1):HP_LVC3_OCP_V3_2_P12V_PWRGD    I79 @T6G_MB_LIB.T6G(SCH_1):PAGE344
     2 P3V3_OCP_EN_2 @T6G_MB_LIB.T6G(SCH_1):P3V3_OCP_EN_2    I79 @T6G_MB_LIB.T6G(SCH_1):PAGE344

R1197 Q_RES_0402LF-0,5%,1/16W,EMPTY,CS00002JB13
     1 ESPI_CPU0_ALERT_P0_N @T6G_MB_LIB.T6G(SCH_1):ESPI_CPU0_ALERT_P0_N    I24 @T6G_MB_LIB.T6G(SCH_1):PAGE130
     2 ESPI_CPU0_ALERT_N @T6G_MB_LIB.T6G(SCH_1):ESPI_CPU0_ALERT_N    I24 @T6G_MB_LIB.T6G(SCH_1):PAGE130

R1198 Q_RES_0201LF-0,5%,1/20W,CHIP,CS00001JE10
     1 RST_SMB_RT_ROM_R1_N @T6G_MB_LIB.T6G(SCH_1):RST_SMB_RT_ROM_R1_N    I53 @T6G_MB_LIB.T6G(SCH_1):PAGE376
     2 FM_SMB_RT_ROM_MUX3_SEL @T6G_MB_LIB.T6G(SCH_1):FM_SMB_RT_ROM_MUX3_SEL    I53 @T6G_MB_LIB.T6G(SCH_1):PAGE376

R1199 Q_RES_0201LF-0,5%,1/20W,CHIP,CS00001JE10
     1 RST_SMB_RT_ROM_R1_N @T6G_MB_LIB.T6G(SCH_1):RST_SMB_RT_ROM_R1_N    I40 @T6G_MB_LIB.T6G(SCH_1):PAGE376
     2 FM_SMB_RT_ROM_MUX2_SEL @T6G_MB_LIB.T6G(SCH_1):FM_SMB_RT_ROM_MUX2_SEL    I40 @T6G_MB_LIB.T6G(SCH_1):PAGE376

R1200 Q_RES_0201LF-0,5%,1/20W,CHIP,CS00001JE10
     1 RST_SMB_RT_ROM_R1_N @T6G_MB_LIB.T6G(SCH_1):RST_SMB_RT_ROM_R1_N    I68 @T6G_MB_LIB.T6G(SCH_1):PAGE376
     2 FM_SMB_RT_ROM_MUX4_SEL @T6G_MB_LIB.T6G(SCH_1):FM_SMB_RT_ROM_MUX4_SEL    I68 @T6G_MB_LIB.T6G(SCH_1):PAGE376

R1201 Q_RES_0201LF-0,5%,1/20W,CHIP,CS00001JE10
     1 RST_SMB_RT_ROM_R1_N @T6G_MB_LIB.T6G(SCH_1):RST_SMB_RT_ROM_R1_N    I30 @T6G_MB_LIB.T6G(SCH_1):PAGE376
     2 FM_SMB_RT_ROM_MUX1_SEL @T6G_MB_LIB.T6G(SCH_1):FM_SMB_RT_ROM_MUX1_SEL    I30 @T6G_MB_LIB.T6G(SCH_1):PAGE376

R1202 Q_RES_0402LF-0,5%,1/16W,CHIP,CS00002JB13
     1 FM_FORCE_ALL_PWRON_R @T6G_MB_LIB.T6G(SCH_1):FM_FORCE_ALL_PWRON_R   I127 @T6G_MB_LIB.T6G(SCH_1):PAGE80
     2 FM_FORCE_ALL_PWRON @T6G_MB_LIB.T6G(SCH_1):FM_FORCE_ALL_PWRON   I127 @T6G_MB_LIB.T6G(SCH_1):PAGE80

R1203 Q_RES_0402LF-33,5%,1/16W,CHIP,CS03302JB10
     1 BIOS_DEBUG_MODE_R @T6G_MB_LIB.T6G(SCH_1):BIOS_DEBUG_MODE_R   I178 @T6G_MB_LIB.T6G(SCH_1):PAGE80
     2 BIOS_DEBUG_MODE @T6G_MB_LIB.T6G(SCH_1):BIOS_DEBUG_MODE   I178 @T6G_MB_LIB.T6G(SCH_1):PAGE80

R1204 Q_RES_0402LF-0,5%,1/16W,CHIP,CS00002JB13
     1 FM_BIOS_USB_RECOVERY_R @T6G_MB_LIB.T6G(SCH_1):FM_BIOS_USB_RECOVERY_R   I353 @T6G_MB_LIB.T6G(SCH_1):PAGE27
     2 FM_BIOS_USB_RECOVERY @T6G_MB_LIB.T6G(SCH_1):FM_BIOS_USB_RECOVERY   I353 @T6G_MB_LIB.T6G(SCH_1):PAGE27

R1205 Q_RES_0402LF-0,5%,1/16W,CHIP,CS00002JB13
     1 FM_PASSWORD_CLEAR_R_N @T6G_MB_LIB.T6G(SCH_1):FM_PASSWORD_CLEAR_R_N   I100 @T6G_MB_LIB.T6G(SCH_1):PAGE28
     2 FM_PASSWORD_CLEAR_N @T6G_MB_LIB.T6G(SCH_1):FM_PASSWORD_CLEAR_N   I100 @T6G_MB_LIB.T6G(SCH_1):PAGE28

R1206 Q_RES_0201LF-0,5%,1/20W,CHIP,CS00001JE10
     1 RST_SMB_RT_ROM_R1_N @T6G_MB_LIB.T6G(SCH_1):RST_SMB_RT_ROM_R1_N   I115 @T6G_MB_LIB.T6G(SCH_1):PAGE376
     2 FM_SMB_RT_ROM_MUX7_SEL @T6G_MB_LIB.T6G(SCH_1):FM_SMB_RT_ROM_MUX7_SEL   I115 @T6G_MB_LIB.T6G(SCH_1):PAGE376

R1207 Q_RES_0402LF-470,1%,1/16W,CHIP,CS14702FB04
     1 P5V_STBY_PWR_LED @T6G_MB_LIB.T6G(SCH_1):P5V_STBY_PWR_LED    I41 @T6G_MB_LIB.T6G(SCH_1):PAGE143
     2 P5V_AUX @T6G_MB_LIB.T6G(SCH_1):P5V_AUX    I41 @T6G_MB_LIB.T6G(SCH_1):PAGE143

R1208 Q_RES_0402LF-470,1%,1/16W,CHIP,CS14702FB04
     1 PU_P12V_ALL_PWROK_LED @T6G_MB_LIB.T6G(SCH_1):PU_P12V_ALL_PWROK_LED    I42 @T6G_MB_LIB.T6G(SCH_1):PAGE143
     2 P5V_AUX @T6G_MB_LIB.T6G(SCH_1):P5V_AUX    I42 @T6G_MB_LIB.T6G(SCH_1):PAGE143

R1209 Q_RES_0201LF-0,5%,1/20W,CHIP,CS00001JE10
     1 RST_SMB_RT_ROM_R1_N @T6G_MB_LIB.T6G(SCH_1):RST_SMB_RT_ROM_R1_N   I123 @T6G_MB_LIB.T6G(SCH_1):PAGE376
     2 FM_SMB_RT_ROM_MUX8_SEL @T6G_MB_LIB.T6G(SCH_1):FM_SMB_RT_ROM_MUX8_SEL   I123 @T6G_MB_LIB.T6G(SCH_1):PAGE376

R1210 Q_RES_0201LF-0,5%,1/20W,CHIP,CS00001JE10
     1 RST_SMB_RT_ROM_R1_N @T6G_MB_LIB.T6G(SCH_1):RST_SMB_RT_ROM_R1_N   I109 @T6G_MB_LIB.T6G(SCH_1):PAGE376
     2 FM_SMB_RT_ROM_MUX6_SEL @T6G_MB_LIB.T6G(SCH_1):FM_SMB_RT_ROM_MUX6_SEL   I109 @T6G_MB_LIB.T6G(SCH_1):PAGE376

R1211 Q_RES_0201LF-0,5%,1/20W,CHIP,CS00001JE10
     1 RST_SMB_RT_ROM_R1_N @T6G_MB_LIB.T6G(SCH_1):RST_SMB_RT_ROM_R1_N    I86 @T6G_MB_LIB.T6G(SCH_1):PAGE376
     2 FM_SMB_RT_ROM_MUX5_SEL @T6G_MB_LIB.T6G(SCH_1):FM_SMB_RT_ROM_MUX5_SEL    I86 @T6G_MB_LIB.T6G(SCH_1):PAGE376

R1212 Q_RES_0201LF-1K,1%,1/20W,CHIP,CS21001FE07
     1    GND @T6G_MB_LIB.T6G(SCH_1):GND    I54 @T6G_MB_LIB.T6G(SCH_1):PAGE376
     2 RT_ROM_MUX3_OE_N @T6G_MB_LIB.T6G(SCH_1):RT_ROM_MUX3_OE_N    I54 @T6G_MB_LIB.T6G(SCH_1):PAGE376

R1213 Q_RES_0201LF-1K,1%,1/20W,CHIP,CS21001FE07
     1    GND @T6G_MB_LIB.T6G(SCH_1):GND    I41 @T6G_MB_LIB.T6G(SCH_1):PAGE376
     2 RT_ROM_MUX2_OE_N @T6G_MB_LIB.T6G(SCH_1):RT_ROM_MUX2_OE_N    I41 @T6G_MB_LIB.T6G(SCH_1):PAGE376

R1214 Q_RES_0201LF-1K,1%,1/20W,CHIP,CS21001FE07
     1    GND @T6G_MB_LIB.T6G(SCH_1):GND    I69 @T6G_MB_LIB.T6G(SCH_1):PAGE376
     2 RT_ROM_MUX4_OE_N @T6G_MB_LIB.T6G(SCH_1):RT_ROM_MUX4_OE_N    I69 @T6G_MB_LIB.T6G(SCH_1):PAGE376

R1215 Q_RES_0201LF-1K,1%,1/20W,CHIP,CS21001FE07
     1    GND @T6G_MB_LIB.T6G(SCH_1):GND    I28 @T6G_MB_LIB.T6G(SCH_1):PAGE376
     2 RT_ROM_MUX1_OE_N @T6G_MB_LIB.T6G(SCH_1):RT_ROM_MUX1_OE_N    I28 @T6G_MB_LIB.T6G(SCH_1):PAGE376

R1216 Q_RES_0201LF-1K,1%,1/20W,CHIP,CS21001FE07
     1    GND @T6G_MB_LIB.T6G(SCH_1):GND   I116 @T6G_MB_LIB.T6G(SCH_1):PAGE376
     2 RT_ROM_MUX7_OE_N @T6G_MB_LIB.T6G(SCH_1):RT_ROM_MUX7_OE_N   I116 @T6G_MB_LIB.T6G(SCH_1):PAGE376

R1217 Q_RES_0201LF-1K,1%,1/20W,CHIP,CS21001FE07
     1    GND @T6G_MB_LIB.T6G(SCH_1):GND   I122 @T6G_MB_LIB.T6G(SCH_1):PAGE376
     2 RT_ROM_MUX8_OE_N @T6G_MB_LIB.T6G(SCH_1):RT_ROM_MUX8_OE_N   I122 @T6G_MB_LIB.T6G(SCH_1):PAGE376

R1218 Q_RES_0201LF-1K,1%,1/20W,CHIP,CS21001FE07
     1    GND @T6G_MB_LIB.T6G(SCH_1):GND   I110 @T6G_MB_LIB.T6G(SCH_1):PAGE376
     2 RT_ROM_MUX6_OE_N @T6G_MB_LIB.T6G(SCH_1):RT_ROM_MUX6_OE_N   I110 @T6G_MB_LIB.T6G(SCH_1):PAGE376

R1219 Q_RES_0201LF-1K,1%,1/20W,CHIP,CS21001FE07
     1    GND @T6G_MB_LIB.T6G(SCH_1):GND    I87 @T6G_MB_LIB.T6G(SCH_1):PAGE376
     2 RT_ROM_MUX5_OE_N @T6G_MB_LIB.T6G(SCH_1):RT_ROM_MUX5_OE_N    I87 @T6G_MB_LIB.T6G(SCH_1):PAGE376

R1220 Q_RES_0402LF-18K,1%,1/16W,CHIP,CS31802FB04
     1 P1V8_CPU0_RT_1D_ADC @T6G_MB_LIB.T6G(SCH_1):P1V8_CPU0_RT_1D_ADC   I244 @T6G_MB_LIB.T6G(SCH_1):PAGE263
     2    GND @T6G_MB_LIB.T6G(SCH_1):GND   I244 @T6G_MB_LIB.T6G(SCH_1):PAGE263

R1221 Q_RES_0402LF-18K,1%,1/16W,CHIP,CS31802FB04
     1 P1V2_AUX_ADC @T6G_MB_LIB.T6G(SCH_1):P1V2_AUX_ADC   I243 @T6G_MB_LIB.T6G(SCH_1):PAGE263
     2    GND @T6G_MB_LIB.T6G(SCH_1):GND   I243 @T6G_MB_LIB.T6G(SCH_1):PAGE263

R1222 Q_RES_0402LF-18K,1%,1/16W,CHIP,CS31802FB04
     1 PVDD18_S5_P0_ADC @T6G_MB_LIB.T6G(SCH_1):PVDD18_S5_P0_ADC   I246 @T6G_MB_LIB.T6G(SCH_1):PAGE263
     2    GND @T6G_MB_LIB.T6G(SCH_1):GND   I246 @T6G_MB_LIB.T6G(SCH_1):PAGE263

R1223 Q_RES_0402LF-18K,1%,1/16W,CHIP,CS31802FB04
     1 P1V8_CPU1_RT_1D_ADC @T6G_MB_LIB.T6G(SCH_1):P1V8_CPU1_RT_1D_ADC   I245 @T6G_MB_LIB.T6G(SCH_1):PAGE263
     2    GND @T6G_MB_LIB.T6G(SCH_1):GND   I245 @T6G_MB_LIB.T6G(SCH_1):PAGE263

R1224 Q_RES_0402LF-4.7K,1%,1/16W,CHIP,CS24702FB06
     1 PVDD_33_S5_ADC @T6G_MB_LIB.T6G(SCH_1):PVDD_33_S5_ADC   I216 @T6G_MB_LIB.T6G(SCH_1):PAGE263
     2    GND @T6G_MB_LIB.T6G(SCH_1):GND   I216 @T6G_MB_LIB.T6G(SCH_1):PAGE263

R1225 Q_RES_0402LF-18K,1%,1/16W,CHIP,CS31802FB04
     1 PVDD18_S5_P1_ADC @T6G_MB_LIB.T6G(SCH_1):PVDD18_S5_P1_ADC   I247 @T6G_MB_LIB.T6G(SCH_1):PAGE263
     2    GND @T6G_MB_LIB.T6G(SCH_1):GND   I247 @T6G_MB_LIB.T6G(SCH_1):PAGE263

R1226 Q_RES_0402LF-9.09K,1%,1/16W,CHIP,CS29092FB05
     1 P5V_AUX_ADC @T6G_MB_LIB.T6G(SCH_1):P5V_AUX_ADC    I12 @T6G_MB_LIB.T6G(SCH_1):PAGE263
     2    GND @T6G_MB_LIB.T6G(SCH_1):GND    I12 @T6G_MB_LIB.T6G(SCH_1):PAGE263

R1227 Q_RES_0402LF-0,5%,1/16W,EMPTY,CS00002JB13
     1 SMB_ADC_SDA_R @T6G_MB_LIB.T6G(SCH_1):SMB_ADC_SDA_R   I138 @T6G_MB_LIB.T6G(SCH_1):PAGE263
     2 SMB_SEN_MAM_2_3V3AUX_SDA @T6G_MB_LIB.T6G(SCH_1):SMB_SEN_MAM_2_3V3AUX_SDA   I138 @T6G_MB_LIB.T6G(SCH_1):PAGE263

R1228 Q_RES_0402LF-0,5%,1/16W,EMPTY,CS00002JB13
     1 SMB_ADC_SCL_R @T6G_MB_LIB.T6G(SCH_1):SMB_ADC_SCL_R   I139 @T6G_MB_LIB.T6G(SCH_1):PAGE263
     2 SMB_SEN_MAM_2_3V3AUX_SCL @T6G_MB_LIB.T6G(SCH_1):SMB_SEN_MAM_2_3V3AUX_SCL   I139 @T6G_MB_LIB.T6G(SCH_1):PAGE263

R1229 Q_RES_0402LF-18K,1%,1/16W,CHIP,CS31802FB04
     1 P1V8_AUX_ADC @T6G_MB_LIB.T6G(SCH_1):P1V8_AUX_ADC   I242 @T6G_MB_LIB.T6G(SCH_1):PAGE263
     2    GND @T6G_MB_LIB.T6G(SCH_1):GND   I242 @T6G_MB_LIB.T6G(SCH_1):PAGE263

R1230 Q_RES_0402LF-2K,1%,1/16W,CHIP,CS22002FB07
     1 MAX11617_2_VREF @T6G_MB_LIB.T6G(SCH_1):MAX11617_2_VREF   I154 @T6G_MB_LIB.T6G(SCH_1):PAGE263
     2 MAX11617_2_VREF_R @T6G_MB_LIB.T6G(SCH_1):MAX11617_2_VREF_R   I154 @T6G_MB_LIB.T6G(SCH_1):PAGE263

R1231 Q_RES_0402LF-5.11K,1%,1/16W,CHIP,CS25112FB04
     1 P1V8_CPU0_RT_1D @T6G_MB_LIB.T6G(SCH_1):P1V8_CPU0_RT_1D   I191 @T6G_MB_LIB.T6G(SCH_1):PAGE263
     2 P1V8_CPU0_RT_1D_ADC @T6G_MB_LIB.T6G(SCH_1):P1V8_CPU0_RT_1D_ADC   I191 @T6G_MB_LIB.T6G(SCH_1):PAGE263

R1232 Q_RES_0402LF-5.11K,1%,1/16W,CHIP,CS25112FB04
     1 P1V2_AUX @T6G_MB_LIB.T6G(SCH_1):P1V2_AUX   I179 @T6G_MB_LIB.T6G(SCH_1):PAGE263
     2 P1V2_AUX_ADC @T6G_MB_LIB.T6G(SCH_1):P1V2_AUX_ADC   I179 @T6G_MB_LIB.T6G(SCH_1):PAGE263

R1233 Q_RES_0402LF-5.11K,1%,1/16W,CHIP,CS25112FB04
     1 PVDD18_S5_P0 @T6G_MB_LIB.T6G(SCH_1):PVDD18_S5_P0   I227 @T6G_MB_LIB.T6G(SCH_1):PAGE263
     2 PVDD18_S5_P0_ADC @T6G_MB_LIB.T6G(SCH_1):PVDD18_S5_P0_ADC   I227 @T6G_MB_LIB.T6G(SCH_1):PAGE263

R1234 Q_RES_0402LF-5.11K,1%,1/16W,CHIP,CS25112FB04
     1 P1V8_CPU1_RT_1D @T6G_MB_LIB.T6G(SCH_1):P1V8_CPU1_RT_1D   I194 @T6G_MB_LIB.T6G(SCH_1):PAGE263
     2 P1V8_CPU1_RT_1D_ADC @T6G_MB_LIB.T6G(SCH_1):P1V8_CPU1_RT_1D_ADC   I194 @T6G_MB_LIB.T6G(SCH_1):PAGE263

R1235 Q_RES_0402LF-5.11K,1%,1/16W,CHIP,CS25112FB04
     1 PVDD_33_S5 @T6G_MB_LIB.T6G(SCH_1):PVDD_33_S5   I215 @T6G_MB_LIB.T6G(SCH_1):PAGE263
     2 PVDD_33_S5_ADC @T6G_MB_LIB.T6G(SCH_1):PVDD_33_S5_ADC   I215 @T6G_MB_LIB.T6G(SCH_1):PAGE263

R1236 Q_RES_0402LF-5.11K,1%,1/16W,CHIP,CS25112FB04
     1 PVDD18_S5_P1 @T6G_MB_LIB.T6G(SCH_1):PVDD18_S5_P1   I230 @T6G_MB_LIB.T6G(SCH_1):PAGE263
     2 PVDD18_S5_P1_ADC @T6G_MB_LIB.T6G(SCH_1):PVDD18_S5_P1_ADC   I230 @T6G_MB_LIB.T6G(SCH_1):PAGE263

R1237 Q_RES_0402LF-5.11K,1%,1/16W,CHIP,CS25112FB04
     1 P1V8_AUX @T6G_MB_LIB.T6G(SCH_1):P1V8_AUX    I19 @T6G_MB_LIB.T6G(SCH_1):PAGE263
     2 P1V8_AUX_ADC @T6G_MB_LIB.T6G(SCH_1):P1V8_AUX_ADC    I19 @T6G_MB_LIB.T6G(SCH_1):PAGE263

R1238 Q_RES_0402LF-18K,1%,1/16W,CHIP,CS31802FB04
     1 P5V_AUX @T6G_MB_LIB.T6G(SCH_1):P5V_AUX    I13 @T6G_MB_LIB.T6G(SCH_1):PAGE263
     2 P5V_AUX_ADC @T6G_MB_LIB.T6G(SCH_1):P5V_AUX_ADC    I13 @T6G_MB_LIB.T6G(SCH_1):PAGE263

R1239 Q_RES_0402LF-1K,1%,1/16W,EMPTY,CS21002FB06
     1 P3V3_AUX @T6G_MB_LIB.T6G(SCH_1):P3V3_AUX    I59 @T6G_MB_LIB.T6G(SCH_1):PAGE263
     2 ADC128_2_A1 @T6G_MB_LIB.T6G(SCH_1):ADC128_2_A1    I59 @T6G_MB_LIB.T6G(SCH_1):PAGE263

R1240 Q_RES_0402LF-1K,1%,1/16W,CHIP,CS21002FB06
     1 ADC128_2_A1 @T6G_MB_LIB.T6G(SCH_1):ADC128_2_A1    I57 @T6G_MB_LIB.T6G(SCH_1):PAGE263
     2    GND @T6G_MB_LIB.T6G(SCH_1):GND    I57 @T6G_MB_LIB.T6G(SCH_1):PAGE263

R1241 Q_RES_0402LF-1K,1%,1/16W,EMPTY,CS21002FB06
     1 P3V3_AUX @T6G_MB_LIB.T6G(SCH_1):P3V3_AUX    I60 @T6G_MB_LIB.T6G(SCH_1):PAGE263
     2 ADC128_2_A0 @T6G_MB_LIB.T6G(SCH_1):ADC128_2_A0    I60 @T6G_MB_LIB.T6G(SCH_1):PAGE263

R1242 Q_RES_0402LF-1K,1%,1/16W,CHIP,CS21002FB06
     1 ADC128_2_A0 @T6G_MB_LIB.T6G(SCH_1):ADC128_2_A0    I58 @T6G_MB_LIB.T6G(SCH_1):PAGE263
     2    GND @T6G_MB_LIB.T6G(SCH_1):GND    I58 @T6G_MB_LIB.T6G(SCH_1):PAGE263

R1243 Q_RES_0402LF-0,5%,1/16W,CHIP,CS00002JB13
     1 SMB_ADC_SDA_R @T6G_MB_LIB.T6G(SCH_1):SMB_ADC_SDA_R   I141 @T6G_MB_LIB.T6G(SCH_1):PAGE263
     2 SMB_SEN_TIC_2_3V3AUX_SDA @T6G_MB_LIB.T6G(SCH_1):SMB_SEN_TIC_2_3V3AUX_SDA   I141 @T6G_MB_LIB.T6G(SCH_1):PAGE263

R1244 Q_RES_0402LF-0,5%,1/16W,CHIP,CS00002JB13
     1 SMB_ADC_SCL_R @T6G_MB_LIB.T6G(SCH_1):SMB_ADC_SCL_R   I140 @T6G_MB_LIB.T6G(SCH_1):PAGE263
     2 SMB_SEN_TIC_2_3V3AUX_SCL @T6G_MB_LIB.T6G(SCH_1):SMB_SEN_TIC_2_3V3AUX_SCL   I140 @T6G_MB_LIB.T6G(SCH_1):PAGE263

R1245 Q_RES_0402LF-0,5%,1/16W,EMPTY,CS00002JB13
     1 P1V2_AUX_ADC @T6G_MB_LIB.T6G(SCH_1):P1V2_AUX_ADC   I177 @T6G_MB_LIB.T6G(SCH_1):PAGE263
     2 P1V2_AUX_ADC_MAM @T6G_MB_LIB.T6G(SCH_1):P1V2_AUX_ADC_MAM   I177 @T6G_MB_LIB.T6G(SCH_1):PAGE263

R1246 Q_RES_0402LF-0,5%,1/16W,EMPTY,CS00002JB13
     1 P1V8_CPU0_RT_1D_ADC @T6G_MB_LIB.T6G(SCH_1):P1V8_CPU0_RT_1D_ADC   I189 @T6G_MB_LIB.T6G(SCH_1):PAGE263
     2 P1V8_CPU0_RT_1D_ADC_MAM @T6G_MB_LIB.T6G(SCH_1):P1V8_CPU0_RT_1D_ADC_MAM   I189 @T6G_MB_LIB.T6G(SCH_1):PAGE263

R1247 Q_RES_0402LF-0,5%,1/16W,EMPTY,CS00002JB13
     1 PVDD18_S5_P0_ADC @T6G_MB_LIB.T6G(SCH_1):PVDD18_S5_P0_ADC   I225 @T6G_MB_LIB.T6G(SCH_1):PAGE263
     2 PVDD18_S5_P0_ADC_MAM @T6G_MB_LIB.T6G(SCH_1):PVDD18_S5_P0_ADC_MAM   I225 @T6G_MB_LIB.T6G(SCH_1):PAGE263

R1248 Q_RES_0402LF-0,5%,1/16W,EMPTY,CS00002JB13
     1 PVDD_33_S5_ADC @T6G_MB_LIB.T6G(SCH_1):PVDD_33_S5_ADC   I213 @T6G_MB_LIB.T6G(SCH_1):PAGE263
     2 PVDD_33_S5_ADC_MAM @T6G_MB_LIB.T6G(SCH_1):PVDD_33_S5_ADC_MAM   I213 @T6G_MB_LIB.T6G(SCH_1):PAGE263

R1249 Q_RES_0402LF-0,5%,1/16W,EMPTY,CS00002JB13
     1 PVDD18_S5_P1_ADC @T6G_MB_LIB.T6G(SCH_1):PVDD18_S5_P1_ADC   I231 @T6G_MB_LIB.T6G(SCH_1):PAGE263
     2 PVDD18_S5_P1_ADC_MAM @T6G_MB_LIB.T6G(SCH_1):PVDD18_S5_P1_ADC_MAM   I231 @T6G_MB_LIB.T6G(SCH_1):PAGE263

R1250 Q_RES_0402LF-0,5%,1/16W,EMPTY,CS00002JB13
     1 P1V8_CPU1_RT_1D_ADC @T6G_MB_LIB.T6G(SCH_1):P1V8_CPU1_RT_1D_ADC   I202 @T6G_MB_LIB.T6G(SCH_1):PAGE263
     2 P1V8_CPU1_RT_1D_ADC_MAM @T6G_MB_LIB.T6G(SCH_1):P1V8_CPU1_RT_1D_ADC_MAM   I202 @T6G_MB_LIB.T6G(SCH_1):PAGE263

R1251 Q_RES_0402LF-0,5%,1/16W,CHIP,CS00002JB13
     1 P1V2_AUX_ADC @T6G_MB_LIB.T6G(SCH_1):P1V2_AUX_ADC   I178 @T6G_MB_LIB.T6G(SCH_1):PAGE263
     2 P1V2_AUX_ADC_TIC @T6G_MB_LIB.T6G(SCH_1):P1V2_AUX_ADC_TIC   I178 @T6G_MB_LIB.T6G(SCH_1):PAGE263

R1252 Q_RES_0402LF-0,5%,1/16W,CHIP,CS00002JB13
     1 P1V8_CPU0_RT_1D_ADC @T6G_MB_LIB.T6G(SCH_1):P1V8_CPU0_RT_1D_ADC   I190 @T6G_MB_LIB.T6G(SCH_1):PAGE263
     2 P1V8_CPU0_RT_1D_ADC_TIC @T6G_MB_LIB.T6G(SCH_1):P1V8_CPU0_RT_1D_ADC_TIC   I190 @T6G_MB_LIB.T6G(SCH_1):PAGE263

R1253 Q_RES_0402LF-33,5%,1/16W,CHIP,CS03302JB10
     1 UART_LS_EN_N @T6G_MB_LIB.T6G(SCH_1):UART_LS_EN_N   I211 @T6G_MB_LIB.T6G(SCH_1):PAGE141
     2 UART_LS_EN_R_N @T6G_MB_LIB.T6G(SCH_1):UART_LS_EN_R_N   I211 @T6G_MB_LIB.T6G(SCH_1):PAGE141

R1254 Q_RES_0402LF-0,5%,1/16W,CHIP,CS00002JB13
     1 PVDD18_S5_P0_ADC @T6G_MB_LIB.T6G(SCH_1):PVDD18_S5_P0_ADC   I226 @T6G_MB_LIB.T6G(SCH_1):PAGE263
     2 PVDD18_S5_P0_ADC_TIC @T6G_MB_LIB.T6G(SCH_1):PVDD18_S5_P0_ADC_TIC   I226 @T6G_MB_LIB.T6G(SCH_1):PAGE263

R1255 Q_RES_0402LF-0,5%,1/16W,CHIP,CS00002JB13
     1 PVDD_33_S5_ADC @T6G_MB_LIB.T6G(SCH_1):PVDD_33_S5_ADC   I214 @T6G_MB_LIB.T6G(SCH_1):PAGE263
     2 PVDD_33_S5_ADC_TIC @T6G_MB_LIB.T6G(SCH_1):PVDD_33_S5_ADC_TIC   I214 @T6G_MB_LIB.T6G(SCH_1):PAGE263

R1256 Q_RES_0402LF-0,5%,1/16W,CHIP,CS00002JB13
     1 PVDD18_S5_P1_ADC @T6G_MB_LIB.T6G(SCH_1):PVDD18_S5_P1_ADC   I239 @T6G_MB_LIB.T6G(SCH_1):PAGE263
     2 PVDD18_S5_P1_ADC_TIC @T6G_MB_LIB.T6G(SCH_1):PVDD18_S5_P1_ADC_TIC   I239 @T6G_MB_LIB.T6G(SCH_1):PAGE263

R1257 Q_RES_0402LF-0,5%,1/16W,CHIP,CS00002JB13
     1 P1V8_CPU1_RT_1D_ADC @T6G_MB_LIB.T6G(SCH_1):P1V8_CPU1_RT_1D_ADC   I203 @T6G_MB_LIB.T6G(SCH_1):PAGE263
     2 P1V8_CPU1_RT_1D_ADC_TIC @T6G_MB_LIB.T6G(SCH_1):P1V8_CPU1_RT_1D_ADC_TIC   I203 @T6G_MB_LIB.T6G(SCH_1):PAGE263

R1258 Q_RES_0402LF-0,5%,1/16W,EMPTY,CS00002JB13
     1 P1V8_AUX_ADC @T6G_MB_LIB.T6G(SCH_1):P1V8_AUX_ADC    I22 @T6G_MB_LIB.T6G(SCH_1):PAGE263
     2 P1V8_AUX_ADC_MAM @T6G_MB_LIB.T6G(SCH_1):P1V8_AUX_ADC_MAM    I22 @T6G_MB_LIB.T6G(SCH_1):PAGE263

R1259 Q_RES_0402LF-0,5%,1/16W,CHIP,CS00002JB13
     1 P1V8_AUX_ADC @T6G_MB_LIB.T6G(SCH_1):P1V8_AUX_ADC    I21 @T6G_MB_LIB.T6G(SCH_1):PAGE263
     2 P1V8_AUX_ADC_TIC @T6G_MB_LIB.T6G(SCH_1):P1V8_AUX_ADC_TIC    I21 @T6G_MB_LIB.T6G(SCH_1):PAGE263

R1260 Q_RES_0402LF-0,5%,1/16W,EMPTY,CS00002JB13
     1 P5V_AUX_ADC @T6G_MB_LIB.T6G(SCH_1):P5V_AUX_ADC    I16 @T6G_MB_LIB.T6G(SCH_1):PAGE263
     2 P5V_AUX_ADC_MAM @T6G_MB_LIB.T6G(SCH_1):P5V_AUX_ADC_MAM    I16 @T6G_MB_LIB.T6G(SCH_1):PAGE263

R1261 Q_RES_0402LF-10K,5%,1/16W,CHIP,CS31002JB08
     1 P1V8_AUX @T6G_MB_LIB.T6G(SCH_1):P1V8_AUX    I15 @T6G_MB_LIB.T6G(SCH_1):PAGE144
     2 FM_SPD_CPU0_SWITCH_CTRL_N @T6G_MB_LIB.T6G(SCH_1):FM_SPD_CPU0_SWITCH_CTRL_N    I15 @T6G_MB_LIB.T6G(SCH_1):PAGE144

R1262 Q_RES_0402LF-10K,5%,1/16W,CHIP,CS31002JB08
     1 P1V8_AUX @T6G_MB_LIB.T6G(SCH_1):P1V8_AUX    I30 @T6G_MB_LIB.T6G(SCH_1):PAGE144
     2 BMC_JTAG_SEL @T6G_MB_LIB.T6G(SCH_1):BMC_JTAG_SEL    I30 @T6G_MB_LIB.T6G(SCH_1):PAGE144

R1263 Q_RES_0402LF-0,5%,1/16W,CHIP,CS00002JB13
     1 P5V_AUX_ADC @T6G_MB_LIB.T6G(SCH_1):P5V_AUX_ADC    I15 @T6G_MB_LIB.T6G(SCH_1):PAGE263
     2 P5V_AUX_ADC_TIC @T6G_MB_LIB.T6G(SCH_1):P5V_AUX_ADC_TIC    I15 @T6G_MB_LIB.T6G(SCH_1):PAGE263

R1264 Q_RES_0402LF-1K,1%,1/16W,EMPTY,CS21002FB06
     1 P1V8_AUX @T6G_MB_LIB.T6G(SCH_1):P1V8_AUX    I44 @T6G_MB_LIB.T6G(SCH_1):PAGE144
     2 BIOS_DEBUG_MODE @T6G_MB_LIB.T6G(SCH_1):BIOS_DEBUG_MODE    I44 @T6G_MB_LIB.T6G(SCH_1):PAGE144

R1265 Q_RES_0402LF-10K,5%,1/16W,CHIP,CS31002JB08
     1 FM_BIOS_USB_RECOVERY @T6G_MB_LIB.T6G(SCH_1):FM_BIOS_USB_RECOVERY    I52 @T6G_MB_LIB.T6G(SCH_1):PAGE144
     2    GND @T6G_MB_LIB.T6G(SCH_1):GND    I52 @T6G_MB_LIB.T6G(SCH_1):PAGE144

R1266 Q_RES_0402LF-200,1%,1/16W,CHIP,CS12002FB06
     1 P3V3_AUX @T6G_MB_LIB.T6G(SCH_1):P3V3_AUX    I45 @T6G_MB_LIB.T6G(SCH_1):PAGE84
     2 BMC_FPGA_LED1_R_N @T6G_MB_LIB.T6G(SCH_1):BMC_FPGA_LED1_R_N    I45 @T6G_MB_LIB.T6G(SCH_1):PAGE84

R1267 Q_RES_0402LF-4.7K,1%,1/16W,EMPTY,CS24702FB06
     1 P3V3_ADC128_2_VCC @T6G_MB_LIB.T6G(SCH_1):P3V3_ADC128_2_VCC   I131 @T6G_MB_LIB.T6G(SCH_1):PAGE263
     2 ADC128_2_VREF @T6G_MB_LIB.T6G(SCH_1):ADC128_2_VREF   I131 @T6G_MB_LIB.T6G(SCH_1):PAGE263

R1268 Q_RES_0402LF-4.7K,1%,1/16W,EMPTY,CS24702FB06
     1 ADC128_2_VREF @T6G_MB_LIB.T6G(SCH_1):ADC128_2_VREF   I119 @T6G_MB_LIB.T6G(SCH_1):PAGE263
     2    GND @T6G_MB_LIB.T6G(SCH_1):GND   I119 @T6G_MB_LIB.T6G(SCH_1):PAGE263

R1269 Q_RES_0402LF-0,5%,1/16W,CHIP,CS00002JB13
     1 P12V_E1S_0_ADC_ALERT_R @T6G_MB_LIB.T6G(SCH_1):P12V_E1S_0_ADC_ALERT_R    I62 @T6G_MB_LIB.T6G(SCH_1):PAGE466
     2 E1S_0_P3V3_P12V_ADC_R_ALERT @T6G_MB_LIB.T6G(SCH_1):E1S_0_P3V3_P12V_ADC_R_ALERT    I62 @T6G_MB_LIB.T6G(SCH_1):PAGE466

R1270 Q_RES_0402LF-0,5%,1/16W,CHIP,CS00002JB13
     1 P12V_OCP_SFF_ADC_ALERT_R @T6G_MB_LIB.T6G(SCH_1):P12V_OCP_SFF_ADC_ALERT_R    I23 @T6G_MB_LIB.T6G(SCH_1):PAGE466
     2 OCP_SFF_P3V3_P12V_ADC_R_ALERT @T6G_MB_LIB.T6G(SCH_1):OCP_SFF_P3V3_P12V_ADC_R_ALERT    I23 @T6G_MB_LIB.T6G(SCH_1):PAGE466

R1271 Q_RES_0402LF-0,5%,1/16W,CHIP,CS00002JB13
     1 P12V_OCP_V3_2_ADC_ALERT_R @T6G_MB_LIB.T6G(SCH_1):P12V_OCP_V3_2_ADC_ALERT_R    I33 @T6G_MB_LIB.T6G(SCH_1):PAGE466
     2 OCP_V3_2_P3V3_P12V_ADC_R_ALERT @T6G_MB_LIB.T6G(SCH_1):OCP_V3_2_P3V3_P12V_ADC_R_ALERT    I33 @T6G_MB_LIB.T6G(SCH_1):PAGE466

R1272 Q_RES_0402LF-0,5%,1/16W,CHIP,CS00002JB13
     1 SMB_INA230_8_3V3AUX_SCL_R @T6G_MB_LIB.T6G(SCH_1):SMB_INA230_8_3V3AUX_SCL_R    I71 @T6G_MB_LIB.T6G(SCH_1):PAGE466
     2 SMB_INA230_8_3V3AUX_SCL_R1 @T6G_MB_LIB.T6G(SCH_1):SMB_INA230_8_3V3AUX_SCL_R1    I71 @T6G_MB_LIB.T6G(SCH_1):PAGE466

R1273 Q_RES_0402LF-0,5%,1/16W,CHIP,CS00002JB13
     1 SMB_INA230_6_3V3AUX_SCL_R @T6G_MB_LIB.T6G(SCH_1):SMB_INA230_6_3V3AUX_SCL_R    I27 @T6G_MB_LIB.T6G(SCH_1):PAGE466
     2 SMB_INA230_6_3V3AUX_SCL_R1 @T6G_MB_LIB.T6G(SCH_1):SMB_INA230_6_3V3AUX_SCL_R1    I27 @T6G_MB_LIB.T6G(SCH_1):PAGE466

R1274 Q_RES_0402LF-0,5%,1/16W,CHIP,CS00002JB13
     1 SMB_INA230_7_3V3AUX_SCL_R @T6G_MB_LIB.T6G(SCH_1):SMB_INA230_7_3V3AUX_SCL_R    I42 @T6G_MB_LIB.T6G(SCH_1):PAGE466
     2 SMB_INA230_7_3V3AUX_SCL_R1 @T6G_MB_LIB.T6G(SCH_1):SMB_INA230_7_3V3AUX_SCL_R1    I42 @T6G_MB_LIB.T6G(SCH_1):PAGE466

R1275 Q_RES_0402LF-0,5%,1/16W,CHIP,CS00002JB13
     1 SMB_INA230_8_3V3AUX_SDA_R @T6G_MB_LIB.T6G(SCH_1):SMB_INA230_8_3V3AUX_SDA_R    I70 @T6G_MB_LIB.T6G(SCH_1):PAGE466
     2 SMB_INA230_8_3V3AUX_SDA_R1 @T6G_MB_LIB.T6G(SCH_1):SMB_INA230_8_3V3AUX_SDA_R1    I70 @T6G_MB_LIB.T6G(SCH_1):PAGE466

R1276 Q_RES_0402LF-0,5%,1/16W,CHIP,CS00002JB13
     1 SMB_INA230_6_3V3AUX_SDA_R @T6G_MB_LIB.T6G(SCH_1):SMB_INA230_6_3V3AUX_SDA_R    I14 @T6G_MB_LIB.T6G(SCH_1):PAGE466
     2 SMB_INA230_6_3V3AUX_SDA_R1 @T6G_MB_LIB.T6G(SCH_1):SMB_INA230_6_3V3AUX_SDA_R1    I14 @T6G_MB_LIB.T6G(SCH_1):PAGE466

R1277 Q_RES_0402LF-0,5%,1/16W,CHIP,CS00002JB13
     1 SMB_INA230_7_3V3AUX_SDA_R @T6G_MB_LIB.T6G(SCH_1):SMB_INA230_7_3V3AUX_SDA_R    I41 @T6G_MB_LIB.T6G(SCH_1):PAGE466
     2 SMB_INA230_7_3V3AUX_SDA_R1 @T6G_MB_LIB.T6G(SCH_1):SMB_INA230_7_3V3AUX_SDA_R1    I41 @T6G_MB_LIB.T6G(SCH_1):PAGE466

R1278 Q_RES_0402LF-33,5%,1/16W,CHIP,CS03302JB10
     1 FM_P1_PCC0_N @T6G_MB_LIB.T6G(SCH_1):FM_P1_PCC0_N   I105 @T6G_MB_LIB.T6G(SCH_1):PAGE80
     2 FM_P1_PCC0_R_N @T6G_MB_LIB.T6G(SCH_1):FM_P1_PCC0_R_N   I105 @T6G_MB_LIB.T6G(SCH_1):PAGE80

R1279 Q_RES_0402LF-33,5%,1/16W,CHIP,CS03302JB10
     1 FM_P1_PCC1_N @T6G_MB_LIB.T6G(SCH_1):FM_P1_PCC1_N   I103 @T6G_MB_LIB.T6G(SCH_1):PAGE80
     2 FM_P1_PCC1_R_N @T6G_MB_LIB.T6G(SCH_1):FM_P1_PCC1_R_N   I103 @T6G_MB_LIB.T6G(SCH_1):PAGE80

R1280 Q_RES_0402LF-33,5%,1/16W,CHIP,CS03302JB10
     1 FM_P0_PCC0_N @T6G_MB_LIB.T6G(SCH_1):FM_P0_PCC0_N   I102 @T6G_MB_LIB.T6G(SCH_1):PAGE80
     2 FM_P0_PCC0_R_N @T6G_MB_LIB.T6G(SCH_1):FM_P0_PCC0_R_N   I102 @T6G_MB_LIB.T6G(SCH_1):PAGE80

R1281 Q_RES_0402LF-33,5%,1/16W,CHIP,CS03302JB10
     1 FM_P0_PCC1_N @T6G_MB_LIB.T6G(SCH_1):FM_P0_PCC1_N   I101 @T6G_MB_LIB.T6G(SCH_1):PAGE80
     2 FM_P0_PCC1_R_N @T6G_MB_LIB.T6G(SCH_1):FM_P0_PCC1_R_N   I101 @T6G_MB_LIB.T6G(SCH_1):PAGE80

R1282 Q_RES_0402LF-33,5%,1/16W,CHIP,CS03302JB10
     1 FM_NCSI_OCP_SFF_R_OE @T6G_MB_LIB.T6G(SCH_1):FM_NCSI_OCP_SFF_R_OE    I29 @T6G_MB_LIB.T6G(SCH_1):PAGE80
     2 FM_PLD_OCP_SFF_PWR_GOOD_R @T6G_MB_LIB.T6G(SCH_1):FM_PLD_OCP_SFF_PWR_GOOD_R    I29 @T6G_MB_LIB.T6G(SCH_1):PAGE80

R1283 Q_RES_0402LF-10,1%,1/16W,CHIP,CS01002FB07
     1 P12V_E1S_0 @T6G_MB_LIB.T6G(SCH_1):P12V_E1S_0    I74 @T6G_MB_LIB.T6G(SCH_1):PAGE466
     2 VSENSE_P12V_INA230_8_INP @T6G_MB_LIB.T6G(SCH_1):VSENSE_P12V_INA230_8_INP    I74 @T6G_MB_LIB.T6G(SCH_1):PAGE466

R1284 Q_RES_0402LF-10,1%,1/16W,CHIP,CS01002FB07
     1 P12V_OCP_SFF @T6G_MB_LIB.T6G(SCH_1):P12V_OCP_SFF    I10 @T6G_MB_LIB.T6G(SCH_1):PAGE466
     2 VSENSE_P12V_INA230_6_INP @T6G_MB_LIB.T6G(SCH_1):VSENSE_P12V_INA230_6_INP    I10 @T6G_MB_LIB.T6G(SCH_1):PAGE466

R1285 Q_RES_0402LF-4.7K,5%,1/16W,CHIP,CS24702JB10
     1 FM_P1_PCC0_N @T6G_MB_LIB.T6G(SCH_1):FM_P1_PCC0_N    I77 @T6G_MB_LIB.T6G(SCH_1):PAGE82
     2 PVDD18_S5_P1 @T6G_MB_LIB.T6G(SCH_1):PVDD18_S5_P1    I77 @T6G_MB_LIB.T6G(SCH_1):PAGE82

R1286 Q_RES_0402LF-4.7K,5%,1/16W,CHIP,CS24702JB10
     1 FM_P1_PCC1_N @T6G_MB_LIB.T6G(SCH_1):FM_P1_PCC1_N    I76 @T6G_MB_LIB.T6G(SCH_1):PAGE82
     2 PVDD18_S5_P1 @T6G_MB_LIB.T6G(SCH_1):PVDD18_S5_P1    I76 @T6G_MB_LIB.T6G(SCH_1):PAGE82

R1287 Q_RES_0402LF-4.7K,5%,1/16W,CHIP,CS24702JB10
     1 FM_P0_PCC0_N @T6G_MB_LIB.T6G(SCH_1):FM_P0_PCC0_N    I74 @T6G_MB_LIB.T6G(SCH_1):PAGE82
     2 PVDD18_S5_P0 @T6G_MB_LIB.T6G(SCH_1):PVDD18_S5_P0    I74 @T6G_MB_LIB.T6G(SCH_1):PAGE82

R1288 Q_RES_0402LF-4.7K,5%,1/16W,CHIP,CS24702JB10
     1 FM_P0_PCC1_N @T6G_MB_LIB.T6G(SCH_1):FM_P0_PCC1_N    I73 @T6G_MB_LIB.T6G(SCH_1):PAGE82
     2 PVDD18_S5_P0 @T6G_MB_LIB.T6G(SCH_1):PVDD18_S5_P0    I73 @T6G_MB_LIB.T6G(SCH_1):PAGE82

R1289 Q_RES_0402LF-100K,1%,1/16W,CHIP,CS41002FB09
     1 FB_BMC_ISOLATE @T6G_MB_LIB.T6G(SCH_1):FB_BMC_ISOLATE    I56 @T6G_MB_LIB.T6G(SCH_1):PAGE336
     2    GND @T6G_MB_LIB.T6G(SCH_1):GND    I56 @T6G_MB_LIB.T6G(SCH_1):PAGE336

R1290 Q_RES_0402LF-22,1%,1/16W,EMPTY,CS02202FB02
     1 OCP_SFF_RBT_ARB_IN_R @T6G_MB_LIB.T6G(SCH_1):OCP_SFF_RBT_ARB_IN_R    I98 @T6G_MB_LIB.T6G(SCH_1):PAGE336
     2 OCP_SFF_RBT_ARB_IN @T6G_MB_LIB.T6G(SCH_1):OCP_SFF_RBT_ARB_IN    I98 @T6G_MB_LIB.T6G(SCH_1):PAGE336

R1291 Q_RES_0402LF-10,1%,1/16W,CHIP,CS01002FB07
     1 P12V_OCP_V3_2 @T6G_MB_LIB.T6G(SCH_1):P12V_OCP_V3_2    I43 @T6G_MB_LIB.T6G(SCH_1):PAGE466
     2 VSENSE_P12V_INA230_7_INP @T6G_MB_LIB.T6G(SCH_1):VSENSE_P12V_INA230_7_INP    I43 @T6G_MB_LIB.T6G(SCH_1):PAGE466

R1292 Q_RES_0402LF-10,1%,1/16W,CHIP,CS01002FB07
     1 P12V_E1S_0_R @T6G_MB_LIB.T6G(SCH_1):P12V_E1S_0_R    I75 @T6G_MB_LIB.T6G(SCH_1):PAGE466
     2 VSENSE_P12V_INA230_8_INN @T6G_MB_LIB.T6G(SCH_1):VSENSE_P12V_INA230_8_INN    I75 @T6G_MB_LIB.T6G(SCH_1):PAGE466

R1293 Q_RES_0402LF-0,5%,1/16W,CHIP,CS00002JB13
     1 I3C_SPD_DDRAF_CPU1_SCL @T6G_MB_LIB.T6G(SCH_1):I3C_SPD_DDRAF_CPU1_SCL    I35 @T6G_MB_LIB.T6G(SCH_1):PAGE136
     2 I3C_SPD_DDRAF_CPU1_LVC1_SCL @T6G_MB_LIB.T6G(SCH_1):I3C_SPD_DDRAF_CPU1_LVC1_SCL    I35 @T6G_MB_LIB.T6G(SCH_1):PAGE136

R1294 Q_RES_0402LF-0,5%,1/16W,CHIP,CS00002JB13
     1 I3C_SPD_DDRAF_CPU1_SDA @T6G_MB_LIB.T6G(SCH_1):I3C_SPD_DDRAF_CPU1_SDA    I36 @T6G_MB_LIB.T6G(SCH_1):PAGE136
     2 I3C_SPD_DDRAF_CPU1_LVC1_SDA @T6G_MB_LIB.T6G(SCH_1):I3C_SPD_DDRAF_CPU1_LVC1_SDA    I36 @T6G_MB_LIB.T6G(SCH_1):PAGE136

R1295 Q_RES_0402LF-0,5%,1/16W,CHIP,CS00002JB13
     1 I3C_SPD_DDRGL_CPU1_SCL @T6G_MB_LIB.T6G(SCH_1):I3C_SPD_DDRGL_CPU1_SCL    I37 @T6G_MB_LIB.T6G(SCH_1):PAGE136
     2 I3C_SPD_DDRGL_CPU1_LVC1_SCL @T6G_MB_LIB.T6G(SCH_1):I3C_SPD_DDRGL_CPU1_LVC1_SCL    I37 @T6G_MB_LIB.T6G(SCH_1):PAGE136

R1296 Q_RES_0402LF-0,5%,1/16W,CHIP,CS00002JB13
     1 I3C_SPD_DDRGL_CPU1_SDA @T6G_MB_LIB.T6G(SCH_1):I3C_SPD_DDRGL_CPU1_SDA    I38 @T6G_MB_LIB.T6G(SCH_1):PAGE136
     2 I3C_SPD_DDRGL_CPU1_LVC1_SDA @T6G_MB_LIB.T6G(SCH_1):I3C_SPD_DDRGL_CPU1_LVC1_SDA    I38 @T6G_MB_LIB.T6G(SCH_1):PAGE136

R1297 Q_RES_0402LF-0,5%,1/16W,CHIP,CS00002JB13
     1 I3C_SPD_DDRAF_CPU0_SCL @T6G_MB_LIB.T6G(SCH_1):I3C_SPD_DDRAF_CPU0_SCL    I31 @T6G_MB_LIB.T6G(SCH_1):PAGE136
     2 I3C_SPD_DDRAF_CPU0_LVC1_SCL @T6G_MB_LIB.T6G(SCH_1):I3C_SPD_DDRAF_CPU0_LVC1_SCL    I31 @T6G_MB_LIB.T6G(SCH_1):PAGE136

R1298 Q_RES_0402LF-0,5%,1/16W,CHIP,CS00002JB13
     1 I3C_SPD_DDRAF_CPU0_SDA @T6G_MB_LIB.T6G(SCH_1):I3C_SPD_DDRAF_CPU0_SDA    I32 @T6G_MB_LIB.T6G(SCH_1):PAGE136
     2 I3C_SPD_DDRAF_CPU0_LVC1_SDA @T6G_MB_LIB.T6G(SCH_1):I3C_SPD_DDRAF_CPU0_LVC1_SDA    I32 @T6G_MB_LIB.T6G(SCH_1):PAGE136

R1299 Q_RES_0402LF-0,5%,1/16W,CHIP,CS00002JB13
     1 I3C_SPD_DDRGL_CPU0_SCL @T6G_MB_LIB.T6G(SCH_1):I3C_SPD_DDRGL_CPU0_SCL    I33 @T6G_MB_LIB.T6G(SCH_1):PAGE136
     2 I3C_SPD_DDRGL_CPU0_LVC1_SCL @T6G_MB_LIB.T6G(SCH_1):I3C_SPD_DDRGL_CPU0_LVC1_SCL    I33 @T6G_MB_LIB.T6G(SCH_1):PAGE136

R1300 Q_RES_0402LF-0,5%,1/16W,CHIP,CS00002JB13
     1 I3C_SPD_DDRGL_CPU0_SDA @T6G_MB_LIB.T6G(SCH_1):I3C_SPD_DDRGL_CPU0_SDA    I34 @T6G_MB_LIB.T6G(SCH_1):PAGE136
     2 I3C_SPD_DDRGL_CPU0_LVC1_SDA @T6G_MB_LIB.T6G(SCH_1):I3C_SPD_DDRGL_CPU0_LVC1_SDA    I34 @T6G_MB_LIB.T6G(SCH_1):PAGE136

R1301 Q_RES_0402LF-10,1%,1/16W,CHIP,CS01002FB07
     1 P12V_OCP_SFF_R @T6G_MB_LIB.T6G(SCH_1):P12V_OCP_SFF_R    I11 @T6G_MB_LIB.T6G(SCH_1):PAGE466
     2 VSENSE_P12V_INA230_6_INN @T6G_MB_LIB.T6G(SCH_1):VSENSE_P12V_INA230_6_INN    I11 @T6G_MB_LIB.T6G(SCH_1):PAGE466

R1302 Q_RES_0402LF-10,1%,1/16W,CHIP,CS01002FB07
     1 P12V_OCP_V3_2_R @T6G_MB_LIB.T6G(SCH_1):P12V_OCP_V3_2_R    I55 @T6G_MB_LIB.T6G(SCH_1):PAGE466
     2 VSENSE_P12V_INA230_7_INN @T6G_MB_LIB.T6G(SCH_1):VSENSE_P12V_INA230_7_INN    I55 @T6G_MB_LIB.T6G(SCH_1):PAGE466

R1303 Q_RES_0402LF-1K,1%,1/16W,CHIP,CS21002FB06
     1 FM_SMB_RST_E1S_0_N @T6G_MB_LIB.T6G(SCH_1):FM_SMB_RST_E1S_0_N     I5 @T6G_MB_LIB.T6G(SCH_1):PAGE84
     2 P3V3_AUX @T6G_MB_LIB.T6G(SCH_1):P3V3_AUX     I5 @T6G_MB_LIB.T6G(SCH_1):PAGE84

R1304 Q_RES_0402LF-10K,1%,1/16W,CHIP,CS31002FB08
     1 E1S_0_PRSNT_N @T6G_MB_LIB.T6G(SCH_1):E1S_0_PRSNT_N   I171 @T6G_MB_LIB.T6G(SCH_1):PAGE82
     2 P3V3_AUX @T6G_MB_LIB.T6G(SCH_1):P3V3_AUX   I171 @T6G_MB_LIB.T6G(SCH_1):PAGE82

R1305 Q_RES_0402LF-4.7K,1%,1/16W,EMPTY,CS24702FB06
     1    GND @T6G_MB_LIB.T6G(SCH_1):GND    I72 @T6G_MB_LIB.T6G(SCH_1):PAGE466
     2 INA230_8_A1 @T6G_MB_LIB.T6G(SCH_1):INA230_8_A1    I72 @T6G_MB_LIB.T6G(SCH_1):PAGE466

R1306 Q_RES_0402LF-4.7K,1%,1/16W,EMPTY,CS24702FB06
     1    GND @T6G_MB_LIB.T6G(SCH_1):GND    I12 @T6G_MB_LIB.T6G(SCH_1):PAGE466
     2 INA230_6_A1 @T6G_MB_LIB.T6G(SCH_1):INA230_6_A1    I12 @T6G_MB_LIB.T6G(SCH_1):PAGE466

R1307 Q_RES_0402LF-4.7K,1%,1/16W,EMPTY,CS24702FB06
     1    GND @T6G_MB_LIB.T6G(SCH_1):GND    I44 @T6G_MB_LIB.T6G(SCH_1):PAGE466
     2 INA230_7_A1 @T6G_MB_LIB.T6G(SCH_1):INA230_7_A1    I44 @T6G_MB_LIB.T6G(SCH_1):PAGE466

R1308 Q_RES_0402LF-4.7K,1%,1/16W,CHIP,CS24702FB06
     1    GND @T6G_MB_LIB.T6G(SCH_1):GND    I96 @T6G_MB_LIB.T6G(SCH_1):PAGE466
     2 INA230_8_A0 @T6G_MB_LIB.T6G(SCH_1):INA230_8_A0    I96 @T6G_MB_LIB.T6G(SCH_1):PAGE466

R1309 Q_RES_0402LF-4.7K,1%,1/16W,EMPTY,CS24702FB06
     1    GND @T6G_MB_LIB.T6G(SCH_1):GND    I13 @T6G_MB_LIB.T6G(SCH_1):PAGE466
     2 INA230_6_A0 @T6G_MB_LIB.T6G(SCH_1):INA230_6_A0    I13 @T6G_MB_LIB.T6G(SCH_1):PAGE466

R1310 Q_RES_0402LF-4.7K,1%,1/16W,EMPTY,CS24702FB06
     1    GND @T6G_MB_LIB.T6G(SCH_1):GND    I45 @T6G_MB_LIB.T6G(SCH_1):PAGE466
     2 INA230_7_A0 @T6G_MB_LIB.T6G(SCH_1):INA230_7_A0    I45 @T6G_MB_LIB.T6G(SCH_1):PAGE466

R1311 Q_RES_0402LF-33,5%,1/16W,CHIP,CS03302JB10
     1 IRQ_WAKE_R_N @T6G_MB_LIB.T6G(SCH_1):IRQ_WAKE_R_N    I16 @T6G_MB_LIB.T6G(SCH_1):PAGE132
     2 IRQ_WAKE_N @T6G_MB_LIB.T6G(SCH_1):IRQ_WAKE_N    I16 @T6G_MB_LIB.T6G(SCH_1):PAGE132

R1312 Q_RES_0402LF-0,5%,1/16W,CHIP,CS00002JB13
     1 SMB_ADC_SDA @T6G_MB_LIB.T6G(SCH_1):SMB_ADC_SDA    I79 @T6G_MB_LIB.T6G(SCH_1):PAGE251
     2 SMB_ADC_SDA_R @T6G_MB_LIB.T6G(SCH_1):SMB_ADC_SDA_R    I79 @T6G_MB_LIB.T6G(SCH_1):PAGE251

R1313 Q_RES_0402LF-4.7K,5%,1/16W,CHIP,CS24702JB10
     1 PD_U160_EN_N @T6G_MB_LIB.T6G(SCH_1):PD_U160_EN_N   I383 @T6G_MB_LIB.T6G(SCH_1):PAGE148
     2    GND @T6G_MB_LIB.T6G(SCH_1):GND   I383 @T6G_MB_LIB.T6G(SCH_1):PAGE148

R1314 Q_RES_0402LF-4.7K,5%,1/16W,EMPTY,CS24702JB10
     1 E1S_0_P12V_EN @T6G_MB_LIB.T6G(SCH_1):E1S_0_P12V_EN    I54 @T6G_MB_LIB.T6G(SCH_1):PAGE82
     2 P3V3_AUX @T6G_MB_LIB.T6G(SCH_1):P3V3_AUX    I54 @T6G_MB_LIB.T6G(SCH_1):PAGE82

R1315 Q_RES_0402LF-0,5%,1/16W,CHIP,CS00002JB13
     1 SMB_ADC_SCL @T6G_MB_LIB.T6G(SCH_1):SMB_ADC_SCL    I80 @T6G_MB_LIB.T6G(SCH_1):PAGE251
     2 SMB_ADC_SCL_R @T6G_MB_LIB.T6G(SCH_1):SMB_ADC_SCL_R    I80 @T6G_MB_LIB.T6G(SCH_1):PAGE251

R1316 Q_RES_0402LF-2.2K,5%,1/16W,CHIP,CS22202JB07
     1 P3V3_AUX @T6G_MB_LIB.T6G(SCH_1):P3V3_AUX    I83 @T6G_MB_LIB.T6G(SCH_1):PAGE251
     2 SMB_ADC_SCL_R @T6G_MB_LIB.T6G(SCH_1):SMB_ADC_SCL_R    I83 @T6G_MB_LIB.T6G(SCH_1):PAGE251

R1317 Q_RES_0402LF-4.7K,1%,1/16W,EMPTY,CS24702FB06
     1 P3V3_AUX @T6G_MB_LIB.T6G(SCH_1):P3V3_AUX    I95 @T6G_MB_LIB.T6G(SCH_1):PAGE466
     2 INA230_8_A1 @T6G_MB_LIB.T6G(SCH_1):INA230_8_A1    I95 @T6G_MB_LIB.T6G(SCH_1):PAGE466

R1318 Q_RES_0402LF-4.7K,5%,1/16W,CHIP,CS24702JB10
     1 PD_U212_EN_N @T6G_MB_LIB.T6G(SCH_1):PD_U212_EN_N   I378 @T6G_MB_LIB.T6G(SCH_1):PAGE148
     2    GND @T6G_MB_LIB.T6G(SCH_1):GND   I378 @T6G_MB_LIB.T6G(SCH_1):PAGE148

R1319 Q_RES_0402LF-2K,1%,1/16W,EMPTY,CS22002FB07
     1 SMB_CPU0_CPU1_APML_SCL @T6G_MB_LIB.T6G(SCH_1):SMB_CPU0_CPU1_APML_SCL   I138 @T6G_MB_LIB.T6G(SCH_1):PAGE349
     2 P3V3_AUX @T6G_MB_LIB.T6G(SCH_1):P3V3_AUX   I138 @T6G_MB_LIB.T6G(SCH_1):PAGE349

R1320 Q_RES_0402LF-4.7K,1%,1/16W,CHIP,CS24702FB06
     1 P3V3_AUX @T6G_MB_LIB.T6G(SCH_1):P3V3_AUX    I17 @T6G_MB_LIB.T6G(SCH_1):PAGE466
     2 INA230_6_A1 @T6G_MB_LIB.T6G(SCH_1):INA230_6_A1    I17 @T6G_MB_LIB.T6G(SCH_1):PAGE466

R1321 Q_RES_0402LF-33,5%,1/16W,CHIP,CS03302JB10
     1 SMB_VR_3V3STBY_SCL @T6G_MB_LIB.T6G(SCH_1):SMB_VR_3V3STBY_SCL    I10 @T6G_MB_LIB.T6G(SCH_1):PAGE349
     2 SMB_SCM_2_R1_SCL @T6G_MB_LIB.T6G(SCH_1):SMB_SCM_2_R1_SCL    I10 @T6G_MB_LIB.T6G(SCH_1):PAGE349

R1322 Q_RES_0402LF-4.7K,1%,1/16W,CHIP,CS24702FB06
     1 P3V3_AUX @T6G_MB_LIB.T6G(SCH_1):P3V3_AUX    I39 @T6G_MB_LIB.T6G(SCH_1):PAGE466
     2 INA230_7_A1 @T6G_MB_LIB.T6G(SCH_1):INA230_7_A1    I39 @T6G_MB_LIB.T6G(SCH_1):PAGE466

R1323 Q_RES_2512LF-0.002,1%,2W,CHIP,CS+002AFR06
     1 P12V_E1S_0_R @T6G_MB_LIB.T6G(SCH_1):P12V_E1S_0_R    I84 @T6G_MB_LIB.T6G(SCH_1):PAGE466
     2 P12V_E1S_0 @T6G_MB_LIB.T6G(SCH_1):P12V_E1S_0    I84 @T6G_MB_LIB.T6G(SCH_1):PAGE466

R1324 Q_RES_2512LF-0.002,1%,2W,CHIP,CS+002AFR06
     1 P12V_OCP_SFF_R @T6G_MB_LIB.T6G(SCH_1):P12V_OCP_SFF_R     I2 @T6G_MB_LIB.T6G(SCH_1):PAGE466
     2 P12V_OCP_SFF @T6G_MB_LIB.T6G(SCH_1):P12V_OCP_SFF     I2 @T6G_MB_LIB.T6G(SCH_1):PAGE466

R1325 Q_RES_2512LF-0.002,1%,2W,CHIP,CS+002AFR06
     1 P12V_OCP_V3_2_R @T6G_MB_LIB.T6G(SCH_1):P12V_OCP_V3_2_R    I53 @T6G_MB_LIB.T6G(SCH_1):PAGE466
     2 P12V_OCP_V3_2 @T6G_MB_LIB.T6G(SCH_1):P12V_OCP_V3_2    I53 @T6G_MB_LIB.T6G(SCH_1):PAGE466

R1326 Q_RES_0402LF-1K,1%,1/16W,EMPTY,CS21002FB06
     1 P3V3_AUX @T6G_MB_LIB.T6G(SCH_1):P3V3_AUX    I90 @T6G_MB_LIB.T6G(SCH_1):PAGE466
     2 E1S_0_P3V3_P12V_ADC_R_ALERT @T6G_MB_LIB.T6G(SCH_1):E1S_0_P3V3_P12V_ADC_R_ALERT    I90 @T6G_MB_LIB.T6G(SCH_1):PAGE466

R1327 Q_RES_0402LF-1K,1%,1/16W,EMPTY,CS21002FB06
     1 P3V3_AUX @T6G_MB_LIB.T6G(SCH_1):P3V3_AUX    I85 @T6G_MB_LIB.T6G(SCH_1):PAGE466
     2 OCP_SFF_P3V3_P12V_ADC_R_ALERT @T6G_MB_LIB.T6G(SCH_1):OCP_SFF_P3V3_P12V_ADC_R_ALERT    I85 @T6G_MB_LIB.T6G(SCH_1):PAGE466

R1328 Q_RES_0402LF-1K,1%,1/16W,EMPTY,CS21002FB06
     1 P3V3_AUX @T6G_MB_LIB.T6G(SCH_1):P3V3_AUX    I87 @T6G_MB_LIB.T6G(SCH_1):PAGE466
     2 OCP_V3_2_P3V3_P12V_ADC_R_ALERT @T6G_MB_LIB.T6G(SCH_1):OCP_V3_2_P3V3_P12V_ADC_R_ALERT    I87 @T6G_MB_LIB.T6G(SCH_1):PAGE466

R1329 Q_RES_0402LF-0,5%,1/16W,CHIP,CS00002JB13
     1 E1S_0_P3V3_P12V_ADC_R_ALERT @T6G_MB_LIB.T6G(SCH_1):E1S_0_P3V3_P12V_ADC_R_ALERT   I178 @T6G_MB_LIB.T6G(SCH_1):PAGE81
     2 E1S_0_P3V3_P12V_ADC_ALERT @T6G_MB_LIB.T6G(SCH_1):E1S_0_P3V3_P12V_ADC_ALERT   I178 @T6G_MB_LIB.T6G(SCH_1):PAGE81

R1330 Q_RES_0402LF-0,5%,1/16W,EMPTY,CS00002JB13
     1 I3C_SPD_DDRAF_CPU0_BYPASS_SCL @T6G_MB_LIB.T6G(SCH_1):I3C_SPD_DDRAF_CPU0_BYPASS_SCL   I131 @T6G_MB_LIB.T6G(SCH_1):PAGE136
     2 I3C_SPD_DDRAF_CPU0_SCL @T6G_MB_LIB.T6G(SCH_1):I3C_SPD_DDRAF_CPU0_SCL   I131 @T6G_MB_LIB.T6G(SCH_1):PAGE136

R1331 Q_RES_0402LF-0,5%,1/16W,EMPTY,CS00002JB13
     1 I3C_SPD_DDRAF_CPU0_BYPASS_SDA @T6G_MB_LIB.T6G(SCH_1):I3C_SPD_DDRAF_CPU0_BYPASS_SDA   I132 @T6G_MB_LIB.T6G(SCH_1):PAGE136
     2 I3C_SPD_DDRAF_CPU0_SDA @T6G_MB_LIB.T6G(SCH_1):I3C_SPD_DDRAF_CPU0_SDA   I132 @T6G_MB_LIB.T6G(SCH_1):PAGE136

R1332 Q_RES_0402LF-0,5%,1/16W,EMPTY,CS00002JB13
     1 I3C_SPD_DDRGL_CPU0_BYPASS_SCL @T6G_MB_LIB.T6G(SCH_1):I3C_SPD_DDRGL_CPU0_BYPASS_SCL   I134 @T6G_MB_LIB.T6G(SCH_1):PAGE136
     2 I3C_SPD_DDRGL_CPU0_SCL @T6G_MB_LIB.T6G(SCH_1):I3C_SPD_DDRGL_CPU0_SCL   I134 @T6G_MB_LIB.T6G(SCH_1):PAGE136

R1333 Q_RES_0402LF-0,5%,1/16W,EMPTY,CS00002JB13
     1 I3C_SPD_DDRGL_CPU0_BYPASS_SDA @T6G_MB_LIB.T6G(SCH_1):I3C_SPD_DDRGL_CPU0_BYPASS_SDA   I133 @T6G_MB_LIB.T6G(SCH_1):PAGE136
     2 I3C_SPD_DDRGL_CPU0_SDA @T6G_MB_LIB.T6G(SCH_1):I3C_SPD_DDRGL_CPU0_SDA   I133 @T6G_MB_LIB.T6G(SCH_1):PAGE136

R1334 Q_RES_0402LF-0,5%,1/16W,EMPTY,CS00002JB13
     1 I3C_SPD_DDRAF_CPU1_BYPASS_SCL @T6G_MB_LIB.T6G(SCH_1):I3C_SPD_DDRAF_CPU1_BYPASS_SCL   I139 @T6G_MB_LIB.T6G(SCH_1):PAGE136
     2 I3C_SPD_DDRAF_CPU1_SCL @T6G_MB_LIB.T6G(SCH_1):I3C_SPD_DDRAF_CPU1_SCL   I139 @T6G_MB_LIB.T6G(SCH_1):PAGE136

R1335 Q_RES_0402LF-0,5%,1/16W,EMPTY,CS00002JB13
     1 I3C_SPD_DDRAF_CPU1_BYPASS_SDA @T6G_MB_LIB.T6G(SCH_1):I3C_SPD_DDRAF_CPU1_BYPASS_SDA   I140 @T6G_MB_LIB.T6G(SCH_1):PAGE136
     2 I3C_SPD_DDRAF_CPU1_SDA @T6G_MB_LIB.T6G(SCH_1):I3C_SPD_DDRAF_CPU1_SDA   I140 @T6G_MB_LIB.T6G(SCH_1):PAGE136

R1336 Q_RES_0402LF-0,5%,1/16W,EMPTY,CS00002JB13
     1 I3C_SPD_DDRGL_CPU1_BYPASS_SCL @T6G_MB_LIB.T6G(SCH_1):I3C_SPD_DDRGL_CPU1_BYPASS_SCL   I143 @T6G_MB_LIB.T6G(SCH_1):PAGE136
     2 I3C_SPD_DDRGL_CPU1_SCL @T6G_MB_LIB.T6G(SCH_1):I3C_SPD_DDRGL_CPU1_SCL   I143 @T6G_MB_LIB.T6G(SCH_1):PAGE136

R1337 Q_RES_0402LF-0,5%,1/16W,EMPTY,CS00002JB13
     1 I3C_SPD_DDRGL_CPU1_BYPASS_SDA @T6G_MB_LIB.T6G(SCH_1):I3C_SPD_DDRGL_CPU1_BYPASS_SDA   I144 @T6G_MB_LIB.T6G(SCH_1):PAGE136
     2 I3C_SPD_DDRGL_CPU1_SDA @T6G_MB_LIB.T6G(SCH_1):I3C_SPD_DDRGL_CPU1_SDA   I144 @T6G_MB_LIB.T6G(SCH_1):PAGE136

R1338 Q_RES_0402LF-4.7K,5%,1/16W,CHIP,CS24702JB10
     1 P3V3_AUX @T6G_MB_LIB.T6G(SCH_1):P3V3_AUX    I29 @T6G_MB_LIB.T6G(SCH_1):PAGE83
     2 SCM_IRQ_N @T6G_MB_LIB.T6G(SCH_1):SCM_IRQ_N    I29 @T6G_MB_LIB.T6G(SCH_1):PAGE83

R1339 Q_RES_0402LF-0,5%,1/16W,CHIP,CS00002JB13
     1 OCP_V3_2_P3V3_P12V_ADC_R_ALERT @T6G_MB_LIB.T6G(SCH_1):OCP_V3_2_P3V3_P12V_ADC_R_ALERT   I180 @T6G_MB_LIB.T6G(SCH_1):PAGE81
     2 OCP_V3_2_P3V3_P12V_ADC_ALERT @T6G_MB_LIB.T6G(SCH_1):OCP_V3_2_P3V3_P12V_ADC_ALERT   I180 @T6G_MB_LIB.T6G(SCH_1):PAGE81

R1340 Q_RES_0402LF-0,5%,1/16W,CHIP,CS00002JB13
     1 OCP_SFF_P3V3_P12V_ADC_ALERT @T6G_MB_LIB.T6G(SCH_1):OCP_SFF_P3V3_P12V_ADC_ALERT   I176 @T6G_MB_LIB.T6G(SCH_1):PAGE81
     2 OCP_SFF_P3V3_P12V_ADC_R_ALERT @T6G_MB_LIB.T6G(SCH_1):OCP_SFF_P3V3_P12V_ADC_R_ALERT   I176 @T6G_MB_LIB.T6G(SCH_1):PAGE81

R1341 Q_RES_0402LF-2.2K,5%,1/16W,CHIP,CS22202JB07
     1 P3V3_AUX @T6G_MB_LIB.T6G(SCH_1):P3V3_AUX    I84 @T6G_MB_LIB.T6G(SCH_1):PAGE251
     2 SMB_ADC_SDA_R @T6G_MB_LIB.T6G(SCH_1):SMB_ADC_SDA_R    I84 @T6G_MB_LIB.T6G(SCH_1):PAGE251

R1342 Q_RES_0402LF-10K,1%,1/16W,CHIP,CS31002FB08
     1 FW_RECOVERY_R @T6G_MB_LIB.T6G(SCH_1):FW_RECOVERY_R   I369 @T6G_MB_LIB.T6G(SCH_1):PAGE148
     2    GND @T6G_MB_LIB.T6G(SCH_1):GND   I369 @T6G_MB_LIB.T6G(SCH_1):PAGE148

R1343 Q_RES_0402LF-4.7K,5%,1/16W,EMPTY,CS24702JB10
     1 P3V3_AUX @T6G_MB_LIB.T6G(SCH_1):P3V3_AUX   I339 @T6G_MB_LIB.T6G(SCH_1):PAGE148
     2 SCM_JTAG_MUX_S1 @T6G_MB_LIB.T6G(SCH_1):SCM_JTAG_MUX_S1   I339 @T6G_MB_LIB.T6G(SCH_1):PAGE148

R1344 Q_RES_0402LF-33.2,1%,1/16W,CHIP,CS03322FB03
     1 SMB_INA230_3V3AUX_SCL @T6G_MB_LIB.T6G(SCH_1):SMB_INA230_3V3AUX_SCL    I23 @T6G_MB_LIB.T6G(SCH_1):PAGE253
     2 SMB_INA230_6_3V3AUX_SCL_R @T6G_MB_LIB.T6G(SCH_1):SMB_INA230_6_3V3AUX_SCL_R    I23 @T6G_MB_LIB.T6G(SCH_1):PAGE253

R1345 Q_RES_0402LF-33.2,1%,1/16W,CHIP,CS03322FB03
     1 SMB_INA230_3V3AUX_SDA @T6G_MB_LIB.T6G(SCH_1):SMB_INA230_3V3AUX_SDA    I24 @T6G_MB_LIB.T6G(SCH_1):PAGE253
     2 SMB_INA230_6_3V3AUX_SDA_R @T6G_MB_LIB.T6G(SCH_1):SMB_INA230_6_3V3AUX_SDA_R    I24 @T6G_MB_LIB.T6G(SCH_1):PAGE253

R1346 Q_RES_0402LF-33.2,1%,1/16W,CHIP,CS03322FB03
     1 SMB_INA230_3V3AUX_SCL @T6G_MB_LIB.T6G(SCH_1):SMB_INA230_3V3AUX_SCL    I25 @T6G_MB_LIB.T6G(SCH_1):PAGE253
     2 SMB_INA230_7_3V3AUX_SCL_R @T6G_MB_LIB.T6G(SCH_1):SMB_INA230_7_3V3AUX_SCL_R    I25 @T6G_MB_LIB.T6G(SCH_1):PAGE253

R1347 Q_RES_0402LF-33.2,1%,1/16W,CHIP,CS03322FB03
     1 SMB_INA230_3V3AUX_SDA @T6G_MB_LIB.T6G(SCH_1):SMB_INA230_3V3AUX_SDA    I26 @T6G_MB_LIB.T6G(SCH_1):PAGE253
     2 SMB_INA230_7_3V3AUX_SDA_R @T6G_MB_LIB.T6G(SCH_1):SMB_INA230_7_3V3AUX_SDA_R    I26 @T6G_MB_LIB.T6G(SCH_1):PAGE253

R1348 Q_RES_0402LF-33.2,1%,1/16W,CHIP,CS03322FB03
     1 SMB_INA230_3V3AUX_SCL @T6G_MB_LIB.T6G(SCH_1):SMB_INA230_3V3AUX_SCL    I27 @T6G_MB_LIB.T6G(SCH_1):PAGE253
     2 SMB_INA230_8_3V3AUX_SCL_R @T6G_MB_LIB.T6G(SCH_1):SMB_INA230_8_3V3AUX_SCL_R    I27 @T6G_MB_LIB.T6G(SCH_1):PAGE253

R1349 Q_RES_0402LF-33.2,1%,1/16W,CHIP,CS03322FB03
     1 SMB_INA230_3V3AUX_SDA @T6G_MB_LIB.T6G(SCH_1):SMB_INA230_3V3AUX_SDA    I28 @T6G_MB_LIB.T6G(SCH_1):PAGE253
     2 SMB_INA230_8_3V3AUX_SDA_R @T6G_MB_LIB.T6G(SCH_1):SMB_INA230_8_3V3AUX_SDA_R    I28 @T6G_MB_LIB.T6G(SCH_1):PAGE253

R1350 Q_RES_0402LF-0,5%,1/16W,CHIP,CS00002JB13
     1 INA230_8_A1 @T6G_MB_LIB.T6G(SCH_1):INA230_8_A1    I94 @T6G_MB_LIB.T6G(SCH_1):PAGE466
     2 SMB_INA230_8_3V3AUX_SDA_R1 @T6G_MB_LIB.T6G(SCH_1):SMB_INA230_8_3V3AUX_SDA_R1    I94 @T6G_MB_LIB.T6G(SCH_1):PAGE466

R1351 Q_RES_0402LF-2.2K,5%,1/16W,CHIP,CS22202JB07
     1 RST_CPU0_KBRST_R_N @T6G_MB_LIB.T6G(SCH_1):RST_CPU0_KBRST_R_N    I72 @T6G_MB_LIB.T6G(SCH_1):PAGE82
     2 PVDD18_S5_P0 @T6G_MB_LIB.T6G(SCH_1):PVDD18_S5_P0    I72 @T6G_MB_LIB.T6G(SCH_1):PAGE82

R1352 Q_RES_0402LF-0,5%,1/16W,CHIP,CS00002JB13
     1 HDT_HDR_R_TCK @T6G_MB_LIB.T6G(SCH_1):HDT_HDR_R_TCK   I132 @T6G_MB_LIB.T6G(SCH_1):PAGE149
     2 HDT_HDR_TCK @T6G_MB_LIB.T6G(SCH_1):HDT_HDR_TCK   I132 @T6G_MB_LIB.T6G(SCH_1):PAGE149

R1353 Q_RES_0402LF-0,5%,1/16W,CHIP,CS00002JB13
     1 HDT_HDR_R_TMS @T6G_MB_LIB.T6G(SCH_1):HDT_HDR_R_TMS   I133 @T6G_MB_LIB.T6G(SCH_1):PAGE149
     2 HDT_HDR_TMS @T6G_MB_LIB.T6G(SCH_1):HDT_HDR_TMS   I133 @T6G_MB_LIB.T6G(SCH_1):PAGE149

R1354 Q_RES_0402LF-0,5%,1/16W,CHIP,CS00002JB13
     1 HDT_HDR_R_TDI @T6G_MB_LIB.T6G(SCH_1):HDT_HDR_R_TDI   I109 @T6G_MB_LIB.T6G(SCH_1):PAGE149
     2 HDT_HDR_TDI @T6G_MB_LIB.T6G(SCH_1):HDT_HDR_TDI   I109 @T6G_MB_LIB.T6G(SCH_1):PAGE149

R1355 Q_RES_0402LF-0,5%,1/16W,CHIP,CS00002JB13
     1 INA230_6_A0 @T6G_MB_LIB.T6G(SCH_1):INA230_6_A0    I92 @T6G_MB_LIB.T6G(SCH_1):PAGE466
     2 SMB_INA230_6_3V3AUX_SDA_R1 @T6G_MB_LIB.T6G(SCH_1):SMB_INA230_6_3V3AUX_SDA_R1    I92 @T6G_MB_LIB.T6G(SCH_1):PAGE466

R1356 Q_RES_0402LF-4.7K,5%,1/16W,CHIP,CS24702JB10
     1 P3V3_AUX @T6G_MB_LIB.T6G(SCH_1):P3V3_AUX    I77 @T6G_MB_LIB.T6G(SCH_1):PAGE144
     2 FM_PRSNT_CPU0_N @T6G_MB_LIB.T6G(SCH_1):FM_PRSNT_CPU0_N    I77 @T6G_MB_LIB.T6G(SCH_1):PAGE144

R1357 Q_RES_0402LF-2.2K,5%,1/16W,CHIP,CS22202JB07
     1 P3V3_AUX @T6G_MB_LIB.T6G(SCH_1):P3V3_AUX    I74 @T6G_MB_LIB.T6G(SCH_1):PAGE144
     2 FM_PRSNT_CPU1_N @T6G_MB_LIB.T6G(SCH_1):FM_PRSNT_CPU1_N    I74 @T6G_MB_LIB.T6G(SCH_1):PAGE144

R1358 Q_RES_0402LF-10K,5%,1/16W,EMPTY,CS31002JB08
     1 P1V8_AUX @T6G_MB_LIB.T6G(SCH_1):P1V8_AUX    I72 @T6G_MB_LIB.T6G(SCH_1):PAGE144
     2 FM_PASSWORD_CLEAR_N @T6G_MB_LIB.T6G(SCH_1):FM_PASSWORD_CLEAR_N    I72 @T6G_MB_LIB.T6G(SCH_1):PAGE144

R1359 Q_RES_0402LF-0,5%,1/16W,CHIP,CS00002JB13
     1 BMC_JTAG_SEL_R @T6G_MB_LIB.T6G(SCH_1):BMC_JTAG_SEL_R   I158 @T6G_MB_LIB.T6G(SCH_1):PAGE80
     2 BMC_JTAG_SEL @T6G_MB_LIB.T6G(SCH_1):BMC_JTAG_SEL   I158 @T6G_MB_LIB.T6G(SCH_1):PAGE80

R1360 Q_RES_0402LF-0,5%,1/16W,CHIP,CS00002JB13
     1 INA230_7_A0 @T6G_MB_LIB.T6G(SCH_1):INA230_7_A0    I93 @T6G_MB_LIB.T6G(SCH_1):PAGE466
     2 SMB_INA230_7_3V3AUX_SCL_R1 @T6G_MB_LIB.T6G(SCH_1):SMB_INA230_7_3V3AUX_SCL_R1    I93 @T6G_MB_LIB.T6G(SCH_1):PAGE466

R1361 Q_RES_0201LF-4.7K,5%,1/20W,CHIP,CS24701JE04
     1 P1V8_CPU1_RT_1D @T6G_MB_LIB.T6G(SCH_1):P1V8_CPU1_RT_1D   I104 @T6G_MB_LIB.T6G(SCH_1):PAGE377
     2 SMB_RT_CPU1_P0_ROM_MUX_2D_R_SDA @T6G_MB_LIB.T6G(SCH_1):SMB_RT_CPU1_P0_ROM_MUX_2D_R_SDA   I104 @T6G_MB_LIB.T6G(SCH_1):PAGE377

R1362 Q_RES_0402LF-33,5%,1/16W,CHIP,CS03302JB10
     1 PWRGD_P3V3_R1 @T6G_MB_LIB.T6G(SCH_1):PWRGD_P3V3_R1   I130 @T6G_MB_LIB.T6G(SCH_1):PAGE273
     2 PWRGD_P3V3_R2 @T6G_MB_LIB.T6G(SCH_1):PWRGD_P3V3_R2   I130 @T6G_MB_LIB.T6G(SCH_1):PAGE273

R1363 Q_RES_0402LF-33,5%,1/16W,CHIP,CS03302JB10
     1 PWRGD_P12V_MEM @T6G_MB_LIB.T6G(SCH_1):PWRGD_P12V_MEM    I17 @T6G_MB_LIB.T6G(SCH_1):PAGE264
     2 PWRGD_P12V_MEM_R @T6G_MB_LIB.T6G(SCH_1):PWRGD_P12V_MEM_R    I17 @T6G_MB_LIB.T6G(SCH_1):PAGE264

R1364 Q_RES_0201LF-1K,1%,1/20W,CHIP,CS21001FE07
     1 JTAG_TRST_RT_CPU0_P0_N @T6G_MB_LIB.T6G(SCH_1):JTAG_TRST_RT_CPU0_P0_N   I111 @T6G_MB_LIB.T6G(SCH_1):PAGE385
     2    GND @T6G_MB_LIB.T6G(SCH_1):GND   I111 @T6G_MB_LIB.T6G(SCH_1):PAGE385

R1365 Q_RES_0201LF-4.7K,5%,1/20W,CHIP,CS24701JE04
     1 JTAG_TCK_RT_CPU0_P0 @T6G_MB_LIB.T6G(SCH_1):JTAG_TCK_RT_CPU0_P0   I123 @T6G_MB_LIB.T6G(SCH_1):PAGE385
     2    GND @T6G_MB_LIB.T6G(SCH_1):GND   I123 @T6G_MB_LIB.T6G(SCH_1):PAGE385

R1366 Q_RES_0201LF-4.7K,5%,1/20W,CHIP,CS24701JE04
     1 P1V8_CPU0_RT_1D @T6G_MB_LIB.T6G(SCH_1):P1V8_CPU0_RT_1D   I122 @T6G_MB_LIB.T6G(SCH_1):PAGE377
     2 SMB_RT_CPU0_P0_ROM_MUX_2D_R_SDA @T6G_MB_LIB.T6G(SCH_1):SMB_RT_CPU0_P0_ROM_MUX_2D_R_SDA   I122 @T6G_MB_LIB.T6G(SCH_1):PAGE377

R1367 Q_RES_0201LF-4.7K,5%,1/20W,CHIP,CS24701JE04
     1 P1V8_CPU0_RT_1D @T6G_MB_LIB.T6G(SCH_1):P1V8_CPU0_RT_1D   I121 @T6G_MB_LIB.T6G(SCH_1):PAGE377
     2 SMB_RT_CPU0_P0_ROM_MUX_2D_R_SCL @T6G_MB_LIB.T6G(SCH_1):SMB_RT_CPU0_P0_ROM_MUX_2D_R_SCL   I121 @T6G_MB_LIB.T6G(SCH_1):PAGE377

R1368 Q_RES_0201LF-4.7K,5%,1/20W,CHIP,CS24701JE04
     1 CLKREQ_RT_CPU0_P0_N @T6G_MB_LIB.T6G(SCH_1):CLKREQ_RT_CPU0_P0_N   I119 @T6G_MB_LIB.T6G(SCH_1):PAGE385
     2    GND @T6G_MB_LIB.T6G(SCH_1):GND   I119 @T6G_MB_LIB.T6G(SCH_1):PAGE385

R1369 Q_RES_0201LF-1K,1%,1/20W,EMPTY,CS21001FE07
     1 P1V8_CPU0_RT_1D @T6G_MB_LIB.T6G(SCH_1):P1V8_CPU0_RT_1D   I116 @T6G_MB_LIB.T6G(SCH_1):PAGE385
     2 RXDET_BYP_RT_CPU0_P0 @T6G_MB_LIB.T6G(SCH_1):RXDET_BYP_RT_CPU0_P0   I116 @T6G_MB_LIB.T6G(SCH_1):PAGE385

R1370 Q_RES_0201LF-10K,1%,1/20W,CHIP,CS31001FE17
     1 RXDET_BYP_RT_CPU0_P0 @T6G_MB_LIB.T6G(SCH_1):RXDET_BYP_RT_CPU0_P0   I114 @T6G_MB_LIB.T6G(SCH_1):PAGE385
     2    GND @T6G_MB_LIB.T6G(SCH_1):GND   I114 @T6G_MB_LIB.T6G(SCH_1):PAGE385

R1371 Q_RES_0201LF-4.7K,5%,1/20W,CHIP,CS24701JE04
     1 P1V8_CPU0_RT_1D @T6G_MB_LIB.T6G(SCH_1):P1V8_CPU0_RT_1D   I124 @T6G_MB_LIB.T6G(SCH_1):PAGE377
     2 SMB_RT_CPU0_P1_ROM_MUX_2D_R_SDA @T6G_MB_LIB.T6G(SCH_1):SMB_RT_CPU0_P1_ROM_MUX_2D_R_SDA   I124 @T6G_MB_LIB.T6G(SCH_1):PAGE377

R1372 Q_RES_0201LF-1K,1%,1/20W,CHIP,CS21001FE07
     1 JTAG_TRST_RT_CPU1_P1_N @T6G_MB_LIB.T6G(SCH_1):JTAG_TRST_RT_CPU1_P1_N   I115 @T6G_MB_LIB.T6G(SCH_1):PAGE392
     2    GND @T6G_MB_LIB.T6G(SCH_1):GND   I115 @T6G_MB_LIB.T6G(SCH_1):PAGE392

R1373 Q_RES_0201LF-4.7K,5%,1/20W,CHIP,CS24701JE04
     1 JTAG_TCK_RT_CPU1_P1 @T6G_MB_LIB.T6G(SCH_1):JTAG_TCK_RT_CPU1_P1   I150 @T6G_MB_LIB.T6G(SCH_1):PAGE392
     2    GND @T6G_MB_LIB.T6G(SCH_1):GND   I150 @T6G_MB_LIB.T6G(SCH_1):PAGE392

R1374 Q_RES_0201LF-4.7K,5%,1/20W,CHIP,CS24701JE04
     1 P1V8_CPU0_RT_1D @T6G_MB_LIB.T6G(SCH_1):P1V8_CPU0_RT_1D   I123 @T6G_MB_LIB.T6G(SCH_1):PAGE377
     2 SMB_RT_CPU0_P1_ROM_MUX_2D_R_SCL @T6G_MB_LIB.T6G(SCH_1):SMB_RT_CPU0_P1_ROM_MUX_2D_R_SCL   I123 @T6G_MB_LIB.T6G(SCH_1):PAGE377

R1375 Q_RES_0201LF-4.7K,5%,1/20W,CHIP,CS24701JE04
     1 P1V8_CPU0_RT_1D @T6G_MB_LIB.T6G(SCH_1):P1V8_CPU0_RT_1D   I125 @T6G_MB_LIB.T6G(SCH_1):PAGE377
     2 SMB_RT_CPU0_P3_ROM_MUX_2D_R_SDA @T6G_MB_LIB.T6G(SCH_1):SMB_RT_CPU0_P3_ROM_MUX_2D_R_SDA   I125 @T6G_MB_LIB.T6G(SCH_1):PAGE377

R1376 Q_RES_0201LF-4.7K,5%,1/20W,CHIP,CS24701JE04
     1 CLKREQ_RT_CPU1_P1_N @T6G_MB_LIB.T6G(SCH_1):CLKREQ_RT_CPU1_P1_N   I111 @T6G_MB_LIB.T6G(SCH_1):PAGE392
     2    GND @T6G_MB_LIB.T6G(SCH_1):GND   I111 @T6G_MB_LIB.T6G(SCH_1):PAGE392

R1377 Q_RES_0201LF-1K,1%,1/20W,EMPTY,CS21001FE07
     1 P1V8_CPU1_RT_1D @T6G_MB_LIB.T6G(SCH_1):P1V8_CPU1_RT_1D   I125 @T6G_MB_LIB.T6G(SCH_1):PAGE392
     2 RXDET_BYP_RT_CPU1_P1 @T6G_MB_LIB.T6G(SCH_1):RXDET_BYP_RT_CPU1_P1   I125 @T6G_MB_LIB.T6G(SCH_1):PAGE392

R1378 Q_RES_0201LF-10K,1%,1/20W,CHIP,CS31001FE17
     1 RXDET_BYP_RT_CPU1_P1 @T6G_MB_LIB.T6G(SCH_1):RXDET_BYP_RT_CPU1_P1   I126 @T6G_MB_LIB.T6G(SCH_1):PAGE392
     2    GND @T6G_MB_LIB.T6G(SCH_1):GND   I126 @T6G_MB_LIB.T6G(SCH_1):PAGE392

R1379 Q_RES_0201LF-4.7K,5%,1/20W,CHIP,CS24701JE04
     1 P1V8_CPU0_RT_1D @T6G_MB_LIB.T6G(SCH_1):P1V8_CPU0_RT_1D   I126 @T6G_MB_LIB.T6G(SCH_1):PAGE377
     2 SMB_RT_CPU0_P3_ROM_MUX_2D_R_SCL @T6G_MB_LIB.T6G(SCH_1):SMB_RT_CPU0_P3_ROM_MUX_2D_R_SCL   I126 @T6G_MB_LIB.T6G(SCH_1):PAGE377

R1380 Q_RES_0201LF-1K,1%,1/20W,CHIP,CS21001FE07
     1 JTAG_TRST_RT_CPU1_P0_N @T6G_MB_LIB.T6G(SCH_1):JTAG_TRST_RT_CPU1_P0_N   I112 @T6G_MB_LIB.T6G(SCH_1):PAGE401
     2    GND @T6G_MB_LIB.T6G(SCH_1):GND   I112 @T6G_MB_LIB.T6G(SCH_1):PAGE401

R1381 Q_RES_0201LF-4.7K,5%,1/20W,CHIP,CS24701JE04
     1 JTAG_TCK_RT_CPU1_P0 @T6G_MB_LIB.T6G(SCH_1):JTAG_TCK_RT_CPU1_P0   I144 @T6G_MB_LIB.T6G(SCH_1):PAGE401
     2    GND @T6G_MB_LIB.T6G(SCH_1):GND   I144 @T6G_MB_LIB.T6G(SCH_1):PAGE401

R1382 Q_RES_0201LF-4.7K,5%,1/20W,CHIP,CS24701JE04
     1 P1V8_CPU0_RT_1D @T6G_MB_LIB.T6G(SCH_1):P1V8_CPU0_RT_1D   I127 @T6G_MB_LIB.T6G(SCH_1):PAGE377
     2 SMB_RT_CPU0_P2_ROM_MUX_2D_R_SDA @T6G_MB_LIB.T6G(SCH_1):SMB_RT_CPU0_P2_ROM_MUX_2D_R_SDA   I127 @T6G_MB_LIB.T6G(SCH_1):PAGE377

R1383 Q_RES_0201LF-4.7K,5%,1/20W,CHIP,CS24701JE04
     1 P1V8_CPU0_RT_1D @T6G_MB_LIB.T6G(SCH_1):P1V8_CPU0_RT_1D   I128 @T6G_MB_LIB.T6G(SCH_1):PAGE377
     2 SMB_RT_CPU0_P2_ROM_MUX_2D_R_SCL @T6G_MB_LIB.T6G(SCH_1):SMB_RT_CPU0_P2_ROM_MUX_2D_R_SCL   I128 @T6G_MB_LIB.T6G(SCH_1):PAGE377

R1384 Q_RES_0402LF-2K,1%,1/16W,EMPTY,CS22002FB07
     1 SMB_CPU0_CPU1_SEC_SCL @T6G_MB_LIB.T6G(SCH_1):SMB_CPU0_CPU1_SEC_SCL   I136 @T6G_MB_LIB.T6G(SCH_1):PAGE349
     2 P3V3_AUX @T6G_MB_LIB.T6G(SCH_1):P3V3_AUX   I136 @T6G_MB_LIB.T6G(SCH_1):PAGE349

R1385 Q_RES_0402LF-2K,1%,1/16W,EMPTY,CS22002FB07
     1 SMB_CPU0_CPU1_SEC_SDA @T6G_MB_LIB.T6G(SCH_1):SMB_CPU0_CPU1_SEC_SDA   I135 @T6G_MB_LIB.T6G(SCH_1):PAGE349
     2 P3V3_AUX @T6G_MB_LIB.T6G(SCH_1):P3V3_AUX   I135 @T6G_MB_LIB.T6G(SCH_1):PAGE349

R1386 Q_RES_0402LF-2K,1%,1/16W,EMPTY,CS22002FB07
     1 SMB_PMBUS_3V3AUX_SCL @T6G_MB_LIB.T6G(SCH_1):SMB_PMBUS_3V3AUX_SCL   I134 @T6G_MB_LIB.T6G(SCH_1):PAGE349
     2 P3V3_AUX @T6G_MB_LIB.T6G(SCH_1):P3V3_AUX   I134 @T6G_MB_LIB.T6G(SCH_1):PAGE349

R1387 Q_RES_0201LF-4.7K,5%,1/20W,CHIP,CS24701JE04
     1 CLKREQ_RT_CPU1_P0_N @T6G_MB_LIB.T6G(SCH_1):CLKREQ_RT_CPU1_P0_N   I108 @T6G_MB_LIB.T6G(SCH_1):PAGE401
     2    GND @T6G_MB_LIB.T6G(SCH_1):GND   I108 @T6G_MB_LIB.T6G(SCH_1):PAGE401

R1388 Q_RES_0201LF-1K,1%,1/20W,EMPTY,CS21001FE07
     1 P1V8_CPU1_RT_1D @T6G_MB_LIB.T6G(SCH_1):P1V8_CPU1_RT_1D   I125 @T6G_MB_LIB.T6G(SCH_1):PAGE401
     2 RXDET_BYP_RT_CPU1_P0 @T6G_MB_LIB.T6G(SCH_1):RXDET_BYP_RT_CPU1_P0   I125 @T6G_MB_LIB.T6G(SCH_1):PAGE401

R1389 Q_RES_0201LF-10K,1%,1/20W,CHIP,CS31001FE17
     1 RXDET_BYP_RT_CPU1_P0 @T6G_MB_LIB.T6G(SCH_1):RXDET_BYP_RT_CPU1_P0   I124 @T6G_MB_LIB.T6G(SCH_1):PAGE401
     2    GND @T6G_MB_LIB.T6G(SCH_1):GND   I124 @T6G_MB_LIB.T6G(SCH_1):PAGE401

R1390 Q_RES_0201LF-4.7K,5%,1/20W,CHIP,CS24701JE04
     1 P1V8_CPU1_RT_1D @T6G_MB_LIB.T6G(SCH_1):P1V8_CPU1_RT_1D   I105 @T6G_MB_LIB.T6G(SCH_1):PAGE377
     2 SMB_RT_CPU1_P0_ROM_MUX_2D_R_SCL @T6G_MB_LIB.T6G(SCH_1):SMB_RT_CPU1_P0_ROM_MUX_2D_R_SCL   I105 @T6G_MB_LIB.T6G(SCH_1):PAGE377

R1391 Q_RES_0201LF-1K,1%,1/20W,CHIP,CS21001FE07
     1 JTAG_TRST_RT_CPU0_P1_N @T6G_MB_LIB.T6G(SCH_1):JTAG_TRST_RT_CPU0_P1_N    I84 @T6G_MB_LIB.T6G(SCH_1):PAGE408
     2    GND @T6G_MB_LIB.T6G(SCH_1):GND    I84 @T6G_MB_LIB.T6G(SCH_1):PAGE408

R1392 Q_RES_0201LF-4.7K,5%,1/20W,CHIP,CS24701JE04
     1 JTAG_TCK_RT_CPU0_P1 @T6G_MB_LIB.T6G(SCH_1):JTAG_TCK_RT_CPU0_P1   I119 @T6G_MB_LIB.T6G(SCH_1):PAGE408
     2    GND @T6G_MB_LIB.T6G(SCH_1):GND   I119 @T6G_MB_LIB.T6G(SCH_1):PAGE408

R1393 Q_RES_0201LF-4.7K,5%,1/20W,CHIP,CS24701JE04
     1 P1V8_CPU1_RT_1D @T6G_MB_LIB.T6G(SCH_1):P1V8_CPU1_RT_1D   I106 @T6G_MB_LIB.T6G(SCH_1):PAGE377
     2 SMB_RT_CPU1_P1_ROM_MUX_2D_R_SDA @T6G_MB_LIB.T6G(SCH_1):SMB_RT_CPU1_P1_ROM_MUX_2D_R_SDA   I106 @T6G_MB_LIB.T6G(SCH_1):PAGE377

R1394 Q_RES_0201LF-4.7K,5%,1/20W,CHIP,CS24701JE04
     1 P1V8_CPU1_RT_1D @T6G_MB_LIB.T6G(SCH_1):P1V8_CPU1_RT_1D   I107 @T6G_MB_LIB.T6G(SCH_1):PAGE377
     2 SMB_RT_CPU1_P1_ROM_MUX_2D_R_SCL @T6G_MB_LIB.T6G(SCH_1):SMB_RT_CPU1_P1_ROM_MUX_2D_R_SCL   I107 @T6G_MB_LIB.T6G(SCH_1):PAGE377

R1395 Q_RES_0201LF-4.7K,5%,1/20W,CHIP,CS24701JE04
     1 CLKREQ_RT_CPU0_P1_N @T6G_MB_LIB.T6G(SCH_1):CLKREQ_RT_CPU0_P1_N    I94 @T6G_MB_LIB.T6G(SCH_1):PAGE408
     2    GND @T6G_MB_LIB.T6G(SCH_1):GND    I94 @T6G_MB_LIB.T6G(SCH_1):PAGE408

R1396 Q_RES_0402LF-10K,1%,1/16W,CHIP,CS31002FB08
     1 FM_M2_SSD_0_PEDET @T6G_MB_LIB.T6G(SCH_1):FM_M2_SSD_0_PEDET    I66 @T6G_MB_LIB.T6G(SCH_1):PAGE345
     2 P3V3_AUX @T6G_MB_LIB.T6G(SCH_1):P3V3_AUX    I66 @T6G_MB_LIB.T6G(SCH_1):PAGE345

R1397 Q_RES_0201LF-1K,1%,1/20W,EMPTY,CS21001FE07
     1 P1V8_CPU0_RT_1D @T6G_MB_LIB.T6G(SCH_1):P1V8_CPU0_RT_1D    I99 @T6G_MB_LIB.T6G(SCH_1):PAGE408
     2 RXDET_BYP_RT_CPU0_P1 @T6G_MB_LIB.T6G(SCH_1):RXDET_BYP_RT_CPU0_P1    I99 @T6G_MB_LIB.T6G(SCH_1):PAGE408

R1398 Q_RES_0201LF-10K,1%,1/20W,CHIP,CS31001FE17
     1 RXDET_BYP_RT_CPU0_P1 @T6G_MB_LIB.T6G(SCH_1):RXDET_BYP_RT_CPU0_P1    I98 @T6G_MB_LIB.T6G(SCH_1):PAGE408
     2    GND @T6G_MB_LIB.T6G(SCH_1):GND    I98 @T6G_MB_LIB.T6G(SCH_1):PAGE408

R1399 Q_RES_0201LF-4.7K,5%,1/20W,CHIP,CS24701JE04
     1 P1V8_CPU1_RT_1D @T6G_MB_LIB.T6G(SCH_1):P1V8_CPU1_RT_1D   I108 @T6G_MB_LIB.T6G(SCH_1):PAGE377
     2 SMB_RT_CPU1_P3_ROM_MUX_2D_R_SDA @T6G_MB_LIB.T6G(SCH_1):SMB_RT_CPU1_P3_ROM_MUX_2D_R_SDA   I108 @T6G_MB_LIB.T6G(SCH_1):PAGE377

R1400 Q_RES_0201LF-1K,1%,1/20W,CHIP,CS21001FE07
     1 JTAG_TRST_RT_CPU0_P2_N @T6G_MB_LIB.T6G(SCH_1):JTAG_TRST_RT_CPU0_P2_N    I84 @T6G_MB_LIB.T6G(SCH_1):PAGE419
     2    GND @T6G_MB_LIB.T6G(SCH_1):GND    I84 @T6G_MB_LIB.T6G(SCH_1):PAGE419

R1401 Q_RES_0201LF-4.7K,5%,1/20W,CHIP,CS24701JE04
     1 JTAG_TCK_RT_CPU0_P2 @T6G_MB_LIB.T6G(SCH_1):JTAG_TCK_RT_CPU0_P2   I120 @T6G_MB_LIB.T6G(SCH_1):PAGE419
     2    GND @T6G_MB_LIB.T6G(SCH_1):GND   I120 @T6G_MB_LIB.T6G(SCH_1):PAGE419

R1402 Q_RES_0201LF-4.7K,5%,1/20W,CHIP,CS24701JE04
     1 P1V8_CPU1_RT_1D @T6G_MB_LIB.T6G(SCH_1):P1V8_CPU1_RT_1D   I109 @T6G_MB_LIB.T6G(SCH_1):PAGE377
     2 SMB_RT_CPU1_P3_ROM_MUX_2D_R_SCL @T6G_MB_LIB.T6G(SCH_1):SMB_RT_CPU1_P3_ROM_MUX_2D_R_SCL   I109 @T6G_MB_LIB.T6G(SCH_1):PAGE377

R1403 Q_RES_0201LF-4.7K,5%,1/20W,CHIP,CS24701JE04
     1 P1V8_CPU1_RT_1D @T6G_MB_LIB.T6G(SCH_1):P1V8_CPU1_RT_1D   I110 @T6G_MB_LIB.T6G(SCH_1):PAGE377
     2 SMB_RT_CPU1_P2_ROM_MUX_2D_R_SDA @T6G_MB_LIB.T6G(SCH_1):SMB_RT_CPU1_P2_ROM_MUX_2D_R_SDA   I110 @T6G_MB_LIB.T6G(SCH_1):PAGE377

R1404 Q_RES_0201LF-4.7K,5%,1/20W,CHIP,CS24701JE04
     1 CLKREQ_RT_CPU0_P2_N @T6G_MB_LIB.T6G(SCH_1):CLKREQ_RT_CPU0_P2_N    I99 @T6G_MB_LIB.T6G(SCH_1):PAGE419
     2    GND @T6G_MB_LIB.T6G(SCH_1):GND    I99 @T6G_MB_LIB.T6G(SCH_1):PAGE419

R1405 Q_RES_0201LF-1K,1%,1/20W,EMPTY,CS21001FE07
     1 P1V8_CPU0_RT_1D @T6G_MB_LIB.T6G(SCH_1):P1V8_CPU0_RT_1D    I96 @T6G_MB_LIB.T6G(SCH_1):PAGE419
     2 RXDET_BYP_RT_CPU0_P2 @T6G_MB_LIB.T6G(SCH_1):RXDET_BYP_RT_CPU0_P2    I96 @T6G_MB_LIB.T6G(SCH_1):PAGE419

R1406 Q_RES_0201LF-10K,1%,1/20W,CHIP,CS31001FE17
     1 RXDET_BYP_RT_CPU0_P2 @T6G_MB_LIB.T6G(SCH_1):RXDET_BYP_RT_CPU0_P2    I95 @T6G_MB_LIB.T6G(SCH_1):PAGE419
     2    GND @T6G_MB_LIB.T6G(SCH_1):GND    I95 @T6G_MB_LIB.T6G(SCH_1):PAGE419

R1407 Q_RES_0201LF-4.7K,5%,1/20W,CHIP,CS24701JE04
     1 P1V8_CPU1_RT_1D @T6G_MB_LIB.T6G(SCH_1):P1V8_CPU1_RT_1D   I111 @T6G_MB_LIB.T6G(SCH_1):PAGE377
     2 SMB_RT_CPU1_P2_ROM_MUX_2D_R_SCL @T6G_MB_LIB.T6G(SCH_1):SMB_RT_CPU1_P2_ROM_MUX_2D_R_SCL   I111 @T6G_MB_LIB.T6G(SCH_1):PAGE377

R1408 Q_RES_0201LF-1K,1%,1/20W,CHIP,CS21001FE07
     1 JTAG_TRST_RT_CPU0_P3_N @T6G_MB_LIB.T6G(SCH_1):JTAG_TRST_RT_CPU0_P3_N    I85 @T6G_MB_LIB.T6G(SCH_1):PAGE430
     2    GND @T6G_MB_LIB.T6G(SCH_1):GND    I85 @T6G_MB_LIB.T6G(SCH_1):PAGE430

R1409 Q_RES_0201LF-4.7K,5%,1/20W,CHIP,CS24701JE04
     1 JTAG_TCK_RT_CPU0_P3 @T6G_MB_LIB.T6G(SCH_1):JTAG_TCK_RT_CPU0_P3   I117 @T6G_MB_LIB.T6G(SCH_1):PAGE430
     2    GND @T6G_MB_LIB.T6G(SCH_1):GND   I117 @T6G_MB_LIB.T6G(SCH_1):PAGE430

R1410 Q_RES_0201LF-1K,1%,1/20W,CHIP,CS21001FE07
     1 P1V8_CPU0_RT_1D @T6G_MB_LIB.T6G(SCH_1):P1V8_CPU0_RT_1D   I164 @T6G_MB_LIB.T6G(SCH_1):PAGE377
     2 SMB_RT_CPU0_P0_ROM_MUX_1D_SDA @T6G_MB_LIB.T6G(SCH_1):SMB_RT_CPU0_P0_ROM_MUX_1D_SDA   I164 @T6G_MB_LIB.T6G(SCH_1):PAGE377

R1411 Q_RES_0201LF-1K,1%,1/20W,CHIP,CS21001FE07
     1 P1V8_CPU0_RT_1D @T6G_MB_LIB.T6G(SCH_1):P1V8_CPU0_RT_1D   I165 @T6G_MB_LIB.T6G(SCH_1):PAGE377
     2 SMB_RT_CPU0_P0_ROM_MUX_1D_SCL @T6G_MB_LIB.T6G(SCH_1):SMB_RT_CPU0_P0_ROM_MUX_1D_SCL   I165 @T6G_MB_LIB.T6G(SCH_1):PAGE377

R1412 Q_RES_0201LF-4.7K,5%,1/20W,CHIP,CS24701JE04
     1 CLKREQ_RT_CPU0_P3_N @T6G_MB_LIB.T6G(SCH_1):CLKREQ_RT_CPU0_P3_N   I101 @T6G_MB_LIB.T6G(SCH_1):PAGE430
     2    GND @T6G_MB_LIB.T6G(SCH_1):GND   I101 @T6G_MB_LIB.T6G(SCH_1):PAGE430

R1413 Q_RES_0201LF-1K,1%,1/20W,EMPTY,CS21001FE07
     1 P1V8_CPU0_RT_1D @T6G_MB_LIB.T6G(SCH_1):P1V8_CPU0_RT_1D    I97 @T6G_MB_LIB.T6G(SCH_1):PAGE430
     2 RXDET_BYP_RT_CPU0_P3 @T6G_MB_LIB.T6G(SCH_1):RXDET_BYP_RT_CPU0_P3    I97 @T6G_MB_LIB.T6G(SCH_1):PAGE430

R1414 Q_RES_0201LF-10K,1%,1/20W,CHIP,CS31001FE17
     1 RXDET_BYP_RT_CPU0_P3 @T6G_MB_LIB.T6G(SCH_1):RXDET_BYP_RT_CPU0_P3    I96 @T6G_MB_LIB.T6G(SCH_1):PAGE430
     2    GND @T6G_MB_LIB.T6G(SCH_1):GND    I96 @T6G_MB_LIB.T6G(SCH_1):PAGE430

R1415 Q_RES_0201LF-1K,1%,1/20W,CHIP,CS21001FE07
     1 P1V8_CPU0_RT_1D @T6G_MB_LIB.T6G(SCH_1):P1V8_CPU0_RT_1D   I166 @T6G_MB_LIB.T6G(SCH_1):PAGE377
     2 SMB_RT_CPU0_P1_ROM_MUX_1D_SDA @T6G_MB_LIB.T6G(SCH_1):SMB_RT_CPU0_P1_ROM_MUX_1D_SDA   I166 @T6G_MB_LIB.T6G(SCH_1):PAGE377

R1416 Q_RES_0201LF-1K,1%,1/20W,CHIP,CS21001FE07
     1 JTAG_TRST_RT_CPU1_P2_N @T6G_MB_LIB.T6G(SCH_1):JTAG_TRST_RT_CPU1_P2_N   I102 @T6G_MB_LIB.T6G(SCH_1):PAGE451
     2    GND @T6G_MB_LIB.T6G(SCH_1):GND   I102 @T6G_MB_LIB.T6G(SCH_1):PAGE451

R1417 Q_RES_0201LF-4.7K,5%,1/20W,CHIP,CS24701JE04
     1 JTAG_TCK_RT_CPU1_P2 @T6G_MB_LIB.T6G(SCH_1):JTAG_TCK_RT_CPU1_P2   I136 @T6G_MB_LIB.T6G(SCH_1):PAGE451
     2    GND @T6G_MB_LIB.T6G(SCH_1):GND   I136 @T6G_MB_LIB.T6G(SCH_1):PAGE451

R1418 Q_RES_0201LF-1K,1%,1/20W,CHIP,CS21001FE07
     1 P1V8_CPU0_RT_1D @T6G_MB_LIB.T6G(SCH_1):P1V8_CPU0_RT_1D   I167 @T6G_MB_LIB.T6G(SCH_1):PAGE377
     2 SMB_RT_CPU0_P1_ROM_MUX_1D_SCL @T6G_MB_LIB.T6G(SCH_1):SMB_RT_CPU0_P1_ROM_MUX_1D_SCL   I167 @T6G_MB_LIB.T6G(SCH_1):PAGE377

R1419 Q_RES_0402LF-4.7K,5%,1/16W,CHIP,CS24702JB10
     1 PVDD18_S5_P0 @T6G_MB_LIB.T6G(SCH_1):PVDD18_S5_P0    I91 @T6G_MB_LIB.T6G(SCH_1):PAGE141
     2 UART_LS_EN_R_N @T6G_MB_LIB.T6G(SCH_1):UART_LS_EN_R_N    I91 @T6G_MB_LIB.T6G(SCH_1):PAGE141

R1420 Q_RES_0201LF-1K,1%,1/20W,CHIP,CS21001FE07
     1 P1V8_CPU0_RT_1D @T6G_MB_LIB.T6G(SCH_1):P1V8_CPU0_RT_1D   I168 @T6G_MB_LIB.T6G(SCH_1):PAGE377
     2 SMB_RT_CPU0_P3_ROM_MUX_1D_SDA @T6G_MB_LIB.T6G(SCH_1):SMB_RT_CPU0_P3_ROM_MUX_1D_SDA   I168 @T6G_MB_LIB.T6G(SCH_1):PAGE377

R1421 Q_RES_0201LF-4.7K,5%,1/20W,CHIP,CS24701JE04
     1 CLKREQ_RT_CPU1_P2_N @T6G_MB_LIB.T6G(SCH_1):CLKREQ_RT_CPU1_P2_N    I98 @T6G_MB_LIB.T6G(SCH_1):PAGE451
     2    GND @T6G_MB_LIB.T6G(SCH_1):GND    I98 @T6G_MB_LIB.T6G(SCH_1):PAGE451

R1422 Q_RES_0402LF-100,1%,1/16W,CHIP,CS11002FB07
     1 PWRGD_CPU0_PWROK @T6G_MB_LIB.T6G(SCH_1):PWRGD_CPU0_PWROK   I104 @T6G_MB_LIB.T6G(SCH_1):PAGE84
     2 PWRGD_CPU1_PWROK @T6G_MB_LIB.T6G(SCH_1):PWRGD_CPU1_PWROK   I104 @T6G_MB_LIB.T6G(SCH_1):PAGE84

R1423 Q_RES_0402LF-0,5%,1/16W,CHIP,CS00002JB13
     1 UART_CPU0_SCM_UART1_RX @T6G_MB_LIB.T6G(SCH_1):UART_CPU0_SCM_UART1_RX   I232 @T6G_MB_LIB.T6G(SCH_1):PAGE141
     2 UART_CPU0_SCM_UART1_R_RX @T6G_MB_LIB.T6G(SCH_1):UART_CPU0_SCM_UART1_R_RX   I232 @T6G_MB_LIB.T6G(SCH_1):PAGE141

R1424 Q_RES_0402LF-2.2K,5%,1/16W,CHIP,CS22202JB07
     1 PVDD18_S5_P1 @T6G_MB_LIB.T6G(SCH_1):PVDD18_S5_P1   I292 @T6G_MB_LIB.T6G(SCH_1):PAGE55
     2 INT_CPU1_HP_UBM_N @T6G_MB_LIB.T6G(SCH_1):INT_CPU1_HP_UBM_N   I292 @T6G_MB_LIB.T6G(SCH_1):PAGE55

R1425 Q_RES_0402LF-0,5%,1/16W,CHIP,CS00002JB13
     1 UART_CPU0_SCM_LVC3_UART1_R_TX @T6G_MB_LIB.T6G(SCH_1):UART_CPU0_SCM_LVC3_UART1_R_TX   I221 @T6G_MB_LIB.T6G(SCH_1):PAGE141
     2 UART_CPU0_SCM_LVC3_UART1_TX @T6G_MB_LIB.T6G(SCH_1):UART_CPU0_SCM_LVC3_UART1_TX   I221 @T6G_MB_LIB.T6G(SCH_1):PAGE141

R1426 Q_RES_0201LF-1K,1%,1/20W,EMPTY,CS21001FE07
     1 P1V8_CPU1_RT_1D @T6G_MB_LIB.T6G(SCH_1):P1V8_CPU1_RT_1D   I114 @T6G_MB_LIB.T6G(SCH_1):PAGE451
     2 RXDET_BYP_RT_CPU1_P2 @T6G_MB_LIB.T6G(SCH_1):RXDET_BYP_RT_CPU1_P2   I114 @T6G_MB_LIB.T6G(SCH_1):PAGE451

R1427 Q_RES_0201LF-10K,1%,1/20W,CHIP,CS31001FE17
     1 RXDET_BYP_RT_CPU1_P2 @T6G_MB_LIB.T6G(SCH_1):RXDET_BYP_RT_CPU1_P2   I113 @T6G_MB_LIB.T6G(SCH_1):PAGE451
     2    GND @T6G_MB_LIB.T6G(SCH_1):GND   I113 @T6G_MB_LIB.T6G(SCH_1):PAGE451

R1428 Q_RES_0201LF-1K,1%,1/20W,CHIP,CS21001FE07
     1 P1V8_CPU0_RT_1D @T6G_MB_LIB.T6G(SCH_1):P1V8_CPU0_RT_1D   I169 @T6G_MB_LIB.T6G(SCH_1):PAGE377
     2 SMB_RT_CPU0_P3_ROM_MUX_1D_SCL @T6G_MB_LIB.T6G(SCH_1):SMB_RT_CPU0_P3_ROM_MUX_1D_SCL   I169 @T6G_MB_LIB.T6G(SCH_1):PAGE377

R1429 Q_RES_0201LF-1K,1%,1/20W,CHIP,CS21001FE07
     1 JTAG_TRST_RT_CPU1_P3_N @T6G_MB_LIB.T6G(SCH_1):JTAG_TRST_RT_CPU1_P3_N   I103 @T6G_MB_LIB.T6G(SCH_1):PAGE462
     2    GND @T6G_MB_LIB.T6G(SCH_1):GND   I103 @T6G_MB_LIB.T6G(SCH_1):PAGE462

R1430 Q_RES_0201LF-4.7K,5%,1/20W,CHIP,CS24701JE04
     1 JTAG_TCK_RT_CPU1_P3 @T6G_MB_LIB.T6G(SCH_1):JTAG_TCK_RT_CPU1_P3   I136 @T6G_MB_LIB.T6G(SCH_1):PAGE462
     2    GND @T6G_MB_LIB.T6G(SCH_1):GND   I136 @T6G_MB_LIB.T6G(SCH_1):PAGE462

R1431 Q_RES_0201LF-1K,1%,1/20W,CHIP,CS21001FE07
     1 P1V8_CPU0_RT_1D @T6G_MB_LIB.T6G(SCH_1):P1V8_CPU0_RT_1D   I170 @T6G_MB_LIB.T6G(SCH_1):PAGE377
     2 SMB_RT_CPU0_P2_ROM_MUX_1D_SDA @T6G_MB_LIB.T6G(SCH_1):SMB_RT_CPU0_P2_ROM_MUX_1D_SDA   I170 @T6G_MB_LIB.T6G(SCH_1):PAGE377

R1432 Q_RES_0201LF-1K,1%,1/20W,CHIP,CS21001FE07
     1 P1V8_CPU0_RT_1D @T6G_MB_LIB.T6G(SCH_1):P1V8_CPU0_RT_1D   I171 @T6G_MB_LIB.T6G(SCH_1):PAGE377
     2 SMB_RT_CPU0_P2_ROM_MUX_1D_SCL @T6G_MB_LIB.T6G(SCH_1):SMB_RT_CPU0_P2_ROM_MUX_1D_SCL   I171 @T6G_MB_LIB.T6G(SCH_1):PAGE377

R1433 Q_RES_0201LF-4.7K,5%,1/20W,CHIP,CS24701JE04
     1 CLKREQ_RT_CPU1_P3_N @T6G_MB_LIB.T6G(SCH_1):CLKREQ_RT_CPU1_P3_N    I98 @T6G_MB_LIB.T6G(SCH_1):PAGE462
     2    GND @T6G_MB_LIB.T6G(SCH_1):GND    I98 @T6G_MB_LIB.T6G(SCH_1):PAGE462

R1434 Q_RES_0201LF-1K,1%,1/20W,EMPTY,CS21001FE07
     1 P1V8_CPU1_RT_1D @T6G_MB_LIB.T6G(SCH_1):P1V8_CPU1_RT_1D   I115 @T6G_MB_LIB.T6G(SCH_1):PAGE462
     2 RXDET_BYP_RT_CPU1_P3 @T6G_MB_LIB.T6G(SCH_1):RXDET_BYP_RT_CPU1_P3   I115 @T6G_MB_LIB.T6G(SCH_1):PAGE462

R1435 Q_RES_0201LF-10K,1%,1/20W,CHIP,CS31001FE17
     1 RXDET_BYP_RT_CPU1_P3 @T6G_MB_LIB.T6G(SCH_1):RXDET_BYP_RT_CPU1_P3   I114 @T6G_MB_LIB.T6G(SCH_1):PAGE462
     2    GND @T6G_MB_LIB.T6G(SCH_1):GND   I114 @T6G_MB_LIB.T6G(SCH_1):PAGE462

R1436 Q_RES_0201LF-1K,1%,1/20W,CHIP,CS21001FE07
     1 P1V8_CPU1_RT_1D @T6G_MB_LIB.T6G(SCH_1):P1V8_CPU1_RT_1D   I173 @T6G_MB_LIB.T6G(SCH_1):PAGE377
     2 SMB_RT_CPU1_P0_ROM_MUX_1D_SDA @T6G_MB_LIB.T6G(SCH_1):SMB_RT_CPU1_P0_ROM_MUX_1D_SDA   I173 @T6G_MB_LIB.T6G(SCH_1):PAGE377

R1437 Q_RES_0201LF-1K,1%,1/20W,CHIP,CS21001FE07
     1 P1V8_CPU1_RT_1D @T6G_MB_LIB.T6G(SCH_1):P1V8_CPU1_RT_1D   I172 @T6G_MB_LIB.T6G(SCH_1):PAGE377
     2 SMB_RT_CPU1_P0_ROM_MUX_1D_SCL @T6G_MB_LIB.T6G(SCH_1):SMB_RT_CPU1_P0_ROM_MUX_1D_SCL   I172 @T6G_MB_LIB.T6G(SCH_1):PAGE377

R1438 Q_RES_0201LF-4.7K,5%,1/20W,EMPTY,CS24701JE04
     1 P1V8_CPU0_RT_1D @T6G_MB_LIB.T6G(SCH_1):P1V8_CPU0_RT_1D   I147 @T6G_MB_LIB.T6G(SCH_1):PAGE385
     2 JTAG_TDI_RT_CPU0_P0 @T6G_MB_LIB.T6G(SCH_1):JTAG_TDI_RT_CPU0_P0   I147 @T6G_MB_LIB.T6G(SCH_1):PAGE385

R1439 Q_RES_0201LF-4.7K,5%,1/20W,EMPTY,CS24701JE04
     1 P1V8_CPU0_RT_1D @T6G_MB_LIB.T6G(SCH_1):P1V8_CPU0_RT_1D   I146 @T6G_MB_LIB.T6G(SCH_1):PAGE385
     2 JTAG_TMS_RT_CPU0_P0 @T6G_MB_LIB.T6G(SCH_1):JTAG_TMS_RT_CPU0_P0   I146 @T6G_MB_LIB.T6G(SCH_1):PAGE385

R1440 Q_RES_0402LF-100K,1%,1/16W,CHIP,CS41002FB09
     1 P12V_MEM_CPU1 @T6G_MB_LIB.T6G(SCH_1):P12V_MEM_CPU1    I25 @T6G_MB_LIB.T6G(SCH_1):PAGE264
     2 PWRGD_P12V_MEM_CPU1_EN @T6G_MB_LIB.T6G(SCH_1):PWRGD_P12V_MEM_CPU1_EN    I25 @T6G_MB_LIB.T6G(SCH_1):PAGE264

R1441 Q_RES_0402LF-16.9K,1%,1/16W,CHIP,CS31692FB03
     1 PWRGD_P12V_MEM_CPU1_EN @T6G_MB_LIB.T6G(SCH_1):PWRGD_P12V_MEM_CPU1_EN    I24 @T6G_MB_LIB.T6G(SCH_1):PAGE264
     2    GND @T6G_MB_LIB.T6G(SCH_1):GND    I24 @T6G_MB_LIB.T6G(SCH_1):PAGE264

R1442 Q_RES_0402LF-100K,1%,1/16W,CHIP,CS41002FB09
     1 P12V_MEM_CPU0 @T6G_MB_LIB.T6G(SCH_1):P12V_MEM_CPU0    I30 @T6G_MB_LIB.T6G(SCH_1):PAGE264
     2 PWRGD_P12V_MEM_CPU0_EN @T6G_MB_LIB.T6G(SCH_1):PWRGD_P12V_MEM_CPU0_EN    I30 @T6G_MB_LIB.T6G(SCH_1):PAGE264

R1443 Q_RES_0402LF-16.9K,1%,1/16W,CHIP,CS31692FB03
     1 PWRGD_P12V_MEM_CPU0_EN @T6G_MB_LIB.T6G(SCH_1):PWRGD_P12V_MEM_CPU0_EN    I27 @T6G_MB_LIB.T6G(SCH_1):PAGE264
     2    GND @T6G_MB_LIB.T6G(SCH_1):GND    I27 @T6G_MB_LIB.T6G(SCH_1):PAGE264

R1444 Q_RES_0402LF-130,1%,1/16W,CHIP,CS11302FB03
     1 P3V3_AUX @T6G_MB_LIB.T6G(SCH_1):P3V3_AUX    I82 @T6G_MB_LIB.T6G(SCH_1):PAGE142
     2 LED_BIOS_DBG_MODE_R @T6G_MB_LIB.T6G(SCH_1):LED_BIOS_DBG_MODE_R    I82 @T6G_MB_LIB.T6G(SCH_1):PAGE142

R1445 Q_RES_0201LF-1K,1%,1/20W,EMPTY,CS21001FE07
     1 P1V8_CPU0_RT_1D @T6G_MB_LIB.T6G(SCH_1):P1V8_CPU0_RT_1D   I145 @T6G_MB_LIB.T6G(SCH_1):PAGE385
     2 JTAG_TDO_RT_CPU0_P0 @T6G_MB_LIB.T6G(SCH_1):JTAG_TDO_RT_CPU0_P0   I145 @T6G_MB_LIB.T6G(SCH_1):PAGE385

R1446 Q_RES_0201LF-4.7K,5%,1/20W,EMPTY,CS24701JE04
     1 P1V8_CPU0_RT_1D @T6G_MB_LIB.T6G(SCH_1):P1V8_CPU0_RT_1D   I143 @T6G_MB_LIB.T6G(SCH_1):PAGE385
     2 JTAG_TCK_RT_CPU0_P0 @T6G_MB_LIB.T6G(SCH_1):JTAG_TCK_RT_CPU0_P0   I143 @T6G_MB_LIB.T6G(SCH_1):PAGE385

R1447 Q_RES_0402LF-0,5%,1/16W,CHIP,CS00002JB13
     1 SMB_CPU_5_SCL @T6G_MB_LIB.T6G(SCH_1):SMB_CPU_5_SCL    I57 @T6G_MB_LIB.T6G(SCH_1):PAGE349
     2 SMB_CPU_5_R1_SCL @T6G_MB_LIB.T6G(SCH_1):SMB_CPU_5_R1_SCL    I57 @T6G_MB_LIB.T6G(SCH_1):PAGE349

R1448 Q_RES_0201LF-1K,1%,1/20W,CHIP,CS21001FE07
     1 P1V8_CPU1_RT_1D @T6G_MB_LIB.T6G(SCH_1):P1V8_CPU1_RT_1D   I174 @T6G_MB_LIB.T6G(SCH_1):PAGE377
     2 SMB_RT_CPU1_P1_ROM_MUX_1D_SDA @T6G_MB_LIB.T6G(SCH_1):SMB_RT_CPU1_P1_ROM_MUX_1D_SDA   I174 @T6G_MB_LIB.T6G(SCH_1):PAGE377

R1449 Q_RES_0402LF-10K,5%,1/16W,CHIP,CS31002JB08
     1 P3V3_AUX @T6G_MB_LIB.T6G(SCH_1):P3V3_AUX    I26 @T6G_MB_LIB.T6G(SCH_1):PAGE264
     2 PWRGD_P12V_MEM_CPU1_EN_N @T6G_MB_LIB.T6G(SCH_1):PWRGD_P12V_MEM_CPU1_EN_N    I26 @T6G_MB_LIB.T6G(SCH_1):PAGE264

R1450 Q_RES_0402LF-10K,5%,1/16W,CHIP,CS31002JB08
     1 P3V3_AUX @T6G_MB_LIB.T6G(SCH_1):P3V3_AUX    I39 @T6G_MB_LIB.T6G(SCH_1):PAGE264
     2 PWRGD_P12V_MEM_CPU0_EN_N @T6G_MB_LIB.T6G(SCH_1):PWRGD_P12V_MEM_CPU0_EN_N    I39 @T6G_MB_LIB.T6G(SCH_1):PAGE264

R1451 Q_RES_0201LF-1K,1%,1/20W,CHIP,CS21001FE07
     1 P1V8_CPU1_RT_1D @T6G_MB_LIB.T6G(SCH_1):P1V8_CPU1_RT_1D   I175 @T6G_MB_LIB.T6G(SCH_1):PAGE377
     2 SMB_RT_CPU1_P1_ROM_MUX_1D_SCL @T6G_MB_LIB.T6G(SCH_1):SMB_RT_CPU1_P1_ROM_MUX_1D_SCL   I175 @T6G_MB_LIB.T6G(SCH_1):PAGE377

R1452 Q_RES_0402LF-10K,5%,1/16W,CHIP,CS31002JB08
     1 P1V8_AUX @T6G_MB_LIB.T6G(SCH_1):P1V8_AUX    I43 @T6G_MB_LIB.T6G(SCH_1):PAGE264
     2 PWRGD_P12V_MEM_CPU1 @T6G_MB_LIB.T6G(SCH_1):PWRGD_P12V_MEM_CPU1    I43 @T6G_MB_LIB.T6G(SCH_1):PAGE264

R1453 Q_RES_0402LF-0,5%,1/16W,CHIP,CS00002JB13
     1 SMB_CPU_5_SDA @T6G_MB_LIB.T6G(SCH_1):SMB_CPU_5_SDA    I56 @T6G_MB_LIB.T6G(SCH_1):PAGE349
     2 SMB_CPU_5_R1_SDA @T6G_MB_LIB.T6G(SCH_1):SMB_CPU_5_R1_SDA    I56 @T6G_MB_LIB.T6G(SCH_1):PAGE349

R1454 Q_RES_0201LF-4.7K,5%,1/20W,EMPTY,CS24701JE04
     1 P1V8_CPU1_RT_1D @T6G_MB_LIB.T6G(SCH_1):P1V8_CPU1_RT_1D   I145 @T6G_MB_LIB.T6G(SCH_1):PAGE392
     2 JTAG_TDI_RT_CPU1_P1 @T6G_MB_LIB.T6G(SCH_1):JTAG_TDI_RT_CPU1_P1   I145 @T6G_MB_LIB.T6G(SCH_1):PAGE392

R1455 Q_RES_0201LF-4.7K,5%,1/20W,EMPTY,CS24701JE04
     1 P1V8_CPU1_RT_1D @T6G_MB_LIB.T6G(SCH_1):P1V8_CPU1_RT_1D   I146 @T6G_MB_LIB.T6G(SCH_1):PAGE392
     2 JTAG_TMS_RT_CPU1_P1 @T6G_MB_LIB.T6G(SCH_1):JTAG_TMS_RT_CPU1_P1   I146 @T6G_MB_LIB.T6G(SCH_1):PAGE392

R1456 Q_RES_0201LF-1K,1%,1/20W,EMPTY,CS21001FE07
     1 P1V8_CPU1_RT_1D @T6G_MB_LIB.T6G(SCH_1):P1V8_CPU1_RT_1D   I153 @T6G_MB_LIB.T6G(SCH_1):PAGE392
     2 JTAG_TDO_RT_CPU1_P1 @T6G_MB_LIB.T6G(SCH_1):JTAG_TDO_RT_CPU1_P1   I153 @T6G_MB_LIB.T6G(SCH_1):PAGE392

R1457 Q_RES_0402LF-10K,5%,1/16W,CHIP,CS31002JB08
     1 P1V8_AUX @T6G_MB_LIB.T6G(SCH_1):P1V8_AUX    I41 @T6G_MB_LIB.T6G(SCH_1):PAGE264
     2 PWRGD_P12V_MEM_CPU0 @T6G_MB_LIB.T6G(SCH_1):PWRGD_P12V_MEM_CPU0    I41 @T6G_MB_LIB.T6G(SCH_1):PAGE264

R1458 Q_RES_0402LF-33,5%,1/16W,CHIP,CS03302JB10
     1 PWRGD_P12V_MEM_CPU0 @T6G_MB_LIB.T6G(SCH_1):PWRGD_P12V_MEM_CPU0     I6 @T6G_MB_LIB.T6G(SCH_1):PAGE264
     2 PWRGD_P12V_MEM_CPU0_R @T6G_MB_LIB.T6G(SCH_1):PWRGD_P12V_MEM_CPU0_R     I6 @T6G_MB_LIB.T6G(SCH_1):PAGE264

R1459 Q_RES_0402LF-33,5%,1/16W,CHIP,CS03302JB10
     1 PWRGD_P12V_MEM_CPU1 @T6G_MB_LIB.T6G(SCH_1):PWRGD_P12V_MEM_CPU1     I5 @T6G_MB_LIB.T6G(SCH_1):PAGE264
     2 PWRGD_P12V_MEM_CPU1_R @T6G_MB_LIB.T6G(SCH_1):PWRGD_P12V_MEM_CPU1_R     I5 @T6G_MB_LIB.T6G(SCH_1):PAGE264

R1460 Q_RES_0402LF-2.2K,5%,1/16W,EMPTY,CS22202JB07
     1 I3C_BMC_SWB_SDA @T6G_MB_LIB.T6G(SCH_1):I3C_BMC_SWB_SDA   I127 @T6G_MB_LIB.T6G(SCH_1):PAGE349
     2 P3V3_AUX @T6G_MB_LIB.T6G(SCH_1):P3V3_AUX   I127 @T6G_MB_LIB.T6G(SCH_1):PAGE349

R1461 Q_RES_0201LF-4.7K,5%,1/20W,EMPTY,CS24701JE04
     1 P1V8_CPU1_RT_1D @T6G_MB_LIB.T6G(SCH_1):P1V8_CPU1_RT_1D   I151 @T6G_MB_LIB.T6G(SCH_1):PAGE392
     2 JTAG_TCK_RT_CPU1_P1 @T6G_MB_LIB.T6G(SCH_1):JTAG_TCK_RT_CPU1_P1   I151 @T6G_MB_LIB.T6G(SCH_1):PAGE392

R1462 Q_RES_0201LF-1K,1%,1/20W,CHIP,CS21001FE07
     1 P1V8_CPU1_RT_1D @T6G_MB_LIB.T6G(SCH_1):P1V8_CPU1_RT_1D   I176 @T6G_MB_LIB.T6G(SCH_1):PAGE377
     2 SMB_RT_CPU1_P3_ROM_MUX_1D_SDA @T6G_MB_LIB.T6G(SCH_1):SMB_RT_CPU1_P3_ROM_MUX_1D_SDA   I176 @T6G_MB_LIB.T6G(SCH_1):PAGE377

R1463 Q_RES_0201LF-1K,1%,1/20W,CHIP,CS21001FE07
     1 P1V8_CPU1_RT_1D @T6G_MB_LIB.T6G(SCH_1):P1V8_CPU1_RT_1D   I177 @T6G_MB_LIB.T6G(SCH_1):PAGE377
     2 SMB_RT_CPU1_P3_ROM_MUX_1D_SCL @T6G_MB_LIB.T6G(SCH_1):SMB_RT_CPU1_P3_ROM_MUX_1D_SCL   I177 @T6G_MB_LIB.T6G(SCH_1):PAGE377

R1464 Q_RES_0201LF-4.7K,5%,1/20W,EMPTY,CS24701JE04
     1 P1V8_CPU1_RT_1D @T6G_MB_LIB.T6G(SCH_1):P1V8_CPU1_RT_1D   I149 @T6G_MB_LIB.T6G(SCH_1):PAGE401
     2 JTAG_TDI_RT_CPU1_P0 @T6G_MB_LIB.T6G(SCH_1):JTAG_TDI_RT_CPU1_P0   I149 @T6G_MB_LIB.T6G(SCH_1):PAGE401

R1465 Q_RES_0201LF-4.7K,5%,1/20W,EMPTY,CS24701JE04
     1 P1V8_CPU1_RT_1D @T6G_MB_LIB.T6G(SCH_1):P1V8_CPU1_RT_1D   I145 @T6G_MB_LIB.T6G(SCH_1):PAGE401
     2 JTAG_TMS_RT_CPU1_P0 @T6G_MB_LIB.T6G(SCH_1):JTAG_TMS_RT_CPU1_P0   I145 @T6G_MB_LIB.T6G(SCH_1):PAGE401

R1466 Q_RES_0201LF-1K,1%,1/20W,EMPTY,CS21001FE07
     1 P1V8_CPU1_RT_1D @T6G_MB_LIB.T6G(SCH_1):P1V8_CPU1_RT_1D   I146 @T6G_MB_LIB.T6G(SCH_1):PAGE401
     2 JTAG_TDO_RT_CPU1_P0 @T6G_MB_LIB.T6G(SCH_1):JTAG_TDO_RT_CPU1_P0   I146 @T6G_MB_LIB.T6G(SCH_1):PAGE401

R1467 Q_RES_0201LF-4.7K,5%,1/20W,EMPTY,CS24701JE04
     1 P1V8_CPU1_RT_1D @T6G_MB_LIB.T6G(SCH_1):P1V8_CPU1_RT_1D   I147 @T6G_MB_LIB.T6G(SCH_1):PAGE401
     2 JTAG_TCK_RT_CPU1_P0 @T6G_MB_LIB.T6G(SCH_1):JTAG_TCK_RT_CPU1_P0   I147 @T6G_MB_LIB.T6G(SCH_1):PAGE401

R1468 Q_RES_0201LF-1K,1%,1/20W,CHIP,CS21001FE07
     1 P1V8_CPU1_RT_1D @T6G_MB_LIB.T6G(SCH_1):P1V8_CPU1_RT_1D   I178 @T6G_MB_LIB.T6G(SCH_1):PAGE377
     2 SMB_RT_CPU1_P2_ROM_MUX_1D_SDA @T6G_MB_LIB.T6G(SCH_1):SMB_RT_CPU1_P2_ROM_MUX_1D_SDA   I178 @T6G_MB_LIB.T6G(SCH_1):PAGE377

R1469 Q_RES_0201LF-1K,1%,1/20W,CHIP,CS21001FE07
     1 P1V8_CPU1_RT_1D @T6G_MB_LIB.T6G(SCH_1):P1V8_CPU1_RT_1D   I179 @T6G_MB_LIB.T6G(SCH_1):PAGE377
     2 SMB_RT_CPU1_P2_ROM_MUX_1D_SCL @T6G_MB_LIB.T6G(SCH_1):SMB_RT_CPU1_P2_ROM_MUX_1D_SCL   I179 @T6G_MB_LIB.T6G(SCH_1):PAGE377

R1470 Q_RES_0201LF-4.7K,5%,1/20W,EMPTY,CS24701JE04
     1 P1V8_CPU0_RT_1D @T6G_MB_LIB.T6G(SCH_1):P1V8_CPU0_RT_1D   I115 @T6G_MB_LIB.T6G(SCH_1):PAGE408
     2 JTAG_TDI_RT_CPU0_P1 @T6G_MB_LIB.T6G(SCH_1):JTAG_TDI_RT_CPU0_P1   I115 @T6G_MB_LIB.T6G(SCH_1):PAGE408

R1471 Q_RES_0201LF-4.7K,5%,1/20W,EMPTY,CS24701JE04
     1 P1V8_CPU0_RT_1D @T6G_MB_LIB.T6G(SCH_1):P1V8_CPU0_RT_1D   I116 @T6G_MB_LIB.T6G(SCH_1):PAGE408
     2 JTAG_TMS_RT_CPU0_P1 @T6G_MB_LIB.T6G(SCH_1):JTAG_TMS_RT_CPU0_P1   I116 @T6G_MB_LIB.T6G(SCH_1):PAGE408

R1472 Q_RES_0201LF-1K,1%,1/20W,EMPTY,CS21001FE07
     1 P1V8_CPU0_RT_1D @T6G_MB_LIB.T6G(SCH_1):P1V8_CPU0_RT_1D   I121 @T6G_MB_LIB.T6G(SCH_1):PAGE408
     2 JTAG_TDO_RT_CPU0_P1 @T6G_MB_LIB.T6G(SCH_1):JTAG_TDO_RT_CPU0_P1   I121 @T6G_MB_LIB.T6G(SCH_1):PAGE408

R1473 Q_RES_0201LF-4.7K,5%,1/20W,EMPTY,CS24701JE04
     1 P1V8_CPU0_RT_1D @T6G_MB_LIB.T6G(SCH_1):P1V8_CPU0_RT_1D   I122 @T6G_MB_LIB.T6G(SCH_1):PAGE408
     2 JTAG_TCK_RT_CPU0_P1 @T6G_MB_LIB.T6G(SCH_1):JTAG_TCK_RT_CPU0_P1   I122 @T6G_MB_LIB.T6G(SCH_1):PAGE408

R1474 Q_RES_0402LF-10K,1%,1/16W,EMPTY,CS31002FB08
     1 P12V_AUX_DSC_G2 @T6G_MB_LIB.T6G(SCH_1):P12V_AUX_DSC_G2    I14 @T6G_MB_LIB.T6G(SCH_1):PAGE146
     2    GND @T6G_MB_LIB.T6G(SCH_1):GND    I14 @T6G_MB_LIB.T6G(SCH_1):PAGE146

R1475 Q_RES_0402LF-10K,1%,1/16W,EMPTY,CS31002FB08
     1 P3V3_AUX_DSC_G2 @T6G_MB_LIB.T6G(SCH_1):P3V3_AUX_DSC_G2    I28 @T6G_MB_LIB.T6G(SCH_1):PAGE146
     2    GND @T6G_MB_LIB.T6G(SCH_1):GND    I28 @T6G_MB_LIB.T6G(SCH_1):PAGE146

R1476 Q_RES_0201LF-4.7K,5%,1/20W,EMPTY,CS24701JE04
     1 P1V8_CPU0_RT_1D @T6G_MB_LIB.T6G(SCH_1):P1V8_CPU0_RT_1D   I116 @T6G_MB_LIB.T6G(SCH_1):PAGE419
     2 JTAG_TDI_RT_CPU0_P2 @T6G_MB_LIB.T6G(SCH_1):JTAG_TDI_RT_CPU0_P2   I116 @T6G_MB_LIB.T6G(SCH_1):PAGE419

R1477 Q_RES_0201LF-4.7K,5%,1/20W,EMPTY,CS24701JE04
     1 P1V8_CPU0_RT_1D @T6G_MB_LIB.T6G(SCH_1):P1V8_CPU0_RT_1D   I117 @T6G_MB_LIB.T6G(SCH_1):PAGE419
     2 JTAG_TMS_RT_CPU0_P2 @T6G_MB_LIB.T6G(SCH_1):JTAG_TMS_RT_CPU0_P2   I117 @T6G_MB_LIB.T6G(SCH_1):PAGE419

R1478 Q_RES_0201LF-1K,1%,1/20W,EMPTY,CS21001FE07
     1 P1V8_CPU0_RT_1D @T6G_MB_LIB.T6G(SCH_1):P1V8_CPU0_RT_1D   I118 @T6G_MB_LIB.T6G(SCH_1):PAGE419
     2 JTAG_TDO_RT_CPU0_P2 @T6G_MB_LIB.T6G(SCH_1):JTAG_TDO_RT_CPU0_P2   I118 @T6G_MB_LIB.T6G(SCH_1):PAGE419

R1479 Q_RES_0201LF-4.7K,5%,1/20W,EMPTY,CS24701JE04
     1 P1V8_CPU0_RT_1D @T6G_MB_LIB.T6G(SCH_1):P1V8_CPU0_RT_1D   I121 @T6G_MB_LIB.T6G(SCH_1):PAGE419
     2 JTAG_TCK_RT_CPU0_P2 @T6G_MB_LIB.T6G(SCH_1):JTAG_TCK_RT_CPU0_P2   I121 @T6G_MB_LIB.T6G(SCH_1):PAGE419

R1480 Q_RES_2512LF-10,1%,2W,EMPTY,CS0100AFR00
     1 P12V_AUX @T6G_MB_LIB.T6G(SCH_1):P12V_AUX    I19 @T6G_MB_LIB.T6G(SCH_1):PAGE146
     2 P12V_AUX_DSC @T6G_MB_LIB.T6G(SCH_1):P12V_AUX_DSC    I19 @T6G_MB_LIB.T6G(SCH_1):PAGE146

R1481 Q_RES_2512LF-10,1%,2W,EMPTY,CS0100AFR00
     1 P3V3_AUX @T6G_MB_LIB.T6G(SCH_1):P3V3_AUX    I21 @T6G_MB_LIB.T6G(SCH_1):PAGE146
     2 P3V3_AUX_DSC @T6G_MB_LIB.T6G(SCH_1):P3V3_AUX_DSC    I21 @T6G_MB_LIB.T6G(SCH_1):PAGE146

R1482 Q_RES_0201LF-4.7K,5%,1/20W,EMPTY,CS24701JE04
     1 P1V8_CPU0_RT_1D @T6G_MB_LIB.T6G(SCH_1):P1V8_CPU0_RT_1D   I112 @T6G_MB_LIB.T6G(SCH_1):PAGE430
     2 JTAG_TDI_RT_CPU0_P3 @T6G_MB_LIB.T6G(SCH_1):JTAG_TDI_RT_CPU0_P3   I112 @T6G_MB_LIB.T6G(SCH_1):PAGE430

R1483 Q_RES_0201LF-4.7K,5%,1/20W,EMPTY,CS24701JE04
     1 P1V8_CPU0_RT_1D @T6G_MB_LIB.T6G(SCH_1):P1V8_CPU0_RT_1D   I113 @T6G_MB_LIB.T6G(SCH_1):PAGE430
     2 JTAG_TMS_RT_CPU0_P3 @T6G_MB_LIB.T6G(SCH_1):JTAG_TMS_RT_CPU0_P3   I113 @T6G_MB_LIB.T6G(SCH_1):PAGE430

R1484 Q_RES_0201LF-1K,1%,1/20W,EMPTY,CS21001FE07
     1 P1V8_CPU0_RT_1D @T6G_MB_LIB.T6G(SCH_1):P1V8_CPU0_RT_1D   I118 @T6G_MB_LIB.T6G(SCH_1):PAGE430
     2 JTAG_TDO_RT_CPU0_P3 @T6G_MB_LIB.T6G(SCH_1):JTAG_TDO_RT_CPU0_P3   I118 @T6G_MB_LIB.T6G(SCH_1):PAGE430

R1485 Q_RES_0201LF-4.7K,5%,1/20W,EMPTY,CS24701JE04
     1 P1V8_CPU0_RT_1D @T6G_MB_LIB.T6G(SCH_1):P1V8_CPU0_RT_1D   I119 @T6G_MB_LIB.T6G(SCH_1):PAGE430
     2 JTAG_TCK_RT_CPU0_P3 @T6G_MB_LIB.T6G(SCH_1):JTAG_TCK_RT_CPU0_P3   I119 @T6G_MB_LIB.T6G(SCH_1):PAGE430

R1486 Q_RES_0402LF-0,5%,1/16W,CHIP,CS00002JB13
     1 P12V_OCP_SFF_BUF_EN_R @T6G_MB_LIB.T6G(SCH_1):P12V_OCP_SFF_BUF_EN_R   I135 @T6G_MB_LIB.T6G(SCH_1):PAGE338
     2 P3V3_OCP_EN_1_R @T6G_MB_LIB.T6G(SCH_1):P3V3_OCP_EN_1_R   I135 @T6G_MB_LIB.T6G(SCH_1):PAGE338

R1487 Q_RES_0402LF-0,5%,1/16W,CHIP,CS00002JB13
     1 P12V_OCP_SFF_BUF_EN_R @T6G_MB_LIB.T6G(SCH_1):P12V_OCP_SFF_BUF_EN_R   I134 @T6G_MB_LIB.T6G(SCH_1):PAGE339
     2 P3V3_OCP_EN_1_R2 @T6G_MB_LIB.T6G(SCH_1):P3V3_OCP_EN_1_R2   I134 @T6G_MB_LIB.T6G(SCH_1):PAGE339

R1488 Q_RES_0201LF-4.7K,5%,1/20W,EMPTY,CS24701JE04
     1 P1V8_CPU1_RT_1D @T6G_MB_LIB.T6G(SCH_1):P1V8_CPU1_RT_1D   I132 @T6G_MB_LIB.T6G(SCH_1):PAGE451
     2 JTAG_TDI_RT_CPU1_P2 @T6G_MB_LIB.T6G(SCH_1):JTAG_TDI_RT_CPU1_P2   I132 @T6G_MB_LIB.T6G(SCH_1):PAGE451

R1489 Q_RES_0201LF-4.7K,5%,1/20W,EMPTY,CS24701JE04
     1 P1V8_CPU1_RT_1D @T6G_MB_LIB.T6G(SCH_1):P1V8_CPU1_RT_1D   I140 @T6G_MB_LIB.T6G(SCH_1):PAGE451
     2 JTAG_TMS_RT_CPU1_P2 @T6G_MB_LIB.T6G(SCH_1):JTAG_TMS_RT_CPU1_P2   I140 @T6G_MB_LIB.T6G(SCH_1):PAGE451

R1490 Q_RES_0201LF-1K,1%,1/20W,EMPTY,CS21001FE07
     1 P1V8_CPU1_RT_1D @T6G_MB_LIB.T6G(SCH_1):P1V8_CPU1_RT_1D   I139 @T6G_MB_LIB.T6G(SCH_1):PAGE451
     2 JTAG_TDO_RT_CPU1_P2 @T6G_MB_LIB.T6G(SCH_1):JTAG_TDO_RT_CPU1_P2   I139 @T6G_MB_LIB.T6G(SCH_1):PAGE451

R1491 Q_RES_0402LF-10K,5%,1/16W,EMPTY,CS31002JB08
     1   P3V3 @T6G_MB_LIB.T6G(SCH_1):P3V3   I141 @T6G_MB_LIB.T6G(SCH_1):PAGE273
     2 PWRGD_P3V3_EN_R @T6G_MB_LIB.T6G(SCH_1):PWRGD_P3V3_EN_R   I141 @T6G_MB_LIB.T6G(SCH_1):PAGE273

R1492 Q_RES_0402LF-10K,5%,1/16W,CHIP,CS31002JB08
     1 P3V3_AUX @T6G_MB_LIB.T6G(SCH_1):P3V3_AUX   I120 @T6G_MB_LIB.T6G(SCH_1):PAGE273
     2 PWRGD_P3V3_EN_N @T6G_MB_LIB.T6G(SCH_1):PWRGD_P3V3_EN_N   I120 @T6G_MB_LIB.T6G(SCH_1):PAGE273

R1493 Q_RES_0402LF-10K,5%,1/16W,CHIP,CS31002JB08
     1 P1V8_AUX @T6G_MB_LIB.T6G(SCH_1):P1V8_AUX   I125 @T6G_MB_LIB.T6G(SCH_1):PAGE273
     2 PWRGD_P3V3_R1 @T6G_MB_LIB.T6G(SCH_1):PWRGD_P3V3_R1   I125 @T6G_MB_LIB.T6G(SCH_1):PAGE273

R1494 Q_RES_0402LF-33,5%,1/16W,CHIP,CS03302JB10
     1 SMB_VR_3V3STBY_SDA @T6G_MB_LIB.T6G(SCH_1):SMB_VR_3V3STBY_SDA     I9 @T6G_MB_LIB.T6G(SCH_1):PAGE349
     2 SMB_SCM_2_R1_SDA @T6G_MB_LIB.T6G(SCH_1):SMB_SCM_2_R1_SDA     I9 @T6G_MB_LIB.T6G(SCH_1):PAGE349

R1495 Q_RES_0402LF-33,5%,1/16W,CHIP,CS03302JB10
     1 SMB_SCM_2_R1_SCL @T6G_MB_LIB.T6G(SCH_1):SMB_SCM_2_R1_SCL    I49 @T6G_MB_LIB.T6G(SCH_1):PAGE349
     2 SMB_SCM_2_R2_SCL @T6G_MB_LIB.T6G(SCH_1):SMB_SCM_2_R2_SCL    I49 @T6G_MB_LIB.T6G(SCH_1):PAGE349

R1496 Q_RES_0402LF-33,5%,1/16W,CHIP,CS03302JB10
     1 SMB_SCM_2_R1_SDA @T6G_MB_LIB.T6G(SCH_1):SMB_SCM_2_R1_SDA    I48 @T6G_MB_LIB.T6G(SCH_1):PAGE349
     2 SMB_SCM_2_R2_SDA @T6G_MB_LIB.T6G(SCH_1):SMB_SCM_2_R2_SDA    I48 @T6G_MB_LIB.T6G(SCH_1):PAGE349

R1497 Q_RES_0402LF-33,5%,1/16W,CHIP,CS03302JB10
     1 SMB_VR_3V3AUX_SCL @T6G_MB_LIB.T6G(SCH_1):SMB_VR_3V3AUX_SCL   I176 @T6G_MB_LIB.T6G(SCH_1):PAGE349
     2 SMB_SCM_2_R3_SCL @T6G_MB_LIB.T6G(SCH_1):SMB_SCM_2_R3_SCL   I176 @T6G_MB_LIB.T6G(SCH_1):PAGE349

R1498 Q_RES_0402LF-33,5%,1/16W,CHIP,CS03302JB10
     1 SMB_VR_3V3AUX_SDA @T6G_MB_LIB.T6G(SCH_1):SMB_VR_3V3AUX_SDA   I183 @T6G_MB_LIB.T6G(SCH_1):PAGE349
     2 SMB_SCM_2_R3_SDA @T6G_MB_LIB.T6G(SCH_1):SMB_SCM_2_R3_SDA   I183 @T6G_MB_LIB.T6G(SCH_1):PAGE349

R1499 Q_RES_0201LF-4.7K,5%,1/20W,EMPTY,CS24701JE04
     1 P1V8_CPU1_RT_1D @T6G_MB_LIB.T6G(SCH_1):P1V8_CPU1_RT_1D   I137 @T6G_MB_LIB.T6G(SCH_1):PAGE451
     2 JTAG_TCK_RT_CPU1_P2 @T6G_MB_LIB.T6G(SCH_1):JTAG_TCK_RT_CPU1_P2   I137 @T6G_MB_LIB.T6G(SCH_1):PAGE451

R1500 Q_RES_0402LF-0,5%,1/16W,CHIP,CS00002JB13
     1 HP_LVC3_OCP_V3_1_R_EN @T6G_MB_LIB.T6G(SCH_1):HP_LVC3_OCP_V3_1_R_EN    I43 @T6G_MB_LIB.T6G(SCH_1):PAGE248
     2 P12V_OCP_SFF_BUF_EN_R @T6G_MB_LIB.T6G(SCH_1):P12V_OCP_SFF_BUF_EN_R    I43 @T6G_MB_LIB.T6G(SCH_1):PAGE248

R1501 Q_RES_0402LF-10K,5%,1/16W,EMPTY,CS31002JB08
     1 PVDD18_S5_P1 @T6G_MB_LIB.T6G(SCH_1):PVDD18_S5_P1    I90 @T6G_MB_LIB.T6G(SCH_1):PAGE75
     2 CLK_CPU1_RTCCLK @T6G_MB_LIB.T6G(SCH_1):CLK_CPU1_RTCCLK    I90 @T6G_MB_LIB.T6G(SCH_1):PAGE75

R1502 Q_RES_0402LF-10K,5%,1/16W,CHIP,CS31002JB08
     1    GND @T6G_MB_LIB.T6G(SCH_1):GND    I94 @T6G_MB_LIB.T6G(SCH_1):PAGE75
     2 CLK_CPU1_RTCCLK @T6G_MB_LIB.T6G(SCH_1):CLK_CPU1_RTCCLK    I94 @T6G_MB_LIB.T6G(SCH_1):PAGE75

R1503 Q_RES_0402LF-30K,1%,1/16W,CHIP,CS33002FB02
     1 PVDD18_S5_P0 @T6G_MB_LIB.T6G(SCH_1):PVDD18_S5_P0   I396 @T6G_MB_LIB.T6G(SCH_1):PAGE29
     2 ESPI_CPU0_D0 @T6G_MB_LIB.T6G(SCH_1):ESPI_CPU0_D0   I396 @T6G_MB_LIB.T6G(SCH_1):PAGE29

R1504 Q_RES_0402LF-30K,1%,1/16W,CHIP,CS33002FB02
     1 PVDD18_S5_P0 @T6G_MB_LIB.T6G(SCH_1):PVDD18_S5_P0   I397 @T6G_MB_LIB.T6G(SCH_1):PAGE29
     2 ESPI_CPU0_D1 @T6G_MB_LIB.T6G(SCH_1):ESPI_CPU0_D1   I397 @T6G_MB_LIB.T6G(SCH_1):PAGE29

R1505 Q_RES_0402LF-30K,1%,1/16W,CHIP,CS33002FB02
     1 PVDD18_S5_P0 @T6G_MB_LIB.T6G(SCH_1):PVDD18_S5_P0   I398 @T6G_MB_LIB.T6G(SCH_1):PAGE29
     2 ESPI_CPU0_D2 @T6G_MB_LIB.T6G(SCH_1):ESPI_CPU0_D2   I398 @T6G_MB_LIB.T6G(SCH_1):PAGE29

R1506 Q_RES_0402LF-30K,1%,1/16W,CHIP,CS33002FB02
     1 PVDD18_S5_P0 @T6G_MB_LIB.T6G(SCH_1):PVDD18_S5_P0   I399 @T6G_MB_LIB.T6G(SCH_1):PAGE29
     2 ESPI_CPU0_D3 @T6G_MB_LIB.T6G(SCH_1):ESPI_CPU0_D3   I399 @T6G_MB_LIB.T6G(SCH_1):PAGE29

R1507 Q_RES_0402LF-1K,1%,1/16W,CHIP,CS21002FB06
     1 P3V3_AUX @T6G_MB_LIB.T6G(SCH_1):P3V3_AUX    I87 @T6G_MB_LIB.T6G(SCH_1):PAGE142
     2 LED_BIOS_DBG_MODE_N @T6G_MB_LIB.T6G(SCH_1):LED_BIOS_DBG_MODE_N    I87 @T6G_MB_LIB.T6G(SCH_1):PAGE142

R1508 Q_RES_0402LF-100,1%,1/16W,CHIP,CS11002FB07
     1    GND @T6G_MB_LIB.T6G(SCH_1):GND     I6 @T6G_MB_LIB.T6G(SCH_1):PAGE144
     2 PD_BIOS_DEBUG_MODE @T6G_MB_LIB.T6G(SCH_1):PD_BIOS_DEBUG_MODE     I6 @T6G_MB_LIB.T6G(SCH_1):PAGE144

R1509 Q_RES_0402LF-0,5%,1/16W,CHIP,CS00002JB13
     1 HP_LVC3_OCP_V3_1_P12V_PWRGD @T6G_MB_LIB.T6G(SCH_1):HP_LVC3_OCP_V3_1_P12V_PWRGD    I96 @T6G_MB_LIB.T6G(SCH_1):PAGE340
     2 HP_LVC3_OCP_V3_1_P12V_R2_PWRGD @T6G_MB_LIB.T6G(SCH_1):HP_LVC3_OCP_V3_1_P12V_R2_PWRGD    I96 @T6G_MB_LIB.T6G(SCH_1):PAGE340

R1510 Q_RES_0201LF-4.7K,5%,1/20W,EMPTY,CS24701JE04
     1 P1V8_CPU1_RT_1D @T6G_MB_LIB.T6G(SCH_1):P1V8_CPU1_RT_1D   I139 @T6G_MB_LIB.T6G(SCH_1):PAGE462
     2 JTAG_TDI_RT_CPU1_P3 @T6G_MB_LIB.T6G(SCH_1):JTAG_TDI_RT_CPU1_P3   I139 @T6G_MB_LIB.T6G(SCH_1):PAGE462

R1511 Q_RES_0201LF-4.7K,5%,1/20W,EMPTY,CS24701JE04
     1 P1V8_CPU1_RT_1D @T6G_MB_LIB.T6G(SCH_1):P1V8_CPU1_RT_1D   I132 @T6G_MB_LIB.T6G(SCH_1):PAGE462
     2 JTAG_TMS_RT_CPU1_P3 @T6G_MB_LIB.T6G(SCH_1):JTAG_TMS_RT_CPU1_P3   I132 @T6G_MB_LIB.T6G(SCH_1):PAGE462

R1512 Q_RES_0201LF-1K,1%,1/20W,EMPTY,CS21001FE07
     1 P1V8_CPU1_RT_1D @T6G_MB_LIB.T6G(SCH_1):P1V8_CPU1_RT_1D   I140 @T6G_MB_LIB.T6G(SCH_1):PAGE462
     2 JTAG_TDO_RT_CPU1_P3 @T6G_MB_LIB.T6G(SCH_1):JTAG_TDO_RT_CPU1_P3   I140 @T6G_MB_LIB.T6G(SCH_1):PAGE462

R1513 Q_RES_0201LF-4.7K,5%,1/20W,EMPTY,CS24701JE04
     1 P1V8_CPU1_RT_1D @T6G_MB_LIB.T6G(SCH_1):P1V8_CPU1_RT_1D   I137 @T6G_MB_LIB.T6G(SCH_1):PAGE462
     2 JTAG_TCK_RT_CPU1_P3 @T6G_MB_LIB.T6G(SCH_1):JTAG_TCK_RT_CPU1_P3   I137 @T6G_MB_LIB.T6G(SCH_1):PAGE462

R1514 Q_RES_0201LF-0,5%,1/20W,CHIP,CS00001JE10
     1 SMB_MUX_RT_R1_SCL @T6G_MB_LIB.T6G(SCH_1):SMB_MUX_RT_R1_SCL   I118 @T6G_MB_LIB.T6G(SCH_1):PAGE378
     2 SMB_MUX_RT_R2_SCL @T6G_MB_LIB.T6G(SCH_1):SMB_MUX_RT_R2_SCL   I118 @T6G_MB_LIB.T6G(SCH_1):PAGE378

R1515 Q_RES_0201LF-0,5%,1/20W,CHIP,CS00001JE10
     1 SMB_MUX_RT_R1_SDA @T6G_MB_LIB.T6G(SCH_1):SMB_MUX_RT_R1_SDA   I117 @T6G_MB_LIB.T6G(SCH_1):PAGE378
     2 SMB_MUX_RT_R2_SDA @T6G_MB_LIB.T6G(SCH_1):SMB_MUX_RT_R2_SDA   I117 @T6G_MB_LIB.T6G(SCH_1):PAGE378

R1516 Q_RES_0402LF-33.2,1%,1/16W,CHIP,CS03322FB03
     1 SMB_HOST_CLK_3V3AUX_SCL @T6G_MB_LIB.T6G(SCH_1):SMB_HOST_CLK_3V3AUX_SCL   I222 @T6G_MB_LIB.T6G(SCH_1):PAGE349
     2 SMB_HOST_CLK_3V3AUX_SCL_R1 @T6G_MB_LIB.T6G(SCH_1):SMB_HOST_CLK_3V3AUX_SCL_R1   I222 @T6G_MB_LIB.T6G(SCH_1):PAGE349

R1517 Q_RES_0402LF-33.2,1%,1/16W,CHIP,CS03322FB03
     1 SMB_HOST_CLK_3V3AUX_SDA @T6G_MB_LIB.T6G(SCH_1):SMB_HOST_CLK_3V3AUX_SDA   I223 @T6G_MB_LIB.T6G(SCH_1):PAGE349
     2 SMB_HOST_CLK_3V3AUX_SDA_R1 @T6G_MB_LIB.T6G(SCH_1):SMB_HOST_CLK_3V3AUX_SDA_R1   I223 @T6G_MB_LIB.T6G(SCH_1):PAGE349

R1518 Q_RES_0402LF-0,5%,1/16W,CHIP,CS00002JB13
     1 HP_LVC3_OCP_V3_1_PWRGD_R2 @T6G_MB_LIB.T6G(SCH_1):HP_LVC3_OCP_V3_1_PWRGD_R2   I102 @T6G_MB_LIB.T6G(SCH_1):PAGE340
     2 OCP_V3_1_P3V3_R3_PWRGD @T6G_MB_LIB.T6G(SCH_1):OCP_V3_1_P3V3_R3_PWRGD   I102 @T6G_MB_LIB.T6G(SCH_1):PAGE340

R1519 Q_RES_0402LF-0,5%,1/16W,EMPTY,CS00002JB13
     1 OCP_V3_1_P3V3_R3_PWRGD @T6G_MB_LIB.T6G(SCH_1):OCP_V3_1_P3V3_R3_PWRGD   I101 @T6G_MB_LIB.T6G(SCH_1):PAGE340
     2 OCP_V3_1_P3V3_PWRGD @T6G_MB_LIB.T6G(SCH_1):OCP_V3_1_P3V3_PWRGD   I101 @T6G_MB_LIB.T6G(SCH_1):PAGE340

R1520 Q_RES_0402LF-0,5%,1/16W,CHIP,CS00002JB13
     1 P12V_OCP_V3_2_BUF_EN_R @T6G_MB_LIB.T6G(SCH_1):P12V_OCP_V3_2_BUF_EN_R   I130 @T6G_MB_LIB.T6G(SCH_1):PAGE343
     2 P3V3_OCP_EN_2_R @T6G_MB_LIB.T6G(SCH_1):P3V3_OCP_EN_2_R   I130 @T6G_MB_LIB.T6G(SCH_1):PAGE343

R1521 Q_RES_0402LF-0,5%,1/16W,CHIP,CS00002JB13
     1 P12V_OCP_V3_2_BUF_EN_R @T6G_MB_LIB.T6G(SCH_1):P12V_OCP_V3_2_BUF_EN_R    I80 @T6G_MB_LIB.T6G(SCH_1):PAGE344
     2 P3V3_OCP_EN_2 @T6G_MB_LIB.T6G(SCH_1):P3V3_OCP_EN_2    I80 @T6G_MB_LIB.T6G(SCH_1):PAGE344

R1522 Q_RES_0402LF-0,5%,1/16W,CHIP,CS00002JB13
     1 HP_LVC3_OCP_V3_2_R_EN @T6G_MB_LIB.T6G(SCH_1):HP_LVC3_OCP_V3_2_R_EN    I44 @T6G_MB_LIB.T6G(SCH_1):PAGE248
     2 P12V_OCP_V3_2_BUF_EN_R @T6G_MB_LIB.T6G(SCH_1):P12V_OCP_V3_2_BUF_EN_R    I44 @T6G_MB_LIB.T6G(SCH_1):PAGE248

R1523 Q_RES_0402LF-0,5%,1/16W,CHIP,CS00002JB13
     1 HP_LVC3_OCP_V3_2_P12V_PWRGD @T6G_MB_LIB.T6G(SCH_1):HP_LVC3_OCP_V3_2_P12V_PWRGD    I84 @T6G_MB_LIB.T6G(SCH_1):PAGE257
     2 HP_LVC3_OCP_V3_2_P12V_PWRGD_R2 @T6G_MB_LIB.T6G(SCH_1):HP_LVC3_OCP_V3_2_P12V_PWRGD_R2    I84 @T6G_MB_LIB.T6G(SCH_1):PAGE257

R1524 Q_RES_0402LF-0,5%,1/16W,CHIP,CS00002JB13
     1 HP_LVC3_OCP_V3_2_PWRGD_R2 @T6G_MB_LIB.T6G(SCH_1):HP_LVC3_OCP_V3_2_PWRGD_R2    I89 @T6G_MB_LIB.T6G(SCH_1):PAGE257
     2 OCP_V3_2_P3V3_R3_PWRGD @T6G_MB_LIB.T6G(SCH_1):OCP_V3_2_P3V3_R3_PWRGD    I89 @T6G_MB_LIB.T6G(SCH_1):PAGE257

R1525 Q_RES_0402LF-0,5%,1/16W,EMPTY,CS00002JB13
     1 OCP_V3_2_P3V3_PWRGD @T6G_MB_LIB.T6G(SCH_1):OCP_V3_2_P3V3_PWRGD    I88 @T6G_MB_LIB.T6G(SCH_1):PAGE257
     2 OCP_V3_2_P3V3_R3_PWRGD @T6G_MB_LIB.T6G(SCH_1):OCP_V3_2_P3V3_R3_PWRGD    I88 @T6G_MB_LIB.T6G(SCH_1):PAGE257

R1526 Q_RES_0402LF-0,5%,1/16W,CHIP,CS00002JB13
     1 PDB_PRSNT_N @T6G_MB_LIB.T6G(SCH_1):PDB_PRSNT_N   I476 @T6G_MB_LIB.T6G(SCH_1):PAGE363
     2 PDB_PRSNT_R_N @T6G_MB_LIB.T6G(SCH_1):PDB_PRSNT_R_N   I476 @T6G_MB_LIB.T6G(SCH_1):PAGE363

R1527 Q_RES_0402LF-1K,1%,1/16W,CHIP,CS21002FB06
     1 PRSNT_HDT_N @T6G_MB_LIB.T6G(SCH_1):PRSNT_HDT_N    I56 @T6G_MB_LIB.T6G(SCH_1):PAGE82
     2 P3V3_AUX @T6G_MB_LIB.T6G(SCH_1):P3V3_AUX    I56 @T6G_MB_LIB.T6G(SCH_1):PAGE82

R1528 Q_RES_0402LF-33,5%,1/16W,CHIP,CS03302JB10
     1 PRSNT_HDT_N @T6G_MB_LIB.T6G(SCH_1):PRSNT_HDT_N   I157 @T6G_MB_LIB.T6G(SCH_1):PAGE149
     2 PRSNT_HDT_R_N @T6G_MB_LIB.T6G(SCH_1):PRSNT_HDT_R_N   I157 @T6G_MB_LIB.T6G(SCH_1):PAGE149

R1529 Q_RES_0402LF-1K,1%,1/16W,EMPTY,CS21002FB06
     1 PVDD18_S5_P0 @T6G_MB_LIB.T6G(SCH_1):PVDD18_S5_P0   I134 @T6G_MB_LIB.T6G(SCH_1):PAGE76
     2 SPI_CPU0_D3 @T6G_MB_LIB.T6G(SCH_1):SPI_CPU0_D3   I134 @T6G_MB_LIB.T6G(SCH_1):PAGE76

R1530 Q_RES_0402LF-1K,1%,1/16W,EMPTY,CS21002FB06
     1 PVDD18_S5_P0 @T6G_MB_LIB.T6G(SCH_1):PVDD18_S5_P0   I133 @T6G_MB_LIB.T6G(SCH_1):PAGE76
     2 SPI_CPU0_D2 @T6G_MB_LIB.T6G(SCH_1):SPI_CPU0_D2   I133 @T6G_MB_LIB.T6G(SCH_1):PAGE76

R1531 Q_RES_0402LF-1K,1%,1/16W,EMPTY,CS21002FB06
     1 PVDD18_S5_P0 @T6G_MB_LIB.T6G(SCH_1):PVDD18_S5_P0   I132 @T6G_MB_LIB.T6G(SCH_1):PAGE76
     2 SPI_CPU0_D1 @T6G_MB_LIB.T6G(SCH_1):SPI_CPU0_D1   I132 @T6G_MB_LIB.T6G(SCH_1):PAGE76

R1532 Q_RES_0402LF-1K,1%,1/16W,EMPTY,CS21002FB06
     1 PVDD18_S5_P0 @T6G_MB_LIB.T6G(SCH_1):PVDD18_S5_P0   I131 @T6G_MB_LIB.T6G(SCH_1):PAGE76
     2 SPI_CPU0_D0 @T6G_MB_LIB.T6G(SCH_1):SPI_CPU0_D0   I131 @T6G_MB_LIB.T6G(SCH_1):PAGE76

R1533 Q_RES_0402LF-0,5%,1/16W,CHIP,CS00002JB13
     1 CPU0_THERMTRIP_R_N @T6G_MB_LIB.T6G(SCH_1):CPU0_THERMTRIP_R_N   I429 @T6G_MB_LIB.T6G(SCH_1):PAGE27
     2 CPU1_THERMTRIP_R_N @T6G_MB_LIB.T6G(SCH_1):CPU1_THERMTRIP_R_N   I429 @T6G_MB_LIB.T6G(SCH_1):PAGE27

R1546 Q_RES_0402LF-1K,1%,1/16W,CHIP,CS21002FB06
     1 P3V3_AUX @T6G_MB_LIB.T6G(SCH_1):P3V3_AUX    I30 @T6G_MB_LIB.T6G(SCH_1):PAGE349
     2 RST_MB_STBY_N @T6G_MB_LIB.T6G(SCH_1):RST_MB_STBY_N    I30 @T6G_MB_LIB.T6G(SCH_1):PAGE349

R1547 Q_RES_0402LF-4.7K,5%,1/16W,CHIP,CS24702JB10
     1 P3V3_AUX @T6G_MB_LIB.T6G(SCH_1):P3V3_AUX   I148 @T6G_MB_LIB.T6G(SCH_1):PAGE76
     2 SPI_CPU0_LVC3_TPM_CS_N @T6G_MB_LIB.T6G(SCH_1):SPI_CPU0_LVC3_TPM_CS_N   I148 @T6G_MB_LIB.T6G(SCH_1):PAGE76

R1549 Q_RES_0402LF-33,5%,1/16W,CHIP,CS03302JB10
     1 ESPI_CPU0_R1_D0 @T6G_MB_LIB.T6G(SCH_1):ESPI_CPU0_R1_D0   I173 @T6G_MB_LIB.T6G(SCH_1):PAGE80
     2 ESPI_CPU0_D0 @T6G_MB_LIB.T6G(SCH_1):ESPI_CPU0_D0   I173 @T6G_MB_LIB.T6G(SCH_1):PAGE80

R1550 Q_RES_0402LF-33,5%,1/16W,CHIP,CS03302JB10
     1 ESPI_CPU0_R1_D1 @T6G_MB_LIB.T6G(SCH_1):ESPI_CPU0_R1_D1   I171 @T6G_MB_LIB.T6G(SCH_1):PAGE80
     2 ESPI_CPU0_D1 @T6G_MB_LIB.T6G(SCH_1):ESPI_CPU0_D1   I171 @T6G_MB_LIB.T6G(SCH_1):PAGE80

R1551 Q_RES_0402LF-33,5%,1/16W,CHIP,CS03302JB10
     1 ESPI_CPU0_R1_D2 @T6G_MB_LIB.T6G(SCH_1):ESPI_CPU0_R1_D2   I169 @T6G_MB_LIB.T6G(SCH_1):PAGE80
     2 ESPI_CPU0_D2 @T6G_MB_LIB.T6G(SCH_1):ESPI_CPU0_D2   I169 @T6G_MB_LIB.T6G(SCH_1):PAGE80

R1552 Q_RES_0402LF-33,5%,1/16W,CHIP,CS03302JB10
     1 ESPI_CPU0_R1_D3 @T6G_MB_LIB.T6G(SCH_1):ESPI_CPU0_R1_D3   I170 @T6G_MB_LIB.T6G(SCH_1):PAGE80
     2 ESPI_CPU0_D3 @T6G_MB_LIB.T6G(SCH_1):ESPI_CPU0_D3   I170 @T6G_MB_LIB.T6G(SCH_1):PAGE80

R1553 Q_RES_0402LF-33,5%,1/16W,CHIP,CS03302JB10
     1 ESPI_CPU0_CS1_R_N @T6G_MB_LIB.T6G(SCH_1):ESPI_CPU0_CS1_R_N   I174 @T6G_MB_LIB.T6G(SCH_1):PAGE80
     2 ESPI_CPU0_CS1_N @T6G_MB_LIB.T6G(SCH_1):ESPI_CPU0_CS1_N   I174 @T6G_MB_LIB.T6G(SCH_1):PAGE80

R1556 Q_RES_0402LF-33,5%,1/16W,CHIP,CS03302JB10
     1 CLK_ESPI_CPU0_R1_CLK1 @T6G_MB_LIB.T6G(SCH_1):CLK_ESPI_CPU0_R1_CLK1   I176 @T6G_MB_LIB.T6G(SCH_1):PAGE80
     2 CLK_ESPI_CPU0_CLK1 @T6G_MB_LIB.T6G(SCH_1):CLK_ESPI_CPU0_CLK1   I176 @T6G_MB_LIB.T6G(SCH_1):PAGE80

R1557 Q_RES_0402LF-33,5%,1/16W,CHIP,CS03302JB10
     1 ESPI_CPU0_ALERT_R_N @T6G_MB_LIB.T6G(SCH_1):ESPI_CPU0_ALERT_R_N   I175 @T6G_MB_LIB.T6G(SCH_1):PAGE80
     2 ESPI_CPU0_ALERT_PLD_N @T6G_MB_LIB.T6G(SCH_1):ESPI_CPU0_ALERT_PLD_N   I175 @T6G_MB_LIB.T6G(SCH_1):PAGE80

R1558 Q_RES_0402LF-33,5%,1/16W,CHIP,CS03302JB10
     1 RST_ESPI_CPU0_RSTOUT_R_N @T6G_MB_LIB.T6G(SCH_1):RST_ESPI_CPU0_RSTOUT_R_N   I172 @T6G_MB_LIB.T6G(SCH_1):PAGE80
     2 RST_ESPI_CPU0_RSTOUT_N @T6G_MB_LIB.T6G(SCH_1):RST_ESPI_CPU0_RSTOUT_N   I172 @T6G_MB_LIB.T6G(SCH_1):PAGE80

R1563 Q_RES_0402LF-33,5%,1/16W,CHIP,CS03302JB10
     1 UART_LS_EN @T6G_MB_LIB.T6G(SCH_1):UART_LS_EN    I63 @T6G_MB_LIB.T6G(SCH_1):PAGE80
     2 FM_UART_LS_EN @T6G_MB_LIB.T6G(SCH_1):FM_UART_LS_EN    I63 @T6G_MB_LIB.T6G(SCH_1):PAGE80

R1564 Q_RES_0402LF-33,5%,1/16W,CHIP,CS03302JB10
     1 FM_ROM_LS_EN @T6G_MB_LIB.T6G(SCH_1):FM_ROM_LS_EN   I156 @T6G_MB_LIB.T6G(SCH_1):PAGE80
     2 ROM_LS_EN @T6G_MB_LIB.T6G(SCH_1):ROM_LS_EN   I156 @T6G_MB_LIB.T6G(SCH_1):PAGE80

R1567 Q_RES_0402LF-4.7K,5%,1/16W,CHIP,CS24702JB10
     1 PVDD18_S5_P0 @T6G_MB_LIB.T6G(SCH_1):PVDD18_S5_P0   I150 @T6G_MB_LIB.T6G(SCH_1):PAGE76
     2 ROM_LS_EN @T6G_MB_LIB.T6G(SCH_1):ROM_LS_EN   I150 @T6G_MB_LIB.T6G(SCH_1):PAGE76

R1568 Q_RES_0402LF-49.9,1%,1/16W,CHIP,CS04992FB07
     1 I3C_SPD_DDRAF_CPU0_SCL @T6G_MB_LIB.T6G(SCH_1):I3C_SPD_DDRAF_CPU0_SCL   I539 @T6G_MB_LIB.T6G(SCH_1):PAGE85
     2 I3C_SPD_DDRA_CPU0_SCL @T6G_MB_LIB.T6G(SCH_1):I3C_SPD_DDRA_CPU0_SCL   I539 @T6G_MB_LIB.T6G(SCH_1):PAGE85

R1569 Q_RES_0402LF-49.9,1%,1/16W,CHIP,CS04992FB07
     1 I3C_SPD_DDRAF_CPU0_SCL @T6G_MB_LIB.T6G(SCH_1):I3C_SPD_DDRAF_CPU0_SCL   I372 @T6G_MB_LIB.T6G(SCH_1):PAGE86
     2 I3C_SPD_DDRB_CPU0_SCL @T6G_MB_LIB.T6G(SCH_1):I3C_SPD_DDRB_CPU0_SCL   I372 @T6G_MB_LIB.T6G(SCH_1):PAGE86

R1570 Q_RES_0402LF-49.9,1%,1/16W,CHIP,CS04992FB07
     1 I3C_SPD_DDRAF_CPU0_SCL @T6G_MB_LIB.T6G(SCH_1):I3C_SPD_DDRAF_CPU0_SCL   I417 @T6G_MB_LIB.T6G(SCH_1):PAGE87
     2 I3C_SPD_DDRC_CPU0_SCL @T6G_MB_LIB.T6G(SCH_1):I3C_SPD_DDRC_CPU0_SCL   I417 @T6G_MB_LIB.T6G(SCH_1):PAGE87

R1571 Q_RES_0402LF-0,5%,1/16W,CHIP,CS00002JB13
     1 PWRGD_P5V_AUX @T6G_MB_LIB.T6G(SCH_1):PWRGD_P5V_AUX    I11 @T6G_MB_LIB.T6G(SCH_1):PAGE245
     2 P3V3_AUX_EN @T6G_MB_LIB.T6G(SCH_1):P3V3_AUX_EN    I11 @T6G_MB_LIB.T6G(SCH_1):PAGE245

R1572 Q_RES_0402LF-49.9,1%,1/16W,CHIP,CS04992FB07
     1 I3C_SPD_DDRAF_CPU0_SCL @T6G_MB_LIB.T6G(SCH_1):I3C_SPD_DDRAF_CPU0_SCL   I416 @T6G_MB_LIB.T6G(SCH_1):PAGE89
     2 I3C_SPD_DDRE_CPU0_SCL @T6G_MB_LIB.T6G(SCH_1):I3C_SPD_DDRE_CPU0_SCL   I416 @T6G_MB_LIB.T6G(SCH_1):PAGE89

R1573 Q_RES_0402LF-49.9,1%,1/16W,CHIP,CS04992FB07
     1 I3C_SPD_DDRAF_CPU0_SCL @T6G_MB_LIB.T6G(SCH_1):I3C_SPD_DDRAF_CPU0_SCL   I418 @T6G_MB_LIB.T6G(SCH_1):PAGE90
     2 I3C_SPD_DDRF_CPU0_SCL @T6G_MB_LIB.T6G(SCH_1):I3C_SPD_DDRF_CPU0_SCL   I418 @T6G_MB_LIB.T6G(SCH_1):PAGE90

R1574 Q_RES_0402LF-49.9,1%,1/16W,CHIP,CS04992FB07
     1 I3C_SPD_DDRGL_CPU0_SCL @T6G_MB_LIB.T6G(SCH_1):I3C_SPD_DDRGL_CPU0_SCL   I242 @T6G_MB_LIB.T6G(SCH_1):PAGE91
     2 I3C_SPD_DDRG_CPU0_SCL @T6G_MB_LIB.T6G(SCH_1):I3C_SPD_DDRG_CPU0_SCL   I242 @T6G_MB_LIB.T6G(SCH_1):PAGE91

R1575 Q_RES_0402LF-49.9,1%,1/16W,CHIP,CS04992FB07
     1 I3C_SPD_DDRGL_CPU0_SCL @T6G_MB_LIB.T6G(SCH_1):I3C_SPD_DDRGL_CPU0_SCL   I243 @T6G_MB_LIB.T6G(SCH_1):PAGE92
     2 I3C_SPD_DDRH_CPU0_SCL @T6G_MB_LIB.T6G(SCH_1):I3C_SPD_DDRH_CPU0_SCL   I243 @T6G_MB_LIB.T6G(SCH_1):PAGE92

R1576 Q_RES_0402LF-49.9,1%,1/16W,CHIP,CS04992FB07
     1 I3C_SPD_DDRGL_CPU0_SCL @T6G_MB_LIB.T6G(SCH_1):I3C_SPD_DDRGL_CPU0_SCL   I242 @T6G_MB_LIB.T6G(SCH_1):PAGE93
     2 I3C_SPD_DDRI_CPU0_SCL @T6G_MB_LIB.T6G(SCH_1):I3C_SPD_DDRI_CPU0_SCL   I242 @T6G_MB_LIB.T6G(SCH_1):PAGE93

R1577 Q_RES_0402LF-49.9,1%,1/16W,CHIP,CS04992FB07
     1 I3C_SPD_DDRGL_CPU0_SCL @T6G_MB_LIB.T6G(SCH_1):I3C_SPD_DDRGL_CPU0_SCL   I242 @T6G_MB_LIB.T6G(SCH_1):PAGE94
     2 I3C_SPD_DDRJ_CPU0_SCL @T6G_MB_LIB.T6G(SCH_1):I3C_SPD_DDRJ_CPU0_SCL   I242 @T6G_MB_LIB.T6G(SCH_1):PAGE94

R1578 Q_RES_0402LF-49.9,1%,1/16W,CHIP,CS04992FB07
     1 I3C_SPD_DDRGL_CPU0_SCL @T6G_MB_LIB.T6G(SCH_1):I3C_SPD_DDRGL_CPU0_SCL   I242 @T6G_MB_LIB.T6G(SCH_1):PAGE95
     2 I3C_SPD_DDRK_CPU0_SCL @T6G_MB_LIB.T6G(SCH_1):I3C_SPD_DDRK_CPU0_SCL   I242 @T6G_MB_LIB.T6G(SCH_1):PAGE95

R1579 Q_RES_0402LF-49.9,1%,1/16W,CHIP,CS04992FB07
     1 I3C_SPD_DDRGL_CPU0_SCL @T6G_MB_LIB.T6G(SCH_1):I3C_SPD_DDRGL_CPU0_SCL   I242 @T6G_MB_LIB.T6G(SCH_1):PAGE96
     2 I3C_SPD_DDRL_CPU0_SCL @T6G_MB_LIB.T6G(SCH_1):I3C_SPD_DDRL_CPU0_SCL   I242 @T6G_MB_LIB.T6G(SCH_1):PAGE96

R1580 Q_RES_0402LF-49.9,1%,1/16W,CHIP,CS04992FB07
     1 I3C_SPD_DDRAF_CPU1_SCL @T6G_MB_LIB.T6G(SCH_1):I3C_SPD_DDRAF_CPU1_SCL   I244 @T6G_MB_LIB.T6G(SCH_1):PAGE97
     2 I3C_SPD_DDRA_CPU1_SCL @T6G_MB_LIB.T6G(SCH_1):I3C_SPD_DDRA_CPU1_SCL   I244 @T6G_MB_LIB.T6G(SCH_1):PAGE97

R1581 Q_RES_0402LF-49.9,1%,1/16W,CHIP,CS04992FB07
     1 I3C_SPD_DDRAF_CPU1_SCL @T6G_MB_LIB.T6G(SCH_1):I3C_SPD_DDRAF_CPU1_SCL   I242 @T6G_MB_LIB.T6G(SCH_1):PAGE98
     2 I3C_SPD_DDRB_CPU1_SCL @T6G_MB_LIB.T6G(SCH_1):I3C_SPD_DDRB_CPU1_SCL   I242 @T6G_MB_LIB.T6G(SCH_1):PAGE98

R1582 Q_RES_0402LF-49.9,1%,1/16W,CHIP,CS04992FB07
     1 I3C_SPD_DDRAF_CPU1_SCL @T6G_MB_LIB.T6G(SCH_1):I3C_SPD_DDRAF_CPU1_SCL   I242 @T6G_MB_LIB.T6G(SCH_1):PAGE99
     2 I3C_SPD_DDRC_CPU1_SCL @T6G_MB_LIB.T6G(SCH_1):I3C_SPD_DDRC_CPU1_SCL   I242 @T6G_MB_LIB.T6G(SCH_1):PAGE99

R1583 Q_RES_0402LF-49.9,1%,1/16W,CHIP,CS04992FB07
     1 I3C_SPD_DDRAF_CPU1_SCL @T6G_MB_LIB.T6G(SCH_1):I3C_SPD_DDRAF_CPU1_SCL   I242 @T6G_MB_LIB.T6G(SCH_1):PAGE100
     2 I3C_SPD_DDRD_CPU1_SCL @T6G_MB_LIB.T6G(SCH_1):I3C_SPD_DDRD_CPU1_SCL   I242 @T6G_MB_LIB.T6G(SCH_1):PAGE100

R1584 Q_RES_0402LF-49.9,1%,1/16W,CHIP,CS04992FB07
     1 I3C_SPD_DDRAF_CPU1_SCL @T6G_MB_LIB.T6G(SCH_1):I3C_SPD_DDRAF_CPU1_SCL   I242 @T6G_MB_LIB.T6G(SCH_1):PAGE101
     2 I3C_SPD_DDRE_CPU1_SCL @T6G_MB_LIB.T6G(SCH_1):I3C_SPD_DDRE_CPU1_SCL   I242 @T6G_MB_LIB.T6G(SCH_1):PAGE101

R1585 Q_RES_0402LF-49.9,1%,1/16W,CHIP,CS04992FB07
     1 I3C_SPD_DDRAF_CPU1_SCL @T6G_MB_LIB.T6G(SCH_1):I3C_SPD_DDRAF_CPU1_SCL   I242 @T6G_MB_LIB.T6G(SCH_1):PAGE102
     2 I3C_SPD_DDRF_CPU1_SCL @T6G_MB_LIB.T6G(SCH_1):I3C_SPD_DDRF_CPU1_SCL   I242 @T6G_MB_LIB.T6G(SCH_1):PAGE102

R1586 Q_RES_0402LF-49.9,1%,1/16W,CHIP,CS04992FB07
     1 I3C_SPD_DDRGL_CPU1_SCL @T6G_MB_LIB.T6G(SCH_1):I3C_SPD_DDRGL_CPU1_SCL   I244 @T6G_MB_LIB.T6G(SCH_1):PAGE103
     2 I3C_SPD_DDRG_CPU1_SCL @T6G_MB_LIB.T6G(SCH_1):I3C_SPD_DDRG_CPU1_SCL   I244 @T6G_MB_LIB.T6G(SCH_1):PAGE103

R1587 Q_RES_0402LF-49.9,1%,1/16W,CHIP,CS04992FB07
     1 I3C_SPD_DDRGL_CPU1_SCL @T6G_MB_LIB.T6G(SCH_1):I3C_SPD_DDRGL_CPU1_SCL   I244 @T6G_MB_LIB.T6G(SCH_1):PAGE104
     2 I3C_SPD_DDRH_CPU1_SCL @T6G_MB_LIB.T6G(SCH_1):I3C_SPD_DDRH_CPU1_SCL   I244 @T6G_MB_LIB.T6G(SCH_1):PAGE104

R1588 Q_RES_0402LF-49.9,1%,1/16W,CHIP,CS04992FB07
     1 I3C_SPD_DDRGL_CPU1_SCL @T6G_MB_LIB.T6G(SCH_1):I3C_SPD_DDRGL_CPU1_SCL   I242 @T6G_MB_LIB.T6G(SCH_1):PAGE105
     2 I3C_SPD_DDRI_CPU1_SCL @T6G_MB_LIB.T6G(SCH_1):I3C_SPD_DDRI_CPU1_SCL   I242 @T6G_MB_LIB.T6G(SCH_1):PAGE105

R1589 Q_RES_0402LF-49.9,1%,1/16W,CHIP,CS04992FB07
     1 I3C_SPD_DDRGL_CPU1_SCL @T6G_MB_LIB.T6G(SCH_1):I3C_SPD_DDRGL_CPU1_SCL   I242 @T6G_MB_LIB.T6G(SCH_1):PAGE106
     2 I3C_SPD_DDRJ_CPU1_SCL @T6G_MB_LIB.T6G(SCH_1):I3C_SPD_DDRJ_CPU1_SCL   I242 @T6G_MB_LIB.T6G(SCH_1):PAGE106

R1590 Q_RES_0402LF-49.9,1%,1/16W,CHIP,CS04992FB07
     1 I3C_SPD_DDRGL_CPU1_SCL @T6G_MB_LIB.T6G(SCH_1):I3C_SPD_DDRGL_CPU1_SCL   I241 @T6G_MB_LIB.T6G(SCH_1):PAGE107
     2 I3C_SPD_DDRK_CPU1_SCL @T6G_MB_LIB.T6G(SCH_1):I3C_SPD_DDRK_CPU1_SCL   I241 @T6G_MB_LIB.T6G(SCH_1):PAGE107

R1591 Q_RES_0402LF-49.9,1%,1/16W,CHIP,CS04992FB07
     1 I3C_SPD_DDRGL_CPU1_SCL @T6G_MB_LIB.T6G(SCH_1):I3C_SPD_DDRGL_CPU1_SCL   I241 @T6G_MB_LIB.T6G(SCH_1):PAGE108
     2 I3C_SPD_DDRL_CPU1_SCL @T6G_MB_LIB.T6G(SCH_1):I3C_SPD_DDRL_CPU1_SCL   I241 @T6G_MB_LIB.T6G(SCH_1):PAGE108

R1592 Q_RES_0402LF-33,5%,1/16W,CHIP,CS03302JB10
     1 ESPI_CPU0_CS1_N @T6G_MB_LIB.T6G(SCH_1):ESPI_CPU0_CS1_N   I426 @T6G_MB_LIB.T6G(SCH_1):PAGE29
     2 CPU0_ESPI_CS0_N @T6G_MB_LIB.T6G(SCH_1):CPU0_ESPI_CS0_N   I426 @T6G_MB_LIB.T6G(SCH_1):PAGE29

R1593 Q_RES_0402LF-33,5%,1/16W,CHIP,CS03302JB10
     1 ESPI_CPU0_ALERT_P0_N @T6G_MB_LIB.T6G(SCH_1):ESPI_CPU0_ALERT_P0_N   I427 @T6G_MB_LIB.T6G(SCH_1):PAGE29
     2 CPU0_ESPI0_ALERT_N @T6G_MB_LIB.T6G(SCH_1):CPU0_ESPI0_ALERT_N   I427 @T6G_MB_LIB.T6G(SCH_1):PAGE29

R1594 Q_RES_0402LF-33.2,1%,1/16W,CHIP,CS03322FB03
     1 OCP_SFF_WAKE_BUFF_N @T6G_MB_LIB.T6G(SCH_1):OCP_SFF_WAKE_BUFF_N    I31 @T6G_MB_LIB.T6G(SCH_1):PAGE337
     2 OCP_SFF_WAKE_BUFF_R_N @T6G_MB_LIB.T6G(SCH_1):OCP_SFF_WAKE_BUFF_R_N    I31 @T6G_MB_LIB.T6G(SCH_1):PAGE337

R1595 Q_RES_0402LF-33.2,1%,1/16W,CHIP,CS03322FB03
     1 OCP_SFF_PWRBRK_BUFF_N @T6G_MB_LIB.T6G(SCH_1):OCP_SFF_PWRBRK_BUFF_N    I44 @T6G_MB_LIB.T6G(SCH_1):PAGE337
     2 OCP_SFF_PWRBRK_N @T6G_MB_LIB.T6G(SCH_1):OCP_SFF_PWRBRK_N    I44 @T6G_MB_LIB.T6G(SCH_1):PAGE337

R1605 Q_RES_0402LF-1K,1%,1/16W,CHIP,CS21002FB06
     1 PD_M2_0_DEVSLP @T6G_MB_LIB.T6G(SCH_1):PD_M2_0_DEVSLP    I83 @T6G_MB_LIB.T6G(SCH_1):PAGE345
     2    GND @T6G_MB_LIB.T6G(SCH_1):GND    I83 @T6G_MB_LIB.T6G(SCH_1):PAGE345

R1616 Q_RES_0402LF-33,5%,1/16W,CHIP,CS03302JB10
     1 FM_ROM_SD_LS_OE @T6G_MB_LIB.T6G(SCH_1):FM_ROM_SD_LS_OE   I157 @T6G_MB_LIB.T6G(SCH_1):PAGE80
     2 ROM_SD_LS_OE @T6G_MB_LIB.T6G(SCH_1):ROM_SD_LS_OE   I157 @T6G_MB_LIB.T6G(SCH_1):PAGE80

R1619 Q_RES_0402LF-0,5%,1/16W,CHIP,CS00002JB13
     1 JTAG_BMC_OE @T6G_MB_LIB.T6G(SCH_1):JTAG_BMC_OE    I92 @T6G_MB_LIB.T6G(SCH_1):PAGE149
     2 JTAG_BMC_R_D_OE @T6G_MB_LIB.T6G(SCH_1):JTAG_BMC_R_D_OE    I92 @T6G_MB_LIB.T6G(SCH_1):PAGE149

R1620 Q_RES_0402LF-33,5%,1/16W,CHIP,CS03302JB10
     1 HDT_HDR_TRST_N @T6G_MB_LIB.T6G(SCH_1):HDT_HDR_TRST_N   I149 @T6G_MB_LIB.T6G(SCH_1):PAGE149
     2 HDT_HDR_TRST_N_R @T6G_MB_LIB.T6G(SCH_1):HDT_HDR_TRST_N_R   I149 @T6G_MB_LIB.T6G(SCH_1):PAGE149

R1621 Q_RES_0402LF-1K,1%,1/16W,CHIP,CS21002FB06
     1 PVDD18_S5_P0 @T6G_MB_LIB.T6G(SCH_1):PVDD18_S5_P0   I146 @T6G_MB_LIB.T6G(SCH_1):PAGE149
     2 HDT_HDR_TRST_N_R @T6G_MB_LIB.T6G(SCH_1):HDT_HDR_TRST_N_R   I146 @T6G_MB_LIB.T6G(SCH_1):PAGE149

R1622 Q_RES_0402LF-4.7K,5%,1/16W,CHIP,CS24702JB10
     1 P3V3_AUX @T6G_MB_LIB.T6G(SCH_1):P3V3_AUX    I83 @T6G_MB_LIB.T6G(SCH_1):PAGE149
     2 JTAG_BMC_OE_N @T6G_MB_LIB.T6G(SCH_1):JTAG_BMC_OE_N    I83 @T6G_MB_LIB.T6G(SCH_1):PAGE149

R1624 Q_RES_0402LF-1K,1%,1/16W,CHIP,CS21002FB06
     1 PVDD18_S5_P0 @T6G_MB_LIB.T6G(SCH_1):PVDD18_S5_P0   I111 @T6G_MB_LIB.T6G(SCH_1):PAGE149
     2 HDT_HDR_TCK @T6G_MB_LIB.T6G(SCH_1):HDT_HDR_TCK   I111 @T6G_MB_LIB.T6G(SCH_1):PAGE149

R1625 Q_RES_0402LF-0,5%,1/16W,CHIP,CS00002JB13
     1 JTAG_TDI_R @T6G_MB_LIB.T6G(SCH_1):JTAG_TDI_R    I53 @T6G_MB_LIB.T6G(SCH_1):PAGE149
     2 JTAG_TDI @T6G_MB_LIB.T6G(SCH_1):JTAG_TDI    I53 @T6G_MB_LIB.T6G(SCH_1):PAGE149

R1626 Q_RES_0402LF-1K,1%,1/16W,CHIP,CS21002FB06
     1 PVDD18_S5_P0 @T6G_MB_LIB.T6G(SCH_1):PVDD18_S5_P0   I115 @T6G_MB_LIB.T6G(SCH_1):PAGE149
     2 HDT_HDR_TMS @T6G_MB_LIB.T6G(SCH_1):HDT_HDR_TMS   I115 @T6G_MB_LIB.T6G(SCH_1):PAGE149

R1627 Q_RES_0402LF-1K,1%,1/16W,CHIP,CS21002FB06
     1 PVDD18_S5_P0 @T6G_MB_LIB.T6G(SCH_1):PVDD18_S5_P0   I116 @T6G_MB_LIB.T6G(SCH_1):PAGE149
     2 HDT_HDR_TDI @T6G_MB_LIB.T6G(SCH_1):HDT_HDR_TDI   I116 @T6G_MB_LIB.T6G(SCH_1):PAGE149

R1628 Q_RES_0402LF-1K,1%,1/16W,CHIP,CS21002FB06
     1 PVDD18_S5_P0 @T6G_MB_LIB.T6G(SCH_1):PVDD18_S5_P0   I117 @T6G_MB_LIB.T6G(SCH_1):PAGE149
     2 HDT_HDR_TDO @T6G_MB_LIB.T6G(SCH_1):HDT_HDR_TDO   I117 @T6G_MB_LIB.T6G(SCH_1):PAGE149

R1629 Q_RES_0402LF-1K,1%,1/16W,CHIP,CS21002FB06
     1 HDT_CPU0_HDT_CONN_TESTEN @T6G_MB_LIB.T6G(SCH_1):HDT_CPU0_HDT_CONN_TESTEN   I112 @T6G_MB_LIB.T6G(SCH_1):PAGE149
     2    GND @T6G_MB_LIB.T6G(SCH_1):GND   I112 @T6G_MB_LIB.T6G(SCH_1):PAGE149

R1630 Q_RES_0402LF-1K,1%,1/16W,CHIP,CS21002FB06
     1 PVDD18_S5_P0 @T6G_MB_LIB.T6G(SCH_1):PVDD18_S5_P0   I118 @T6G_MB_LIB.T6G(SCH_1):PAGE149
     2 HDT_HDR_DBREQ_R_N @T6G_MB_LIB.T6G(SCH_1):HDT_HDR_DBREQ_R_N   I118 @T6G_MB_LIB.T6G(SCH_1):PAGE149

R1631 Q_RES_0402LF-33,5%,1/16W,CHIP,CS03302JB10
     1 HDT_HDR_DBREQ_R_N @T6G_MB_LIB.T6G(SCH_1):HDT_HDR_DBREQ_R_N   I113 @T6G_MB_LIB.T6G(SCH_1):PAGE149
     2 HDT_HDR_DBREQ_N @T6G_MB_LIB.T6G(SCH_1):HDT_HDR_DBREQ_N   I113 @T6G_MB_LIB.T6G(SCH_1):PAGE149

R1632 Q_RES_0402LF-33,5%,1/16W,CHIP,CS03302JB10
     1 HDT_CPU0_HDT_CONN_TESTEN @T6G_MB_LIB.T6G(SCH_1):HDT_CPU0_HDT_CONN_TESTEN   I114 @T6G_MB_LIB.T6G(SCH_1):PAGE149
     2 CPU0_HDT_CONN_TESTEN @T6G_MB_LIB.T6G(SCH_1):CPU0_HDT_CONN_TESTEN   I114 @T6G_MB_LIB.T6G(SCH_1):PAGE149

R1633 Q_RES_0402LF-0,5%,1/16W,CHIP,CS00002JB13
     1 JTAG_TCK_R @T6G_MB_LIB.T6G(SCH_1):JTAG_TCK_R     I7 @T6G_MB_LIB.T6G(SCH_1):PAGE149
     2 JTAG_TCK @T6G_MB_LIB.T6G(SCH_1):JTAG_TCK     I7 @T6G_MB_LIB.T6G(SCH_1):PAGE149

R1634 Q_RES_0402LF-0,5%,1/16W,CHIP,CS00002JB13
     1 JTAG_TMS_R @T6G_MB_LIB.T6G(SCH_1):JTAG_TMS_R    I96 @T6G_MB_LIB.T6G(SCH_1):PAGE149
     2 JTAG_TMS @T6G_MB_LIB.T6G(SCH_1):JTAG_TMS    I96 @T6G_MB_LIB.T6G(SCH_1):PAGE149

R1635 Q_RES_0402LF-22,1%,1/16W,CHIP,CS02202FB02
     1 JTAG_TRST_R_N @T6G_MB_LIB.T6G(SCH_1):JTAG_TRST_R_N     I8 @T6G_MB_LIB.T6G(SCH_1):PAGE149
     2 JTAG_TRST_N @T6G_MB_LIB.T6G(SCH_1):JTAG_TRST_N     I8 @T6G_MB_LIB.T6G(SCH_1):PAGE149

R1636 Q_RES_0402LF-22,1%,1/16W,CHIP,CS02202FB02
     1 JTAG_DBREQ_R_N @T6G_MB_LIB.T6G(SCH_1):JTAG_DBREQ_R_N     I9 @T6G_MB_LIB.T6G(SCH_1):PAGE149
     2 JTAG_DBREQ_N @T6G_MB_LIB.T6G(SCH_1):JTAG_DBREQ_N     I9 @T6G_MB_LIB.T6G(SCH_1):PAGE149

R1637 Q_RES_0402LF-4.7K,5%,1/16W,CHIP,CS24702JB10
     1 U152_OE_N @T6G_MB_LIB.T6G(SCH_1):U152_OE_N    I71 @T6G_MB_LIB.T6G(SCH_1):PAGE150
     2    GND @T6G_MB_LIB.T6G(SCH_1):GND    I71 @T6G_MB_LIB.T6G(SCH_1):PAGE150

R1638 Q_RES_0402LF-22,1%,1/16W,CHIP,CS02202FB02
     1 JTAG_P0_R_TCK @T6G_MB_LIB.T6G(SCH_1):JTAG_P0_R_TCK    I27 @T6G_MB_LIB.T6G(SCH_1):PAGE150
     2 JTAG_CPU0_TCK @T6G_MB_LIB.T6G(SCH_1):JTAG_CPU0_TCK    I27 @T6G_MB_LIB.T6G(SCH_1):PAGE150

R1639 Q_RES_0402LF-22,1%,1/16W,CHIP,CS02202FB02
     1 JTAG_P0_R_TMS @T6G_MB_LIB.T6G(SCH_1):JTAG_P0_R_TMS    I25 @T6G_MB_LIB.T6G(SCH_1):PAGE150
     2 JTAG_CPU0_TMS @T6G_MB_LIB.T6G(SCH_1):JTAG_CPU0_TMS    I25 @T6G_MB_LIB.T6G(SCH_1):PAGE150

R1640 Q_RES_0402LF-22,1%,1/16W,CHIP,CS02202FB02
     1 JTAG_P0_R_TRST_N @T6G_MB_LIB.T6G(SCH_1):JTAG_P0_R_TRST_N    I26 @T6G_MB_LIB.T6G(SCH_1):PAGE150
     2 JTAG_CPU0_TRST_N @T6G_MB_LIB.T6G(SCH_1):JTAG_CPU0_TRST_N    I26 @T6G_MB_LIB.T6G(SCH_1):PAGE150

R1641 Q_RES_0402LF-22,1%,1/16W,CHIP,CS02202FB02
     1 JTAG_P0_R_DBREQ_N @T6G_MB_LIB.T6G(SCH_1):JTAG_P0_R_DBREQ_N    I24 @T6G_MB_LIB.T6G(SCH_1):PAGE150
     2 JTAG_CPU0_DBREQ_N @T6G_MB_LIB.T6G(SCH_1):JTAG_CPU0_DBREQ_N    I24 @T6G_MB_LIB.T6G(SCH_1):PAGE150

R1642 Q_RES_0402LF-22,1%,1/16W,CHIP,CS02202FB02
     1 JTAG_P1_R_TCK @T6G_MB_LIB.T6G(SCH_1):JTAG_P1_R_TCK    I33 @T6G_MB_LIB.T6G(SCH_1):PAGE150
     2 JTAG_CPU1_TCK @T6G_MB_LIB.T6G(SCH_1):JTAG_CPU1_TCK    I33 @T6G_MB_LIB.T6G(SCH_1):PAGE150

R1643 Q_RES_0402LF-22,1%,1/16W,CHIP,CS02202FB02
     1 JTAG_P1_R_TMS @T6G_MB_LIB.T6G(SCH_1):JTAG_P1_R_TMS    I34 @T6G_MB_LIB.T6G(SCH_1):PAGE150
     2 JTAG_CPU1_TMS @T6G_MB_LIB.T6G(SCH_1):JTAG_CPU1_TMS    I34 @T6G_MB_LIB.T6G(SCH_1):PAGE150

R1644 Q_RES_0402LF-22,1%,1/16W,CHIP,CS02202FB02
     1 JTAG_P1_R_TRST_N @T6G_MB_LIB.T6G(SCH_1):JTAG_P1_R_TRST_N    I35 @T6G_MB_LIB.T6G(SCH_1):PAGE150
     2 JTAG_CPU1_TRST_N @T6G_MB_LIB.T6G(SCH_1):JTAG_CPU1_TRST_N    I35 @T6G_MB_LIB.T6G(SCH_1):PAGE150

R1645 Q_RES_0402LF-22,1%,1/16W,CHIP,CS02202FB02
     1 JTAG_P1_R_DBREQ_N @T6G_MB_LIB.T6G(SCH_1):JTAG_P1_R_DBREQ_N    I36 @T6G_MB_LIB.T6G(SCH_1):PAGE150
     2 JTAG_CPU1_DBREQ_N @T6G_MB_LIB.T6G(SCH_1):JTAG_CPU1_DBREQ_N    I36 @T6G_MB_LIB.T6G(SCH_1):PAGE150

R1646 Q_RES_0402LF-1K,1%,1/16W,CHIP,CS21002FB06
     1 PVDD18_S5_P0 @T6G_MB_LIB.T6G(SCH_1):PVDD18_S5_P0    I10 @T6G_MB_LIB.T6G(SCH_1):PAGE151
     2 CPU0_HDT_BYPASS_SEL @T6G_MB_LIB.T6G(SCH_1):CPU0_HDT_BYPASS_SEL    I10 @T6G_MB_LIB.T6G(SCH_1):PAGE151

R1647 Q_RES_0402LF-1K,1%,1/16W,CHIP,CS21002FB06
     1 PVDD18_S5_P0 @T6G_MB_LIB.T6G(SCH_1):PVDD18_S5_P0    I11 @T6G_MB_LIB.T6G(SCH_1):PAGE151
     2 FM_PLD_CPU0_PRSNT_HDT_N @T6G_MB_LIB.T6G(SCH_1):FM_PLD_CPU0_PRSNT_HDT_N    I11 @T6G_MB_LIB.T6G(SCH_1):PAGE151

R1648 Q_RES_0402LF-0,5%,1/16W,CHIP,CS00002JB13
     1 JTAG_CPU0_R_TDI @T6G_MB_LIB.T6G(SCH_1):JTAG_CPU0_R_TDI     I2 @T6G_MB_LIB.T6G(SCH_1):PAGE151
     2 JTAG_CPU0_TDI @T6G_MB_LIB.T6G(SCH_1):JTAG_CPU0_TDI     I2 @T6G_MB_LIB.T6G(SCH_1):PAGE151

R1649 Q_RES_0402LF-1K,1%,1/16W,CHIP,CS21002FB06
     1 PVDD18_S5_P0 @T6G_MB_LIB.T6G(SCH_1):PVDD18_S5_P0    I25 @T6G_MB_LIB.T6G(SCH_1):PAGE151
     2 CPU1_HDT_BYPASS_SEL @T6G_MB_LIB.T6G(SCH_1):CPU1_HDT_BYPASS_SEL    I25 @T6G_MB_LIB.T6G(SCH_1):PAGE151

R1650 Q_RES_0402LF-1K,1%,1/16W,CHIP,CS21002FB06
     1 PVDD18_S5_P0 @T6G_MB_LIB.T6G(SCH_1):PVDD18_S5_P0    I27 @T6G_MB_LIB.T6G(SCH_1):PAGE151
     2 FM_PLD_CPU1_PRSNT_HDT_N @T6G_MB_LIB.T6G(SCH_1):FM_PLD_CPU1_PRSNT_HDT_N    I27 @T6G_MB_LIB.T6G(SCH_1):PAGE151

R1651 Q_RES_0402LF-0,5%,1/16W,CHIP,CS00002JB13
     1 JTAG_CPU1_R_TDI @T6G_MB_LIB.T6G(SCH_1):JTAG_CPU1_R_TDI    I34 @T6G_MB_LIB.T6G(SCH_1):PAGE151
     2 JTAG_CPU1_TDI @T6G_MB_LIB.T6G(SCH_1):JTAG_CPU1_TDI    I34 @T6G_MB_LIB.T6G(SCH_1):PAGE151

R1654 Q_RES_0402LF-1K,1%,1/16W,CHIP,CS21002FB06
     1 VR_P5V_EN_D_R @T6G_MB_LIB.T6G(SCH_1):VR_P5V_EN_D_R    I22 @T6G_MB_LIB.T6G(SCH_1):PAGE273
     2 VR_P5V_EN_D_R1 @T6G_MB_LIB.T6G(SCH_1):VR_P5V_EN_D_R1    I22 @T6G_MB_LIB.T6G(SCH_1):PAGE273

R1655 Q_RES_0402LF-1K,1%,1/16W,EMPTY,CS21002FB06
     1 P3V3_AUX @T6G_MB_LIB.T6G(SCH_1):P3V3_AUX   I191 @T6G_MB_LIB.T6G(SCH_1):PAGE76
     2 SPI_CPU0_LVC3_SCM_CS1_N @T6G_MB_LIB.T6G(SCH_1):SPI_CPU0_LVC3_SCM_CS1_N   I191 @T6G_MB_LIB.T6G(SCH_1):PAGE76

R1658 Q_RES_0402LF-4.7K,5%,1/16W,CHIP,CS24702JB10
     1 SCM_JTAG_MUX_S0 @T6G_MB_LIB.T6G(SCH_1):SCM_JTAG_MUX_S0   I310 @T6G_MB_LIB.T6G(SCH_1):PAGE148
     2    GND @T6G_MB_LIB.T6G(SCH_1):GND   I310 @T6G_MB_LIB.T6G(SCH_1):PAGE148

R1659 Q_RES_0402LF-4.7K,5%,1/16W,EMPTY,CS24702JB10
     1 P3V3_AUX @T6G_MB_LIB.T6G(SCH_1):P3V3_AUX   I309 @T6G_MB_LIB.T6G(SCH_1):PAGE148
     2 SCM_JTAG_MUX_S0 @T6G_MB_LIB.T6G(SCH_1):SCM_JTAG_MUX_S0   I309 @T6G_MB_LIB.T6G(SCH_1):PAGE148

R1671 Q_RES_0402LF-0,5%,1/16W,CHIP,CS00002JB13
     1 OCP_SFF_AUX_PWR_EN @T6G_MB_LIB.T6G(SCH_1):OCP_SFF_AUX_PWR_EN    I54 @T6G_MB_LIB.T6G(SCH_1):PAGE335
     2 OCP_SFF_AUX_PWR_EN_R @T6G_MB_LIB.T6G(SCH_1):OCP_SFF_AUX_PWR_EN_R    I54 @T6G_MB_LIB.T6G(SCH_1):PAGE335

R1673 Q_RES_0402LF-10K,1%,1/16W,CHIP,CS31002FB08
     1 P3V3_E1S_0 @T6G_MB_LIB.T6G(SCH_1):P3V3_E1S_0   I105 @T6G_MB_LIB.T6G(SCH_1):PAGE297
     2 RST_SMB_E1S_0_N @T6G_MB_LIB.T6G(SCH_1):RST_SMB_E1S_0_N   I105 @T6G_MB_LIB.T6G(SCH_1):PAGE297

R1674 Q_RES_0402LF-10,1%,1/16W,CHIP,CS01002FB07
     1 I3C_SPD_DDRAF_CPU0_SDA @T6G_MB_LIB.T6G(SCH_1):I3C_SPD_DDRAF_CPU0_SDA   I554 @T6G_MB_LIB.T6G(SCH_1):PAGE85
     2 I3C_SPD_DDRA_CPU0_SDA @T6G_MB_LIB.T6G(SCH_1):I3C_SPD_DDRA_CPU0_SDA   I554 @T6G_MB_LIB.T6G(SCH_1):PAGE85

R1675 Q_RES_0402LF-10,1%,1/16W,CHIP,CS01002FB07
     1 I3C_SPD_DDRAF_CPU0_SDA @T6G_MB_LIB.T6G(SCH_1):I3C_SPD_DDRAF_CPU0_SDA   I373 @T6G_MB_LIB.T6G(SCH_1):PAGE86
     2 I3C_SPD_DDRB_CPU0_SDA @T6G_MB_LIB.T6G(SCH_1):I3C_SPD_DDRB_CPU0_SDA   I373 @T6G_MB_LIB.T6G(SCH_1):PAGE86

R1676 Q_RES_0402LF-10,1%,1/16W,CHIP,CS01002FB07
     1 I3C_SPD_DDRAF_CPU0_SDA @T6G_MB_LIB.T6G(SCH_1):I3C_SPD_DDRAF_CPU0_SDA   I422 @T6G_MB_LIB.T6G(SCH_1):PAGE88
     2 I3C_SPD_DDRD_CPU0_SDA @T6G_MB_LIB.T6G(SCH_1):I3C_SPD_DDRD_CPU0_SDA   I422 @T6G_MB_LIB.T6G(SCH_1):PAGE88

R1677 Q_RES_0402LF-10,1%,1/16W,CHIP,CS01002FB07
     1 I3C_SPD_DDRAF_CPU0_SDA @T6G_MB_LIB.T6G(SCH_1):I3C_SPD_DDRAF_CPU0_SDA   I418 @T6G_MB_LIB.T6G(SCH_1):PAGE87
     2 I3C_SPD_DDRC_CPU0_SDA @T6G_MB_LIB.T6G(SCH_1):I3C_SPD_DDRC_CPU0_SDA   I418 @T6G_MB_LIB.T6G(SCH_1):PAGE87

R1678 Q_RES_0402LF-10,1%,1/16W,CHIP,CS01002FB07
     1 I3C_SPD_DDRAF_CPU0_SDA @T6G_MB_LIB.T6G(SCH_1):I3C_SPD_DDRAF_CPU0_SDA   I418 @T6G_MB_LIB.T6G(SCH_1):PAGE89
     2 I3C_SPD_DDRE_CPU0_SDA @T6G_MB_LIB.T6G(SCH_1):I3C_SPD_DDRE_CPU0_SDA   I418 @T6G_MB_LIB.T6G(SCH_1):PAGE89

R1679 Q_RES_0402LF-10,1%,1/16W,CHIP,CS01002FB07
     1 I3C_SPD_DDRAF_CPU0_SDA @T6G_MB_LIB.T6G(SCH_1):I3C_SPD_DDRAF_CPU0_SDA   I419 @T6G_MB_LIB.T6G(SCH_1):PAGE90
     2 I3C_SPD_DDRF_CPU0_SDA @T6G_MB_LIB.T6G(SCH_1):I3C_SPD_DDRF_CPU0_SDA   I419 @T6G_MB_LIB.T6G(SCH_1):PAGE90

R1680 Q_RES_0402LF-10,1%,1/16W,CHIP,CS01002FB07
     1 I3C_SPD_DDRGL_CPU0_SDA @T6G_MB_LIB.T6G(SCH_1):I3C_SPD_DDRGL_CPU0_SDA   I254 @T6G_MB_LIB.T6G(SCH_1):PAGE91
     2 I3C_SPD_DDRG_CPU0_SDA @T6G_MB_LIB.T6G(SCH_1):I3C_SPD_DDRG_CPU0_SDA   I254 @T6G_MB_LIB.T6G(SCH_1):PAGE91

R1681 Q_RES_0402LF-10,1%,1/16W,CHIP,CS01002FB07
     1 I3C_SPD_DDRGL_CPU0_SDA @T6G_MB_LIB.T6G(SCH_1):I3C_SPD_DDRGL_CPU0_SDA   I244 @T6G_MB_LIB.T6G(SCH_1):PAGE92
     2 I3C_SPD_DDRH_CPU0_SDA @T6G_MB_LIB.T6G(SCH_1):I3C_SPD_DDRH_CPU0_SDA   I244 @T6G_MB_LIB.T6G(SCH_1):PAGE92

R1683 Q_RES_0402LF-10,1%,1/16W,CHIP,CS01002FB07
     1 I3C_SPD_DDRGL_CPU0_SDA @T6G_MB_LIB.T6G(SCH_1):I3C_SPD_DDRGL_CPU0_SDA   I243 @T6G_MB_LIB.T6G(SCH_1):PAGE93
     2 I3C_SPD_DDRI_CPU0_SDA @T6G_MB_LIB.T6G(SCH_1):I3C_SPD_DDRI_CPU0_SDA   I243 @T6G_MB_LIB.T6G(SCH_1):PAGE93

R1684 Q_RES_0402LF-10,1%,1/16W,CHIP,CS01002FB07
     1 I3C_SPD_DDRGL_CPU0_SDA @T6G_MB_LIB.T6G(SCH_1):I3C_SPD_DDRGL_CPU0_SDA   I243 @T6G_MB_LIB.T6G(SCH_1):PAGE94
     2 I3C_SPD_DDRJ_CPU0_SDA @T6G_MB_LIB.T6G(SCH_1):I3C_SPD_DDRJ_CPU0_SDA   I243 @T6G_MB_LIB.T6G(SCH_1):PAGE94

R1685 Q_RES_0402LF-10,1%,1/16W,CHIP,CS01002FB07
     1 I3C_SPD_DDRGL_CPU0_SDA @T6G_MB_LIB.T6G(SCH_1):I3C_SPD_DDRGL_CPU0_SDA   I243 @T6G_MB_LIB.T6G(SCH_1):PAGE95
     2 I3C_SPD_DDRK_CPU0_SDA @T6G_MB_LIB.T6G(SCH_1):I3C_SPD_DDRK_CPU0_SDA   I243 @T6G_MB_LIB.T6G(SCH_1):PAGE95

R1686 Q_RES_0402LF-10,1%,1/16W,CHIP,CS01002FB07
     1 I3C_SPD_DDRGL_CPU0_SDA @T6G_MB_LIB.T6G(SCH_1):I3C_SPD_DDRGL_CPU0_SDA   I243 @T6G_MB_LIB.T6G(SCH_1):PAGE96
     2 I3C_SPD_DDRL_CPU0_SDA @T6G_MB_LIB.T6G(SCH_1):I3C_SPD_DDRL_CPU0_SDA   I243 @T6G_MB_LIB.T6G(SCH_1):PAGE96

R1687 Q_RES_0402LF-10,1%,1/16W,CHIP,CS01002FB07
     1 I3C_SPD_DDRAF_CPU1_SDA @T6G_MB_LIB.T6G(SCH_1):I3C_SPD_DDRAF_CPU1_SDA   I256 @T6G_MB_LIB.T6G(SCH_1):PAGE97
     2 I3C_SPD_DDRA_CPU1_SDA @T6G_MB_LIB.T6G(SCH_1):I3C_SPD_DDRA_CPU1_SDA   I256 @T6G_MB_LIB.T6G(SCH_1):PAGE97

R1696 Q_RES_0402LF-10,1%,1/16W,CHIP,CS01002FB07
     1 I3C_SPD_DDRAF_CPU1_SDA @T6G_MB_LIB.T6G(SCH_1):I3C_SPD_DDRAF_CPU1_SDA   I243 @T6G_MB_LIB.T6G(SCH_1):PAGE98
     2 I3C_SPD_DDRB_CPU1_SDA @T6G_MB_LIB.T6G(SCH_1):I3C_SPD_DDRB_CPU1_SDA   I243 @T6G_MB_LIB.T6G(SCH_1):PAGE98

R1697 Q_RES_0402LF-10,1%,1/16W,CHIP,CS01002FB07
     1 I3C_SPD_DDRAF_CPU1_SDA @T6G_MB_LIB.T6G(SCH_1):I3C_SPD_DDRAF_CPU1_SDA   I243 @T6G_MB_LIB.T6G(SCH_1):PAGE99
     2 I3C_SPD_DDRC_CPU1_SDA @T6G_MB_LIB.T6G(SCH_1):I3C_SPD_DDRC_CPU1_SDA   I243 @T6G_MB_LIB.T6G(SCH_1):PAGE99

R1699 Q_RES_0402LF-10,1%,1/16W,CHIP,CS01002FB07
     1 I3C_SPD_DDRAF_CPU1_SDA @T6G_MB_LIB.T6G(SCH_1):I3C_SPD_DDRAF_CPU1_SDA   I243 @T6G_MB_LIB.T6G(SCH_1):PAGE100
     2 I3C_SPD_DDRD_CPU1_SDA @T6G_MB_LIB.T6G(SCH_1):I3C_SPD_DDRD_CPU1_SDA   I243 @T6G_MB_LIB.T6G(SCH_1):PAGE100

R1700 Q_RES_0402LF-200K,1%,1/16W,CHIP,CS42002FB05
     1 P3V3_AUX @T6G_MB_LIB.T6G(SCH_1):P3V3_AUX    I72 @T6G_MB_LIB.T6G(SCH_1):PAGE346
     2 SMB_PCIE_M2_0_EN @T6G_MB_LIB.T6G(SCH_1):SMB_PCIE_M2_0_EN    I72 @T6G_MB_LIB.T6G(SCH_1):PAGE346

R1701 Q_RES_0402LF-10,1%,1/16W,CHIP,CS01002FB07
     1 I3C_SPD_DDRAF_CPU1_SDA @T6G_MB_LIB.T6G(SCH_1):I3C_SPD_DDRAF_CPU1_SDA   I243 @T6G_MB_LIB.T6G(SCH_1):PAGE101
     2 I3C_SPD_DDRE_CPU1_SDA @T6G_MB_LIB.T6G(SCH_1):I3C_SPD_DDRE_CPU1_SDA   I243 @T6G_MB_LIB.T6G(SCH_1):PAGE101

R1702 Q_RES_0402LF-4.7K,5%,1/16W,CHIP,CS24702JB10
     1 P1V8_AUX @T6G_MB_LIB.T6G(SCH_1):P1V8_AUX    I43 @T6G_MB_LIB.T6G(SCH_1):PAGE346
     2 SMB_M2_P1_1V8AUX_SDA_R @T6G_MB_LIB.T6G(SCH_1):SMB_M2_P1_1V8AUX_SDA_R    I43 @T6G_MB_LIB.T6G(SCH_1):PAGE346

R1703 Q_RES_0402LF-4.7K,5%,1/16W,CHIP,CS24702JB10
     1 P1V8_AUX @T6G_MB_LIB.T6G(SCH_1):P1V8_AUX    I45 @T6G_MB_LIB.T6G(SCH_1):PAGE346
     2 SMB_M2_P1_1V8AUX_SCL_R @T6G_MB_LIB.T6G(SCH_1):SMB_M2_P1_1V8AUX_SCL_R    I45 @T6G_MB_LIB.T6G(SCH_1):PAGE346

R1704 Q_RES_0402LF-10,1%,1/16W,CHIP,CS01002FB07
     1 I3C_SPD_DDRAF_CPU1_SDA @T6G_MB_LIB.T6G(SCH_1):I3C_SPD_DDRAF_CPU1_SDA   I243 @T6G_MB_LIB.T6G(SCH_1):PAGE102
     2 I3C_SPD_DDRF_CPU1_SDA @T6G_MB_LIB.T6G(SCH_1):I3C_SPD_DDRF_CPU1_SDA   I243 @T6G_MB_LIB.T6G(SCH_1):PAGE102

R1705 Q_RES_0402LF-10,1%,1/16W,CHIP,CS01002FB07
     1 I3C_SPD_DDRGL_CPU1_SDA @T6G_MB_LIB.T6G(SCH_1):I3C_SPD_DDRGL_CPU1_SDA   I256 @T6G_MB_LIB.T6G(SCH_1):PAGE103
     2 I3C_SPD_DDRG_CPU1_SDA @T6G_MB_LIB.T6G(SCH_1):I3C_SPD_DDRG_CPU1_SDA   I256 @T6G_MB_LIB.T6G(SCH_1):PAGE103

R1707 Q_RES_0402LF-10,1%,1/16W,CHIP,CS01002FB07
     1 I3C_SPD_DDRGL_CPU1_SDA @T6G_MB_LIB.T6G(SCH_1):I3C_SPD_DDRGL_CPU1_SDA   I245 @T6G_MB_LIB.T6G(SCH_1):PAGE104
     2 I3C_SPD_DDRH_CPU1_SDA @T6G_MB_LIB.T6G(SCH_1):I3C_SPD_DDRH_CPU1_SDA   I245 @T6G_MB_LIB.T6G(SCH_1):PAGE104

R1708 Q_RES_0402LF-10,1%,1/16W,CHIP,CS01002FB07
     1 I3C_SPD_DDRGL_CPU1_SDA @T6G_MB_LIB.T6G(SCH_1):I3C_SPD_DDRGL_CPU1_SDA   I243 @T6G_MB_LIB.T6G(SCH_1):PAGE105
     2 I3C_SPD_DDRI_CPU1_SDA @T6G_MB_LIB.T6G(SCH_1):I3C_SPD_DDRI_CPU1_SDA   I243 @T6G_MB_LIB.T6G(SCH_1):PAGE105

R1709 Q_RES_0402LF-10,1%,1/16W,CHIP,CS01002FB07
     1 I3C_SPD_DDRGL_CPU1_SDA @T6G_MB_LIB.T6G(SCH_1):I3C_SPD_DDRGL_CPU1_SDA   I243 @T6G_MB_LIB.T6G(SCH_1):PAGE106
     2 I3C_SPD_DDRJ_CPU1_SDA @T6G_MB_LIB.T6G(SCH_1):I3C_SPD_DDRJ_CPU1_SDA   I243 @T6G_MB_LIB.T6G(SCH_1):PAGE106

R1710 Q_RES_0402LF-10,1%,1/16W,CHIP,CS01002FB07
     1 I3C_SPD_DDRGL_CPU1_SDA @T6G_MB_LIB.T6G(SCH_1):I3C_SPD_DDRGL_CPU1_SDA   I242 @T6G_MB_LIB.T6G(SCH_1):PAGE107
     2 I3C_SPD_DDRK_CPU1_SDA @T6G_MB_LIB.T6G(SCH_1):I3C_SPD_DDRK_CPU1_SDA   I242 @T6G_MB_LIB.T6G(SCH_1):PAGE107

R1711 Q_RES_0402LF-10,1%,1/16W,CHIP,CS01002FB07
     1 I3C_SPD_DDRGL_CPU1_SDA @T6G_MB_LIB.T6G(SCH_1):I3C_SPD_DDRGL_CPU1_SDA   I242 @T6G_MB_LIB.T6G(SCH_1):PAGE108
     2 I3C_SPD_DDRL_CPU1_SDA @T6G_MB_LIB.T6G(SCH_1):I3C_SPD_DDRL_CPU1_SDA   I242 @T6G_MB_LIB.T6G(SCH_1):PAGE108

R1714 Q_RES_0402LF-0,5%,1/16W,CHIP,CS00002JB13
     1 SMB_SML1_PMBUS_HSC_SDA @T6G_MB_LIB.T6G(SCH_1):SMB_SML1_PMBUS_HSC_SDA    I36 @T6G_MB_LIB.T6G(SCH_1):PAGE267
     2 SMB_SML1_PMBUS_HSC_R_SDA @T6G_MB_LIB.T6G(SCH_1):SMB_SML1_PMBUS_HSC_R_SDA    I36 @T6G_MB_LIB.T6G(SCH_1):PAGE267

R1719 Q_RES_0402LF-33.2,1%,1/16W,CHIP,CS03322FB03
     1 OCP_SFF_AUX_PWR_EN @T6G_MB_LIB.T6G(SCH_1):OCP_SFF_AUX_PWR_EN   I119 @T6G_MB_LIB.T6G(SCH_1):PAGE336
     2 OCP_SFF_AUX_PWR_EN_R1 @T6G_MB_LIB.T6G(SCH_1):OCP_SFF_AUX_PWR_EN_R1   I119 @T6G_MB_LIB.T6G(SCH_1):PAGE336

R1727 Q_RES_0402LF-10K,1%,1/16W,EMPTY,CS31002FB08
     1 P3V3_AUX @T6G_MB_LIB.T6G(SCH_1):P3V3_AUX   I250 @T6G_MB_LIB.T6G(SCH_1):PAGE148
     2 JTAG_SCM_TDO @T6G_MB_LIB.T6G(SCH_1):JTAG_SCM_TDO   I250 @T6G_MB_LIB.T6G(SCH_1):PAGE148

R1728 Q_RES_0402LF-10K,1%,1/16W,EMPTY,CS31002FB08
     1 P3V3_AUX @T6G_MB_LIB.T6G(SCH_1):P3V3_AUX   I249 @T6G_MB_LIB.T6G(SCH_1):PAGE148
     2 JTAG_SCM_TDI @T6G_MB_LIB.T6G(SCH_1):JTAG_SCM_TDI   I249 @T6G_MB_LIB.T6G(SCH_1):PAGE148

R1729 Q_RES_0402LF-4.7K,5%,1/16W,CHIP,CS24702JB10
     1 SCM_JTAG_MUX_S1 @T6G_MB_LIB.T6G(SCH_1):SCM_JTAG_MUX_S1   I306 @T6G_MB_LIB.T6G(SCH_1):PAGE148
     2    GND @T6G_MB_LIB.T6G(SCH_1):GND   I306 @T6G_MB_LIB.T6G(SCH_1):PAGE148

R1730 Q_RES_0402LF-4.7K,5%,1/16W,EMPTY,CS24702JB10
     1 P3V3_AUX @T6G_MB_LIB.T6G(SCH_1):P3V3_AUX   I305 @T6G_MB_LIB.T6G(SCH_1):PAGE148
     2 SCM_JTAG_MUX_S1 @T6G_MB_LIB.T6G(SCH_1):SCM_JTAG_MUX_S1   I305 @T6G_MB_LIB.T6G(SCH_1):PAGE148

R1731 Q_RES_0402LF-10K,1%,1/16W,EMPTY,CS31002FB08
     1 P3V3_AUX @T6G_MB_LIB.T6G(SCH_1):P3V3_AUX   I245 @T6G_MB_LIB.T6G(SCH_1):PAGE148
     2 JTAG_SCM_TMS @T6G_MB_LIB.T6G(SCH_1):JTAG_SCM_TMS   I245 @T6G_MB_LIB.T6G(SCH_1):PAGE148

R1734 Q_RES_0402LF-10K,1%,1/16W,CHIP,CS31002FB08
     1 P3V3_AUX @T6G_MB_LIB.T6G(SCH_1):P3V3_AUX   I244 @T6G_MB_LIB.T6G(SCH_1):PAGE148
     2 JTAG_SCM_TCK @T6G_MB_LIB.T6G(SCH_1):JTAG_SCM_TCK   I244 @T6G_MB_LIB.T6G(SCH_1):PAGE148

R1735 Q_RES_0402LF-10K,1%,1/16W,EMPTY,CS31002FB08
     1 JTAG_SCM_TCK @T6G_MB_LIB.T6G(SCH_1):JTAG_SCM_TCK   I246 @T6G_MB_LIB.T6G(SCH_1):PAGE148
     2    GND @T6G_MB_LIB.T6G(SCH_1):GND   I246 @T6G_MB_LIB.T6G(SCH_1):PAGE148

R1736 Q_RES_0402LF-0,5%,1/16W,CHIP,CS00002JB13
     1 JTAG_SCM_MUX_R_TCK @T6G_MB_LIB.T6G(SCH_1):JTAG_SCM_MUX_R_TCK   I363 @T6G_MB_LIB.T6G(SCH_1):PAGE148
     2 JTAG_SCM_MUX_TCK @T6G_MB_LIB.T6G(SCH_1):JTAG_SCM_MUX_TCK   I363 @T6G_MB_LIB.T6G(SCH_1):PAGE148

R1737 Q_RES_0402LF-0,5%,1/16W,CHIP,CS00002JB13
     1 JTAG_SCM_MUX_R_TMS @T6G_MB_LIB.T6G(SCH_1):JTAG_SCM_MUX_R_TMS   I357 @T6G_MB_LIB.T6G(SCH_1):PAGE148
     2 JTAG_SCM_MUX_TMS @T6G_MB_LIB.T6G(SCH_1):JTAG_SCM_MUX_TMS   I357 @T6G_MB_LIB.T6G(SCH_1):PAGE148

R1738 Q_RES_0402LF-0,5%,1/16W,CHIP,CS00002JB13
     1 JTAG_SCM_MUX_R_TDI @T6G_MB_LIB.T6G(SCH_1):JTAG_SCM_MUX_R_TDI   I349 @T6G_MB_LIB.T6G(SCH_1):PAGE148
     2 JTAG_SCM_MUX_TDI @T6G_MB_LIB.T6G(SCH_1):JTAG_SCM_MUX_TDI   I349 @T6G_MB_LIB.T6G(SCH_1):PAGE148

R1739 Q_RES_0402LF-0,5%,1/16W,CHIP,CS00002JB13
     1 JTAG_SCM_MUX_R_TDO @T6G_MB_LIB.T6G(SCH_1):JTAG_SCM_MUX_R_TDO   I388 @T6G_MB_LIB.T6G(SCH_1):PAGE148
     2 JTAG_SCM_MUX_TDO @T6G_MB_LIB.T6G(SCH_1):JTAG_SCM_MUX_TDO   I388 @T6G_MB_LIB.T6G(SCH_1):PAGE148

R1740 Q_RES_0402LF-22,1%,1/16W,CHIP,CS02202FB02
     1 JTAG_SCM_PLD_R_TCK @T6G_MB_LIB.T6G(SCH_1):JTAG_SCM_PLD_R_TCK   I368 @T6G_MB_LIB.T6G(SCH_1):PAGE148
     2 JTAG_SCM_PLD_TCK @T6G_MB_LIB.T6G(SCH_1):JTAG_SCM_PLD_TCK   I368 @T6G_MB_LIB.T6G(SCH_1):PAGE148

R1741 Q_RES_0402LF-22,1%,1/16W,CHIP,CS02202FB02
     1 JTAG_SCM_PLD_R_TMS @T6G_MB_LIB.T6G(SCH_1):JTAG_SCM_PLD_R_TMS   I366 @T6G_MB_LIB.T6G(SCH_1):PAGE148
     2 JTAG_SCM_PLD_TMS @T6G_MB_LIB.T6G(SCH_1):JTAG_SCM_PLD_TMS   I366 @T6G_MB_LIB.T6G(SCH_1):PAGE148

R1742 Q_RES_0402LF-22,1%,1/16W,CHIP,CS02202FB02
     1 JTAG_SCM_PLD_R_TDI @T6G_MB_LIB.T6G(SCH_1):JTAG_SCM_PLD_R_TDI   I352 @T6G_MB_LIB.T6G(SCH_1):PAGE148
     2 JTAG_SCM_PLD_TDI @T6G_MB_LIB.T6G(SCH_1):JTAG_SCM_PLD_TDI   I352 @T6G_MB_LIB.T6G(SCH_1):PAGE148

R1743 Q_RES_0402LF-22,1%,1/16W,CHIP,CS02202FB02
     1 JTAG_SCM_PLD_R_TDO @T6G_MB_LIB.T6G(SCH_1):JTAG_SCM_PLD_R_TDO   I332 @T6G_MB_LIB.T6G(SCH_1):PAGE148
     2 JTAG_SCM_PLD_TDO @T6G_MB_LIB.T6G(SCH_1):JTAG_SCM_PLD_TDO   I332 @T6G_MB_LIB.T6G(SCH_1):PAGE148

R1744 Q_RES_0402LF-10K,1%,1/16W,CHIP,CS31002FB08
     1 P3V3_AUX @T6G_MB_LIB.T6G(SCH_1):P3V3_AUX   I261 @T6G_MB_LIB.T6G(SCH_1):PAGE148
     2 JTAG_SCM_MUX_TDI @T6G_MB_LIB.T6G(SCH_1):JTAG_SCM_MUX_TDI   I261 @T6G_MB_LIB.T6G(SCH_1):PAGE148

R1745 Q_RES_0402LF-10K,1%,1/16W,CHIP,CS31002FB08
     1 P3V3_AUX @T6G_MB_LIB.T6G(SCH_1):P3V3_AUX   I257 @T6G_MB_LIB.T6G(SCH_1):PAGE148
     2 JTAG_SCM_MUX_TDO @T6G_MB_LIB.T6G(SCH_1):JTAG_SCM_MUX_TDO   I257 @T6G_MB_LIB.T6G(SCH_1):PAGE148

R1746 Q_RES_0402LF-10K,1%,1/16W,CHIP,CS31002FB08
     1 P3V3_AUX @T6G_MB_LIB.T6G(SCH_1):P3V3_AUX   I256 @T6G_MB_LIB.T6G(SCH_1):PAGE148
     2 JTAG_SCM_MUX_TMS @T6G_MB_LIB.T6G(SCH_1):JTAG_SCM_MUX_TMS   I256 @T6G_MB_LIB.T6G(SCH_1):PAGE148

R1747 Q_RES_0402LF-10K,1%,1/16W,CHIP,CS31002FB08
     1 P3V3_AUX @T6G_MB_LIB.T6G(SCH_1):P3V3_AUX   I255 @T6G_MB_LIB.T6G(SCH_1):PAGE148
     2 JTAG_SCM_MUX_TCK @T6G_MB_LIB.T6G(SCH_1):JTAG_SCM_MUX_TCK   I255 @T6G_MB_LIB.T6G(SCH_1):PAGE148

R1748 Q_RES_0402LF-10K,1%,1/16W,EMPTY,CS31002FB08
     1 JTAG_SCM_MUX_TCK @T6G_MB_LIB.T6G(SCH_1):JTAG_SCM_MUX_TCK   I258 @T6G_MB_LIB.T6G(SCH_1):PAGE148
     2    GND @T6G_MB_LIB.T6G(SCH_1):GND   I258 @T6G_MB_LIB.T6G(SCH_1):PAGE148

R1775 Q_RES_0402LF-1K,1%,1/16W,CHIP,CS21002FB06
     1 P3V_BAT @T6G_MB_LIB.T6G(SCH_1):P3V_BAT   I131 @T6G_MB_LIB.T6G(SCH_1):PAGE156
     2 P3V_BAT_R @T6G_MB_LIB.T6G(SCH_1):P3V_BAT_R   I131 @T6G_MB_LIB.T6G(SCH_1):PAGE156

R1776 Q_RES_0402LF-1K,1%,1/16W,CHIP,CS21002FB06
     1 CLR_CMOS @T6G_MB_LIB.T6G(SCH_1):CLR_CMOS    I94 @T6G_MB_LIB.T6G(SCH_1):PAGE156
     2    GND @T6G_MB_LIB.T6G(SCH_1):GND    I94 @T6G_MB_LIB.T6G(SCH_1):PAGE156

R1777 Q_RES_0402LF-1K,1%,1/16W,CHIP,CS21002FB06
     1 P1V5_BAT_IN @T6G_MB_LIB.T6G(SCH_1):P1V5_BAT_IN   I129 @T6G_MB_LIB.T6G(SCH_1):PAGE156
     2 BAT_LDO_EN @T6G_MB_LIB.T6G(SCH_1):BAT_LDO_EN   I129 @T6G_MB_LIB.T6G(SCH_1):PAGE156

R1779 Q_RES_0402LF-100,1%,1/16W,CHIP,CS11002FB07
     1 CLR_CMOS_N @T6G_MB_LIB.T6G(SCH_1):CLR_CMOS_N   I116 @T6G_MB_LIB.T6G(SCH_1):PAGE156
     2 P1V5_BAT @T6G_MB_LIB.T6G(SCH_1):P1V5_BAT   I116 @T6G_MB_LIB.T6G(SCH_1):PAGE156

R1785 Q_RES_0402LF-4.7K,1%,1/16W,CHIP,CS24702FB06
     1 P3V3_AUX_ADC @T6G_MB_LIB.T6G(SCH_1):P3V3_AUX_ADC    I26 @T6G_MB_LIB.T6G(SCH_1):PAGE369
     2    GND @T6G_MB_LIB.T6G(SCH_1):GND    I26 @T6G_MB_LIB.T6G(SCH_1):PAGE369

R1791 Q_RES_0402LF-9.09K,1%,1/16W,CHIP,CS29092FB05
     1 P5V_ADC @T6G_MB_LIB.T6G(SCH_1):P5V_ADC    I14 @T6G_MB_LIB.T6G(SCH_1):PAGE369
     2    GND @T6G_MB_LIB.T6G(SCH_1):GND    I14 @T6G_MB_LIB.T6G(SCH_1):PAGE369

R1792 Q_RES_0402LF-0,5%,1/16W,EMPTY,CS00002JB13
     1 SMB_SCM_2_R4_SDA @T6G_MB_LIB.T6G(SCH_1):SMB_SCM_2_R4_SDA   I146 @T6G_MB_LIB.T6G(SCH_1):PAGE369
     2 SMB_SEN_MAM_3V3AUX_SDA @T6G_MB_LIB.T6G(SCH_1):SMB_SEN_MAM_3V3AUX_SDA   I146 @T6G_MB_LIB.T6G(SCH_1):PAGE369

R1793 Q_RES_0402LF-0,5%,1/16W,EMPTY,CS00002JB13
     1 SMB_SCM_2_R4_SCL @T6G_MB_LIB.T6G(SCH_1):SMB_SCM_2_R4_SCL   I147 @T6G_MB_LIB.T6G(SCH_1):PAGE369
     2 SMB_SEN_MAM_3V3AUX_SCL @T6G_MB_LIB.T6G(SCH_1):SMB_SEN_MAM_3V3AUX_SCL   I147 @T6G_MB_LIB.T6G(SCH_1):PAGE369

R1798 Q_RES_0402LF-0,5%,1/16W,CHIP,CS00002JB13
     1 SCM_ROT_CPU_RST_R_N @T6G_MB_LIB.T6G(SCH_1):SCM_ROT_CPU_RST_R_N    I26 @T6G_MB_LIB.T6G(SCH_1):PAGE348
     2 SCM_ROT_CPU_RST_N @T6G_MB_LIB.T6G(SCH_1):SCM_ROT_CPU_RST_N    I26 @T6G_MB_LIB.T6G(SCH_1):PAGE348

R1799 Q_RES_0402LF-7.87K,1%,1/16W,CHIP,CS27872FB02
     1 P12V_AUX @T6G_MB_LIB.T6G(SCH_1):P12V_AUX     I6 @T6G_MB_LIB.T6G(SCH_1):PAGE369
     2 P12V_AUX_ADC @T6G_MB_LIB.T6G(SCH_1):P12V_AUX_ADC     I6 @T6G_MB_LIB.T6G(SCH_1):PAGE369

R1800 Q_RES_0402LF-1.21K,1%,1/16W,CHIP,CS21212FB05
     1 P12V_AUX_ADC @T6G_MB_LIB.T6G(SCH_1):P12V_AUX_ADC   I170 @T6G_MB_LIB.T6G(SCH_1):PAGE369
     2    GND @T6G_MB_LIB.T6G(SCH_1):GND   I170 @T6G_MB_LIB.T6G(SCH_1):PAGE369

R1801 Q_RES_0402LF-0,5%,1/16W,CHIP,CS00002JB13
     1 PRSNT0_N @T6G_MB_LIB.T6G(SCH_1):PRSNT0_N   I171 @T6G_MB_LIB.T6G(SCH_1):PAGE348
     2    GND @T6G_MB_LIB.T6G(SCH_1):GND   I171 @T6G_MB_LIB.T6G(SCH_1):PAGE348

R1815 Q_RES_0402LF-0,5%,1/16W,CHIP,CS00002JB13
     1 SCM_SYS_PWRBTN_N @T6G_MB_LIB.T6G(SCH_1):SCM_SYS_PWRBTN_N    I29 @T6G_MB_LIB.T6G(SCH_1):PAGE348
     2 SCM_SYS_PWRBTN_R_N @T6G_MB_LIB.T6G(SCH_1):SCM_SYS_PWRBTN_R_N    I29 @T6G_MB_LIB.T6G(SCH_1):PAGE348

R1816 Q_RES_0402LF-0,5%,1/16W,CHIP,CS00002JB13
     1 PWRGD_PS_PWROK @T6G_MB_LIB.T6G(SCH_1):PWRGD_PS_PWROK    I32 @T6G_MB_LIB.T6G(SCH_1):PAGE348
     2 PWRGD_PS_PWROK_R @T6G_MB_LIB.T6G(SCH_1):PWRGD_PS_PWROK_R    I32 @T6G_MB_LIB.T6G(SCH_1):PAGE348

R1822 Q_RES_0402LF-10K,1%,1/16W,CHIP,CS31002FB08
     1 P3V3_AUX @T6G_MB_LIB.T6G(SCH_1):P3V3_AUX    I21 @T6G_MB_LIB.T6G(SCH_1):PAGE252
     2 RST_SMB_SWITCH_N @T6G_MB_LIB.T6G(SCH_1):RST_SMB_SWITCH_N    I21 @T6G_MB_LIB.T6G(SCH_1):PAGE252

R1824 Q_RES_0402LF-10K,1%,1/16W,CHIP,CS31002FB08
     1 P3V3_OCP_SFF @T6G_MB_LIB.T6G(SCH_1):P3V3_OCP_SFF    I11 @T6G_MB_LIB.T6G(SCH_1):PAGE337
     2 IRQ_LVC3_OCP_SFF_WAKE_N @T6G_MB_LIB.T6G(SCH_1):IRQ_LVC3_OCP_SFF_WAKE_N    I11 @T6G_MB_LIB.T6G(SCH_1):PAGE337

R1837 Q_RES_4P_12-0.001,1%,3W,SMLF,CHIP,SP_CS+001DFR10
     1 P12V_AUX @T6G_MB_LIB.T6G(SCH_1):P12V_AUX    I54 @T6G_MB_LIB.T6G(SCH_1):PAGE264
     2 P12V_MEM_CPU1 @T6G_MB_LIB.T6G(SCH_1):P12V_MEM_CPU1    I54 @T6G_MB_LIB.T6G(SCH_1):PAGE264
     3 TP_P12V_AUX_CPU1_DIMM_ISEN_P @T6G_MB_LIB.T6G(SCH_1):TP_P12V_AUX_CPU1_DIMM_ISEN_P    I54 @T6G_MB_LIB.T6G(SCH_1):PAGE264
     4 TP_P12V_AUX_CPU1_DIMM_ISEN_N @T6G_MB_LIB.T6G(SCH_1):TP_P12V_AUX_CPU1_DIMM_ISEN_N    I54 @T6G_MB_LIB.T6G(SCH_1):PAGE264

R1838 Q_RES_4P_12-0.001,1%,3W,SMLF,CHIP,SP_CS+001DFR10
     1 P12V_AUX @T6G_MB_LIB.T6G(SCH_1):P12V_AUX    I58 @T6G_MB_LIB.T6G(SCH_1):PAGE264
     2 P12V_MEM_CPU0 @T6G_MB_LIB.T6G(SCH_1):P12V_MEM_CPU0    I58 @T6G_MB_LIB.T6G(SCH_1):PAGE264
     3 TP_P12V_AUX_CPU0_DIMM_ISEN_P @T6G_MB_LIB.T6G(SCH_1):TP_P12V_AUX_CPU0_DIMM_ISEN_P    I58 @T6G_MB_LIB.T6G(SCH_1):PAGE264
     4 TP_P12V_AUX_CPU0_DIMM_ISEN_N @T6G_MB_LIB.T6G(SCH_1):TP_P12V_AUX_CPU0_DIMM_ISEN_N    I58 @T6G_MB_LIB.T6G(SCH_1):PAGE264

R1854 Q_RES_0402LF-1K,1%,1/16W,CHIP,CS21002FB06
     1 P3V3_AUX @T6G_MB_LIB.T6G(SCH_1):P3V3_AUX     I2 @T6G_MB_LIB.T6G(SCH_1):PAGE350
     2 FM_SCM_PRSNT1_N @T6G_MB_LIB.T6G(SCH_1):FM_SCM_PRSNT1_N     I2 @T6G_MB_LIB.T6G(SCH_1):PAGE350

R1856 Q_RES_0402LF-100,1%,1/16W,CHIP,CS11002FB07
     1 FM_SCM_PRSNT1_N @T6G_MB_LIB.T6G(SCH_1):FM_SCM_PRSNT1_N     I3 @T6G_MB_LIB.T6G(SCH_1):PAGE350
     2 FM_SCM_PRSNT1_R_N @T6G_MB_LIB.T6G(SCH_1):FM_SCM_PRSNT1_R_N     I3 @T6G_MB_LIB.T6G(SCH_1):PAGE350

R1857 Q_RES_0402LF-10K,1%,1/16W,CHIP,CS31002FB08
     1 P3V3_AUX @T6G_MB_LIB.T6G(SCH_1):P3V3_AUX    I18 @T6G_MB_LIB.T6G(SCH_1):PAGE350
     2 P12V_SCM_EN @T6G_MB_LIB.T6G(SCH_1):P12V_SCM_EN    I18 @T6G_MB_LIB.T6G(SCH_1):PAGE350

R1895 Q_RES_0402LF-0,5%,1/16W,CHIP,CS00002JB13
     1 OCP_SFF_PRSNTA_R_N @T6G_MB_LIB.T6G(SCH_1):OCP_SFF_PRSNTA_R_N   I169 @T6G_MB_LIB.T6G(SCH_1):PAGE335
     2    GND @T6G_MB_LIB.T6G(SCH_1):GND   I169 @T6G_MB_LIB.T6G(SCH_1):PAGE335

R1896 Q_RES_0402LF-100,1%,1/16W,CHIP,CS11002FB07
     1 OCP_SFF_ISO_BIF0_EN @T6G_MB_LIB.T6G(SCH_1):OCP_SFF_ISO_BIF0_EN   I123 @T6G_MB_LIB.T6G(SCH_1):PAGE336
     2    GND @T6G_MB_LIB.T6G(SCH_1):GND   I123 @T6G_MB_LIB.T6G(SCH_1):PAGE336

R1897 Q_RES_0402LF-100,1%,1/16W,CHIP,CS11002FB07
     1 OCP_SFF_ISO_BIF1_EN @T6G_MB_LIB.T6G(SCH_1):OCP_SFF_ISO_BIF1_EN   I124 @T6G_MB_LIB.T6G(SCH_1):PAGE336
     2    GND @T6G_MB_LIB.T6G(SCH_1):GND   I124 @T6G_MB_LIB.T6G(SCH_1):PAGE336

R1898 Q_RES_0402LF-100,1%,1/16W,CHIP,CS11002FB07
     1 OCP_SFF_ISO_BIF2_EN @T6G_MB_LIB.T6G(SCH_1):OCP_SFF_ISO_BIF2_EN   I122 @T6G_MB_LIB.T6G(SCH_1):PAGE336
     2    GND @T6G_MB_LIB.T6G(SCH_1):GND   I122 @T6G_MB_LIB.T6G(SCH_1):PAGE336

R1905 Q_RES_0402LF-1K,1%,1/16W,CHIP,CS21002FB06
     1 P3V3_AUX @T6G_MB_LIB.T6G(SCH_1):P3V3_AUX    I15 @T6G_MB_LIB.T6G(SCH_1):PAGE338
     2 OCP_SFF_PRSNT0_R_N @T6G_MB_LIB.T6G(SCH_1):OCP_SFF_PRSNT0_R_N    I15 @T6G_MB_LIB.T6G(SCH_1):PAGE338

R1906 Q_RES_0402LF-1K,1%,1/16W,CHIP,CS21002FB06
     1 P3V3_AUX @T6G_MB_LIB.T6G(SCH_1):P3V3_AUX     I9 @T6G_MB_LIB.T6G(SCH_1):PAGE338
     2 OCP_SFF_PRSNT2_R_N @T6G_MB_LIB.T6G(SCH_1):OCP_SFF_PRSNT2_R_N     I9 @T6G_MB_LIB.T6G(SCH_1):PAGE338

R1907 Q_RES_0402LF-1K,1%,1/16W,CHIP,CS21002FB06
     1 P3V3_AUX @T6G_MB_LIB.T6G(SCH_1):P3V3_AUX    I28 @T6G_MB_LIB.T6G(SCH_1):PAGE338
     2 OCP_SFF_PRSNT1_R_N @T6G_MB_LIB.T6G(SCH_1):OCP_SFF_PRSNT1_R_N    I28 @T6G_MB_LIB.T6G(SCH_1):PAGE338

R1908 Q_RES_0402LF-1K,1%,1/16W,CHIP,CS21002FB06
     1 P3V3_AUX @T6G_MB_LIB.T6G(SCH_1):P3V3_AUX    I24 @T6G_MB_LIB.T6G(SCH_1):PAGE338
     2 OCP_SFF_PRSNT3_R_N @T6G_MB_LIB.T6G(SCH_1):OCP_SFF_PRSNT3_R_N    I24 @T6G_MB_LIB.T6G(SCH_1):PAGE338

R1929 Q_RES_0402LF-10K,1%,1/16W,CHIP,CS31002FB08
     1    GND @T6G_MB_LIB.T6G(SCH_1):GND     I8 @T6G_MB_LIB.T6G(SCH_1):PAGE335
     2 OCP_SFF_AUX_PWR_EN @T6G_MB_LIB.T6G(SCH_1):OCP_SFF_AUX_PWR_EN     I8 @T6G_MB_LIB.T6G(SCH_1):PAGE335

R1930 Q_RES_0402LF-10K,1%,1/16W,CHIP,CS31002FB08
     1    GND @T6G_MB_LIB.T6G(SCH_1):GND     I7 @T6G_MB_LIB.T6G(SCH_1):PAGE335
     2 OCP_SFF_MAIN_PWR_EN @T6G_MB_LIB.T6G(SCH_1):OCP_SFF_MAIN_PWR_EN     I7 @T6G_MB_LIB.T6G(SCH_1):PAGE335

R2113 Q_RES_0402LF-0,5%,1/16W,CHIP,CS00002JB13
     1 RST_PERST_BUF_M2_0_N @T6G_MB_LIB.T6G(SCH_1):RST_PERST_BUF_M2_0_N    I12 @T6G_MB_LIB.T6G(SCH_1):PAGE345
     2 RST_PERST_BUF_M2_0_R_N @T6G_MB_LIB.T6G(SCH_1):RST_PERST_BUF_M2_0_R_N    I12 @T6G_MB_LIB.T6G(SCH_1):PAGE345

R2114 Q_RES_0402LF-0,5%,1/16W,CHIP,CS00002JB13
     1 SMB_PCIE_E1S_ISO_EN_R2 @T6G_MB_LIB.T6G(SCH_1):SMB_PCIE_E1S_ISO_EN_R2    I37 @T6G_MB_LIB.T6G(SCH_1):PAGE297
     2 SMB_PCIE_E1S_ISO_EN @T6G_MB_LIB.T6G(SCH_1):SMB_PCIE_E1S_ISO_EN    I37 @T6G_MB_LIB.T6G(SCH_1):PAGE297

R2121 Q_RES_0402LF-4.7K,5%,1/16W,CHIP,CS24702JB10
     1 P3V3_AUX @T6G_MB_LIB.T6G(SCH_1):P3V3_AUX    I10 @T6G_MB_LIB.T6G(SCH_1):PAGE345
     2 RST_PERST_BUF_M2_0_N @T6G_MB_LIB.T6G(SCH_1):RST_PERST_BUF_M2_0_N    I10 @T6G_MB_LIB.T6G(SCH_1):PAGE345

R2125 Q_RES_0402LF-4.7K,5%,1/16W,CHIP,CS24702JB10
     1 P3V3_AUX @T6G_MB_LIB.T6G(SCH_1):P3V3_AUX    I40 @T6G_MB_LIB.T6G(SCH_1):PAGE297
     2 SMB_PCIE_E1S_ISO_EN @T6G_MB_LIB.T6G(SCH_1):SMB_PCIE_E1S_ISO_EN    I40 @T6G_MB_LIB.T6G(SCH_1):PAGE297

R2204 Q_RES_0402LF-2.2K,5%,1/16W,EMPTY,CS22202JB07
     1 P3V3_AUX @T6G_MB_LIB.T6G(SCH_1):P3V3_AUX    I50 @T6G_MB_LIB.T6G(SCH_1):PAGE252
     2 SMB_PCIE0_3V3AUX_SCL @T6G_MB_LIB.T6G(SCH_1):SMB_PCIE0_3V3AUX_SCL    I50 @T6G_MB_LIB.T6G(SCH_1):PAGE252

R2205 Q_RES_0402LF-2.2K,5%,1/16W,EMPTY,CS22202JB07
     1 P3V3_AUX @T6G_MB_LIB.T6G(SCH_1):P3V3_AUX    I49 @T6G_MB_LIB.T6G(SCH_1):PAGE252
     2 SMB_PCIE0_3V3AUX_SDA @T6G_MB_LIB.T6G(SCH_1):SMB_PCIE0_3V3AUX_SDA    I49 @T6G_MB_LIB.T6G(SCH_1):PAGE252

R2212 Q_RES_0402LF-2.2K,5%,1/16W,EMPTY,CS22202JB07
     1 SMB_HOST_CLK_3V3AUX_SCL @T6G_MB_LIB.T6G(SCH_1):SMB_HOST_CLK_3V3AUX_SCL   I126 @T6G_MB_LIB.T6G(SCH_1):PAGE349
     2 P3V3_AUX @T6G_MB_LIB.T6G(SCH_1):P3V3_AUX   I126 @T6G_MB_LIB.T6G(SCH_1):PAGE349

R2213 Q_RES_0402LF-2.2K,5%,1/16W,EMPTY,CS22202JB07
     1 SMB_HOST_CLK_3V3AUX_SDA @T6G_MB_LIB.T6G(SCH_1):SMB_HOST_CLK_3V3AUX_SDA   I125 @T6G_MB_LIB.T6G(SCH_1):PAGE349
     2 P3V3_AUX @T6G_MB_LIB.T6G(SCH_1):P3V3_AUX   I125 @T6G_MB_LIB.T6G(SCH_1):PAGE349

R2219 Q_RES_0402LF-267K,1%,1/16W,EMPTY,CS42672FB03
     1 P12V_AUX @T6G_MB_LIB.T6G(SCH_1):P12V_AUX    I30 @T6G_MB_LIB.T6G(SCH_1):PAGE372
     2 A_P12V_STBY_ADR_TRIGGER @T6G_MB_LIB.T6G(SCH_1):A_P12V_STBY_ADR_TRIGGER    I30 @T6G_MB_LIB.T6G(SCH_1):PAGE372

R2221 Q_RES_0402LF-26.7K,1%,1/16W,EMPTY,CS32672FB03
     1 P12V_AUX @T6G_MB_LIB.T6G(SCH_1):P12V_AUX    I35 @T6G_MB_LIB.T6G(SCH_1):PAGE372
     2 A_P12V_STBY_FP_TRIGGER @T6G_MB_LIB.T6G(SCH_1):A_P12V_STBY_FP_TRIGGER    I35 @T6G_MB_LIB.T6G(SCH_1):PAGE372

R2222 Q_RES_0402LF-1K,1%,1/16W,EMPTY,CS21002FB06
     1 A_P12V_STBY_FP_TRIGGER @T6G_MB_LIB.T6G(SCH_1):A_P12V_STBY_FP_TRIGGER    I33 @T6G_MB_LIB.T6G(SCH_1):PAGE372
     2    GND @T6G_MB_LIB.T6G(SCH_1):GND    I33 @T6G_MB_LIB.T6G(SCH_1):PAGE372

R2227 Q_RES_0402LF-10K,1%,1/16W,EMPTY,CS31002FB08
     1 A_P12V_STBY_ADR_TRIGGER @T6G_MB_LIB.T6G(SCH_1):A_P12V_STBY_ADR_TRIGGER    I29 @T6G_MB_LIB.T6G(SCH_1):PAGE372
     2    GND @T6G_MB_LIB.T6G(SCH_1):GND    I29 @T6G_MB_LIB.T6G(SCH_1):PAGE372

R2230 Q_RES_0402LF-10K,1%,1/16W,EMPTY,CS31002FB08
     1 P3V3_AUX @T6G_MB_LIB.T6G(SCH_1):P3V3_AUX    I43 @T6G_MB_LIB.T6G(SCH_1):PAGE372
     2 A_P12V_STBY_FPH_GATE @T6G_MB_LIB.T6G(SCH_1):A_P12V_STBY_FPH_GATE    I43 @T6G_MB_LIB.T6G(SCH_1):PAGE372

R2233 Q_RES_0402LF-1K,1%,1/16W,EMPTY,CS21002FB06
     1 P3V3_AUX @T6G_MB_LIB.T6G(SCH_1):P3V3_AUX    I45 @T6G_MB_LIB.T6G(SCH_1):PAGE372
     2 FM_UV_ADR_TRIGGER_N @T6G_MB_LIB.T6G(SCH_1):FM_UV_ADR_TRIGGER_N    I45 @T6G_MB_LIB.T6G(SCH_1):PAGE372

R2261 Q_RES_0402LF-33.2,1%,1/16W,CHIP,CS03322FB03
     1 FM_SWB_PWR_EN_R @T6G_MB_LIB.T6G(SCH_1):FM_SWB_PWR_EN_R   I284 @T6G_MB_LIB.T6G(SCH_1):PAGE80
     2 FM_SWB_PWR_EN @T6G_MB_LIB.T6G(SCH_1):FM_SWB_PWR_EN   I284 @T6G_MB_LIB.T6G(SCH_1):PAGE80

R2262 Q_RES_0402LF-33.2,1%,1/16W,CHIP,CS03322FB03
     1 FM_GPU_PWR_EN_R @T6G_MB_LIB.T6G(SCH_1):FM_GPU_PWR_EN_R   I294 @T6G_MB_LIB.T6G(SCH_1):PAGE80
     2 FM_GPU_PWR_EN @T6G_MB_LIB.T6G(SCH_1):FM_GPU_PWR_EN   I294 @T6G_MB_LIB.T6G(SCH_1):PAGE80

R2268 Q_RES_0402LF-0,5%,1/16W,CHIP,CS00002JB13
     1 RST_SMB_SWITCH_N @T6G_MB_LIB.T6G(SCH_1):RST_SMB_SWITCH_N    I28 @T6G_MB_LIB.T6G(SCH_1):PAGE252
     2 PU_RST_SMB_PCIE0_N @T6G_MB_LIB.T6G(SCH_1):PU_RST_SMB_PCIE0_N    I28 @T6G_MB_LIB.T6G(SCH_1):PAGE252

R2310 Q_RES_0402LF-0,5%,1/16W,EMPTY,CS00002JB13
     1 I3C_0_SPD_DDRAF_CPU0_R_SCL @T6G_MB_LIB.T6G(SCH_1):I3C_0_SPD_DDRAF_CPU0_R_SCL   I123 @T6G_MB_LIB.T6G(SCH_1):PAGE136
     2 I3C_SPD_DDRAF_CPU0_BYPASS_SCL @T6G_MB_LIB.T6G(SCH_1):I3C_SPD_DDRAF_CPU0_BYPASS_SCL   I123 @T6G_MB_LIB.T6G(SCH_1):PAGE136

R2311 Q_RES_0402LF-0,5%,1/16W,EMPTY,CS00002JB13
     1 I3C_0_SPD_DDRAF_CPU0_R_SDA @T6G_MB_LIB.T6G(SCH_1):I3C_0_SPD_DDRAF_CPU0_R_SDA   I124 @T6G_MB_LIB.T6G(SCH_1):PAGE136
     2 I3C_SPD_DDRAF_CPU0_BYPASS_SDA @T6G_MB_LIB.T6G(SCH_1):I3C_SPD_DDRAF_CPU0_BYPASS_SDA   I124 @T6G_MB_LIB.T6G(SCH_1):PAGE136

R2316 Q_RES_0402LF-0,5%,1/16W,CHIP,CS00002JB13
     1 PWRGD_P5V_AUX_R @T6G_MB_LIB.T6G(SCH_1):PWRGD_P5V_AUX_R    I26 @T6G_MB_LIB.T6G(SCH_1):PAGE244
     2 PWRGD_P5V_AUX @T6G_MB_LIB.T6G(SCH_1):PWRGD_P5V_AUX    I26 @T6G_MB_LIB.T6G(SCH_1):PAGE244

R2317 Q_RES_0402LF-10K,1%,1/16W,CHIP,CS31002FB08
     1 P3V3_E1S_0 @T6G_MB_LIB.T6G(SCH_1):P3V3_E1S_0    I31 @T6G_MB_LIB.T6G(SCH_1):PAGE297
     2 PU_E1S_0_DUALPORT_EN_N @T6G_MB_LIB.T6G(SCH_1):PU_E1S_0_DUALPORT_EN_N    I31 @T6G_MB_LIB.T6G(SCH_1):PAGE297

R2318 Q_RES_0402LF-0,5%,1/16W,CHIP,CS00002JB13
     1 UART_CPU0_SCM_UART1_R_TX @T6G_MB_LIB.T6G(SCH_1):UART_CPU0_SCM_UART1_R_TX   I288 @T6G_MB_LIB.T6G(SCH_1):PAGE27
     2 UART_CPU0_SCM_UART1_TX @T6G_MB_LIB.T6G(SCH_1):UART_CPU0_SCM_UART1_TX   I288 @T6G_MB_LIB.T6G(SCH_1):PAGE27

R2343 Q_RES_0402LF-10K,1%,1/16W,EMPTY,CS31002FB08
     1 P5V_AUX_VCC @T6G_MB_LIB.T6G(SCH_1):P5V_AUX_VCC    I63 @T6G_MB_LIB.T6G(SCH_1):PAGE84
     2 PWRGD_P5V_AUX @T6G_MB_LIB.T6G(SCH_1):PWRGD_P5V_AUX    I63 @T6G_MB_LIB.T6G(SCH_1):PAGE84

R2344 Q_RES_0402LF-4.7K,5%,1/16W,CHIP,CS24702JB10
     1 P3V3_AUX @T6G_MB_LIB.T6G(SCH_1):P3V3_AUX    I67 @T6G_MB_LIB.T6G(SCH_1):PAGE84
     2 PWRGD_P5V_AUX_R1 @T6G_MB_LIB.T6G(SCH_1):PWRGD_P5V_AUX_R1    I67 @T6G_MB_LIB.T6G(SCH_1):PAGE84

R2346 Q_RES_0402LF-100K,1%,1/16W,CHIP,CS41002FB09
     1 P3V3_AUX @T6G_MB_LIB.T6G(SCH_1):P3V3_AUX    I70 @T6G_MB_LIB.T6G(SCH_1):PAGE84
     2 PWRGD_P5V_AUX_R2 @T6G_MB_LIB.T6G(SCH_1):PWRGD_P5V_AUX_R2    I70 @T6G_MB_LIB.T6G(SCH_1):PAGE84

R2356 Q_RES_0402LF-10K,1%,1/16W,CHIP,CS31002FB08
     1 P5V_AUX_VCC @T6G_MB_LIB.T6G(SCH_1):P5V_AUX_VCC    I25 @T6G_MB_LIB.T6G(SCH_1):PAGE244
     2 PWRGD_P5V_AUX_R @T6G_MB_LIB.T6G(SCH_1):PWRGD_P5V_AUX_R    I25 @T6G_MB_LIB.T6G(SCH_1):PAGE244

R2410 Q_RES_0402LF-33.2,1%,1/16W,CHIP,CS03322FB03
     1 SMB_M2_P1_1V8AUX_SDA_R @T6G_MB_LIB.T6G(SCH_1):SMB_M2_P1_1V8AUX_SDA_R    I65 @T6G_MB_LIB.T6G(SCH_1):PAGE346
     2 SMB_M2_P1_1V8AUX_SDA @T6G_MB_LIB.T6G(SCH_1):SMB_M2_P1_1V8AUX_SDA    I65 @T6G_MB_LIB.T6G(SCH_1):PAGE346

R2411 Q_RES_0402LF-33.2,1%,1/16W,CHIP,CS03322FB03
     1 SMB_M2_P1_1V8AUX_SCL_R @T6G_MB_LIB.T6G(SCH_1):SMB_M2_P1_1V8AUX_SCL_R    I66 @T6G_MB_LIB.T6G(SCH_1):PAGE346
     2 SMB_M2_P1_1V8AUX_SCL @T6G_MB_LIB.T6G(SCH_1):SMB_M2_P1_1V8AUX_SCL    I66 @T6G_MB_LIB.T6G(SCH_1):PAGE346

R2413 Q_RES_0402LF-33.2,1%,1/16W,CHIP,CS03322FB03
     1 SMB_2_BMC_GPU_SCL @T6G_MB_LIB.T6G(SCH_1):SMB_2_BMC_GPU_SCL    I86 @T6G_MB_LIB.T6G(SCH_1):PAGE348
     2 SMB_PCIE2_3V3AUX_SCL_R0 @T6G_MB_LIB.T6G(SCH_1):SMB_PCIE2_3V3AUX_SCL_R0    I86 @T6G_MB_LIB.T6G(SCH_1):PAGE348

R2414 Q_RES_0402LF-33.2,1%,1/16W,CHIP,CS03322FB03
     1 SMB_2_BMC_GPU_SDA @T6G_MB_LIB.T6G(SCH_1):SMB_2_BMC_GPU_SDA    I85 @T6G_MB_LIB.T6G(SCH_1):PAGE348
     2 SMB_PCIE2_3V3AUX_SDA_R0 @T6G_MB_LIB.T6G(SCH_1):SMB_PCIE2_3V3AUX_SDA_R0    I85 @T6G_MB_LIB.T6G(SCH_1):PAGE348

R2415 Q_RES_0402LF-33.2,1%,1/16W,CHIP,CS03322FB03
     1 SMB_1_BMC_GPU_SCL @T6G_MB_LIB.T6G(SCH_1):SMB_1_BMC_GPU_SCL    I60 @T6G_MB_LIB.T6G(SCH_1):PAGE348
     2 SMB_PCIE3_3V3AUX_SCL_R @T6G_MB_LIB.T6G(SCH_1):SMB_PCIE3_3V3AUX_SCL_R    I60 @T6G_MB_LIB.T6G(SCH_1):PAGE348

R2416 Q_RES_0402LF-33.2,1%,1/16W,CHIP,CS03322FB03
     1 SMB_1_BMC_GPU_SDA @T6G_MB_LIB.T6G(SCH_1):SMB_1_BMC_GPU_SDA    I33 @T6G_MB_LIB.T6G(SCH_1):PAGE348
     2 SMB_PCIE3_3V3AUX_SDA_R @T6G_MB_LIB.T6G(SCH_1):SMB_PCIE3_3V3AUX_SDA_R    I33 @T6G_MB_LIB.T6G(SCH_1):PAGE348

R2417 Q_RES_0402LF-33.2,1%,1/16W,CHIP,CS03322FB03
     1 SMB_HOST_CLK_3V3AUX_SCL @T6G_MB_LIB.T6G(SCH_1):SMB_HOST_CLK_3V3AUX_SCL    I35 @T6G_MB_LIB.T6G(SCH_1):PAGE348
     2 SMB_HOST_CLK_3V3AUX_SCL_R0 @T6G_MB_LIB.T6G(SCH_1):SMB_HOST_CLK_3V3AUX_SCL_R0    I35 @T6G_MB_LIB.T6G(SCH_1):PAGE348

R2418 Q_RES_0402LF-33.2,1%,1/16W,CHIP,CS03322FB03
     1 SMB_HOST_CLK_3V3AUX_SDA @T6G_MB_LIB.T6G(SCH_1):SMB_HOST_CLK_3V3AUX_SDA    I34 @T6G_MB_LIB.T6G(SCH_1):PAGE348
     2 SMB_HOST_CLK_3V3AUX_SDA_R0 @T6G_MB_LIB.T6G(SCH_1):SMB_HOST_CLK_3V3AUX_SDA_R0    I34 @T6G_MB_LIB.T6G(SCH_1):PAGE348

R2419 Q_RES_0402LF-33.2,1%,1/16W,CHIP,CS03322FB03
     1 SMB_CPU0_CPU1_APML_SCL @T6G_MB_LIB.T6G(SCH_1):SMB_CPU0_CPU1_APML_SCL   I104 @T6G_MB_LIB.T6G(SCH_1):PAGE348
     2 SMB_CPU0_CPU1_APML_SCL_R @T6G_MB_LIB.T6G(SCH_1):SMB_CPU0_CPU1_APML_SCL_R   I104 @T6G_MB_LIB.T6G(SCH_1):PAGE348

R2420 Q_RES_0402LF-33.2,1%,1/16W,CHIP,CS03322FB03
     1 SMB_CPU0_CPU1_APML_SDA @T6G_MB_LIB.T6G(SCH_1):SMB_CPU0_CPU1_APML_SDA   I105 @T6G_MB_LIB.T6G(SCH_1):PAGE348
     2 SMB_CPU0_CPU1_APML_SDA_R @T6G_MB_LIB.T6G(SCH_1):SMB_CPU0_CPU1_APML_SDA_R   I105 @T6G_MB_LIB.T6G(SCH_1):PAGE348

R2421 Q_RES_0402LF-33.2,1%,1/16W,CHIP,CS03322FB03
     1 SMB_VR_SENSOR_3V3AUX_SCL @T6G_MB_LIB.T6G(SCH_1):SMB_VR_SENSOR_3V3AUX_SCL    I98 @T6G_MB_LIB.T6G(SCH_1):PAGE348
     2 SMB_VR_3V3AUX_SCL_R0 @T6G_MB_LIB.T6G(SCH_1):SMB_VR_3V3AUX_SCL_R0    I98 @T6G_MB_LIB.T6G(SCH_1):PAGE348

R2422 Q_RES_0402LF-33.2,1%,1/16W,CHIP,CS03322FB03
     1 SMB_VR_SENSOR_3V3AUX_SDA @T6G_MB_LIB.T6G(SCH_1):SMB_VR_SENSOR_3V3AUX_SDA   I101 @T6G_MB_LIB.T6G(SCH_1):PAGE348
     2 SMB_VR_3V3AUX_SDA_R0 @T6G_MB_LIB.T6G(SCH_1):SMB_VR_3V3AUX_SDA_R0   I101 @T6G_MB_LIB.T6G(SCH_1):PAGE348

R2423 Q_RES_0402LF-33.2,1%,1/16W,CHIP,CS03322FB03
     1 SMB_PMBUS_3V3AUX_SCL @T6G_MB_LIB.T6G(SCH_1):SMB_PMBUS_3V3AUX_SCL   I196 @T6G_MB_LIB.T6G(SCH_1):PAGE348
     2 SMB_PMBUS_3V3AUX_SCL_R0 @T6G_MB_LIB.T6G(SCH_1):SMB_PMBUS_3V3AUX_SCL_R0   I196 @T6G_MB_LIB.T6G(SCH_1):PAGE348

R2424 Q_RES_0402LF-33.2,1%,1/16W,CHIP,CS03322FB03
     1 SMB_PMBUS_3V3AUX_SDA @T6G_MB_LIB.T6G(SCH_1):SMB_PMBUS_3V3AUX_SDA   I195 @T6G_MB_LIB.T6G(SCH_1):PAGE348
     2 SMB_PMBUS_3V3AUX_SDA_R0 @T6G_MB_LIB.T6G(SCH_1):SMB_PMBUS_3V3AUX_SDA_R0   I195 @T6G_MB_LIB.T6G(SCH_1):PAGE348

R2425 Q_RES_0402LF-33.2,1%,1/16W,CHIP,CS03322FB03
     1 SMB_OCP_V3_2_3V3AUX_SCL @T6G_MB_LIB.T6G(SCH_1):SMB_OCP_V3_2_3V3AUX_SCL    I97 @T6G_MB_LIB.T6G(SCH_1):PAGE348
     2 SMB_OCP_V3_2_3V3AUX_SCL_R0 @T6G_MB_LIB.T6G(SCH_1):SMB_OCP_V3_2_3V3AUX_SCL_R0    I97 @T6G_MB_LIB.T6G(SCH_1):PAGE348

R2426 Q_RES_0402LF-100,1%,1/16W,EMPTY,CS11002FB07
     1 E1S_0_PERST1_CLKREQ_N @T6G_MB_LIB.T6G(SCH_1):E1S_0_PERST1_CLKREQ_N    I75 @T6G_MB_LIB.T6G(SCH_1):PAGE297
     2    GND @T6G_MB_LIB.T6G(SCH_1):GND    I75 @T6G_MB_LIB.T6G(SCH_1):PAGE297

R2473 Q_RES_0402LF-0,5%,1/16W,CHIP,CS00002JB13
     1 FB_BMC_ISOLATE_R1 @T6G_MB_LIB.T6G(SCH_1):FB_BMC_ISOLATE_R1   I164 @T6G_MB_LIB.T6G(SCH_1):PAGE336
     2 FB_BMC_ISOLATE @T6G_MB_LIB.T6G(SCH_1):FB_BMC_ISOLATE   I164 @T6G_MB_LIB.T6G(SCH_1):PAGE336

R2474 Q_RES_0402LF-0,5%,1/16W,EMPTY,CS00002JB13
     1 FM_NCSI_OCP_SFF_R_OE @T6G_MB_LIB.T6G(SCH_1):FM_NCSI_OCP_SFF_R_OE   I165 @T6G_MB_LIB.T6G(SCH_1):PAGE336
     2 FB_BMC_ISOLATE @T6G_MB_LIB.T6G(SCH_1):FB_BMC_ISOLATE   I165 @T6G_MB_LIB.T6G(SCH_1):PAGE336

R2476 Q_RES_0402LF-200K,1%,1/16W,EMPTY,CS42002FB05
     1 SMB_PCIE_M2_0_EN @T6G_MB_LIB.T6G(SCH_1):SMB_PCIE_M2_0_EN    I70 @T6G_MB_LIB.T6G(SCH_1):PAGE346
     2 PWRGD_P1V8_AUX_R @T6G_MB_LIB.T6G(SCH_1):PWRGD_P1V8_AUX_R    I70 @T6G_MB_LIB.T6G(SCH_1):PAGE346

R2487 Q_RES_0402LF-4.7K,1%,1/16W,EMPTY,CS24702FB06
     1 P3V3_AUX @T6G_MB_LIB.T6G(SCH_1):P3V3_AUX    I56 @T6G_MB_LIB.T6G(SCH_1):PAGE337
     2 IRQ_LVC3_WAKE_BUF_N @T6G_MB_LIB.T6G(SCH_1):IRQ_LVC3_WAKE_BUF_N    I56 @T6G_MB_LIB.T6G(SCH_1):PAGE337

R2488 Q_RES_0402LF-4.7K,1%,1/16W,CHIP,CS24702FB06
     1 P3V3_AUX @T6G_MB_LIB.T6G(SCH_1):P3V3_AUX    I35 @T6G_MB_LIB.T6G(SCH_1):PAGE337
     2 OCP_SFF_WAKE_BUFF_N @T6G_MB_LIB.T6G(SCH_1):OCP_SFF_WAKE_BUFF_N    I35 @T6G_MB_LIB.T6G(SCH_1):PAGE337

R2489 Q_RES_0402LF-33.2,1%,1/16W,CHIP,CS03322FB03
     1 IRQ_LVC3_WAKE_BUF_N @T6G_MB_LIB.T6G(SCH_1):IRQ_LVC3_WAKE_BUF_N    I50 @T6G_MB_LIB.T6G(SCH_1):PAGE337
     2 IRQ_OCP_SFF_WAKE_BUF_N @T6G_MB_LIB.T6G(SCH_1):IRQ_OCP_SFF_WAKE_BUF_N    I50 @T6G_MB_LIB.T6G(SCH_1):PAGE337

R2528 Q_RES_0402LF-100K,1%,1/16W,CHIP,CS41002FB09
     1 P12V_AUX @T6G_MB_LIB.T6G(SCH_1):P12V_AUX     I8 @T6G_MB_LIB.T6G(SCH_1):PAGE365
     2 FM_P12V_HSC_EN_N @T6G_MB_LIB.T6G(SCH_1):FM_P12V_HSC_EN_N     I8 @T6G_MB_LIB.T6G(SCH_1):PAGE365

R2529 Q_RES_0402LF-0,5%,1/16W,CHIP,CS00002JB13
     1 FM_P12V_HSC_EN_N @T6G_MB_LIB.T6G(SCH_1):FM_P12V_HSC_EN_N     I7 @T6G_MB_LIB.T6G(SCH_1):PAGE365
     2 FM_P12V_HSC_EN_R_N @T6G_MB_LIB.T6G(SCH_1):FM_P12V_HSC_EN_R_N     I7 @T6G_MB_LIB.T6G(SCH_1):PAGE365

R2530 Q_RES_0402LF-4.7K,5%,1/16W,CHIP,CS24702JB10
     1 P12V_AUX @T6G_MB_LIB.T6G(SCH_1):P12V_AUX    I10 @T6G_MB_LIB.T6G(SCH_1):PAGE365
     2 P12V_AUX_BLEEDING @T6G_MB_LIB.T6G(SCH_1):P12V_AUX_BLEEDING    I10 @T6G_MB_LIB.T6G(SCH_1):PAGE365

R2531 Q_RES_0402LF-0,5%,1/16W,CHIP,CS00002JB13
     1 MB0_P12V_STBY_PWRGD @T6G_MB_LIB.T6G(SCH_1):MB0_P12V_STBY_PWRGD     I3 @T6G_MB_LIB.T6G(SCH_1):PAGE365
     2 FM_P12V_HSC_EN_R @T6G_MB_LIB.T6G(SCH_1):FM_P12V_HSC_EN_R     I3 @T6G_MB_LIB.T6G(SCH_1):PAGE365

R2565 Q_RES_0402LF-0,5%,1/16W,CHIP,CS00002JB13
     1 SMB_FRU_3V3AUX_SCL_R @T6G_MB_LIB.T6G(SCH_1):SMB_FRU_3V3AUX_SCL_R    I67 @T6G_MB_LIB.T6G(SCH_1):PAGE252
     2 SMB_FRU_3V3AUX_SCL @T6G_MB_LIB.T6G(SCH_1):SMB_FRU_3V3AUX_SCL    I67 @T6G_MB_LIB.T6G(SCH_1):PAGE252

R2566 Q_RES_0402LF-0,5%,1/16W,CHIP,CS00002JB13
     1 SMB_FRU_3V3AUX_SDA_R @T6G_MB_LIB.T6G(SCH_1):SMB_FRU_3V3AUX_SDA_R    I72 @T6G_MB_LIB.T6G(SCH_1):PAGE252
     2 SMB_FRU_3V3AUX_SDA @T6G_MB_LIB.T6G(SCH_1):SMB_FRU_3V3AUX_SDA    I72 @T6G_MB_LIB.T6G(SCH_1):PAGE252

R2585 Q_RES_0402LF-31.6K,1%,1/16W,CHIP,CS33162FB02
     1 HSC_EN @T6G_MB_LIB.T6G(SCH_1):HSC_EN    I13 @T6G_MB_LIB.T6G(SCH_1):PAGE372
     2    GND @T6G_MB_LIB.T6G(SCH_1):GND    I13 @T6G_MB_LIB.T6G(SCH_1):PAGE372

R2586 Q_RES_0402LF-0,5%,1/16W,CHIP,CS00002JB13
     1 HSC_EN @T6G_MB_LIB.T6G(SCH_1):HSC_EN    I54 @T6G_MB_LIB.T6G(SCH_1):PAGE267
     2 HSC_EN_R @T6G_MB_LIB.T6G(SCH_1):HSC_EN_R    I54 @T6G_MB_LIB.T6G(SCH_1):PAGE267

R2587 Q_RES_0402LF-1K,1%,1/16W,CHIP,CS21002FB06
     1 IRQ_HSC_FAULT_N @T6G_MB_LIB.T6G(SCH_1):IRQ_HSC_FAULT_N    I99 @T6G_MB_LIB.T6G(SCH_1):PAGE267
     2 HSC_VDD @T6G_MB_LIB.T6G(SCH_1):HSC_VDD    I99 @T6G_MB_LIB.T6G(SCH_1):PAGE267

R2588 Q_RES_0402LF-22,1%,1/16W,CHIP,CS02202FB02
     1 HSC_FAULT @T6G_MB_LIB.T6G(SCH_1):HSC_FAULT    I79 @T6G_MB_LIB.T6G(SCH_1):PAGE267
     2 IRQ_HSC_FAULT_N @T6G_MB_LIB.T6G(SCH_1):IRQ_HSC_FAULT_N    I79 @T6G_MB_LIB.T6G(SCH_1):PAGE267

R2624 Q_RES_0402LF-49.9,1%,1/16W,CHIP,CS04992FB07
     1 P12V_HSC_TEMP_E @T6G_MB_LIB.T6G(SCH_1):P12V_HSC_TEMP_E     I2 @T6G_MB_LIB.T6G(SCH_1):PAGE371
     2 P12V_HSC_TEMP_D- @T6G_MB_LIB.T6G(SCH_1):P12V_HSC_TEMP_D-     I2 @T6G_MB_LIB.T6G(SCH_1):PAGE371

R2625 Q_RES_0402LF-49.9,1%,1/16W,CHIP,CS04992FB07
     1 P12V_HSC_TEMP_R @T6G_MB_LIB.T6G(SCH_1):P12V_HSC_TEMP_R     I3 @T6G_MB_LIB.T6G(SCH_1):PAGE371
     2 P12V_HSC_TEMP_D+ @T6G_MB_LIB.T6G(SCH_1):P12V_HSC_TEMP_D+     I3 @T6G_MB_LIB.T6G(SCH_1):PAGE371

R2626 Q_RES_0402LF-0,5%,1/16W,CHIP,CS00002JB13
     1 SMB_P12V_HSC_TEMP_SCL @T6G_MB_LIB.T6G(SCH_1):SMB_P12V_HSC_TEMP_SCL    I40 @T6G_MB_LIB.T6G(SCH_1):PAGE371
     2 SMB_P12V_HSC_SCL @T6G_MB_LIB.T6G(SCH_1):SMB_P12V_HSC_SCL    I40 @T6G_MB_LIB.T6G(SCH_1):PAGE371

R2627 Q_RES_0402LF-0,5%,1/16W,CHIP,CS00002JB13
     1 SMB_P12V_HSC_TEMP_SDA @T6G_MB_LIB.T6G(SCH_1):SMB_P12V_HSC_TEMP_SDA    I39 @T6G_MB_LIB.T6G(SCH_1):PAGE371
     2 SMB_P12V_HSC_SDA @T6G_MB_LIB.T6G(SCH_1):SMB_P12V_HSC_SDA    I39 @T6G_MB_LIB.T6G(SCH_1):PAGE371

R2628 Q_RES_0402LF-0,5%,1/16W,CHIP,CS00002JB13
     1 P12V_HSC_TEMP_ALERT_N @T6G_MB_LIB.T6G(SCH_1):P12V_HSC_TEMP_ALERT_N    I10 @T6G_MB_LIB.T6G(SCH_1):PAGE371
     2 P12V_HSC_TEMP_ALERT_R_N @T6G_MB_LIB.T6G(SCH_1):P12V_HSC_TEMP_ALERT_R_N    I10 @T6G_MB_LIB.T6G(SCH_1):PAGE371

R2656 Q_RES_0402LF-100,1%,1/16W,EMPTY,CS11002FB07
     1 HGX_DETECT_N_ISO @T6G_MB_LIB.T6G(SCH_1):HGX_DETECT_N_ISO    I69 @T6G_MB_LIB.T6G(SCH_1):PAGE330
     2    GND @T6G_MB_LIB.T6G(SCH_1):GND    I69 @T6G_MB_LIB.T6G(SCH_1):PAGE330

R2659 Q_RES_0402LF-0,5%,1/16W,CHIP,CS00002JB13
     1 CLK_100M_CPU0_CLK11_R_DP @T6G_MB_LIB.T6G(SCH_1):CLK_100M_CPU0_CLK11_R_DP   I152 @T6G_MB_LIB.T6G(SCH_1):PAGE28
     2 CLK_100M_CPU0_CLK11_DP @T6G_MB_LIB.T6G(SCH_1):CLK_100M_CPU0_CLK11_DP   I152 @T6G_MB_LIB.T6G(SCH_1):PAGE28

R2660 Q_RES_0402LF-0,5%,1/16W,CHIP,CS00002JB13
     1 CLK_100M_CPU0_CLK11_R_DN @T6G_MB_LIB.T6G(SCH_1):CLK_100M_CPU0_CLK11_R_DN   I151 @T6G_MB_LIB.T6G(SCH_1):PAGE28
     2 CLK_100M_CPU0_CLK11_DN @T6G_MB_LIB.T6G(SCH_1):CLK_100M_CPU0_CLK11_DN   I151 @T6G_MB_LIB.T6G(SCH_1):PAGE28

R2663 Q_RES_0402LF-33.2,1%,1/16W,CHIP,CS03322FB03
     1 FM_SWB_PWRGD_ISO_R @T6G_MB_LIB.T6G(SCH_1):FM_SWB_PWRGD_ISO_R   I271 @T6G_MB_LIB.T6G(SCH_1):PAGE80
     2 FM_SWB_PWRGD_ISO @T6G_MB_LIB.T6G(SCH_1):FM_SWB_PWRGD_ISO   I271 @T6G_MB_LIB.T6G(SCH_1):PAGE80

R2664 Q_RES_0402LF-33.2,1%,1/16W,CHIP,CS03322FB03
     1 FM_GPU_PWRGD_ISO_R @T6G_MB_LIB.T6G(SCH_1):FM_GPU_PWRGD_ISO_R   I272 @T6G_MB_LIB.T6G(SCH_1):PAGE80
     2 FM_GPU_PWRGD_ISO @T6G_MB_LIB.T6G(SCH_1):FM_GPU_PWRGD_ISO   I272 @T6G_MB_LIB.T6G(SCH_1):PAGE80

R2666 Q_RES_0402LF-10K,1%,1/16W,CHIP,CS31002FB08
     1 SMB_BMC_SWB_EN @T6G_MB_LIB.T6G(SCH_1):SMB_BMC_SWB_EN     I8 @T6G_MB_LIB.T6G(SCH_1):PAGE249
     2    GND @T6G_MB_LIB.T6G(SCH_1):GND     I8 @T6G_MB_LIB.T6G(SCH_1):PAGE249

R2667 Q_RES_0402LF-2.2K,5%,1/16W,CHIP,CS22202JB07
     1 P3V3_AUX @T6G_MB_LIB.T6G(SCH_1):P3V3_AUX    I54 @T6G_MB_LIB.T6G(SCH_1):PAGE249
     2 SMB_BMC_SWB_BUF_R_SCL @T6G_MB_LIB.T6G(SCH_1):SMB_BMC_SWB_BUF_R_SCL    I54 @T6G_MB_LIB.T6G(SCH_1):PAGE249

R2668 Q_RES_0402LF-4.7K,5%,1/16W,EMPTY,CS24702JB10
     1 P3V3_AUX @T6G_MB_LIB.T6G(SCH_1):P3V3_AUX    I62 @T6G_MB_LIB.T6G(SCH_1):PAGE249
     2 I3C_BMC_SWB_BUF_R_SDA @T6G_MB_LIB.T6G(SCH_1):I3C_BMC_SWB_BUF_R_SDA    I62 @T6G_MB_LIB.T6G(SCH_1):PAGE249

R2669 Q_RES_0402LF-2.2K,5%,1/16W,CHIP,CS22202JB07
     1 P3V3_AUX @T6G_MB_LIB.T6G(SCH_1):P3V3_AUX    I57 @T6G_MB_LIB.T6G(SCH_1):PAGE249
     2 SMB_BMC_SWB_BUF_R_SDA @T6G_MB_LIB.T6G(SCH_1):SMB_BMC_SWB_BUF_R_SDA    I57 @T6G_MB_LIB.T6G(SCH_1):PAGE249

R2670 Q_RES_0402LF-4.7K,5%,1/16W,EMPTY,CS24702JB10
     1 P3V3_AUX @T6G_MB_LIB.T6G(SCH_1):P3V3_AUX    I63 @T6G_MB_LIB.T6G(SCH_1):PAGE249
     2 I3C_BMC_SWB_BUF_R_SCL @T6G_MB_LIB.T6G(SCH_1):I3C_BMC_SWB_BUF_R_SCL    I63 @T6G_MB_LIB.T6G(SCH_1):PAGE249

R2671 Q_RES_0402LF-33.2,1%,1/16W,CHIP,CS03322FB03
     1 SMB_BMC_SWB_BUF_R_SCL @T6G_MB_LIB.T6G(SCH_1):SMB_BMC_SWB_BUF_R_SCL    I58 @T6G_MB_LIB.T6G(SCH_1):PAGE249
     2 SMB_BMC_SWB_BUF_SCL @T6G_MB_LIB.T6G(SCH_1):SMB_BMC_SWB_BUF_SCL    I58 @T6G_MB_LIB.T6G(SCH_1):PAGE249

R2672 Q_RES_0402LF-33.2,1%,1/16W,CHIP,CS03322FB03
     1 SMB_BMC_SWB_BUF_R_SDA @T6G_MB_LIB.T6G(SCH_1):SMB_BMC_SWB_BUF_R_SDA    I56 @T6G_MB_LIB.T6G(SCH_1):PAGE249
     2 SMB_BMC_SWB_BUF_SDA @T6G_MB_LIB.T6G(SCH_1):SMB_BMC_SWB_BUF_SDA    I56 @T6G_MB_LIB.T6G(SCH_1):PAGE249

R2674 Q_RES_0402LF-27,5%,1/16W,CHIP,CS02702JB02
     1 I3C_BMC_SWB_BUF_R_SDA @T6G_MB_LIB.T6G(SCH_1):I3C_BMC_SWB_BUF_R_SDA    I86 @T6G_MB_LIB.T6G(SCH_1):PAGE249
     2 I3C_BMC_SWB_BUF_SDA @T6G_MB_LIB.T6G(SCH_1):I3C_BMC_SWB_BUF_SDA    I86 @T6G_MB_LIB.T6G(SCH_1):PAGE249

R2675 Q_RES_0402LF-33.2,1%,1/16W,CHIP,CS03322FB03
     1 I3C_BMC_SWB_BUF_R_SCL @T6G_MB_LIB.T6G(SCH_1):I3C_BMC_SWB_BUF_R_SCL    I69 @T6G_MB_LIB.T6G(SCH_1):PAGE249
     2 I3C_BMC_SWB_BUF_SCL @T6G_MB_LIB.T6G(SCH_1):I3C_BMC_SWB_BUF_SCL    I69 @T6G_MB_LIB.T6G(SCH_1):PAGE249

R2676 Q_RES_0402LF-0,5%,1/16W,CHIP,CS00002JB13
     1 SMB_BMC_SWB_EN @T6G_MB_LIB.T6G(SCH_1):SMB_BMC_SWB_EN    I26 @T6G_MB_LIB.T6G(SCH_1):PAGE249
     2 SMB_BMC_SWB_EN_R2 @T6G_MB_LIB.T6G(SCH_1):SMB_BMC_SWB_EN_R2    I26 @T6G_MB_LIB.T6G(SCH_1):PAGE249

R2693 Q_RES_0402LF-1K,1%,1/16W,EMPTY,CS21002FB06
     1 P3V3_AUX @T6G_MB_LIB.T6G(SCH_1):P3V3_AUX     I3 @T6G_MB_LIB.T6G(SCH_1):PAGE246
     2 TCA9539_0_ADD1 @T6G_MB_LIB.T6G(SCH_1):TCA9539_0_ADD1     I3 @T6G_MB_LIB.T6G(SCH_1):PAGE246

R2694 Q_RES_0402LF-1K,1%,1/16W,CHIP,CS21002FB06
     1 TCA9539_0_ADD1 @T6G_MB_LIB.T6G(SCH_1):TCA9539_0_ADD1     I2 @T6G_MB_LIB.T6G(SCH_1):PAGE246
     2    GND @T6G_MB_LIB.T6G(SCH_1):GND     I2 @T6G_MB_LIB.T6G(SCH_1):PAGE246

R2695 Q_RES_0402LF-1K,1%,1/16W,EMPTY,CS21002FB06
     1 P3V3_AUX @T6G_MB_LIB.T6G(SCH_1):P3V3_AUX     I7 @T6G_MB_LIB.T6G(SCH_1):PAGE246
     2 TCA9539_0_ADD0 @T6G_MB_LIB.T6G(SCH_1):TCA9539_0_ADD0     I7 @T6G_MB_LIB.T6G(SCH_1):PAGE246

R2696 Q_RES_0402LF-1K,1%,1/16W,CHIP,CS21002FB06
     1 TCA9539_0_ADD0 @T6G_MB_LIB.T6G(SCH_1):TCA9539_0_ADD0     I6 @T6G_MB_LIB.T6G(SCH_1):PAGE246
     2    GND @T6G_MB_LIB.T6G(SCH_1):GND     I6 @T6G_MB_LIB.T6G(SCH_1):PAGE246

R2703 Q_RES_0402LF-0,5%,1/16W,CHIP,CS00002JB13
     1 SMB_BMC_SWB_SCL_R4 @T6G_MB_LIB.T6G(SCH_1):SMB_BMC_SWB_SCL_R4    I71 @T6G_MB_LIB.T6G(SCH_1):PAGE252
     2 SMB_BMC_SWB_SCL @T6G_MB_LIB.T6G(SCH_1):SMB_BMC_SWB_SCL    I71 @T6G_MB_LIB.T6G(SCH_1):PAGE252

R2704 Q_RES_0402LF-0,5%,1/16W,CHIP,CS00002JB13
     1 SMB_BMC_SWB_SDA_R4 @T6G_MB_LIB.T6G(SCH_1):SMB_BMC_SWB_SDA_R4    I70 @T6G_MB_LIB.T6G(SCH_1):PAGE252
     2 SMB_BMC_SWB_SDA @T6G_MB_LIB.T6G(SCH_1):SMB_BMC_SWB_SDA    I70 @T6G_MB_LIB.T6G(SCH_1):PAGE252

R2705 Q_RES_0402LF-0,5%,1/16W,EMPTY,CS00002JB13
     1 SMB_BMC_SWB_R_SCL @T6G_MB_LIB.T6G(SCH_1):SMB_BMC_SWB_R_SCL    I47 @T6G_MB_LIB.T6G(SCH_1):PAGE249
     2 SMB_BMC_SWB_BUF_R_SCL @T6G_MB_LIB.T6G(SCH_1):SMB_BMC_SWB_BUF_R_SCL    I47 @T6G_MB_LIB.T6G(SCH_1):PAGE249

R2706 Q_RES_0402LF-0,5%,1/16W,CHIP,CS00002JB13
     1 I3C_BMC_SWB_R_SDA @T6G_MB_LIB.T6G(SCH_1):I3C_BMC_SWB_R_SDA    I27 @T6G_MB_LIB.T6G(SCH_1):PAGE249
     2 I3C_BMC_SWB_BUF_R_SDA @T6G_MB_LIB.T6G(SCH_1):I3C_BMC_SWB_BUF_R_SDA    I27 @T6G_MB_LIB.T6G(SCH_1):PAGE249

R2707 Q_RES_0402LF-0,5%,1/16W,CHIP,CS00002JB13
     1 SMB_BMC_SWB_EN @T6G_MB_LIB.T6G(SCH_1):SMB_BMC_SWB_EN    I45 @T6G_MB_LIB.T6G(SCH_1):PAGE249
     2 SMB_BMC_SWB_EN_R @T6G_MB_LIB.T6G(SCH_1):SMB_BMC_SWB_EN_R    I45 @T6G_MB_LIB.T6G(SCH_1):PAGE249

R2724 Q_RES_0402LF-0,5%,1/16W,EMPTY,CS00002JB13
     1 SMB_BMC_SWB_R_SDA @T6G_MB_LIB.T6G(SCH_1):SMB_BMC_SWB_R_SDA    I48 @T6G_MB_LIB.T6G(SCH_1):PAGE249
     2 SMB_BMC_SWB_BUF_R_SDA @T6G_MB_LIB.T6G(SCH_1):SMB_BMC_SWB_BUF_R_SDA    I48 @T6G_MB_LIB.T6G(SCH_1):PAGE249

R2725 Q_RES_0402LF-0,5%,1/16W,CHIP,CS00002JB13
     1 I3C_BMC_SWB_R_SCL @T6G_MB_LIB.T6G(SCH_1):I3C_BMC_SWB_R_SCL    I28 @T6G_MB_LIB.T6G(SCH_1):PAGE249
     2 I3C_BMC_SWB_BUF_R_SCL @T6G_MB_LIB.T6G(SCH_1):I3C_BMC_SWB_BUF_R_SCL    I28 @T6G_MB_LIB.T6G(SCH_1):PAGE249

R2786 Q_RES_0402LF-0,5%,1/16W,CHIP,CS00002JB13
     1 USB2_HUB_SWB_DP @T6G_MB_LIB.T6G(SCH_1):USB2_HUB_SWB_DP    I79 @T6G_MB_LIB.T6G(SCH_1):PAGE358
     2 USB2_HUB_BUF_SWB_R_DP @T6G_MB_LIB.T6G(SCH_1):USB2_HUB_BUF_SWB_R_DP    I79 @T6G_MB_LIB.T6G(SCH_1):PAGE358

R2787 Q_RES_0402LF-0,5%,1/16W,CHIP,CS00002JB13
     1 USB2_HUB_SWB_DN @T6G_MB_LIB.T6G(SCH_1):USB2_HUB_SWB_DN    I78 @T6G_MB_LIB.T6G(SCH_1):PAGE358
     2 USB2_HUB_BUF_SWB_R_DN @T6G_MB_LIB.T6G(SCH_1):USB2_HUB_BUF_SWB_R_DN    I78 @T6G_MB_LIB.T6G(SCH_1):PAGE358

R2788 Q_RES_0402LF-0,5%,1/16W,EMPTY,CS00002JB13
     1 USB2_HOST_BMC_B_BUF_DP @T6G_MB_LIB.T6G(SCH_1):USB2_HOST_BMC_B_BUF_DP    I99 @T6G_MB_LIB.T6G(SCH_1):PAGE358
     2 USB2_HUB_BUF_SWB_R_DP @T6G_MB_LIB.T6G(SCH_1):USB2_HUB_BUF_SWB_R_DP    I99 @T6G_MB_LIB.T6G(SCH_1):PAGE358

R2789 Q_RES_0402LF-0,5%,1/16W,EMPTY,CS00002JB13
     1 USB2_HOST_BMC_B_BUF_DN @T6G_MB_LIB.T6G(SCH_1):USB2_HOST_BMC_B_BUF_DN    I98 @T6G_MB_LIB.T6G(SCH_1):PAGE358
     2 USB2_HUB_BUF_SWB_R_DN @T6G_MB_LIB.T6G(SCH_1):USB2_HUB_BUF_SWB_R_DN    I98 @T6G_MB_LIB.T6G(SCH_1):PAGE358

R2790 Q_RES_0402LF-0,5%,1/16W,EMPTY,CS00002JB13
     1 USB2_HOST_BMC_B_DP @T6G_MB_LIB.T6G(SCH_1):USB2_HOST_BMC_B_DP    I96 @T6G_MB_LIB.T6G(SCH_1):PAGE358
     2 USB2_HOST_BMC_B_BUF_DP @T6G_MB_LIB.T6G(SCH_1):USB2_HOST_BMC_B_BUF_DP    I96 @T6G_MB_LIB.T6G(SCH_1):PAGE358

R2791 Q_RES_0402LF-0,5%,1/16W,EMPTY,CS00002JB13
     1 USB2_HOST_BMC_B_DN @T6G_MB_LIB.T6G(SCH_1):USB2_HOST_BMC_B_DN    I97 @T6G_MB_LIB.T6G(SCH_1):PAGE358
     2 USB2_HOST_BMC_B_BUF_DN @T6G_MB_LIB.T6G(SCH_1):USB2_HOST_BMC_B_BUF_DN    I97 @T6G_MB_LIB.T6G(SCH_1):PAGE358

R2793 Q_RES_0402LF-0,5%,1/16W,CHIP,CS00002JB13
     1 FM_PDB_BUF_EN_R_N @T6G_MB_LIB.T6G(SCH_1):FM_PDB_BUF_EN_R_N   I394 @T6G_MB_LIB.T6G(SCH_1):PAGE363
     2 FM_PDB_BUF_EN_R1_N @T6G_MB_LIB.T6G(SCH_1):FM_PDB_BUF_EN_R1_N   I394 @T6G_MB_LIB.T6G(SCH_1):PAGE363

R2794 Q_RES_0402LF-4.7K,5%,1/16W,CHIP,CS24702JB10
     1 P3V3_AUX @T6G_MB_LIB.T6G(SCH_1):P3V3_AUX   I396 @T6G_MB_LIB.T6G(SCH_1):PAGE363
     2 FM_PDB_BUF_EN_R1 @T6G_MB_LIB.T6G(SCH_1):FM_PDB_BUF_EN_R1   I396 @T6G_MB_LIB.T6G(SCH_1):PAGE363

R2796 Q_RES_0402LF-0,5%,1/16W,CHIP,CS00002JB13
     1 FM_PDB_BUF_EN_R1 @T6G_MB_LIB.T6G(SCH_1):FM_PDB_BUF_EN_R1   I420 @T6G_MB_LIB.T6G(SCH_1):PAGE363
     2 MB_PDB_SMB9_R_EN @T6G_MB_LIB.T6G(SCH_1):MB_PDB_SMB9_R_EN   I420 @T6G_MB_LIB.T6G(SCH_1):PAGE363

R2800 Q_RES_0402LF-0,5%,1/16W,EMPTY,CS00002JB13
     1 SMB_FAN_3V3AUX_R_SCL @T6G_MB_LIB.T6G(SCH_1):SMB_FAN_3V3AUX_R_SCL   I429 @T6G_MB_LIB.T6G(SCH_1):PAGE363
     2 SMB_FAN_3V3AUX_BUF_SCL @T6G_MB_LIB.T6G(SCH_1):SMB_FAN_3V3AUX_BUF_SCL   I429 @T6G_MB_LIB.T6G(SCH_1):PAGE363

R2801 Q_RES_0402LF-0,5%,1/16W,EMPTY,CS00002JB13
     1 SMB_FAN_3V3AUX_R_SDA @T6G_MB_LIB.T6G(SCH_1):SMB_FAN_3V3AUX_R_SDA   I430 @T6G_MB_LIB.T6G(SCH_1):PAGE363
     2 SMB_FAN_3V3AUX_BUF_SDA @T6G_MB_LIB.T6G(SCH_1):SMB_FAN_3V3AUX_BUF_SDA   I430 @T6G_MB_LIB.T6G(SCH_1):PAGE363

R2802 Q_RES_0402LF-0,5%,1/16W,CHIP,CS00002JB13
     1 HPDB_HSC_PWRGD_R @T6G_MB_LIB.T6G(SCH_1):HPDB_HSC_PWRGD_R   I387 @T6G_MB_LIB.T6G(SCH_1):PAGE363
     2 HPDB_HSC_PWRGD @T6G_MB_LIB.T6G(SCH_1):HPDB_HSC_PWRGD   I387 @T6G_MB_LIB.T6G(SCH_1):PAGE363

R2803 Q_RES_0402LF-0,5%,1/16W,CHIP,CS00002JB13
     1 FM_FAN_PWR_EN_R @T6G_MB_LIB.T6G(SCH_1):FM_FAN_PWR_EN_R   I388 @T6G_MB_LIB.T6G(SCH_1):PAGE363
     2 FM_FAN_PWR_EN @T6G_MB_LIB.T6G(SCH_1):FM_FAN_PWR_EN   I388 @T6G_MB_LIB.T6G(SCH_1):PAGE363

R2805 Q_RES_0402LF-4.7K,5%,1/16W,EMPTY,CS24702JB10
     1 P3V3_AUX @T6G_MB_LIB.T6G(SCH_1):P3V3_AUX   I436 @T6G_MB_LIB.T6G(SCH_1):PAGE363
     2 SMB_FAN_3V3AUX_BUF_SCL @T6G_MB_LIB.T6G(SCH_1):SMB_FAN_3V3AUX_BUF_SCL   I436 @T6G_MB_LIB.T6G(SCH_1):PAGE363

R2807 Q_RES_0402LF-4.7K,5%,1/16W,EMPTY,CS24702JB10
     1 P3V3_AUX @T6G_MB_LIB.T6G(SCH_1):P3V3_AUX   I438 @T6G_MB_LIB.T6G(SCH_1):PAGE363
     2 SMB_FAN_3V3AUX_BUF_SDA @T6G_MB_LIB.T6G(SCH_1):SMB_FAN_3V3AUX_BUF_SDA   I438 @T6G_MB_LIB.T6G(SCH_1):PAGE363

R2811 Q_RES_0402LF-33.2,1%,1/16W,CHIP,CS03322FB03
     1 SMB_FAN_3V3AUX_BUF_SCL @T6G_MB_LIB.T6G(SCH_1):SMB_FAN_3V3AUX_BUF_SCL   I425 @T6G_MB_LIB.T6G(SCH_1):PAGE363
     2 SMB_FAN_3V3AUX_BUF_R_SCL @T6G_MB_LIB.T6G(SCH_1):SMB_FAN_3V3AUX_BUF_R_SCL   I425 @T6G_MB_LIB.T6G(SCH_1):PAGE363

R2812 Q_RES_0402LF-33.2,1%,1/16W,CHIP,CS03322FB03
     1 SMB_FAN_3V3AUX_BUF_SDA @T6G_MB_LIB.T6G(SCH_1):SMB_FAN_3V3AUX_BUF_SDA   I426 @T6G_MB_LIB.T6G(SCH_1):PAGE363
     2 SMB_FAN_3V3AUX_BUF_R_SDA @T6G_MB_LIB.T6G(SCH_1):SMB_FAN_3V3AUX_BUF_R_SDA   I426 @T6G_MB_LIB.T6G(SCH_1):PAGE363

R2815 Q_RES_0402LF-100K,1%,1/16W,EMPTY,CS41002FB09
     1 P3V3_AUX @T6G_MB_LIB.T6G(SCH_1):P3V3_AUX    I68 @T6G_MB_LIB.T6G(SCH_1):PAGE256
     2 BMC_MONITER_R @T6G_MB_LIB.T6G(SCH_1):BMC_MONITER_R    I68 @T6G_MB_LIB.T6G(SCH_1):PAGE256

R2820 Q_RES_0402LF-4.7K,5%,1/16W,EMPTY,CS24702JB10
     1 P3V3_AUX @T6G_MB_LIB.T6G(SCH_1):P3V3_AUX    I78 @T6G_MB_LIB.T6G(SCH_1):PAGE256
     2 BMC_MONITER_BUF_R @T6G_MB_LIB.T6G(SCH_1):BMC_MONITER_BUF_R    I78 @T6G_MB_LIB.T6G(SCH_1):PAGE256

R2828 Q_RES_0402LF-100K,1%,1/16W,CHIP,CS41002FB09
     1 P3V3_AUX @T6G_MB_LIB.T6G(SCH_1):P3V3_AUX    I66 @T6G_MB_LIB.T6G(SCH_1):PAGE333
     2 RST_BMC_FROM_SWB_N @T6G_MB_LIB.T6G(SCH_1):RST_BMC_FROM_SWB_N    I66 @T6G_MB_LIB.T6G(SCH_1):PAGE333

R2829 Q_RES_0402LF-100K,1%,1/16W,EMPTY,CS41002FB09
     1 RST_BMC_FROM_SWB_N @T6G_MB_LIB.T6G(SCH_1):RST_BMC_FROM_SWB_N    I58 @T6G_MB_LIB.T6G(SCH_1):PAGE333
     2    GND @T6G_MB_LIB.T6G(SCH_1):GND    I58 @T6G_MB_LIB.T6G(SCH_1):PAGE333

R2830 Q_RES_0402LF-100K,1%,1/16W,CHIP,CS41002FB09
     1 P3V3_AUX @T6G_MB_LIB.T6G(SCH_1):P3V3_AUX    I68 @T6G_MB_LIB.T6G(SCH_1):PAGE333
     2 BIC_MONITER @T6G_MB_LIB.T6G(SCH_1):BIC_MONITER    I68 @T6G_MB_LIB.T6G(SCH_1):PAGE333

R2831 Q_RES_0402LF-100K,1%,1/16W,EMPTY,CS41002FB09
     1 BIC_MONITER @T6G_MB_LIB.T6G(SCH_1):BIC_MONITER    I56 @T6G_MB_LIB.T6G(SCH_1):PAGE333
     2    GND @T6G_MB_LIB.T6G(SCH_1):GND    I56 @T6G_MB_LIB.T6G(SCH_1):PAGE333

R2832 Q_RES_0402LF-100K,1%,1/16W,CHIP,CS41002FB09
     1 P3V3_AUX @T6G_MB_LIB.T6G(SCH_1):P3V3_AUX    I67 @T6G_MB_LIB.T6G(SCH_1):PAGE333
     2 FM_SWB_BIC_READY_N @T6G_MB_LIB.T6G(SCH_1):FM_SWB_BIC_READY_N    I67 @T6G_MB_LIB.T6G(SCH_1):PAGE333

R2833 Q_RES_0402LF-100K,1%,1/16W,EMPTY,CS41002FB09
     1 FM_SWB_BIC_READY_N @T6G_MB_LIB.T6G(SCH_1):FM_SWB_BIC_READY_N    I60 @T6G_MB_LIB.T6G(SCH_1):PAGE333
     2    GND @T6G_MB_LIB.T6G(SCH_1):GND    I60 @T6G_MB_LIB.T6G(SCH_1):PAGE333

R2834 Q_RES_0402LF-4.7K,5%,1/16W,CHIP,CS24702JB10
     1 P3V3_AUX @T6G_MB_LIB.T6G(SCH_1):P3V3_AUX    I18 @T6G_MB_LIB.T6G(SCH_1):PAGE333
     2 RST_BMC_FROM_SWB @T6G_MB_LIB.T6G(SCH_1):RST_BMC_FROM_SWB    I18 @T6G_MB_LIB.T6G(SCH_1):PAGE333

R2835 Q_RES_0402LF-4.7K,5%,1/16W,CHIP,CS24702JB10
     1 P3V3_AUX @T6G_MB_LIB.T6G(SCH_1):P3V3_AUX    I14 @T6G_MB_LIB.T6G(SCH_1):PAGE333
     2 BIC_MONITER_N @T6G_MB_LIB.T6G(SCH_1):BIC_MONITER_N    I14 @T6G_MB_LIB.T6G(SCH_1):PAGE333

R2836 Q_RES_0402LF-4.7K,5%,1/16W,CHIP,CS24702JB10
     1 P3V3_AUX @T6G_MB_LIB.T6G(SCH_1):P3V3_AUX    I19 @T6G_MB_LIB.T6G(SCH_1):PAGE333
     2 FM_SWB_BIC_READY @T6G_MB_LIB.T6G(SCH_1):FM_SWB_BIC_READY    I19 @T6G_MB_LIB.T6G(SCH_1):PAGE333

R2837 Q_RES_0402LF-100K,1%,1/16W,EMPTY,CS41002FB09
     1 P3V3_AUX @T6G_MB_LIB.T6G(SCH_1):P3V3_AUX    I80 @T6G_MB_LIB.T6G(SCH_1):PAGE333
     2 FM_SWB_PWRGD @T6G_MB_LIB.T6G(SCH_1):FM_SWB_PWRGD    I80 @T6G_MB_LIB.T6G(SCH_1):PAGE333

R2838 Q_RES_0402LF-100K,1%,1/16W,CHIP,CS41002FB09
     1 FM_SWB_PWRGD @T6G_MB_LIB.T6G(SCH_1):FM_SWB_PWRGD    I62 @T6G_MB_LIB.T6G(SCH_1):PAGE333
     2    GND @T6G_MB_LIB.T6G(SCH_1):GND    I62 @T6G_MB_LIB.T6G(SCH_1):PAGE333

R2841 Q_RES_0402LF-4.7K,5%,1/16W,CHIP,CS24702JB10
     1 P3V3_AUX @T6G_MB_LIB.T6G(SCH_1):P3V3_AUX    I24 @T6G_MB_LIB.T6G(SCH_1):PAGE333
     2 FM_SWB_PWRGD_N @T6G_MB_LIB.T6G(SCH_1):FM_SWB_PWRGD_N    I24 @T6G_MB_LIB.T6G(SCH_1):PAGE333

R2842 Q_RES_0402LF-4.7K,5%,1/16W,CHIP,CS24702JB10
     1 P3V3_AUX @T6G_MB_LIB.T6G(SCH_1):P3V3_AUX    I30 @T6G_MB_LIB.T6G(SCH_1):PAGE333
     2 FM_GPU_PWRGD_N @T6G_MB_LIB.T6G(SCH_1):FM_GPU_PWRGD_N    I30 @T6G_MB_LIB.T6G(SCH_1):PAGE333

R2843 Q_RES_0402LF-4.7K,1%,1/16W,CHIP,CS24702FB06
     1 P3V3_ADC @T6G_MB_LIB.T6G(SCH_1):P3V3_ADC    I20 @T6G_MB_LIB.T6G(SCH_1):PAGE369
     2    GND @T6G_MB_LIB.T6G(SCH_1):GND    I20 @T6G_MB_LIB.T6G(SCH_1):PAGE369

R2844 Q_RES_0402LF-33.2,1%,1/16W,CHIP,CS03322FB03
     1 FM_SWB_BIC_READY_ISO_R_N @T6G_MB_LIB.T6G(SCH_1):FM_SWB_BIC_READY_ISO_R_N   I263 @T6G_MB_LIB.T6G(SCH_1):PAGE80
     2 FM_SWB_BIC_READY_ISO_N @T6G_MB_LIB.T6G(SCH_1):FM_SWB_BIC_READY_ISO_N   I263 @T6G_MB_LIB.T6G(SCH_1):PAGE80

R2845 Q_RES_0402LF-33.2,1%,1/16W,CHIP,CS03322FB03
     1 BMC_MONITER_R @T6G_MB_LIB.T6G(SCH_1):BMC_MONITER_R   I293 @T6G_MB_LIB.T6G(SCH_1):PAGE80
     2 BMC_MONITER @T6G_MB_LIB.T6G(SCH_1):BMC_MONITER   I293 @T6G_MB_LIB.T6G(SCH_1):PAGE80

R2846 Q_RES_0402LF-33.2,1%,1/16W,CHIP,CS03322FB03
     1 BIC_MONITER_ISO_R @T6G_MB_LIB.T6G(SCH_1):BIC_MONITER_ISO_R   I262 @T6G_MB_LIB.T6G(SCH_1):PAGE80
     2 BIC_MONITER_ISO @T6G_MB_LIB.T6G(SCH_1):BIC_MONITER_ISO   I262 @T6G_MB_LIB.T6G(SCH_1):PAGE80

R2847 Q_RES_0402LF-33.2,1%,1/16W,CHIP,CS03322FB03
     1 RST_BMC_FROM_SWB_ISO_R_N @T6G_MB_LIB.T6G(SCH_1):RST_BMC_FROM_SWB_ISO_R_N   I266 @T6G_MB_LIB.T6G(SCH_1):PAGE80
     2 RST_BMC_FROM_SWB_ISO_N @T6G_MB_LIB.T6G(SCH_1):RST_BMC_FROM_SWB_ISO_N   I266 @T6G_MB_LIB.T6G(SCH_1):PAGE80

R2848 Q_RES_0402LF-0,5%,1/16W,CHIP,CS00002JB13
     1 RST_SWB_BIC_N @T6G_MB_LIB.T6G(SCH_1):RST_SWB_BIC_N    I59 @T6G_MB_LIB.T6G(SCH_1):PAGE246
     2 RST_SWB_BIC_R_N @T6G_MB_LIB.T6G(SCH_1):RST_SWB_BIC_R_N    I59 @T6G_MB_LIB.T6G(SCH_1):PAGE246

R2893 Q_RES_0402LF-0,5%,1/16W,EMPTY,CS00002JB13
     1 SMB_1_BMC_GPU_R_SCL @T6G_MB_LIB.T6G(SCH_1):SMB_1_BMC_GPU_R_SCL    I68 @T6G_MB_LIB.T6G(SCH_1):PAGE249
     2 SMB_1_BMC_GPU_BUF_R_SCL @T6G_MB_LIB.T6G(SCH_1):SMB_1_BMC_GPU_BUF_R_SCL    I68 @T6G_MB_LIB.T6G(SCH_1):PAGE249

R2894 Q_RES_0402LF-0,5%,1/16W,EMPTY,CS00002JB13
     1 SMB_1_BMC_GPU_R_SDA @T6G_MB_LIB.T6G(SCH_1):SMB_1_BMC_GPU_R_SDA    I67 @T6G_MB_LIB.T6G(SCH_1):PAGE249
     2 SMB_1_BMC_GPU_BUF_R_SDA @T6G_MB_LIB.T6G(SCH_1):SMB_1_BMC_GPU_BUF_R_SDA    I67 @T6G_MB_LIB.T6G(SCH_1):PAGE249

R2897 Q_RES_0402LF-33.2,1%,1/16W,CHIP,CS03322FB03
     1 SMB_1_BMC_GPU_BUF_R_SCL @T6G_MB_LIB.T6G(SCH_1):SMB_1_BMC_GPU_BUF_R_SCL    I74 @T6G_MB_LIB.T6G(SCH_1):PAGE249
     2 SMB_1_BMC_GPU_BUF_SCL @T6G_MB_LIB.T6G(SCH_1):SMB_1_BMC_GPU_BUF_SCL    I74 @T6G_MB_LIB.T6G(SCH_1):PAGE249

R2898 Q_RES_0402LF-33.2,1%,1/16W,CHIP,CS03322FB03
     1 SMB_1_BMC_GPU_BUF_R_SDA @T6G_MB_LIB.T6G(SCH_1):SMB_1_BMC_GPU_BUF_R_SDA    I73 @T6G_MB_LIB.T6G(SCH_1):PAGE249
     2 SMB_1_BMC_GPU_BUF_SDA @T6G_MB_LIB.T6G(SCH_1):SMB_1_BMC_GPU_BUF_SDA    I73 @T6G_MB_LIB.T6G(SCH_1):PAGE249

R2899 Q_RES_0402LF-0,5%,1/16W,CHIP,CS00002JB13
     1 SMB_BMC_GPU_EN @T6G_MB_LIB.T6G(SCH_1):SMB_BMC_GPU_EN    I50 @T6G_MB_LIB.T6G(SCH_1):PAGE249
     2 SMB_BMC_GPU_EN_R1 @T6G_MB_LIB.T6G(SCH_1):SMB_BMC_GPU_EN_R1    I50 @T6G_MB_LIB.T6G(SCH_1):PAGE249

R2900 Q_RES_0402LF-2K,1%,1/16W,CHIP,CS22002FB07
     1 MAX11617_VREF @T6G_MB_LIB.T6G(SCH_1):MAX11617_VREF   I160 @T6G_MB_LIB.T6G(SCH_1):PAGE369
     2 MAX11617_VREF_R @T6G_MB_LIB.T6G(SCH_1):MAX11617_VREF_R   I160 @T6G_MB_LIB.T6G(SCH_1):PAGE369

R2905 Q_RES_0402LF-0,5%,1/16W,CHIP,CS00002JB13
     1 RST_SMB_SWITCH_N @T6G_MB_LIB.T6G(SCH_1):RST_SMB_SWITCH_N   I441 @T6G_MB_LIB.T6G(SCH_1):PAGE363
     2 RST_SMB_SWITCH_R_N @T6G_MB_LIB.T6G(SCH_1):RST_SMB_SWITCH_R_N   I441 @T6G_MB_LIB.T6G(SCH_1):PAGE363

R2906 Q_RES_0402LF-0,5%,1/16W,CHIP,CS00002JB13
     1 FM_GPU_HSC_EN_BUF_R1 @T6G_MB_LIB.T6G(SCH_1):FM_GPU_HSC_EN_BUF_R1   I440 @T6G_MB_LIB.T6G(SCH_1):PAGE363
     2 FM_GPU_HSC_EN_BUF @T6G_MB_LIB.T6G(SCH_1):FM_GPU_HSC_EN_BUF   I440 @T6G_MB_LIB.T6G(SCH_1):PAGE363

R2907 Q_RES_0402LF-5.11K,1%,1/16W,CHIP,CS25112FB04
     1 P3V3_AUX @T6G_MB_LIB.T6G(SCH_1):P3V3_AUX    I28 @T6G_MB_LIB.T6G(SCH_1):PAGE369
     2 P3V3_AUX_ADC @T6G_MB_LIB.T6G(SCH_1):P3V3_AUX_ADC    I28 @T6G_MB_LIB.T6G(SCH_1):PAGE369

R2908 Q_RES_0402LF-5.11K,1%,1/16W,CHIP,CS25112FB04
     1   P3V3 @T6G_MB_LIB.T6G(SCH_1):P3V3    I21 @T6G_MB_LIB.T6G(SCH_1):PAGE369
     2 P3V3_ADC @T6G_MB_LIB.T6G(SCH_1):P3V3_ADC    I21 @T6G_MB_LIB.T6G(SCH_1):PAGE369

R2909 Q_RES_0402LF-4.7K,5%,1/16W,CHIP,CS24702JB10
     1 P3V3_AUX @T6G_MB_LIB.T6G(SCH_1):P3V3_AUX   I198 @T6G_MB_LIB.T6G(SCH_1):PAGE256
     2 RST_SWB_BIC_R_N @T6G_MB_LIB.T6G(SCH_1):RST_SWB_BIC_R_N   I198 @T6G_MB_LIB.T6G(SCH_1):PAGE256

R2910 Q_RES_0402LF-100K,1%,1/16W,EMPTY,CS41002FB09
     1 P3V3_AUX @T6G_MB_LIB.T6G(SCH_1):P3V3_AUX   I187 @T6G_MB_LIB.T6G(SCH_1):PAGE334
     2 FM_SWB_PWR_EN_R @T6G_MB_LIB.T6G(SCH_1):FM_SWB_PWR_EN_R   I187 @T6G_MB_LIB.T6G(SCH_1):PAGE334

R2911 Q_RES_0402LF-4.7K,5%,1/16W,EMPTY,CS24702JB10
     1 P3V3_AUX @T6G_MB_LIB.T6G(SCH_1):P3V3_AUX   I153 @T6G_MB_LIB.T6G(SCH_1):PAGE256
     2 RST_SWB_BIC_BUF_R_N @T6G_MB_LIB.T6G(SCH_1):RST_SWB_BIC_BUF_R_N   I153 @T6G_MB_LIB.T6G(SCH_1):PAGE256

R2912 Q_RES_0402LF-4.7K,5%,1/16W,EMPTY,CS24702JB10
     1 P3V3_AUX @T6G_MB_LIB.T6G(SCH_1):P3V3_AUX   I147 @T6G_MB_LIB.T6G(SCH_1):PAGE256
     2 FM_GPU_PWR_EN_R1 @T6G_MB_LIB.T6G(SCH_1):FM_GPU_PWR_EN_R1   I147 @T6G_MB_LIB.T6G(SCH_1):PAGE256

R2914 Q_RES_0402LF-4.7K,5%,1/16W,EMPTY,CS24702JB10
     1 P3V3_AUX @T6G_MB_LIB.T6G(SCH_1):P3V3_AUX   I192 @T6G_MB_LIB.T6G(SCH_1):PAGE334
     2 FM_SWB_PWR_EN_R1_BUF @T6G_MB_LIB.T6G(SCH_1):FM_SWB_PWR_EN_R1_BUF   I192 @T6G_MB_LIB.T6G(SCH_1):PAGE334

R2915 Q_RES_0402LF-4.7K,5%,1/16W,CHIP,CS24702JB10
     1 BMC_MONITER_R @T6G_MB_LIB.T6G(SCH_1):BMC_MONITER_R    I92 @T6G_MB_LIB.T6G(SCH_1):PAGE256
     2    GND @T6G_MB_LIB.T6G(SCH_1):GND    I92 @T6G_MB_LIB.T6G(SCH_1):PAGE256

R2916 Q_RES_0402LF-4.7K,5%,1/16W,EMPTY,CS24702JB10
     1 RST_SWB_BIC_R_N @T6G_MB_LIB.T6G(SCH_1):RST_SWB_BIC_R_N    I93 @T6G_MB_LIB.T6G(SCH_1):PAGE256
     2    GND @T6G_MB_LIB.T6G(SCH_1):GND    I93 @T6G_MB_LIB.T6G(SCH_1):PAGE256

R2917 Q_RES_0402LF-49.9,1%,1/16W,CHIP,CS04992FB07
     1 BMC_MONITER_BUF_R @T6G_MB_LIB.T6G(SCH_1):BMC_MONITER_BUF_R   I154 @T6G_MB_LIB.T6G(SCH_1):PAGE256
     2 BMC_MONITER_BUF @T6G_MB_LIB.T6G(SCH_1):BMC_MONITER_BUF   I154 @T6G_MB_LIB.T6G(SCH_1):PAGE256

R2918 Q_RES_0402LF-4.7K,5%,1/16W,CHIP,CS24702JB10
     1 FM_SWB_PWR_EN_R @T6G_MB_LIB.T6G(SCH_1):FM_SWB_PWR_EN_R   I188 @T6G_MB_LIB.T6G(SCH_1):PAGE334
     2    GND @T6G_MB_LIB.T6G(SCH_1):GND   I188 @T6G_MB_LIB.T6G(SCH_1):PAGE334

R2919 Q_RES_0402LF-100K,1%,1/16W,CHIP,CS41002FB09
     1 P3V3_AUX @T6G_MB_LIB.T6G(SCH_1):P3V3_AUX    I91 @T6G_MB_LIB.T6G(SCH_1):PAGE333
     2 RST_BMC_FROM_SWB_ISO_N @T6G_MB_LIB.T6G(SCH_1):RST_BMC_FROM_SWB_ISO_N    I91 @T6G_MB_LIB.T6G(SCH_1):PAGE333

R2920 Q_RES_0402LF-100K,1%,1/16W,CHIP,CS41002FB09
     1 P3V3_AUX @T6G_MB_LIB.T6G(SCH_1):P3V3_AUX   I177 @T6G_MB_LIB.T6G(SCH_1):PAGE333
     2 BIC_MONITER_ISO @T6G_MB_LIB.T6G(SCH_1):BIC_MONITER_ISO   I177 @T6G_MB_LIB.T6G(SCH_1):PAGE333

R2921 Q_RES_0402LF-10K,1%,1/16W,EMPTY,CS31002FB08
     1 P3V3_AUX @T6G_MB_LIB.T6G(SCH_1):P3V3_AUX    I35 @T6G_MB_LIB.T6G(SCH_1):PAGE246
     2 RST_SMB_SWITCH_N @T6G_MB_LIB.T6G(SCH_1):RST_SMB_SWITCH_N    I35 @T6G_MB_LIB.T6G(SCH_1):PAGE246

R2922 Q_RES_0402LF-0,5%,1/16W,CHIP,CS00002JB13
     1 RST_SMB_SWITCH_N @T6G_MB_LIB.T6G(SCH_1):RST_SMB_SWITCH_N    I31 @T6G_MB_LIB.T6G(SCH_1):PAGE246
     2 PU_RST_SMB_U181_N @T6G_MB_LIB.T6G(SCH_1):PU_RST_SMB_U181_N    I31 @T6G_MB_LIB.T6G(SCH_1):PAGE246

R2923 Q_RES_0402LF-4.7K,5%,1/16W,EMPTY,CS24702JB10
     1 P3V3_AUX @T6G_MB_LIB.T6G(SCH_1):P3V3_AUX    I37 @T6G_MB_LIB.T6G(SCH_1):PAGE246
     2 PU_U181_INT @T6G_MB_LIB.T6G(SCH_1):PU_U181_INT    I37 @T6G_MB_LIB.T6G(SCH_1):PAGE246

R2924 Q_RES_0402LF-49.9,1%,1/16W,CHIP,CS04992FB07
     1 RST_SWB_BIC_BUF_R_N @T6G_MB_LIB.T6G(SCH_1):RST_SWB_BIC_BUF_R_N   I155 @T6G_MB_LIB.T6G(SCH_1):PAGE256
     2 RST_SWB_BIC_BUF_N @T6G_MB_LIB.T6G(SCH_1):RST_SWB_BIC_BUF_N   I155 @T6G_MB_LIB.T6G(SCH_1):PAGE256

R2925 Q_RES_0402LF-49.9,1%,1/16W,CHIP,CS04992FB07
     1 FM_GPU_PWR_EN_R1 @T6G_MB_LIB.T6G(SCH_1):FM_GPU_PWR_EN_R1   I156 @T6G_MB_LIB.T6G(SCH_1):PAGE256
     2 FM_GPU_PWR_EN_R_BUF @T6G_MB_LIB.T6G(SCH_1):FM_GPU_PWR_EN_R_BUF   I156 @T6G_MB_LIB.T6G(SCH_1):PAGE256

R2926 Q_RES_0402LF-4.7K,5%,1/16W,CHIP,CS24702JB10
     1 BMC_MONITER_BUF_R @T6G_MB_LIB.T6G(SCH_1):BMC_MONITER_BUF_R   I121 @T6G_MB_LIB.T6G(SCH_1):PAGE256
     2    GND @T6G_MB_LIB.T6G(SCH_1):GND   I121 @T6G_MB_LIB.T6G(SCH_1):PAGE256

R2927 Q_RES_0402LF-100K,1%,1/16W,CHIP,CS41002FB09
     1 RST_SWB_BIC_BUF_R_N @T6G_MB_LIB.T6G(SCH_1):RST_SWB_BIC_BUF_R_N   I203 @T6G_MB_LIB.T6G(SCH_1):PAGE256
     2    GND @T6G_MB_LIB.T6G(SCH_1):GND   I203 @T6G_MB_LIB.T6G(SCH_1):PAGE256

R2932 Q_RES_0402LF-4.7K,5%,1/16W,CHIP,CS24702JB10
     1 FM_SWB_PWR_EN_R1_BUF @T6G_MB_LIB.T6G(SCH_1):FM_SWB_PWR_EN_R1_BUF   I195 @T6G_MB_LIB.T6G(SCH_1):PAGE334
     2    GND @T6G_MB_LIB.T6G(SCH_1):GND   I195 @T6G_MB_LIB.T6G(SCH_1):PAGE334

R2933 Q_RES_0402LF-100K,1%,1/16W,CHIP,CS41002FB09
     1 P3V3_AUX @T6G_MB_LIB.T6G(SCH_1):P3V3_AUX   I180 @T6G_MB_LIB.T6G(SCH_1):PAGE333
     2 FM_SWB_BIC_READY_ISO_N @T6G_MB_LIB.T6G(SCH_1):FM_SWB_BIC_READY_ISO_N   I180 @T6G_MB_LIB.T6G(SCH_1):PAGE333

R2934 Q_RES_0402LF-100K,1%,1/16W,CHIP,CS41002FB09
     1 P3V3_AUX @T6G_MB_LIB.T6G(SCH_1):P3V3_AUX   I101 @T6G_MB_LIB.T6G(SCH_1):PAGE333
     2 FM_SWB_PWRGD_ISO @T6G_MB_LIB.T6G(SCH_1):FM_SWB_PWRGD_ISO   I101 @T6G_MB_LIB.T6G(SCH_1):PAGE333

R2935 Q_RES_0402LF-100K,1%,1/16W,CHIP,CS41002FB09
     1 P3V3_AUX @T6G_MB_LIB.T6G(SCH_1):P3V3_AUX   I109 @T6G_MB_LIB.T6G(SCH_1):PAGE333
     2 FM_GPU_PWRGD_ISO @T6G_MB_LIB.T6G(SCH_1):FM_GPU_PWRGD_ISO   I109 @T6G_MB_LIB.T6G(SCH_1):PAGE333

R2936 Q_RES_0402LF-100K,1%,1/16W,EMPTY,CS41002FB09
     1 P3V3_AUX @T6G_MB_LIB.T6G(SCH_1):P3V3_AUX   I162 @T6G_MB_LIB.T6G(SCH_1):PAGE256
     2 FM_GPU_PWR_EN_R @T6G_MB_LIB.T6G(SCH_1):FM_GPU_PWR_EN_R   I162 @T6G_MB_LIB.T6G(SCH_1):PAGE256

R2937 Q_RES_0402LF-4.7K,5%,1/16W,CHIP,CS24702JB10
     1 FM_GPU_PWR_EN_R @T6G_MB_LIB.T6G(SCH_1):FM_GPU_PWR_EN_R   I160 @T6G_MB_LIB.T6G(SCH_1):PAGE256
     2    GND @T6G_MB_LIB.T6G(SCH_1):GND   I160 @T6G_MB_LIB.T6G(SCH_1):PAGE256

R2939 Q_RES_0402LF-33.2,1%,1/16W,CHIP,CS03322FB03
     1 FM_GPU_HSC_EN @T6G_MB_LIB.T6G(SCH_1):FM_GPU_HSC_EN   I311 @T6G_MB_LIB.T6G(SCH_1):PAGE80
     2 FM_GPU_HSC_EN_R @T6G_MB_LIB.T6G(SCH_1):FM_GPU_HSC_EN_R   I311 @T6G_MB_LIB.T6G(SCH_1):PAGE80

R2940 Q_RES_0402LF-4.7K,5%,1/16W,EMPTY,CS24702JB10
     1 P3V3_AUX @T6G_MB_LIB.T6G(SCH_1):P3V3_AUX    I28 @T6G_MB_LIB.T6G(SCH_1):PAGE364
     2 FM_GPU_HSC_EN @T6G_MB_LIB.T6G(SCH_1):FM_GPU_HSC_EN    I28 @T6G_MB_LIB.T6G(SCH_1):PAGE364

R2941 Q_RES_0402LF-100K,1%,1/16W,CHIP,CS41002FB09
     1 FM_GPU_HSC_EN @T6G_MB_LIB.T6G(SCH_1):FM_GPU_HSC_EN    I29 @T6G_MB_LIB.T6G(SCH_1):PAGE364
     2    GND @T6G_MB_LIB.T6G(SCH_1):GND    I29 @T6G_MB_LIB.T6G(SCH_1):PAGE364

R2944 Q_RES_0402LF-33.2,1%,1/16W,CHIP,CS03322FB03
     1 FM_GPU_HSC_EN_BUF_R @T6G_MB_LIB.T6G(SCH_1):FM_GPU_HSC_EN_BUF_R    I24 @T6G_MB_LIB.T6G(SCH_1):PAGE364
     2 FM_GPU_HSC_EN_BUF @T6G_MB_LIB.T6G(SCH_1):FM_GPU_HSC_EN_BUF    I24 @T6G_MB_LIB.T6G(SCH_1):PAGE364

R2946 Q_RES_0402LF-4.7K,5%,1/16W,EMPTY,CS24702JB10
     1 P3V3_AUX @T6G_MB_LIB.T6G(SCH_1):P3V3_AUX    I25 @T6G_MB_LIB.T6G(SCH_1):PAGE364
     2 FM_GPU_HSC_EN_BUF_R @T6G_MB_LIB.T6G(SCH_1):FM_GPU_HSC_EN_BUF_R    I25 @T6G_MB_LIB.T6G(SCH_1):PAGE364

R2948 Q_RES_0402LF-4.7K,5%,1/16W,EMPTY,CS24702JB10
     1 FM_GPU_HSC_EN_BUF_R @T6G_MB_LIB.T6G(SCH_1):FM_GPU_HSC_EN_BUF_R    I30 @T6G_MB_LIB.T6G(SCH_1):PAGE364
     2    GND @T6G_MB_LIB.T6G(SCH_1):GND    I30 @T6G_MB_LIB.T6G(SCH_1):PAGE364

R2950 Q_RES_0402LF-1K,1%,1/16W,CHIP,CS21002FB06
     1 P3V3_AUX @T6G_MB_LIB.T6G(SCH_1):P3V3_AUX   I475 @T6G_MB_LIB.T6G(SCH_1):PAGE363
     2 FM_PDB_BUF_EN_R1_N @T6G_MB_LIB.T6G(SCH_1):FM_PDB_BUF_EN_R1_N   I475 @T6G_MB_LIB.T6G(SCH_1):PAGE363

R2967 Q_RES_0402LF-0,5%,1/16W,CHIP,CS00002JB13
     1 SMB_PCIE0_3V3AUX_SCL_R3 @T6G_MB_LIB.T6G(SCH_1):SMB_PCIE0_3V3AUX_SCL_R3    I25 @T6G_MB_LIB.T6G(SCH_1):PAGE252
     2 SMB_SENSOR_M2_P1_3V3AUX_SCL @T6G_MB_LIB.T6G(SCH_1):SMB_SENSOR_M2_P1_3V3AUX_SCL    I25 @T6G_MB_LIB.T6G(SCH_1):PAGE252

R2968 Q_RES_0402LF-0,5%,1/16W,CHIP,CS00002JB13
     1 SMB_PCIE0_3V3AUX_SDA_R3 @T6G_MB_LIB.T6G(SCH_1):SMB_PCIE0_3V3AUX_SDA_R3    I26 @T6G_MB_LIB.T6G(SCH_1):PAGE252
     2 SMB_SENSOR_M2_P1_3V3AUX_SDA @T6G_MB_LIB.T6G(SCH_1):SMB_SENSOR_M2_P1_3V3AUX_SDA    I26 @T6G_MB_LIB.T6G(SCH_1):PAGE252

R2982 Q_RES_0402LF-0,5%,1/16W,CHIP,CS00002JB13
     1 SMB_IOEXP_3V3AUX_SCL @T6G_MB_LIB.T6G(SCH_1):SMB_IOEXP_3V3AUX_SCL    I82 @T6G_MB_LIB.T6G(SCH_1):PAGE246
     2 SMB_IOEXP_3V3AUX_SCL_R1 @T6G_MB_LIB.T6G(SCH_1):SMB_IOEXP_3V3AUX_SCL_R1    I82 @T6G_MB_LIB.T6G(SCH_1):PAGE246

R2983 Q_RES_0402LF-0,5%,1/16W,CHIP,CS00002JB13
     1 SMB_IOEXP_3V3AUX_SDA @T6G_MB_LIB.T6G(SCH_1):SMB_IOEXP_3V3AUX_SDA    I58 @T6G_MB_LIB.T6G(SCH_1):PAGE246
     2 SMB_IOEXP_3V3AUX_SDA_R1 @T6G_MB_LIB.T6G(SCH_1):SMB_IOEXP_3V3AUX_SDA_R1    I58 @T6G_MB_LIB.T6G(SCH_1):PAGE246

R2984 Q_RES_0402LF-2.2K,5%,1/16W,CHIP,CS22202JB07
     1 P3V3_AUX @T6G_MB_LIB.T6G(SCH_1):P3V3_AUX    I41 @T6G_MB_LIB.T6G(SCH_1):PAGE252
     2 SMB_BMC_SWB_SCL @T6G_MB_LIB.T6G(SCH_1):SMB_BMC_SWB_SCL    I41 @T6G_MB_LIB.T6G(SCH_1):PAGE252

R2985 Q_RES_0402LF-2.2K,5%,1/16W,CHIP,CS22202JB07
     1 P3V3_AUX @T6G_MB_LIB.T6G(SCH_1):P3V3_AUX    I42 @T6G_MB_LIB.T6G(SCH_1):PAGE252
     2 SMB_BMC_SWB_SDA @T6G_MB_LIB.T6G(SCH_1):SMB_BMC_SWB_SDA    I42 @T6G_MB_LIB.T6G(SCH_1):PAGE252

R2986 Q_RES_0402LF-0,5%,1/16W,EMPTY,CS00002JB13
     1 SMB_2_BMC_GPU_R_SCL @T6G_MB_LIB.T6G(SCH_1):SMB_2_BMC_GPU_R_SCL    I18 @T6G_MB_LIB.T6G(SCH_1):PAGE249
     2 SMB_2_BMC_GPU_BUF_R_SCL @T6G_MB_LIB.T6G(SCH_1):SMB_2_BMC_GPU_BUF_R_SCL    I18 @T6G_MB_LIB.T6G(SCH_1):PAGE249

R2987 Q_RES_0402LF-0,5%,1/16W,EMPTY,CS00002JB13
     1 SMB_2_BMC_GPU_R_SDA @T6G_MB_LIB.T6G(SCH_1):SMB_2_BMC_GPU_R_SDA    I17 @T6G_MB_LIB.T6G(SCH_1):PAGE249
     2 SMB_2_BMC_GPU_BUF_R_SDA @T6G_MB_LIB.T6G(SCH_1):SMB_2_BMC_GPU_BUF_R_SDA    I17 @T6G_MB_LIB.T6G(SCH_1):PAGE249

R2990 Q_RES_0402LF-33.2,1%,1/16W,CHIP,CS03322FB03
     1 SMB_2_BMC_GPU_BUF_R_SCL @T6G_MB_LIB.T6G(SCH_1):SMB_2_BMC_GPU_BUF_R_SCL    I38 @T6G_MB_LIB.T6G(SCH_1):PAGE249
     2 SMB_2_BMC_GPU_BUF_SCL @T6G_MB_LIB.T6G(SCH_1):SMB_2_BMC_GPU_BUF_SCL    I38 @T6G_MB_LIB.T6G(SCH_1):PAGE249

R2991 Q_RES_0402LF-33.2,1%,1/16W,CHIP,CS03322FB03
     1 SMB_2_BMC_GPU_BUF_R_SDA @T6G_MB_LIB.T6G(SCH_1):SMB_2_BMC_GPU_BUF_R_SDA    I39 @T6G_MB_LIB.T6G(SCH_1):PAGE249
     2 SMB_2_BMC_GPU_BUF_SDA @T6G_MB_LIB.T6G(SCH_1):SMB_2_BMC_GPU_BUF_SDA    I39 @T6G_MB_LIB.T6G(SCH_1):PAGE249

R2992 Q_RES_0402LF-0,5%,1/16W,CHIP,CS00002JB13
     1 SMB_BMC_GPU_EN @T6G_MB_LIB.T6G(SCH_1):SMB_BMC_GPU_EN    I12 @T6G_MB_LIB.T6G(SCH_1):PAGE249
     2 SMB_BMC_GPU_EN_R3 @T6G_MB_LIB.T6G(SCH_1):SMB_BMC_GPU_EN_R3    I12 @T6G_MB_LIB.T6G(SCH_1):PAGE249

R2995 Q_RES_0402LF-33.2,1%,1/16W,CHIP,CS03322FB03
     1 SMB_PMBUS_3V3AUX_SCL @T6G_MB_LIB.T6G(SCH_1):SMB_PMBUS_3V3AUX_SCL    I91 @T6G_MB_LIB.T6G(SCH_1):PAGE349
     2 SMB_SML1_PMBUS_HSC_SCL @T6G_MB_LIB.T6G(SCH_1):SMB_SML1_PMBUS_HSC_SCL    I91 @T6G_MB_LIB.T6G(SCH_1):PAGE349

R2996 Q_RES_0402LF-33.2,1%,1/16W,CHIP,CS03322FB03
     1 SMB_PMBUS_3V3AUX_SDA @T6G_MB_LIB.T6G(SCH_1):SMB_PMBUS_3V3AUX_SDA    I92 @T6G_MB_LIB.T6G(SCH_1):PAGE349
     2 SMB_SML1_PMBUS_HSC_SDA @T6G_MB_LIB.T6G(SCH_1):SMB_SML1_PMBUS_HSC_SDA    I92 @T6G_MB_LIB.T6G(SCH_1):PAGE349

R2999 Q_RES_0402LF-2.2K,5%,1/16W,EMPTY,CS22202JB07
     1 SMB_2_BMC_GPU_SCL @T6G_MB_LIB.T6G(SCH_1):SMB_2_BMC_GPU_SCL   I124 @T6G_MB_LIB.T6G(SCH_1):PAGE349
     2 P3V3_AUX @T6G_MB_LIB.T6G(SCH_1):P3V3_AUX   I124 @T6G_MB_LIB.T6G(SCH_1):PAGE349

R3004 Q_RES_0402LF-2.2K,5%,1/16W,EMPTY,CS22202JB07
     1 SMB_2_BMC_GPU_SDA @T6G_MB_LIB.T6G(SCH_1):SMB_2_BMC_GPU_SDA   I123 @T6G_MB_LIB.T6G(SCH_1):PAGE349
     2 P3V3_AUX @T6G_MB_LIB.T6G(SCH_1):P3V3_AUX   I123 @T6G_MB_LIB.T6G(SCH_1):PAGE349

R3005 Q_RES_0402LF-18K,1%,1/16W,CHIP,CS31802FB04
     1    P5V @T6G_MB_LIB.T6G(SCH_1):P5V    I15 @T6G_MB_LIB.T6G(SCH_1):PAGE369
     2 P5V_ADC @T6G_MB_LIB.T6G(SCH_1):P5V_ADC    I15 @T6G_MB_LIB.T6G(SCH_1):PAGE369

R3028 Q_RES_0402LF-100K,1%,1/16W,EMPTY,CS41002FB09
     1 FM_SMB_1_ALERT_GPU_N @T6G_MB_LIB.T6G(SCH_1):FM_SMB_1_ALERT_GPU_N   I139 @T6G_MB_LIB.T6G(SCH_1):PAGE333
     2    GND @T6G_MB_LIB.T6G(SCH_1):GND   I139 @T6G_MB_LIB.T6G(SCH_1):PAGE333

R3029 Q_RES_0402LF-4.7K,5%,1/16W,CHIP,CS24702JB10
     1 P3V3_AUX @T6G_MB_LIB.T6G(SCH_1):P3V3_AUX   I144 @T6G_MB_LIB.T6G(SCH_1):PAGE333
     2 FM_SMB_1_ALERT_GPU @T6G_MB_LIB.T6G(SCH_1):FM_SMB_1_ALERT_GPU   I144 @T6G_MB_LIB.T6G(SCH_1):PAGE333

R3030 Q_RES_0402LF-100K,1%,1/16W,CHIP,CS41002FB09
     1 P3V3_AUX @T6G_MB_LIB.T6G(SCH_1):P3V3_AUX   I178 @T6G_MB_LIB.T6G(SCH_1):PAGE333
     2 FM_SMB_1_ALERT_GPU_ISO_N @T6G_MB_LIB.T6G(SCH_1):FM_SMB_1_ALERT_GPU_ISO_N   I178 @T6G_MB_LIB.T6G(SCH_1):PAGE333

R3032 Q_RES_0402LF-100K,1%,1/16W,EMPTY,CS41002FB09
     1 FM_SMB_2_ALERT_GPU_N @T6G_MB_LIB.T6G(SCH_1):FM_SMB_2_ALERT_GPU_N   I134 @T6G_MB_LIB.T6G(SCH_1):PAGE333
     2    GND @T6G_MB_LIB.T6G(SCH_1):GND   I134 @T6G_MB_LIB.T6G(SCH_1):PAGE333

R3033 Q_RES_0402LF-0,5%,1/16W,CHIP,CS00002JB13
     1 UART_BMC_BIC_RX @T6G_MB_LIB.T6G(SCH_1):UART_BMC_BIC_RX   I170 @T6G_MB_LIB.T6G(SCH_1):PAGE256
     2 UART_BMC_BIC_R_RX @T6G_MB_LIB.T6G(SCH_1):UART_BMC_BIC_R_RX   I170 @T6G_MB_LIB.T6G(SCH_1):PAGE256

R3034 Q_RES_0402LF-4.7K,5%,1/16W,CHIP,CS24702JB10
     1 P3V3_AUX @T6G_MB_LIB.T6G(SCH_1):P3V3_AUX   I129 @T6G_MB_LIB.T6G(SCH_1):PAGE333
     2 FM_SMB_2_ALERT_GPU @T6G_MB_LIB.T6G(SCH_1):FM_SMB_2_ALERT_GPU   I129 @T6G_MB_LIB.T6G(SCH_1):PAGE333

R3035 Q_RES_0402LF-100K,1%,1/16W,CHIP,CS41002FB09
     1 P3V3_AUX @T6G_MB_LIB.T6G(SCH_1):P3V3_AUX   I179 @T6G_MB_LIB.T6G(SCH_1):PAGE333
     2 FM_SMB_2_ALERT_GPU_ISO_N @T6G_MB_LIB.T6G(SCH_1):FM_SMB_2_ALERT_GPU_ISO_N   I179 @T6G_MB_LIB.T6G(SCH_1):PAGE333

R3036 Q_RES_0402LF-33.2,1%,1/16W,CHIP,CS03322FB03
     1 UART_BMC_BIC_R_BUF_RX @T6G_MB_LIB.T6G(SCH_1):UART_BMC_BIC_R_BUF_RX   I197 @T6G_MB_LIB.T6G(SCH_1):PAGE256
     2 UART_BMC_BIC_BUF_RX @T6G_MB_LIB.T6G(SCH_1):UART_BMC_BIC_BUF_RX   I197 @T6G_MB_LIB.T6G(SCH_1):PAGE256

R3047 Q_RES_0402LF-0,5%,1/16W,CHIP,CS00002JB13
     1 MB0_P12V_STBY_PWRGD @T6G_MB_LIB.T6G(SCH_1):MB0_P12V_STBY_PWRGD     I8 @T6G_MB_LIB.T6G(SCH_1):PAGE368
     2 PWRGD_PS_PWROK_PLD @T6G_MB_LIB.T6G(SCH_1):PWRGD_PS_PWROK_PLD     I8 @T6G_MB_LIB.T6G(SCH_1):PAGE368

R3048 Q_RES_0402LF-0,5%,1/16W,CHIP,CS00002JB13
     1 MB0_P12V_STBY_PWRGD @T6G_MB_LIB.T6G(SCH_1):MB0_P12V_STBY_PWRGD     I7 @T6G_MB_LIB.T6G(SCH_1):PAGE368
     2 PWRGD_PS_PWROK @T6G_MB_LIB.T6G(SCH_1):PWRGD_PS_PWROK     I7 @T6G_MB_LIB.T6G(SCH_1):PAGE368

R3062 Q_RES_0402LF-2K,1%,1/16W,EMPTY,CS22002FB07
     1 SMB_CPU0_CPU1_APML_SDA @T6G_MB_LIB.T6G(SCH_1):SMB_CPU0_CPU1_APML_SDA   I137 @T6G_MB_LIB.T6G(SCH_1):PAGE349
     2 P3V3_AUX @T6G_MB_LIB.T6G(SCH_1):P3V3_AUX   I137 @T6G_MB_LIB.T6G(SCH_1):PAGE349

R3063 Q_RES_0402LF-0,5%,1/16W,CHIP,CS00002JB13
     1 FM_PDB_BUF_EN_R1 @T6G_MB_LIB.T6G(SCH_1):FM_PDB_BUF_EN_R1   I171 @T6G_MB_LIB.T6G(SCH_1):PAGE256
     2 FM_UART_EN @T6G_MB_LIB.T6G(SCH_1):FM_UART_EN   I171 @T6G_MB_LIB.T6G(SCH_1):PAGE256

R3066 Q_RES_0402LF-33.2,1%,1/16W,CHIP,CS03322FB03
     1 FM_SMB_1_ALERT_GPU_ISO_R_N @T6G_MB_LIB.T6G(SCH_1):FM_SMB_1_ALERT_GPU_ISO_R_N   I268 @T6G_MB_LIB.T6G(SCH_1):PAGE80
     2 FM_SMB_1_ALERT_GPU_ISO_N @T6G_MB_LIB.T6G(SCH_1):FM_SMB_1_ALERT_GPU_ISO_N   I268 @T6G_MB_LIB.T6G(SCH_1):PAGE80

R3069 Q_RES_0402LF-130,1%,1/16W,CHIP,CS11302FB03
     1 LED_PWRGD_SYS_PWROK_R @T6G_MB_LIB.T6G(SCH_1):LED_PWRGD_SYS_PWROK_R    I32 @T6G_MB_LIB.T6G(SCH_1):PAGE254
     2 P3V3_AUX @T6G_MB_LIB.T6G(SCH_1):P3V3_AUX    I32 @T6G_MB_LIB.T6G(SCH_1):PAGE254

R3071 Q_RES_0402LF-130,1%,1/16W,CHIP,CS11302FB03
     1 LED_PWRGD_P1V8_AUX @T6G_MB_LIB.T6G(SCH_1):LED_PWRGD_P1V8_AUX    I21 @T6G_MB_LIB.T6G(SCH_1):PAGE254
     2 P3V3_AUX @T6G_MB_LIB.T6G(SCH_1):P3V3_AUX    I21 @T6G_MB_LIB.T6G(SCH_1):PAGE254

R3074 Q_RES_0402LF-130,1%,1/16W,CHIP,CS11302FB03
     1 LED_RST_RSMRST_PLD_R_N @T6G_MB_LIB.T6G(SCH_1):LED_RST_RSMRST_PLD_R_N    I41 @T6G_MB_LIB.T6G(SCH_1):PAGE254
     2 P3V3_AUX @T6G_MB_LIB.T6G(SCH_1):P3V3_AUX    I41 @T6G_MB_LIB.T6G(SCH_1):PAGE254

R3075 Q_RES_0402LF-130,1%,1/16W,CHIP,CS11302FB03
     1 LED_PWRGD_PS_PWROK_PLD @T6G_MB_LIB.T6G(SCH_1):LED_PWRGD_PS_PWROK_PLD    I15 @T6G_MB_LIB.T6G(SCH_1):PAGE254
     2 P3V3_AUX @T6G_MB_LIB.T6G(SCH_1):P3V3_AUX    I15 @T6G_MB_LIB.T6G(SCH_1):PAGE254

R3086 Q_RES_0402LF-130,1%,1/16W,CHIP,CS11302FB03
     1 LED_PWRGD_PVDD33_S5_R @T6G_MB_LIB.T6G(SCH_1):LED_PWRGD_PVDD33_S5_R    I20 @T6G_MB_LIB.T6G(SCH_1):PAGE374
     2 P3V3_AUX @T6G_MB_LIB.T6G(SCH_1):P3V3_AUX    I20 @T6G_MB_LIB.T6G(SCH_1):PAGE374

R3087 Q_RES_0402LF-130,1%,1/16W,CHIP,CS11302FB03
     1 LED_PWRGD_PVDDCR_CPU0_P0_R @T6G_MB_LIB.T6G(SCH_1):LED_PWRGD_PVDDCR_CPU0_P0_R    I16 @T6G_MB_LIB.T6G(SCH_1):PAGE374
     2 P3V3_AUX @T6G_MB_LIB.T6G(SCH_1):P3V3_AUX    I16 @T6G_MB_LIB.T6G(SCH_1):PAGE374

R3088 Q_RES_0402LF-130,1%,1/16W,CHIP,CS11302FB03
     1 LED_PWRGD_PVDDCR_CPU1_P0_R @T6G_MB_LIB.T6G(SCH_1):LED_PWRGD_PVDDCR_CPU1_P0_R    I12 @T6G_MB_LIB.T6G(SCH_1):PAGE374
     2 P3V3_AUX @T6G_MB_LIB.T6G(SCH_1):P3V3_AUX    I12 @T6G_MB_LIB.T6G(SCH_1):PAGE374

R3089 Q_RES_0402LF-130,1%,1/16W,CHIP,CS11302FB03
     1 LED_PWRGD_PVDDCR_SOC_P0_R @T6G_MB_LIB.T6G(SCH_1):LED_PWRGD_PVDDCR_SOC_P0_R    I15 @T6G_MB_LIB.T6G(SCH_1):PAGE374
     2 P3V3_AUX @T6G_MB_LIB.T6G(SCH_1):P3V3_AUX    I15 @T6G_MB_LIB.T6G(SCH_1):PAGE374

R3090 Q_RES_0402LF-130,1%,1/16W,CHIP,CS11302FB03
     1 LED_PWRGD_PVDD11_S3_P0_R @T6G_MB_LIB.T6G(SCH_1):LED_PWRGD_PVDD11_S3_P0_R    I38 @T6G_MB_LIB.T6G(SCH_1):PAGE374
     2 P3V3_AUX @T6G_MB_LIB.T6G(SCH_1):P3V3_AUX    I38 @T6G_MB_LIB.T6G(SCH_1):PAGE374

R3091 Q_RES_0402LF-130,1%,1/16W,CHIP,CS11302FB03
     1 LED_PWRGD_PVDD18_S5_P0_R @T6G_MB_LIB.T6G(SCH_1):LED_PWRGD_PVDD18_S5_P0_R    I37 @T6G_MB_LIB.T6G(SCH_1):PAGE374
     2 P3V3_AUX @T6G_MB_LIB.T6G(SCH_1):P3V3_AUX    I37 @T6G_MB_LIB.T6G(SCH_1):PAGE374

R3092 Q_RES_0402LF-130,1%,1/16W,CHIP,CS11302FB03
     1 LED_PWRGD_PVDDIO_P0_R @T6G_MB_LIB.T6G(SCH_1):LED_PWRGD_PVDDIO_P0_R    I41 @T6G_MB_LIB.T6G(SCH_1):PAGE374
     2 P3V3_AUX @T6G_MB_LIB.T6G(SCH_1):P3V3_AUX    I41 @T6G_MB_LIB.T6G(SCH_1):PAGE374

R3093 Q_RES_0402LF-130,1%,1/16W,CHIP,CS11302FB03
     1 LED_PWRGD_PVDDCR_CPU0_P1_R @T6G_MB_LIB.T6G(SCH_1):LED_PWRGD_PVDDCR_CPU0_P1_R    I20 @T6G_MB_LIB.T6G(SCH_1):PAGE375
     2 P3V3_AUX @T6G_MB_LIB.T6G(SCH_1):P3V3_AUX    I20 @T6G_MB_LIB.T6G(SCH_1):PAGE375

R3094 Q_RES_0402LF-130,1%,1/16W,CHIP,CS11302FB03
     1 LED_PWRGD_PVDDCR_SOC_P1_R @T6G_MB_LIB.T6G(SCH_1):LED_PWRGD_PVDDCR_SOC_P1_R    I18 @T6G_MB_LIB.T6G(SCH_1):PAGE375
     2 P3V3_AUX @T6G_MB_LIB.T6G(SCH_1):P3V3_AUX    I18 @T6G_MB_LIB.T6G(SCH_1):PAGE375

R3095 Q_RES_0402LF-130,1%,1/16W,CHIP,CS11302FB03
     1 LED_PWRGD_PVDDIO_P1_R @T6G_MB_LIB.T6G(SCH_1):LED_PWRGD_PVDDIO_P1_R    I15 @T6G_MB_LIB.T6G(SCH_1):PAGE375
     2 P3V3_AUX @T6G_MB_LIB.T6G(SCH_1):P3V3_AUX    I15 @T6G_MB_LIB.T6G(SCH_1):PAGE375

R3096 Q_RES_0402LF-130,1%,1/16W,CHIP,CS11302FB03
     1 LED_PWRGD_PVDDCR_CPU1_P1_R @T6G_MB_LIB.T6G(SCH_1):LED_PWRGD_PVDDCR_CPU1_P1_R    I16 @T6G_MB_LIB.T6G(SCH_1):PAGE375
     2 P3V3_AUX @T6G_MB_LIB.T6G(SCH_1):P3V3_AUX    I16 @T6G_MB_LIB.T6G(SCH_1):PAGE375

R3097 Q_RES_0402LF-130,1%,1/16W,CHIP,CS11302FB03
     1 LED_PWRGD_PVDD18_S5_P1_R @T6G_MB_LIB.T6G(SCH_1):LED_PWRGD_PVDD18_S5_P1_R    I38 @T6G_MB_LIB.T6G(SCH_1):PAGE375
     2 P3V3_AUX @T6G_MB_LIB.T6G(SCH_1):P3V3_AUX    I38 @T6G_MB_LIB.T6G(SCH_1):PAGE375

R3099 Q_RES_0402LF-130,1%,1/16W,CHIP,CS11302FB03
     1 LED_PWRGD_PVDD11_S3_P1_R @T6G_MB_LIB.T6G(SCH_1):LED_PWRGD_PVDD11_S3_P1_R    I40 @T6G_MB_LIB.T6G(SCH_1):PAGE375
     2 P3V3_AUX @T6G_MB_LIB.T6G(SCH_1):P3V3_AUX    I40 @T6G_MB_LIB.T6G(SCH_1):PAGE375

R3100 Q_RES_0402LF-130,1%,1/16W,CHIP,CS11302FB03
     1 LED_P3V3 @T6G_MB_LIB.T6G(SCH_1):LED_P3V3     I8 @T6G_MB_LIB.T6G(SCH_1):PAGE254
     2   P3V3 @T6G_MB_LIB.T6G(SCH_1):P3V3     I8 @T6G_MB_LIB.T6G(SCH_1):PAGE254

R3102 Q_RES_0402LF-470,1%,1/16W,CHIP,CS14702FB04
     1 LED_P5V @T6G_MB_LIB.T6G(SCH_1):LED_P5V     I9 @T6G_MB_LIB.T6G(SCH_1):PAGE254
     2    P5V @T6G_MB_LIB.T6G(SCH_1):P5V     I9 @T6G_MB_LIB.T6G(SCH_1):PAGE254

R3105 Q_RES_0402LF-0,5%,1/16W,CHIP,CS00002JB13
     1 SMB_BMC_SWB_SCL @T6G_MB_LIB.T6G(SCH_1):SMB_BMC_SWB_SCL    I44 @T6G_MB_LIB.T6G(SCH_1):PAGE249
     2 SMB_BMC_SWB_R_SCL @T6G_MB_LIB.T6G(SCH_1):SMB_BMC_SWB_R_SCL    I44 @T6G_MB_LIB.T6G(SCH_1):PAGE249

R3106 Q_RES_0402LF-0,5%,1/16W,CHIP,CS00002JB13
     1 SMB_BMC_SWB_SDA @T6G_MB_LIB.T6G(SCH_1):SMB_BMC_SWB_SDA    I43 @T6G_MB_LIB.T6G(SCH_1):PAGE249
     2 SMB_BMC_SWB_R_SDA @T6G_MB_LIB.T6G(SCH_1):SMB_BMC_SWB_R_SDA    I43 @T6G_MB_LIB.T6G(SCH_1):PAGE249

R3107 Q_RES_0402LF-0,5%,1/16W,CHIP,CS00002JB13
     1 SMB_2_BMC_GPU_SCL @T6G_MB_LIB.T6G(SCH_1):SMB_2_BMC_GPU_SCL    I13 @T6G_MB_LIB.T6G(SCH_1):PAGE249
     2 SMB_2_BMC_GPU_R_SCL @T6G_MB_LIB.T6G(SCH_1):SMB_2_BMC_GPU_R_SCL    I13 @T6G_MB_LIB.T6G(SCH_1):PAGE249

R3108 Q_RES_0402LF-0,5%,1/16W,CHIP,CS00002JB13
     1 SMB_2_BMC_GPU_SDA @T6G_MB_LIB.T6G(SCH_1):SMB_2_BMC_GPU_SDA    I14 @T6G_MB_LIB.T6G(SCH_1):PAGE249
     2 SMB_2_BMC_GPU_R_SDA @T6G_MB_LIB.T6G(SCH_1):SMB_2_BMC_GPU_R_SDA    I14 @T6G_MB_LIB.T6G(SCH_1):PAGE249

R3109 Q_RES_0402LF-0,5%,1/16W,CHIP,CS00002JB13
     1 SMB_1_BMC_GPU_SCL @T6G_MB_LIB.T6G(SCH_1):SMB_1_BMC_GPU_SCL    I35 @T6G_MB_LIB.T6G(SCH_1):PAGE249
     2 SMB_1_BMC_GPU_R_SCL @T6G_MB_LIB.T6G(SCH_1):SMB_1_BMC_GPU_R_SCL    I35 @T6G_MB_LIB.T6G(SCH_1):PAGE249

R3110 Q_RES_0402LF-0,5%,1/16W,CHIP,CS00002JB13
     1 SMB_1_BMC_GPU_SDA @T6G_MB_LIB.T6G(SCH_1):SMB_1_BMC_GPU_SDA    I34 @T6G_MB_LIB.T6G(SCH_1):PAGE249
     2 SMB_1_BMC_GPU_R_SDA @T6G_MB_LIB.T6G(SCH_1):SMB_1_BMC_GPU_R_SDA    I34 @T6G_MB_LIB.T6G(SCH_1):PAGE249

R3111 Q_RES_0402LF-0,5%,1/16W,CHIP,CS00002JB13
     1 I3C_BMC_SWB_SDA @T6G_MB_LIB.T6G(SCH_1):I3C_BMC_SWB_SDA    I85 @T6G_MB_LIB.T6G(SCH_1):PAGE249
     2 I3C_BMC_SWB_R_SDA @T6G_MB_LIB.T6G(SCH_1):I3C_BMC_SWB_R_SDA    I85 @T6G_MB_LIB.T6G(SCH_1):PAGE249

R3112 Q_RES_0402LF-33.2,1%,1/16W,CHIP,CS03322FB03
     1 I3C_BMC_SWB_SCL @T6G_MB_LIB.T6G(SCH_1):I3C_BMC_SWB_SCL    I25 @T6G_MB_LIB.T6G(SCH_1):PAGE249
     2 I3C_BMC_SWB_R_SCL @T6G_MB_LIB.T6G(SCH_1):I3C_BMC_SWB_R_SCL    I25 @T6G_MB_LIB.T6G(SCH_1):PAGE249

R3113 Q_RES_0402LF-33.2,1%,1/16W,CHIP,CS03322FB03
     1 SMB_FAN_3V3AUX_SCL @T6G_MB_LIB.T6G(SCH_1):SMB_FAN_3V3AUX_SCL   I463 @T6G_MB_LIB.T6G(SCH_1):PAGE363
     2 SMB_FAN_3V3AUX_R_SCL @T6G_MB_LIB.T6G(SCH_1):SMB_FAN_3V3AUX_R_SCL   I463 @T6G_MB_LIB.T6G(SCH_1):PAGE363

R3114 Q_RES_0402LF-33.2,1%,1/16W,CHIP,CS03322FB03
     1 SMB_FAN_3V3AUX_SDA @T6G_MB_LIB.T6G(SCH_1):SMB_FAN_3V3AUX_SDA   I464 @T6G_MB_LIB.T6G(SCH_1):PAGE363
     2 SMB_FAN_3V3AUX_R_SDA @T6G_MB_LIB.T6G(SCH_1):SMB_FAN_3V3AUX_R_SDA   I464 @T6G_MB_LIB.T6G(SCH_1):PAGE363

R3117 Q_RES_0402LF-510K,5%,1/16W,EMPTY,CS45102JB03
     1 P12V_AUX @T6G_MB_LIB.T6G(SCH_1):P12V_AUX     I4 @T6G_MB_LIB.T6G(SCH_1):PAGE245
     2 P3V3_AUX_EN @T6G_MB_LIB.T6G(SCH_1):P3V3_AUX_EN     I4 @T6G_MB_LIB.T6G(SCH_1):PAGE245

R3118 Q_RES_0402LF-86.6K,1%,1/16W,EMPTY,CS38662FB05
     1 P3V3_AUX_EN @T6G_MB_LIB.T6G(SCH_1):P3V3_AUX_EN     I2 @T6G_MB_LIB.T6G(SCH_1):PAGE245
     2    GND @T6G_MB_LIB.T6G(SCH_1):GND     I2 @T6G_MB_LIB.T6G(SCH_1):PAGE245

R3132 Q_RES_0402LF-100K,1%,1/16W,CHIP,CS41002FB09
     1    GND @T6G_MB_LIB.T6G(SCH_1):GND     I6 @T6G_MB_LIB.T6G(SCH_1):PAGE335
     2 FM_OCP_SFF_PWR_GOOD @T6G_MB_LIB.T6G(SCH_1):FM_OCP_SFF_PWR_GOOD     I6 @T6G_MB_LIB.T6G(SCH_1):PAGE335

R3133 Q_RES_0402LF-1K,1%,1/16W,CHIP,CS21002FB06
     1 P3V3_AUX @T6G_MB_LIB.T6G(SCH_1):P3V3_AUX    I14 @T6G_MB_LIB.T6G(SCH_1):PAGE343
     2 OCP_V3_2_PRSNT0_R_N @T6G_MB_LIB.T6G(SCH_1):OCP_V3_2_PRSNT0_R_N    I14 @T6G_MB_LIB.T6G(SCH_1):PAGE343

R3134 Q_RES_0402LF-1K,1%,1/16W,CHIP,CS21002FB06
     1 P3V3_AUX @T6G_MB_LIB.T6G(SCH_1):P3V3_AUX     I4 @T6G_MB_LIB.T6G(SCH_1):PAGE343
     2 OCP_V3_2_PRSNT2_R_N @T6G_MB_LIB.T6G(SCH_1):OCP_V3_2_PRSNT2_R_N     I4 @T6G_MB_LIB.T6G(SCH_1):PAGE343

R3135 Q_RES_0402LF-1K,1%,1/16W,CHIP,CS21002FB06
     1 P3V3_AUX @T6G_MB_LIB.T6G(SCH_1):P3V3_AUX    I16 @T6G_MB_LIB.T6G(SCH_1):PAGE343
     2 OCP_V3_2_PRSNT1_R_N @T6G_MB_LIB.T6G(SCH_1):OCP_V3_2_PRSNT1_R_N    I16 @T6G_MB_LIB.T6G(SCH_1):PAGE343

R3136 Q_RES_0402LF-1K,1%,1/16W,CHIP,CS21002FB06
     1 P3V3_AUX @T6G_MB_LIB.T6G(SCH_1):P3V3_AUX     I6 @T6G_MB_LIB.T6G(SCH_1):PAGE343
     2 OCP_V3_2_PRSNT3_R_N @T6G_MB_LIB.T6G(SCH_1):OCP_V3_2_PRSNT3_R_N     I6 @T6G_MB_LIB.T6G(SCH_1):PAGE343

R3142 Q_RES_0402LF-0,5%,1/16W,CHIP,CS00002JB13
     1 HP_LVC3_OCP_V3_2_PRSNT2_N_R @T6G_MB_LIB.T6G(SCH_1):HP_LVC3_OCP_V3_2_PRSNT2_N_R    I59 @T6G_MB_LIB.T6G(SCH_1):PAGE343
     2 HP_LVC3_OCP_V3_2_PRSNT2_PLD_N @T6G_MB_LIB.T6G(SCH_1):HP_LVC3_OCP_V3_2_PRSNT2_PLD_N    I59 @T6G_MB_LIB.T6G(SCH_1):PAGE343

R3144 Q_RES_0402LF-0,5%,1/16W,CHIP,CS00002JB13
     1 P12V_OCP_PWRGD_1 @T6G_MB_LIB.T6G(SCH_1):P12V_OCP_PWRGD_1    I75 @T6G_MB_LIB.T6G(SCH_1):PAGE338
     2 HP_LVC3_OCP_V3_1_P12V_PWRGD @T6G_MB_LIB.T6G(SCH_1):HP_LVC3_OCP_V3_1_P12V_PWRGD    I75 @T6G_MB_LIB.T6G(SCH_1):PAGE338

R3147 Q_RES_0402LF-1K,1%,1/16W,CHIP,CS21002FB06
     1 P3V3_AUX @T6G_MB_LIB.T6G(SCH_1):P3V3_AUX    I69 @T6G_MB_LIB.T6G(SCH_1):PAGE343
     2 HP_LVC3_OCP_V3_2_PRSNT2_PLD_N @T6G_MB_LIB.T6G(SCH_1):HP_LVC3_OCP_V3_2_PRSNT2_PLD_N    I69 @T6G_MB_LIB.T6G(SCH_1):PAGE343

R3162 Q_RES_0402LF-4.7K,1%,1/16W,CHIP,CS24702FB06
     1 P3V3_OCP_V3_2 @T6G_MB_LIB.T6G(SCH_1):P3V3_OCP_V3_2    I26 @T6G_MB_LIB.T6G(SCH_1):PAGE341
     2 OCP_V3_2_ID0 @T6G_MB_LIB.T6G(SCH_1):OCP_V3_2_ID0    I26 @T6G_MB_LIB.T6G(SCH_1):PAGE341

R3163 Q_RES_0402LF-4.7K,1%,1/16W,EMPTY,CS24702FB06
     1 OCP_V3_2_ID0 @T6G_MB_LIB.T6G(SCH_1):OCP_V3_2_ID0     I2 @T6G_MB_LIB.T6G(SCH_1):PAGE341
     2    GND @T6G_MB_LIB.T6G(SCH_1):GND     I2 @T6G_MB_LIB.T6G(SCH_1):PAGE341

R3164 Q_RES_0402LF-10K,1%,1/16W,CHIP,CS31002FB08
     1    GND @T6G_MB_LIB.T6G(SCH_1):GND    I34 @T6G_MB_LIB.T6G(SCH_1):PAGE341
     2 OCP_V3_2_AUX_PWR_EN @T6G_MB_LIB.T6G(SCH_1):OCP_V3_2_AUX_PWR_EN    I34 @T6G_MB_LIB.T6G(SCH_1):PAGE341

R3165 Q_RES_0402LF-10K,1%,1/16W,CHIP,CS31002FB08
     1    GND @T6G_MB_LIB.T6G(SCH_1):GND    I32 @T6G_MB_LIB.T6G(SCH_1):PAGE341
     2 OCP_V3_2_MAIN_PWR_EN @T6G_MB_LIB.T6G(SCH_1):OCP_V3_2_MAIN_PWR_EN    I32 @T6G_MB_LIB.T6G(SCH_1):PAGE341

R3166 Q_RES_0402LF-4.7K,1%,1/16W,EMPTY,CS24702FB06
     1 P3V3_OCP_V3_2 @T6G_MB_LIB.T6G(SCH_1):P3V3_OCP_V3_2    I28 @T6G_MB_LIB.T6G(SCH_1):PAGE341
     2 OCP_V3_2_ID1 @T6G_MB_LIB.T6G(SCH_1):OCP_V3_2_ID1    I28 @T6G_MB_LIB.T6G(SCH_1):PAGE341

R3167 Q_RES_0402LF-4.7K,1%,1/16W,CHIP,CS24702FB06
     1 OCP_V3_2_ID1 @T6G_MB_LIB.T6G(SCH_1):OCP_V3_2_ID1     I3 @T6G_MB_LIB.T6G(SCH_1):PAGE341
     2    GND @T6G_MB_LIB.T6G(SCH_1):GND     I3 @T6G_MB_LIB.T6G(SCH_1):PAGE341

R3168 Q_RES_0402LF-0,5%,1/16W,CHIP,CS00002JB13
     1 OCP_V3_2_MAIN_PWR_EN @T6G_MB_LIB.T6G(SCH_1):OCP_V3_2_MAIN_PWR_EN    I86 @T6G_MB_LIB.T6G(SCH_1):PAGE341
     2 OCP_V3_2_MAIN_PWR_EN_R @T6G_MB_LIB.T6G(SCH_1):OCP_V3_2_MAIN_PWR_EN_R    I86 @T6G_MB_LIB.T6G(SCH_1):PAGE341

R3169 Q_RES_0402LF-0,5%,1/16W,CHIP,CS00002JB13
     1 OCP_V3_2_ISO_BIF0_EN @T6G_MB_LIB.T6G(SCH_1):OCP_V3_2_ISO_BIF0_EN    I43 @T6G_MB_LIB.T6G(SCH_1):PAGE341
     2 OCP_V3_2_BIF0_R_N @T6G_MB_LIB.T6G(SCH_1):OCP_V3_2_BIF0_R_N    I43 @T6G_MB_LIB.T6G(SCH_1):PAGE341

R3170 Q_RES_0402LF-0,5%,1/16W,CHIP,CS00002JB13
     1 OCP_V3_2_ISO_BIF1_EN @T6G_MB_LIB.T6G(SCH_1):OCP_V3_2_ISO_BIF1_EN    I44 @T6G_MB_LIB.T6G(SCH_1):PAGE341
     2 OCP_V3_2_BIF1_R_N @T6G_MB_LIB.T6G(SCH_1):OCP_V3_2_BIF1_R_N    I44 @T6G_MB_LIB.T6G(SCH_1):PAGE341

R3171 Q_RES_0402LF-0,5%,1/16W,CHIP,CS00002JB13
     1 OCP_V3_2_ISO_BIF2_EN @T6G_MB_LIB.T6G(SCH_1):OCP_V3_2_ISO_BIF2_EN    I45 @T6G_MB_LIB.T6G(SCH_1):PAGE341
     2 OCP_V3_2_BIF2_R_N @T6G_MB_LIB.T6G(SCH_1):OCP_V3_2_BIF2_R_N    I45 @T6G_MB_LIB.T6G(SCH_1):PAGE341

R3172 Q_RES_0402LF-0,5%,1/16W,CHIP,CS00002JB13
     1 OCP_V3_2_AUX_PWR_EN @T6G_MB_LIB.T6G(SCH_1):OCP_V3_2_AUX_PWR_EN    I42 @T6G_MB_LIB.T6G(SCH_1):PAGE341
     2 OCP_V3_2_AUX_PWR_EN_R @T6G_MB_LIB.T6G(SCH_1):OCP_V3_2_AUX_PWR_EN_R    I42 @T6G_MB_LIB.T6G(SCH_1):PAGE341

R3173 Q_RES_0402LF-1K,1%,1/16W,CHIP,CS21002FB06
     1 SGPIO_OCP_V3_2_LD_N @T6G_MB_LIB.T6G(SCH_1):SGPIO_OCP_V3_2_LD_N    I10 @T6G_MB_LIB.T6G(SCH_1):PAGE341
     2 P3V3_OCP_V3_2 @T6G_MB_LIB.T6G(SCH_1):P3V3_OCP_V3_2    I10 @T6G_MB_LIB.T6G(SCH_1):PAGE341

R3174 Q_RES_0402LF-10K,1%,1/16W,CHIP,CS31002FB08
     1 SGPIO_OCP_V3_2_DATAIN @T6G_MB_LIB.T6G(SCH_1):SGPIO_OCP_V3_2_DATAIN     I9 @T6G_MB_LIB.T6G(SCH_1):PAGE341
     2 P3V3_OCP_V3_2 @T6G_MB_LIB.T6G(SCH_1):P3V3_OCP_V3_2     I9 @T6G_MB_LIB.T6G(SCH_1):PAGE341

R3175 Q_RES_0402LF-10K,1%,1/16W,CHIP,CS31002FB08
     1 SGPIO_OCP_V3_2_DATAOUT @T6G_MB_LIB.T6G(SCH_1):SGPIO_OCP_V3_2_DATAOUT    I11 @T6G_MB_LIB.T6G(SCH_1):PAGE341
     2    GND @T6G_MB_LIB.T6G(SCH_1):GND    I11 @T6G_MB_LIB.T6G(SCH_1):PAGE341

R3176 Q_RES_0402LF-1K,1%,1/16W,CHIP,CS21002FB06
     1 SGPIO_OCP_V3_2_CLK @T6G_MB_LIB.T6G(SCH_1):SGPIO_OCP_V3_2_CLK    I12 @T6G_MB_LIB.T6G(SCH_1):PAGE341
     2 P3V3_OCP_V3_2 @T6G_MB_LIB.T6G(SCH_1):P3V3_OCP_V3_2    I12 @T6G_MB_LIB.T6G(SCH_1):PAGE341

R3177 Q_RES_0402LF-0,5%,1/16W,CHIP,CS00002JB13
     1 USB2_P10_DN @T6G_MB_LIB.T6G(SCH_1):USB2_P10_DN   I136 @T6G_MB_LIB.T6G(SCH_1):PAGE341
     2 USB2_CPU0_P10_DN @T6G_MB_LIB.T6G(SCH_1):USB2_CPU0_P10_DN   I136 @T6G_MB_LIB.T6G(SCH_1):PAGE341

R3178 Q_RES_0402LF-0,5%,1/16W,CHIP,CS00002JB13
     1 USB2_P10_DP @T6G_MB_LIB.T6G(SCH_1):USB2_P10_DP   I135 @T6G_MB_LIB.T6G(SCH_1):PAGE341
     2 USB2_CPU0_P10_DP @T6G_MB_LIB.T6G(SCH_1):USB2_CPU0_P10_DP   I135 @T6G_MB_LIB.T6G(SCH_1):PAGE341

R3180 Q_RES_0402LF-0,5%,1/16W,CHIP,CS00002JB13
     1 OCP_V3_2_PRSNTA_R_N @T6G_MB_LIB.T6G(SCH_1):OCP_V3_2_PRSNTA_R_N   I150 @T6G_MB_LIB.T6G(SCH_1):PAGE341
     2    GND @T6G_MB_LIB.T6G(SCH_1):GND   I150 @T6G_MB_LIB.T6G(SCH_1):PAGE341

R3181 Q_RES_0402LF-27.4,1%,1/16W,CHIP,CS02742FB03
     1 CLK_50M_NCSI_OCP_2 @T6G_MB_LIB.T6G(SCH_1):CLK_50M_NCSI_OCP_2    I20 @T6G_MB_LIB.T6G(SCH_1):PAGE337
     2 CLK_50M_NCSI_OCP_V3_2 @T6G_MB_LIB.T6G(SCH_1):CLK_50M_NCSI_OCP_V3_2    I20 @T6G_MB_LIB.T6G(SCH_1):PAGE337

R3182 Q_RES_0402LF-10K,1%,1/16W,CHIP,CS31002FB08
     1 P3V3_OCP_V3_2 @T6G_MB_LIB.T6G(SCH_1):P3V3_OCP_V3_2     I3 @T6G_MB_LIB.T6G(SCH_1):PAGE342
     2 IRQ_LVC3_OCP_V3_2_WAKE_N @T6G_MB_LIB.T6G(SCH_1):IRQ_LVC3_OCP_V3_2_WAKE_N     I3 @T6G_MB_LIB.T6G(SCH_1):PAGE342

R3183 Q_RES_0402LF-10K,1%,1/16W,CHIP,CS31002FB08
     1 P3V3_OCP_V3_2 @T6G_MB_LIB.T6G(SCH_1):P3V3_OCP_V3_2     I4 @T6G_MB_LIB.T6G(SCH_1):PAGE342
     2 PU_OCP_V3_2_WAKE_OE @T6G_MB_LIB.T6G(SCH_1):PU_OCP_V3_2_WAKE_OE     I4 @T6G_MB_LIB.T6G(SCH_1):PAGE342

R3184 Q_RES_0402LF-4.7K,1%,1/16W,CHIP,CS24702FB06
     1 P3V3_AUX @T6G_MB_LIB.T6G(SCH_1):P3V3_AUX    I18 @T6G_MB_LIB.T6G(SCH_1):PAGE342
     2 OCP_V3_2_WAKE_BUFF_N @T6G_MB_LIB.T6G(SCH_1):OCP_V3_2_WAKE_BUFF_N    I18 @T6G_MB_LIB.T6G(SCH_1):PAGE342

R3185 Q_RES_0402LF-33.2,1%,1/16W,CHIP,CS03322FB03
     1 OCP_V3_2_WAKE_BUFF_N @T6G_MB_LIB.T6G(SCH_1):OCP_V3_2_WAKE_BUFF_N    I29 @T6G_MB_LIB.T6G(SCH_1):PAGE342
     2 OCP_V3_2_WAKE_BUFF_R_N @T6G_MB_LIB.T6G(SCH_1):OCP_V3_2_WAKE_BUFF_R_N    I29 @T6G_MB_LIB.T6G(SCH_1):PAGE342

R3190 Q_RES_0402LF-4.7K,1%,1/16W,CHIP,CS24702FB06
     1 P3V3_AUX @T6G_MB_LIB.T6G(SCH_1):P3V3_AUX    I34 @T6G_MB_LIB.T6G(SCH_1):PAGE342
     2 OCP_V3_2_PWRBRK_BUFF_N @T6G_MB_LIB.T6G(SCH_1):OCP_V3_2_PWRBRK_BUFF_N    I34 @T6G_MB_LIB.T6G(SCH_1):PAGE342

R3191 Q_RES_0402LF-33.2,1%,1/16W,CHIP,CS03322FB03
     1 OCP_V3_2_PWRBRK_BUFF_N @T6G_MB_LIB.T6G(SCH_1):OCP_V3_2_PWRBRK_BUFF_N    I33 @T6G_MB_LIB.T6G(SCH_1):PAGE342
     2 OCP_V3_2_PWRBRK_N @T6G_MB_LIB.T6G(SCH_1):OCP_V3_2_PWRBRK_N    I33 @T6G_MB_LIB.T6G(SCH_1):PAGE342

R3192 Q_RES_0402LF-4.7K,1%,1/16W,EMPTY,CS24702FB06
     1 P3V3_AUX @T6G_MB_LIB.T6G(SCH_1):P3V3_AUX    I44 @T6G_MB_LIB.T6G(SCH_1):PAGE342
     2 IRQ_LVC3_V3_2_WAKE_BUF_N @T6G_MB_LIB.T6G(SCH_1):IRQ_LVC3_V3_2_WAKE_BUF_N    I44 @T6G_MB_LIB.T6G(SCH_1):PAGE342

R3193 Q_RES_0402LF-33.2,1%,1/16W,CHIP,CS03322FB03
     1 IRQ_LVC3_V3_2_WAKE_BUF_N @T6G_MB_LIB.T6G(SCH_1):IRQ_LVC3_V3_2_WAKE_BUF_N    I43 @T6G_MB_LIB.T6G(SCH_1):PAGE342
     2 IRQ_OCP_V3_2_WAKE_BUF_N @T6G_MB_LIB.T6G(SCH_1):IRQ_OCP_V3_2_WAKE_BUF_N    I43 @T6G_MB_LIB.T6G(SCH_1):PAGE342

R3194 Q_RES_0402LF-0,5%,1/16W,CHIP,CS00002JB13
     1 CLK_100M_CPU1_CLK02_R_DP @T6G_MB_LIB.T6G(SCH_1):CLK_100M_CPU1_CLK02_R_DP   I308 @T6G_MB_LIB.T6G(SCH_1):PAGE55
     2 CLK_100M_CPU1_CLK02_DP @T6G_MB_LIB.T6G(SCH_1):CLK_100M_CPU1_CLK02_DP   I308 @T6G_MB_LIB.T6G(SCH_1):PAGE55

R3195 Q_RES_0402LF-0,5%,1/16W,CHIP,CS00002JB13
     1 CLK_100M_CPU1_CLK02_R_DN @T6G_MB_LIB.T6G(SCH_1):CLK_100M_CPU1_CLK02_R_DN   I309 @T6G_MB_LIB.T6G(SCH_1):PAGE55
     2 CLK_100M_CPU1_CLK02_DN @T6G_MB_LIB.T6G(SCH_1):CLK_100M_CPU1_CLK02_DN   I309 @T6G_MB_LIB.T6G(SCH_1):PAGE55

R3196 Q_RES_0402LF-0,5%,1/16W,CHIP,CS00002JB13
     1 CLK_100M_CPU1_CLK03_R_DP @T6G_MB_LIB.T6G(SCH_1):CLK_100M_CPU1_CLK03_R_DP   I312 @T6G_MB_LIB.T6G(SCH_1):PAGE55
     2 CLK_100M_CPU1_CLK03_DP @T6G_MB_LIB.T6G(SCH_1):CLK_100M_CPU1_CLK03_DP   I312 @T6G_MB_LIB.T6G(SCH_1):PAGE55

R3197 Q_RES_0402LF-0,5%,1/16W,CHIP,CS00002JB13
     1 CLK_100M_CPU1_CLK03_R_DN @T6G_MB_LIB.T6G(SCH_1):CLK_100M_CPU1_CLK03_R_DN   I313 @T6G_MB_LIB.T6G(SCH_1):PAGE55
     2 CLK_100M_CPU1_CLK03_DN @T6G_MB_LIB.T6G(SCH_1):CLK_100M_CPU1_CLK03_DN   I313 @T6G_MB_LIB.T6G(SCH_1):PAGE55

R3198 Q_RES_0402LF-0,5%,1/16W,CHIP,CS00002JB13
     1 CLK_100M_CPU1_CLK04_R_DP @T6G_MB_LIB.T6G(SCH_1):CLK_100M_CPU1_CLK04_R_DP   I316 @T6G_MB_LIB.T6G(SCH_1):PAGE55
     2 CLK_100M_CPU1_CLK04_DP @T6G_MB_LIB.T6G(SCH_1):CLK_100M_CPU1_CLK04_DP   I316 @T6G_MB_LIB.T6G(SCH_1):PAGE55

R3199 Q_RES_0402LF-0,5%,1/16W,CHIP,CS00002JB13
     1 CLK_100M_CPU1_CLK04_R_DN @T6G_MB_LIB.T6G(SCH_1):CLK_100M_CPU1_CLK04_R_DN   I317 @T6G_MB_LIB.T6G(SCH_1):PAGE55
     2 CLK_100M_CPU1_CLK04_DN @T6G_MB_LIB.T6G(SCH_1):CLK_100M_CPU1_CLK04_DN   I317 @T6G_MB_LIB.T6G(SCH_1):PAGE55

R3200 Q_RES_0402LF-0,5%,1/16W,CHIP,CS00002JB13
     1 CLK_100M_CPU1_CLK05_R_DP @T6G_MB_LIB.T6G(SCH_1):CLK_100M_CPU1_CLK05_R_DP   I320 @T6G_MB_LIB.T6G(SCH_1):PAGE55
     2 CLK_100M_CPU1_CLK05_DP @T6G_MB_LIB.T6G(SCH_1):CLK_100M_CPU1_CLK05_DP   I320 @T6G_MB_LIB.T6G(SCH_1):PAGE55

R3201 Q_RES_0402LF-0,5%,1/16W,CHIP,CS00002JB13
     1 CLK_100M_CPU1_CLK05_R_DN @T6G_MB_LIB.T6G(SCH_1):CLK_100M_CPU1_CLK05_R_DN   I321 @T6G_MB_LIB.T6G(SCH_1):PAGE55
     2 CLK_100M_CPU1_CLK05_DN @T6G_MB_LIB.T6G(SCH_1):CLK_100M_CPU1_CLK05_DN   I321 @T6G_MB_LIB.T6G(SCH_1):PAGE55

R3203 Q_RES_0402LF-33.2,1%,1/16W,CHIP,CS03322FB03
     1 OCP_V3_2_AUX_PWR_EN @T6G_MB_LIB.T6G(SCH_1):OCP_V3_2_AUX_PWR_EN    I81 @T6G_MB_LIB.T6G(SCH_1):PAGE307
     2 OCP_V3_2_AUX_PWR_EN_R1 @T6G_MB_LIB.T6G(SCH_1):OCP_V3_2_AUX_PWR_EN_R1    I81 @T6G_MB_LIB.T6G(SCH_1):PAGE307

R3205 Q_RES_0402LF-0,5%,1/16W,CHIP,CS00002JB13
     1 FB_BMC_ISOLATE_R2 @T6G_MB_LIB.T6G(SCH_1):FB_BMC_ISOLATE_R2    I86 @T6G_MB_LIB.T6G(SCH_1):PAGE307
     2 FB_BMC_ISOLATE1 @T6G_MB_LIB.T6G(SCH_1):FB_BMC_ISOLATE1    I86 @T6G_MB_LIB.T6G(SCH_1):PAGE307

R3206 Q_RES_0402LF-0,5%,1/16W,EMPTY,CS00002JB13
     1 FM_NCSI_OCP_V3_2_R_OE @T6G_MB_LIB.T6G(SCH_1):FM_NCSI_OCP_V3_2_R_OE    I85 @T6G_MB_LIB.T6G(SCH_1):PAGE307
     2 FB_BMC_ISOLATE1 @T6G_MB_LIB.T6G(SCH_1):FB_BMC_ISOLATE1    I85 @T6G_MB_LIB.T6G(SCH_1):PAGE307

R3207 Q_RES_0402LF-100K,1%,1/16W,CHIP,CS41002FB09
     1 FB_BMC_ISOLATE1 @T6G_MB_LIB.T6G(SCH_1):FB_BMC_ISOLATE1    I15 @T6G_MB_LIB.T6G(SCH_1):PAGE307
     2    GND @T6G_MB_LIB.T6G(SCH_1):GND    I15 @T6G_MB_LIB.T6G(SCH_1):PAGE307

R3208 Q_RES_0402LF-100,1%,1/16W,CHIP,CS11002FB07
     1 OCP_V3_2_ISO_BIF0_EN @T6G_MB_LIB.T6G(SCH_1):OCP_V3_2_ISO_BIF0_EN    I37 @T6G_MB_LIB.T6G(SCH_1):PAGE307
     2    GND @T6G_MB_LIB.T6G(SCH_1):GND    I37 @T6G_MB_LIB.T6G(SCH_1):PAGE307

R3209 Q_RES_0402LF-22,1%,1/16W,EMPTY,CS02202FB02
     1 OCP_V3_2_RBT_ARB_IN_R @T6G_MB_LIB.T6G(SCH_1):OCP_V3_2_RBT_ARB_IN_R    I64 @T6G_MB_LIB.T6G(SCH_1):PAGE307
     2 OCP_V3_2_RBT_ARB_IN @T6G_MB_LIB.T6G(SCH_1):OCP_V3_2_RBT_ARB_IN    I64 @T6G_MB_LIB.T6G(SCH_1):PAGE307

R3210 Q_RES_0402LF-22,1%,1/16W,EMPTY,CS02202FB02
     1 NCSI_BMC_CRS_DV_R1 @T6G_MB_LIB.T6G(SCH_1):NCSI_BMC_CRS_DV_R1    I65 @T6G_MB_LIB.T6G(SCH_1):PAGE307
     2 RMII_OCP_BMC_CRSDV @T6G_MB_LIB.T6G(SCH_1):RMII_OCP_BMC_CRSDV    I65 @T6G_MB_LIB.T6G(SCH_1):PAGE307

R3211 Q_RES_0402LF-22,1%,1/16W,EMPTY,CS02202FB02
     1 NCSI_BMC_RXD0_R1 @T6G_MB_LIB.T6G(SCH_1):NCSI_BMC_RXD0_R1    I63 @T6G_MB_LIB.T6G(SCH_1):PAGE307
     2 RMII_OCP_BMC_RXD_0 @T6G_MB_LIB.T6G(SCH_1):RMII_OCP_BMC_RXD_0    I63 @T6G_MB_LIB.T6G(SCH_1):PAGE307

R3212 Q_RES_0402LF-22,1%,1/16W,EMPTY,CS02202FB02
     1 NCSI_BMC_RXD1_R1 @T6G_MB_LIB.T6G(SCH_1):NCSI_BMC_RXD1_R1    I62 @T6G_MB_LIB.T6G(SCH_1):PAGE307
     2 RMII_OCP_BMC_RXD_1 @T6G_MB_LIB.T6G(SCH_1):RMII_OCP_BMC_RXD_1    I62 @T6G_MB_LIB.T6G(SCH_1):PAGE307

R3213 Q_RES_0402LF-0,5%,1/16W,EMPTY,CS00002JB13
     1 NCSI_BMC_TX_EN_R1 @T6G_MB_LIB.T6G(SCH_1):NCSI_BMC_TX_EN_R1    I61 @T6G_MB_LIB.T6G(SCH_1):PAGE307
     2 RMII_BMC_OCP_TX_EN @T6G_MB_LIB.T6G(SCH_1):RMII_BMC_OCP_TX_EN    I61 @T6G_MB_LIB.T6G(SCH_1):PAGE307

R3214 Q_RES_0402LF-0,5%,1/16W,EMPTY,CS00002JB13
     1 NCSI_BMC_TXD0_R1 @T6G_MB_LIB.T6G(SCH_1):NCSI_BMC_TXD0_R1    I60 @T6G_MB_LIB.T6G(SCH_1):PAGE307
     2 RMII_BMC_OCP_TXD_0 @T6G_MB_LIB.T6G(SCH_1):RMII_BMC_OCP_TXD_0    I60 @T6G_MB_LIB.T6G(SCH_1):PAGE307

R3215 Q_RES_0402LF-0,5%,1/16W,EMPTY,CS00002JB13
     1 NCSI_BMC_TXD1_R1 @T6G_MB_LIB.T6G(SCH_1):NCSI_BMC_TXD1_R1    I56 @T6G_MB_LIB.T6G(SCH_1):PAGE307
     2 RMII_BMC_OCP_TXD_1 @T6G_MB_LIB.T6G(SCH_1):RMII_BMC_OCP_TXD_1    I56 @T6G_MB_LIB.T6G(SCH_1):PAGE307

R3216 Q_RES_0402LF-100,1%,1/16W,CHIP,CS11002FB07
     1 OCP_V3_2_ISO_BIF1_EN @T6G_MB_LIB.T6G(SCH_1):OCP_V3_2_ISO_BIF1_EN    I38 @T6G_MB_LIB.T6G(SCH_1):PAGE307
     2    GND @T6G_MB_LIB.T6G(SCH_1):GND    I38 @T6G_MB_LIB.T6G(SCH_1):PAGE307

R3217 Q_RES_0402LF-100,1%,1/16W,CHIP,CS11002FB07
     1 OCP_V3_2_ISO_BIF2_EN @T6G_MB_LIB.T6G(SCH_1):OCP_V3_2_ISO_BIF2_EN    I40 @T6G_MB_LIB.T6G(SCH_1):PAGE307
     2    GND @T6G_MB_LIB.T6G(SCH_1):GND    I40 @T6G_MB_LIB.T6G(SCH_1):PAGE307

R3226 Q_RES_0402LF-2.2K,5%,1/16W,EMPTY,CS22202JB07
     1 SMB_1_BMC_GPU_SCL @T6G_MB_LIB.T6G(SCH_1):SMB_1_BMC_GPU_SCL   I122 @T6G_MB_LIB.T6G(SCH_1):PAGE349
     2 P3V3_AUX @T6G_MB_LIB.T6G(SCH_1):P3V3_AUX   I122 @T6G_MB_LIB.T6G(SCH_1):PAGE349

R3227 Q_RES_0402LF-2.2K,5%,1/16W,EMPTY,CS22202JB07
     1 SMB_1_BMC_GPU_SDA @T6G_MB_LIB.T6G(SCH_1):SMB_1_BMC_GPU_SDA   I121 @T6G_MB_LIB.T6G(SCH_1):PAGE349
     2 P3V3_AUX @T6G_MB_LIB.T6G(SCH_1):P3V3_AUX   I121 @T6G_MB_LIB.T6G(SCH_1):PAGE349

R3228 Q_RES_0402LF-200,1%,1/16W,CHIP,CS12002FB06
     1 SMB_OCP_V3_2_3V3AUX_BUF_R_SCL @T6G_MB_LIB.T6G(SCH_1):SMB_OCP_V3_2_3V3AUX_BUF_R_SCL   I171 @T6G_MB_LIB.T6G(SCH_1):PAGE341
     2 SMB_OCP_V3_2_3V3AUX_BUF_SCL @T6G_MB_LIB.T6G(SCH_1):SMB_OCP_V3_2_3V3AUX_BUF_SCL   I171 @T6G_MB_LIB.T6G(SCH_1):PAGE341

R3229 Q_RES_0402LF-200,1%,1/16W,CHIP,CS12002FB06
     1 SMB_OCP_V3_2_3V3AUX_BUF_R_SDA @T6G_MB_LIB.T6G(SCH_1):SMB_OCP_V3_2_3V3AUX_BUF_R_SDA   I170 @T6G_MB_LIB.T6G(SCH_1):PAGE341
     2 SMB_OCP_V3_2_3V3AUX_BUF_SDA @T6G_MB_LIB.T6G(SCH_1):SMB_OCP_V3_2_3V3AUX_BUF_SDA   I170 @T6G_MB_LIB.T6G(SCH_1):PAGE341

R3231 Q_RES_0402LF-33.2,1%,1/16W,CHIP,CS03322FB03
     1 OCP_SFF_AUX_PWR_EN @T6G_MB_LIB.T6G(SCH_1):OCP_SFF_AUX_PWR_EN   I160 @T6G_MB_LIB.T6G(SCH_1):PAGE336
     2 OCP_SFF_AUX_PWR_EN_R2 @T6G_MB_LIB.T6G(SCH_1):OCP_SFF_AUX_PWR_EN_R2   I160 @T6G_MB_LIB.T6G(SCH_1):PAGE336

R3232 Q_RES_0402LF-100K,1%,1/16W,CHIP,CS41002FB09
     1 RST_HP_OCP_SFF_R_N @T6G_MB_LIB.T6G(SCH_1):RST_HP_OCP_SFF_R_N   I152 @T6G_MB_LIB.T6G(SCH_1):PAGE336
     2    GND @T6G_MB_LIB.T6G(SCH_1):GND   I152 @T6G_MB_LIB.T6G(SCH_1):PAGE336

R3233 Q_RES_0402LF-0,5%,1/16W,CHIP,CS00002JB13
     1 RST_HP_OCP_SFF_R_N @T6G_MB_LIB.T6G(SCH_1):RST_HP_OCP_SFF_R_N   I153 @T6G_MB_LIB.T6G(SCH_1):PAGE336
     2 RST_SMB_OCP_SFF_N @T6G_MB_LIB.T6G(SCH_1):RST_SMB_OCP_SFF_N   I153 @T6G_MB_LIB.T6G(SCH_1):PAGE336

R3234 Q_RES_0402LF-33.2,1%,1/16W,CHIP,CS03322FB03
     1 OCP_V3_2_AUX_PWR_EN @T6G_MB_LIB.T6G(SCH_1):OCP_V3_2_AUX_PWR_EN     I6 @T6G_MB_LIB.T6G(SCH_1):PAGE342
     2 OCP_V3_2_AUX_PWR_EN_R3 @T6G_MB_LIB.T6G(SCH_1):OCP_V3_2_AUX_PWR_EN_R3     I6 @T6G_MB_LIB.T6G(SCH_1):PAGE342

R3235 Q_RES_0402LF-100K,1%,1/16W,CHIP,CS41002FB09
     1 RST_HP_OCP_V3_2_R_N @T6G_MB_LIB.T6G(SCH_1):RST_HP_OCP_V3_2_R_N    I24 @T6G_MB_LIB.T6G(SCH_1):PAGE342
     2    GND @T6G_MB_LIB.T6G(SCH_1):GND    I24 @T6G_MB_LIB.T6G(SCH_1):PAGE342

R3236 Q_RES_0402LF-0,5%,1/16W,CHIP,CS00002JB13
     1 RST_HP_OCP_V3_2_R_N @T6G_MB_LIB.T6G(SCH_1):RST_HP_OCP_V3_2_R_N    I25 @T6G_MB_LIB.T6G(SCH_1):PAGE342
     2 RST_SMB_OCP_V3_2_N @T6G_MB_LIB.T6G(SCH_1):RST_SMB_OCP_V3_2_N    I25 @T6G_MB_LIB.T6G(SCH_1):PAGE342

R3237 Q_RES_0402LF-0,5%,1/16W,CHIP,CS00002JB13
     1 OCP_SFF_RBT_ARB_OUT @T6G_MB_LIB.T6G(SCH_1):OCP_SFF_RBT_ARB_OUT   I156 @T6G_MB_LIB.T6G(SCH_1):PAGE336
     2 OCP_SFF_RBT_ARB_IN_R @T6G_MB_LIB.T6G(SCH_1):OCP_SFF_RBT_ARB_IN_R   I156 @T6G_MB_LIB.T6G(SCH_1):PAGE336

R3238 Q_RES_0402LF-33.2,1%,1/16W,CHIP,CS03322FB03
     1 SMB_OCP_SFF_3V3AUX_SCL @T6G_MB_LIB.T6G(SCH_1):SMB_OCP_SFF_3V3AUX_SCL   I103 @T6G_MB_LIB.T6G(SCH_1):PAGE348
     2 SMB_OCP_SFF_3V3AUX_SCL_R0 @T6G_MB_LIB.T6G(SCH_1):SMB_OCP_SFF_3V3AUX_SCL_R0   I103 @T6G_MB_LIB.T6G(SCH_1):PAGE348

R3239 Q_RES_0402LF-33.2,1%,1/16W,CHIP,CS03322FB03
     1 SMB_OCP_SFF_3V3AUX_SDA @T6G_MB_LIB.T6G(SCH_1):SMB_OCP_SFF_3V3AUX_SDA   I102 @T6G_MB_LIB.T6G(SCH_1):PAGE348
     2 SMB_OCP_SFF_3V3AUX_SDA_R0 @T6G_MB_LIB.T6G(SCH_1):SMB_OCP_SFF_3V3AUX_SDA_R0   I102 @T6G_MB_LIB.T6G(SCH_1):PAGE348

R3240 Q_RES_0402LF-2.2K,5%,1/16W,EMPTY,CS22202JB07
     1 SMB_OCP_SFF_3V3AUX_SCL @T6G_MB_LIB.T6G(SCH_1):SMB_OCP_SFF_3V3AUX_SCL   I120 @T6G_MB_LIB.T6G(SCH_1):PAGE349
     2 P3V3_AUX @T6G_MB_LIB.T6G(SCH_1):P3V3_AUX   I120 @T6G_MB_LIB.T6G(SCH_1):PAGE349

R3241 Q_RES_0402LF-2.2K,5%,1/16W,EMPTY,CS22202JB07
     1 SMB_OCP_SFF_3V3AUX_SDA @T6G_MB_LIB.T6G(SCH_1):SMB_OCP_SFF_3V3AUX_SDA   I149 @T6G_MB_LIB.T6G(SCH_1):PAGE349
     2 P3V3_AUX @T6G_MB_LIB.T6G(SCH_1):P3V3_AUX   I149 @T6G_MB_LIB.T6G(SCH_1):PAGE349

R3242 Q_RES_0402LF-2.2K,5%,1/16W,EMPTY,CS22202JB07
     1 SMB_OCP_V3_2_3V3AUX_SCL @T6G_MB_LIB.T6G(SCH_1):SMB_OCP_V3_2_3V3AUX_SCL   I119 @T6G_MB_LIB.T6G(SCH_1):PAGE349
     2 P3V3_AUX @T6G_MB_LIB.T6G(SCH_1):P3V3_AUX   I119 @T6G_MB_LIB.T6G(SCH_1):PAGE349

R3243 Q_RES_0402LF-2.2K,5%,1/16W,EMPTY,CS22202JB07
     1 SMB_OCP_V3_2_3V3AUX_SDA @T6G_MB_LIB.T6G(SCH_1):SMB_OCP_V3_2_3V3AUX_SDA   I115 @T6G_MB_LIB.T6G(SCH_1):PAGE349
     2 P3V3_AUX @T6G_MB_LIB.T6G(SCH_1):P3V3_AUX   I115 @T6G_MB_LIB.T6G(SCH_1):PAGE349

R3244 Q_RES_0402LF-0,5%,1/16W,CHIP,CS00002JB13
     1 OCP_V3_2_RBT_ARB_OUT @T6G_MB_LIB.T6G(SCH_1):OCP_V3_2_RBT_ARB_OUT    I79 @T6G_MB_LIB.T6G(SCH_1):PAGE307
     2 OCP_V3_2_RBT_ARB_IN_R @T6G_MB_LIB.T6G(SCH_1):OCP_V3_2_RBT_ARB_IN_R    I79 @T6G_MB_LIB.T6G(SCH_1):PAGE307

R3254 Q_RES_0402LF-0,5%,1/16W,EMPTY,CS00002JB13
     1 TP_PCIE_TXP<3> @T6G_MB_LIB.T6G(SCH_1):TP_PCIE_TXP(3)    I50 @T6G_MB_LIB.T6G(SCH_1):PAGE348
     2 LED_HDD_ACTIVITY_B_N @T6G_MB_LIB.T6G(SCH_1):LED_HDD_ACTIVITY_B_N    I50 @T6G_MB_LIB.T6G(SCH_1):PAGE348

R3263 Q_RES_0402LF-0,5%,1/16W,EMPTY,CS00002JB13
     1 HP_LVC3_OCP_V3_1_R_EN @T6G_MB_LIB.T6G(SCH_1):HP_LVC3_OCP_V3_1_R_EN    I35 @T6G_MB_LIB.T6G(SCH_1):PAGE248
     2 P3V3_OCP_SFF_EN_R @T6G_MB_LIB.T6G(SCH_1):P3V3_OCP_SFF_EN_R    I35 @T6G_MB_LIB.T6G(SCH_1):PAGE248

R3264 Q_RES_0402LF-0,5%,1/16W,EMPTY,CS00002JB13
     1 HP_LVC3_OCP_V3_2_R_EN @T6G_MB_LIB.T6G(SCH_1):HP_LVC3_OCP_V3_2_R_EN    I38 @T6G_MB_LIB.T6G(SCH_1):PAGE248
     2 P3V3_OCP_V3_2_EN_R @T6G_MB_LIB.T6G(SCH_1):P3V3_OCP_V3_2_EN_R    I38 @T6G_MB_LIB.T6G(SCH_1):PAGE248

R3265 Q_RES_0402LF-4.7K,1%,1/16W,EMPTY,CS24702FB06
     1 CLK_GEN2_GPU_FPGA_OE_OR_N @T6G_MB_LIB.T6G(SCH_1):CLK_GEN2_GPU_FPGA_OE_OR_N    I81 @T6G_MB_LIB.T6G(SCH_1):PAGE110
     2    GND @T6G_MB_LIB.T6G(SCH_1):GND    I81 @T6G_MB_LIB.T6G(SCH_1):PAGE110

R3266 Q_RES_0402LF-4.7K,1%,1/16W,CHIP,CS24702FB06
     1 P3V3_AUX @T6G_MB_LIB.T6G(SCH_1):P3V3_AUX    I93 @T6G_MB_LIB.T6G(SCH_1):PAGE110
     2 FM_P2E_MODE @T6G_MB_LIB.T6G(SCH_1):FM_P2E_MODE    I93 @T6G_MB_LIB.T6G(SCH_1):PAGE110

R3267 Q_RES_0402LF-68K,1%,1/16W,EMPTY,CS36802FB04
     1 FM_P2E_FGB @T6G_MB_LIB.T6G(SCH_1):FM_P2E_FGB     I8 @T6G_MB_LIB.T6G(SCH_1):PAGE110
     2    GND @T6G_MB_LIB.T6G(SCH_1):GND     I8 @T6G_MB_LIB.T6G(SCH_1):PAGE110

R3268 Q_RES_0402LF-68K,1%,1/16W,EMPTY,CS36802FB04
     1 FM_P2E_EQA1 @T6G_MB_LIB.T6G(SCH_1):FM_P2E_EQA1     I2 @T6G_MB_LIB.T6G(SCH_1):PAGE110
     2    GND @T6G_MB_LIB.T6G(SCH_1):GND     I2 @T6G_MB_LIB.T6G(SCH_1):PAGE110

R3269 Q_RES_0402LF-1K,1%,1/16W,EMPTY,CS21002FB06
     1 P3V3_AUX @T6G_MB_LIB.T6G(SCH_1):P3V3_AUX    I14 @T6G_MB_LIB.T6G(SCH_1):PAGE110
     2 FM_P2E_FGB @T6G_MB_LIB.T6G(SCH_1):FM_P2E_FGB    I14 @T6G_MB_LIB.T6G(SCH_1):PAGE110

R3270 Q_RES_0402LF-1K,1%,1/16W,EMPTY,CS21002FB06
     1 FM_P2E_FGB @T6G_MB_LIB.T6G(SCH_1):FM_P2E_FGB     I9 @T6G_MB_LIB.T6G(SCH_1):PAGE110
     2    GND @T6G_MB_LIB.T6G(SCH_1):GND     I9 @T6G_MB_LIB.T6G(SCH_1):PAGE110

R3271 Q_RES_0402LF-1K,1%,1/16W,EMPTY,CS21002FB06
     1 P3V3_AUX @T6G_MB_LIB.T6G(SCH_1):P3V3_AUX     I5 @T6G_MB_LIB.T6G(SCH_1):PAGE110
     2 FM_P2E_EQA1 @T6G_MB_LIB.T6G(SCH_1):FM_P2E_EQA1     I5 @T6G_MB_LIB.T6G(SCH_1):PAGE110

R3272 Q_RES_0402LF-1K,1%,1/16W,EMPTY,CS21002FB06
     1 FM_P2E_EQA1 @T6G_MB_LIB.T6G(SCH_1):FM_P2E_EQA1     I4 @T6G_MB_LIB.T6G(SCH_1):PAGE110
     2    GND @T6G_MB_LIB.T6G(SCH_1):GND     I4 @T6G_MB_LIB.T6G(SCH_1):PAGE110

R3273 Q_RES_0402LF-68K,1%,1/16W,EMPTY,CS36802FB04
     1 FM_P2E_FGA @T6G_MB_LIB.T6G(SCH_1):FM_P2E_FGA    I12 @T6G_MB_LIB.T6G(SCH_1):PAGE110
     2    GND @T6G_MB_LIB.T6G(SCH_1):GND    I12 @T6G_MB_LIB.T6G(SCH_1):PAGE110

R3274 Q_RES_0402LF-68K,1%,1/16W,EMPTY,CS36802FB04
     1 FM_P2E_EQA0 @T6G_MB_LIB.T6G(SCH_1):FM_P2E_EQA0    I16 @T6G_MB_LIB.T6G(SCH_1):PAGE110
     2    GND @T6G_MB_LIB.T6G(SCH_1):GND    I16 @T6G_MB_LIB.T6G(SCH_1):PAGE110

R3275 Q_RES_0402LF-1K,1%,1/16W,EMPTY,CS21002FB06
     1 P3V3_AUX @T6G_MB_LIB.T6G(SCH_1):P3V3_AUX    I32 @T6G_MB_LIB.T6G(SCH_1):PAGE110
     2 FM_P2E_FGA @T6G_MB_LIB.T6G(SCH_1):FM_P2E_FGA    I32 @T6G_MB_LIB.T6G(SCH_1):PAGE110

R3276 Q_RES_0402LF-1K,1%,1/16W,EMPTY,CS21002FB06
     1 FM_P2E_FGA @T6G_MB_LIB.T6G(SCH_1):FM_P2E_FGA    I29 @T6G_MB_LIB.T6G(SCH_1):PAGE110
     2    GND @T6G_MB_LIB.T6G(SCH_1):GND    I29 @T6G_MB_LIB.T6G(SCH_1):PAGE110

R3277 Q_RES_0402LF-1K,1%,1/16W,EMPTY,CS21002FB06
     1 P3V3_AUX @T6G_MB_LIB.T6G(SCH_1):P3V3_AUX    I19 @T6G_MB_LIB.T6G(SCH_1):PAGE110
     2 FM_P2E_EQA0 @T6G_MB_LIB.T6G(SCH_1):FM_P2E_EQA0    I19 @T6G_MB_LIB.T6G(SCH_1):PAGE110

R3278 Q_RES_0402LF-1K,1%,1/16W,CHIP,CS21002FB06
     1 FM_P2E_EQA0 @T6G_MB_LIB.T6G(SCH_1):FM_P2E_EQA0    I18 @T6G_MB_LIB.T6G(SCH_1):PAGE110
     2    GND @T6G_MB_LIB.T6G(SCH_1):GND    I18 @T6G_MB_LIB.T6G(SCH_1):PAGE110

R3279 Q_RES_0402LF-68K,1%,1/16W,EMPTY,CS36802FB04
     1 FM_P2E_EQB1 @T6G_MB_LIB.T6G(SCH_1):FM_P2E_EQB1    I22 @T6G_MB_LIB.T6G(SCH_1):PAGE110
     2    GND @T6G_MB_LIB.T6G(SCH_1):GND    I22 @T6G_MB_LIB.T6G(SCH_1):PAGE110

R3280 Q_RES_0402LF-1K,1%,1/16W,EMPTY,CS21002FB06
     1 P3V3_AUX @T6G_MB_LIB.T6G(SCH_1):P3V3_AUX    I26 @T6G_MB_LIB.T6G(SCH_1):PAGE110
     2 FM_P2E_EQB1 @T6G_MB_LIB.T6G(SCH_1):FM_P2E_EQB1    I26 @T6G_MB_LIB.T6G(SCH_1):PAGE110

R3281 Q_RES_0402LF-1K,1%,1/16W,EMPTY,CS21002FB06
     1 FM_P2E_EQB1 @T6G_MB_LIB.T6G(SCH_1):FM_P2E_EQB1    I25 @T6G_MB_LIB.T6G(SCH_1):PAGE110
     2    GND @T6G_MB_LIB.T6G(SCH_1):GND    I25 @T6G_MB_LIB.T6G(SCH_1):PAGE110

R3282 Q_RES_0402LF-68K,1%,1/16W,EMPTY,CS36802FB04
     1 FM_P2E_EQB0 @T6G_MB_LIB.T6G(SCH_1):FM_P2E_EQB0    I34 @T6G_MB_LIB.T6G(SCH_1):PAGE110
     2    GND @T6G_MB_LIB.T6G(SCH_1):GND    I34 @T6G_MB_LIB.T6G(SCH_1):PAGE110

R3283 Q_RES_0402LF-1K,1%,1/16W,EMPTY,CS21002FB06
     1 P3V3_AUX @T6G_MB_LIB.T6G(SCH_1):P3V3_AUX    I37 @T6G_MB_LIB.T6G(SCH_1):PAGE110
     2 FM_P2E_EQB0 @T6G_MB_LIB.T6G(SCH_1):FM_P2E_EQB0    I37 @T6G_MB_LIB.T6G(SCH_1):PAGE110

R3284 Q_RES_0402LF-1K,1%,1/16W,CHIP,CS21002FB06
     1 FM_P2E_EQB0 @T6G_MB_LIB.T6G(SCH_1):FM_P2E_EQB0    I36 @T6G_MB_LIB.T6G(SCH_1):PAGE110
     2    GND @T6G_MB_LIB.T6G(SCH_1):GND    I36 @T6G_MB_LIB.T6G(SCH_1):PAGE110

R3285 Q_RES_0402LF-68K,1%,1/16W,EMPTY,CS36802FB04
     1 FM_P2E_SWB @T6G_MB_LIB.T6G(SCH_1):FM_P2E_SWB    I42 @T6G_MB_LIB.T6G(SCH_1):PAGE110
     2    GND @T6G_MB_LIB.T6G(SCH_1):GND    I42 @T6G_MB_LIB.T6G(SCH_1):PAGE110

R3286 Q_RES_0402LF-1K,1%,1/16W,EMPTY,CS21002FB06
     1 P3V3_AUX @T6G_MB_LIB.T6G(SCH_1):P3V3_AUX    I45 @T6G_MB_LIB.T6G(SCH_1):PAGE110
     2 FM_P2E_SWB @T6G_MB_LIB.T6G(SCH_1):FM_P2E_SWB    I45 @T6G_MB_LIB.T6G(SCH_1):PAGE110

R3287 Q_RES_0402LF-1K,1%,1/16W,EMPTY,CS21002FB06
     1 FM_P2E_SWB @T6G_MB_LIB.T6G(SCH_1):FM_P2E_SWB    I44 @T6G_MB_LIB.T6G(SCH_1):PAGE110
     2    GND @T6G_MB_LIB.T6G(SCH_1):GND    I44 @T6G_MB_LIB.T6G(SCH_1):PAGE110

R3288 Q_RES_0402LF-68K,1%,1/16W,EMPTY,CS36802FB04
     1 FM_P2E_SWA @T6G_MB_LIB.T6G(SCH_1):FM_P2E_SWA    I74 @T6G_MB_LIB.T6G(SCH_1):PAGE110
     2    GND @T6G_MB_LIB.T6G(SCH_1):GND    I74 @T6G_MB_LIB.T6G(SCH_1):PAGE110

R3289 Q_RES_0402LF-1K,1%,1/16W,EMPTY,CS21002FB06
     1 P3V3_AUX @T6G_MB_LIB.T6G(SCH_1):P3V3_AUX    I77 @T6G_MB_LIB.T6G(SCH_1):PAGE110
     2 FM_P2E_SWA @T6G_MB_LIB.T6G(SCH_1):FM_P2E_SWA    I77 @T6G_MB_LIB.T6G(SCH_1):PAGE110

R3290 Q_RES_0402LF-1K,1%,1/16W,EMPTY,CS21002FB06
     1 FM_P2E_SWA @T6G_MB_LIB.T6G(SCH_1):FM_P2E_SWA    I76 @T6G_MB_LIB.T6G(SCH_1):PAGE110
     2    GND @T6G_MB_LIB.T6G(SCH_1):GND    I76 @T6G_MB_LIB.T6G(SCH_1):PAGE110

R3291 Q_RES_0402LF-4.7K,1%,1/16W,EMPTY,CS24702FB06
     1 PU_TEST @T6G_MB_LIB.T6G(SCH_1):PU_TEST    I88 @T6G_MB_LIB.T6G(SCH_1):PAGE110
     2    GND @T6G_MB_LIB.T6G(SCH_1):GND    I88 @T6G_MB_LIB.T6G(SCH_1):PAGE110

R3292 Q_RES_0402LF-4.7K,1%,1/16W,CHIP,CS24702FB06
     1 P3V3_AUX @T6G_MB_LIB.T6G(SCH_1):P3V3_AUX    I89 @T6G_MB_LIB.T6G(SCH_1):PAGE110
     2 CLK_GEN2_GPU_FPGA_OE_OR_N @T6G_MB_LIB.T6G(SCH_1):CLK_GEN2_GPU_FPGA_OE_OR_N    I89 @T6G_MB_LIB.T6G(SCH_1):PAGE110

R3293 Q_RES_0402LF-4.7K,1%,1/16W,EMPTY,CS24702FB06
     1 FM_P2E_MODE @T6G_MB_LIB.T6G(SCH_1):FM_P2E_MODE    I92 @T6G_MB_LIB.T6G(SCH_1):PAGE110
     2    GND @T6G_MB_LIB.T6G(SCH_1):GND    I92 @T6G_MB_LIB.T6G(SCH_1):PAGE110

R3294 Q_RES_0402LF-0,5%,1/16W,CHIP,CS00002JB13
     1 LED_M2_SSD_0_ACT_N @T6G_MB_LIB.T6G(SCH_1):LED_M2_SSD_0_ACT_N    I19 @T6G_MB_LIB.T6G(SCH_1):PAGE345
     2 LED_HDD_ACTIVITY_N @T6G_MB_LIB.T6G(SCH_1):LED_HDD_ACTIVITY_N    I19 @T6G_MB_LIB.T6G(SCH_1):PAGE345

R3295 Q_RES_0402LF-4.7K,1%,1/16W,CHIP,CS24702FB06
     1 P3V3_M2_0 @T6G_MB_LIB.T6G(SCH_1):P3V3_M2_0    I21 @T6G_MB_LIB.T6G(SCH_1):PAGE345
     2 LED_HDD_ACTIVITY_N @T6G_MB_LIB.T6G(SCH_1):LED_HDD_ACTIVITY_N    I21 @T6G_MB_LIB.T6G(SCH_1):PAGE345

R3296 Q_RES_0402LF-4.7K,1%,1/16W,CHIP,CS24702FB06
     1 P3V3_AUX @T6G_MB_LIB.T6G(SCH_1):P3V3_AUX    I51 @T6G_MB_LIB.T6G(SCH_1):PAGE345
     2 HDD_ACTIVITY_BUF @T6G_MB_LIB.T6G(SCH_1):HDD_ACTIVITY_BUF    I51 @T6G_MB_LIB.T6G(SCH_1):PAGE345

R3297 Q_RES_0402LF-10K,1%,1/16W,CHIP,CS31002FB08
     1 LED_HDD_ACTIVITY_B_N @T6G_MB_LIB.T6G(SCH_1):LED_HDD_ACTIVITY_B_N    I60 @T6G_MB_LIB.T6G(SCH_1):PAGE345
     2    GND @T6G_MB_LIB.T6G(SCH_1):GND    I60 @T6G_MB_LIB.T6G(SCH_1):PAGE345

R3298 Q_RES_0402LF-10K,1%,1/16W,CHIP,CS31002FB08
     1 P3V3_AUX @T6G_MB_LIB.T6G(SCH_1):P3V3_AUX    I58 @T6G_MB_LIB.T6G(SCH_1):PAGE345
     2 HDD_ACTIVITY_BUF_N @T6G_MB_LIB.T6G(SCH_1):HDD_ACTIVITY_BUF_N    I58 @T6G_MB_LIB.T6G(SCH_1):PAGE345

R3301 Q_RES_0402LF-33.2,1%,1/16W,CHIP,CS03322FB03
     1 M2_0_PEWAKE_R_N @T6G_MB_LIB.T6G(SCH_1):M2_0_PEWAKE_R_N    I30 @T6G_MB_LIB.T6G(SCH_1):PAGE345
     2 M2_0_PEWAKE_N @T6G_MB_LIB.T6G(SCH_1):M2_0_PEWAKE_N    I30 @T6G_MB_LIB.T6G(SCH_1):PAGE345

R3303 Q_RES_0402LF-0,5%,1/16W,CHIP,CS00002JB13
     1 OCP_SFF_PRSNT_ALL_R_N @T6G_MB_LIB.T6G(SCH_1):OCP_SFF_PRSNT_ALL_R_N    I44 @T6G_MB_LIB.T6G(SCH_1):PAGE258
     2 OCP_SFF_PRSNT_ALL_R1_N @T6G_MB_LIB.T6G(SCH_1):OCP_SFF_PRSNT_ALL_R1_N    I44 @T6G_MB_LIB.T6G(SCH_1):PAGE258

R3304 Q_RES_0402LF-0,5%,1/16W,CHIP,CS00002JB13
     1 OCP_SFF_PRSNT_ALL_R_N @T6G_MB_LIB.T6G(SCH_1):OCP_SFF_PRSNT_ALL_R_N    I45 @T6G_MB_LIB.T6G(SCH_1):PAGE258
     2 OCP_SFF_PRSNT_ALL_R3_N @T6G_MB_LIB.T6G(SCH_1):OCP_SFF_PRSNT_ALL_R3_N    I45 @T6G_MB_LIB.T6G(SCH_1):PAGE258

R3305 Q_RES_0402LF-0,5%,1/16W,CHIP,CS00002JB13
     1 OCP_SFF_RBT_ARB_IN_MUX1 @T6G_MB_LIB.T6G(SCH_1):OCP_SFF_RBT_ARB_IN_MUX1    I50 @T6G_MB_LIB.T6G(SCH_1):PAGE258
     2 OCP_SFF_RBT_ARB_IN_MUX1_R @T6G_MB_LIB.T6G(SCH_1):OCP_SFF_RBT_ARB_IN_MUX1_R    I50 @T6G_MB_LIB.T6G(SCH_1):PAGE258

R3306 Q_RES_0402LF-0,5%,1/16W,CHIP,CS00002JB13
     1 OCP_V3_2_PRSNT_ALL_R_N @T6G_MB_LIB.T6G(SCH_1):OCP_V3_2_PRSNT_ALL_R_N    I47 @T6G_MB_LIB.T6G(SCH_1):PAGE258
     2 OCP_V3_2_PRSNT_ALL_R3_N @T6G_MB_LIB.T6G(SCH_1):OCP_V3_2_PRSNT_ALL_R3_N    I47 @T6G_MB_LIB.T6G(SCH_1):PAGE258

R3307 Q_RES_0402LF-0,5%,1/16W,CHIP,CS00002JB13
     1 OCP_SFF_RBT_ARB_IN_MUX2 @T6G_MB_LIB.T6G(SCH_1):OCP_SFF_RBT_ARB_IN_MUX2    I52 @T6G_MB_LIB.T6G(SCH_1):PAGE258
     2 OCP_SFF_RBT_ARB_IN_MUX2_R @T6G_MB_LIB.T6G(SCH_1):OCP_SFF_RBT_ARB_IN_MUX2_R    I52 @T6G_MB_LIB.T6G(SCH_1):PAGE258

R3308 Q_RES_0402LF-0,5%,1/16W,CHIP,CS00002JB13
     1 OCP_V3_2_PRSNT_ALL_R_N @T6G_MB_LIB.T6G(SCH_1):OCP_V3_2_PRSNT_ALL_R_N    I46 @T6G_MB_LIB.T6G(SCH_1):PAGE258
     2 OCP_V3_2_PRSNT_ALL_R1_N @T6G_MB_LIB.T6G(SCH_1):OCP_V3_2_PRSNT_ALL_R1_N    I46 @T6G_MB_LIB.T6G(SCH_1):PAGE258

R3315 Q_RES_0402LF-33.2,1%,1/16W,CHIP,CS03322FB03
     1 GPU_FPGA_RST_R1_BUF_N @T6G_MB_LIB.T6G(SCH_1):GPU_FPGA_RST_R1_BUF_N   I181 @T6G_MB_LIB.T6G(SCH_1):PAGE256
     2 GPU_FPGA_RST_R_BUF_N @T6G_MB_LIB.T6G(SCH_1):GPU_FPGA_RST_R_BUF_N   I181 @T6G_MB_LIB.T6G(SCH_1):PAGE256

R3317 Q_RES_0402LF-4.7K,5%,1/16W,EMPTY,CS24702JB10
     1 P3V3_AUX @T6G_MB_LIB.T6G(SCH_1):P3V3_AUX   I190 @T6G_MB_LIB.T6G(SCH_1):PAGE256
     2 GPU_FPGA_RST_R1_BUF_N @T6G_MB_LIB.T6G(SCH_1):GPU_FPGA_RST_R1_BUF_N   I190 @T6G_MB_LIB.T6G(SCH_1):PAGE256

R3318 Q_RES_0402LF-100K,1%,1/16W,EMPTY,CS41002FB09
     1 P3V3_AUX @T6G_MB_LIB.T6G(SCH_1):P3V3_AUX   I171 @T6G_MB_LIB.T6G(SCH_1):PAGE333
     2 GPU_FPGA_READY @T6G_MB_LIB.T6G(SCH_1):GPU_FPGA_READY   I171 @T6G_MB_LIB.T6G(SCH_1):PAGE333

R3320 Q_RES_0402LF-4.7K,5%,1/16W,CHIP,CS24702JB10
     1 P3V3_AUX @T6G_MB_LIB.T6G(SCH_1):P3V3_AUX   I162 @T6G_MB_LIB.T6G(SCH_1):PAGE333
     2 GPU_FPGA_READY_N @T6G_MB_LIB.T6G(SCH_1):GPU_FPGA_READY_N   I162 @T6G_MB_LIB.T6G(SCH_1):PAGE333

R3321 Q_RES_0402LF-100K,1%,1/16W,CHIP,CS41002FB09
     1 P3V3_AUX @T6G_MB_LIB.T6G(SCH_1):P3V3_AUX   I158 @T6G_MB_LIB.T6G(SCH_1):PAGE333
     2 GPU_FPGA_READY_ISO @T6G_MB_LIB.T6G(SCH_1):GPU_FPGA_READY_ISO   I158 @T6G_MB_LIB.T6G(SCH_1):PAGE333

R3322 Q_RES_0402LF-1K,1%,1/16W,CHIP,CS21002FB06
     1 P3V3_AUX @T6G_MB_LIB.T6G(SCH_1):P3V3_AUX    I74 @T6G_MB_LIB.T6G(SCH_1):PAGE232
     2 CLK_GEN2_GPU_FPGA_OE_R2_N @T6G_MB_LIB.T6G(SCH_1):CLK_GEN2_GPU_FPGA_OE_R2_N    I74 @T6G_MB_LIB.T6G(SCH_1):PAGE232

R3324 Q_RES_0402LF-33.2,1%,1/16W,CHIP,CS03322FB03
     1 GPU_FPGA_READY_ISO_R @T6G_MB_LIB.T6G(SCH_1):GPU_FPGA_READY_ISO_R   I276 @T6G_MB_LIB.T6G(SCH_1):PAGE80
     2 GPU_FPGA_READY_ISO @T6G_MB_LIB.T6G(SCH_1):GPU_FPGA_READY_ISO   I276 @T6G_MB_LIB.T6G(SCH_1):PAGE80

R3326 Q_RES_0402LF-0,5%,1/16W,CHIP,CS00002JB13
     1 GPU_FPGA_READY_N @T6G_MB_LIB.T6G(SCH_1):GPU_FPGA_READY_N     I7 @T6G_MB_LIB.T6G(SCH_1):PAGE232
     2 GPU_FPGA_READY_R_N @T6G_MB_LIB.T6G(SCH_1):GPU_FPGA_READY_R_N     I7 @T6G_MB_LIB.T6G(SCH_1):PAGE232

R3327 Q_RES_0402LF-0,5%,1/16W,CHIP,CS00002JB13
     1 CLK_GEN2_GPU_FPGA_OE_N @T6G_MB_LIB.T6G(SCH_1):CLK_GEN2_GPU_FPGA_OE_N     I6 @T6G_MB_LIB.T6G(SCH_1):PAGE232
     2 CLK_GEN2_GPU_FPGA_OE_R2_N @T6G_MB_LIB.T6G(SCH_1):CLK_GEN2_GPU_FPGA_OE_R2_N     I6 @T6G_MB_LIB.T6G(SCH_1):PAGE232

R3335 Q_RES_0402LF-0,5%,1/16W,CHIP,CS00002JB13
     1 CLK_100M_BMC_RC_DP_R @T6G_MB_LIB.T6G(SCH_1):CLK_100M_BMC_RC_DP_R    I53 @T6G_MB_LIB.T6G(SCH_1):PAGE232
     2 CLK_100M_BMC_RC_DP @T6G_MB_LIB.T6G(SCH_1):CLK_100M_BMC_RC_DP    I53 @T6G_MB_LIB.T6G(SCH_1):PAGE232

R3336 Q_RES_0402LF-0,5%,1/16W,CHIP,CS00002JB13
     1 CLK_100M_BMC_RC_DN_R @T6G_MB_LIB.T6G(SCH_1):CLK_100M_BMC_RC_DN_R    I52 @T6G_MB_LIB.T6G(SCH_1):PAGE232
     2 CLK_100M_BMC_RC_DN @T6G_MB_LIB.T6G(SCH_1):CLK_100M_BMC_RC_DN    I52 @T6G_MB_LIB.T6G(SCH_1):PAGE232

R3337 Q_RES_0402LF-0,5%,1/16W,CHIP,CS00002JB13
     1 CLK_100M_GPU_FPGA_DP_R @T6G_MB_LIB.T6G(SCH_1):CLK_100M_GPU_FPGA_DP_R    I51 @T6G_MB_LIB.T6G(SCH_1):PAGE232
     2 CLK_100M_GPU_FPGA_DP @T6G_MB_LIB.T6G(SCH_1):CLK_100M_GPU_FPGA_DP    I51 @T6G_MB_LIB.T6G(SCH_1):PAGE232

R3338 Q_RES_0402LF-0,5%,1/16W,CHIP,CS00002JB13
     1 CLK_100M_GPU_FPGA_DN_R @T6G_MB_LIB.T6G(SCH_1):CLK_100M_GPU_FPGA_DN_R    I50 @T6G_MB_LIB.T6G(SCH_1):PAGE232
     2 CLK_100M_GPU_FPGA_DN @T6G_MB_LIB.T6G(SCH_1):CLK_100M_GPU_FPGA_DN    I50 @T6G_MB_LIB.T6G(SCH_1):PAGE232

R3340 Q_RES_0402LF-33.2,1%,1/16W,CHIP,CS03322FB03
     1 SMB_HOST_CLK_3V3AUX_SCL @T6G_MB_LIB.T6G(SCH_1):SMB_HOST_CLK_3V3AUX_SCL    I81 @T6G_MB_LIB.T6G(SCH_1):PAGE349
     2 SMB_HOST_CLK_GEN2_3V3AUX_SCL @T6G_MB_LIB.T6G(SCH_1):SMB_HOST_CLK_GEN2_3V3AUX_SCL    I81 @T6G_MB_LIB.T6G(SCH_1):PAGE349

R3341 Q_RES_0402LF-33.2,1%,1/16W,CHIP,CS03322FB03
     1 SMB_HOST_CLK_3V3AUX_SDA @T6G_MB_LIB.T6G(SCH_1):SMB_HOST_CLK_3V3AUX_SDA    I82 @T6G_MB_LIB.T6G(SCH_1):PAGE349
     2 SMB_HOST_CLK_GEN2_3V3AUX_SDA @T6G_MB_LIB.T6G(SCH_1):SMB_HOST_CLK_GEN2_3V3AUX_SDA    I82 @T6G_MB_LIB.T6G(SCH_1):PAGE349

R3352 Q_RES_0402LF-0,5%,1/16W,CHIP,CS00002JB13
     1 CLK_100M_CPU1_CLK11_R_DP @T6G_MB_LIB.T6G(SCH_1):CLK_100M_CPU1_CLK11_R_DP   I302 @T6G_MB_LIB.T6G(SCH_1):PAGE55
     2 CLK_100M_CPU1_CLK11_DP @T6G_MB_LIB.T6G(SCH_1):CLK_100M_CPU1_CLK11_DP   I302 @T6G_MB_LIB.T6G(SCH_1):PAGE55

R3353 Q_RES_0402LF-0,5%,1/16W,CHIP,CS00002JB13
     1 CLK_100M_CPU1_CLK11_R_DN @T6G_MB_LIB.T6G(SCH_1):CLK_100M_CPU1_CLK11_R_DN   I303 @T6G_MB_LIB.T6G(SCH_1):PAGE55
     2 CLK_100M_CPU1_CLK11_DN @T6G_MB_LIB.T6G(SCH_1):CLK_100M_CPU1_CLK11_DN   I303 @T6G_MB_LIB.T6G(SCH_1):PAGE55

R3354 Q_RES_0402LF-0,5%,1/16W,CHIP,CS00002JB13
     1 CLK_100M_CPU1_CLK01_R_DP @T6G_MB_LIB.T6G(SCH_1):CLK_100M_CPU1_CLK01_R_DP   I307 @T6G_MB_LIB.T6G(SCH_1):PAGE55
     2 CLK_100M_CPU1_CLK01_DP @T6G_MB_LIB.T6G(SCH_1):CLK_100M_CPU1_CLK01_DP   I307 @T6G_MB_LIB.T6G(SCH_1):PAGE55

R3355 Q_RES_0402LF-0,5%,1/16W,CHIP,CS00002JB13
     1 CLK_100M_CPU1_CLK01_R_DN @T6G_MB_LIB.T6G(SCH_1):CLK_100M_CPU1_CLK01_R_DN   I306 @T6G_MB_LIB.T6G(SCH_1):PAGE55
     2 CLK_100M_CPU1_CLK01_DN @T6G_MB_LIB.T6G(SCH_1):CLK_100M_CPU1_CLK01_DN   I306 @T6G_MB_LIB.T6G(SCH_1):PAGE55

R3390 Q_RES_0402LF-49.9,1%,1/16W,CHIP,CS04992FB07
     1 GPU_FPGA_BOOT_EN_BUF_R @T6G_MB_LIB.T6G(SCH_1):GPU_FPGA_BOOT_EN_BUF_R   I162 @T6G_MB_LIB.T6G(SCH_1):PAGE334
     2 GPU_FPGA_BOOT_EN_BUF @T6G_MB_LIB.T6G(SCH_1):GPU_FPGA_BOOT_EN_BUF   I162 @T6G_MB_LIB.T6G(SCH_1):PAGE334

R3391 Q_RES_0402LF-49.9,1%,1/16W,CHIP,CS04992FB07
     1 RST_PERST_2_SWB_BUF_R_N @T6G_MB_LIB.T6G(SCH_1):RST_PERST_2_SWB_BUF_R_N   I140 @T6G_MB_LIB.T6G(SCH_1):PAGE334
     2 RST_PERST_2_SWB_BUF_N @T6G_MB_LIB.T6G(SCH_1):RST_PERST_2_SWB_BUF_N   I140 @T6G_MB_LIB.T6G(SCH_1):PAGE334

R3392 Q_RES_0402LF-49.9,1%,1/16W,CHIP,CS04992FB07
     1 GPU_BASE_STBY_EN_BUF_R @T6G_MB_LIB.T6G(SCH_1):GPU_BASE_STBY_EN_BUF_R    I62 @T6G_MB_LIB.T6G(SCH_1):PAGE334
     2 GPU_BASE_STBY_EN_BUF @T6G_MB_LIB.T6G(SCH_1):GPU_BASE_STBY_EN_BUF    I62 @T6G_MB_LIB.T6G(SCH_1):PAGE334

R3393 Q_RES_0402LF-0,5%,1/16W,CHIP,CS00002JB13
     1 SMB_IOEXP_3V3AUX_SCL_R @T6G_MB_LIB.T6G(SCH_1):SMB_IOEXP_3V3AUX_SCL_R    I27 @T6G_MB_LIB.T6G(SCH_1):PAGE252
     2 SMB_IOEXP_3V3AUX_SCL @T6G_MB_LIB.T6G(SCH_1):SMB_IOEXP_3V3AUX_SCL    I27 @T6G_MB_LIB.T6G(SCH_1):PAGE252

R3394 Q_RES_0402LF-0,5%,1/16W,CHIP,CS00002JB13
     1 SMB_IOEXP_3V3AUX_SDA_R @T6G_MB_LIB.T6G(SCH_1):SMB_IOEXP_3V3AUX_SDA_R    I29 @T6G_MB_LIB.T6G(SCH_1):PAGE252
     2 SMB_IOEXP_3V3AUX_SDA @T6G_MB_LIB.T6G(SCH_1):SMB_IOEXP_3V3AUX_SDA    I29 @T6G_MB_LIB.T6G(SCH_1):PAGE252

R3395 Q_RES_0402LF-2.2K,5%,1/16W,CHIP,CS22202JB07
     1 P3V3_AUX @T6G_MB_LIB.T6G(SCH_1):P3V3_AUX    I47 @T6G_MB_LIB.T6G(SCH_1):PAGE252
     2 SMB_INA230_3V3AUX_SCL @T6G_MB_LIB.T6G(SCH_1):SMB_INA230_3V3AUX_SCL    I47 @T6G_MB_LIB.T6G(SCH_1):PAGE252

R3396 Q_RES_0402LF-2.2K,5%,1/16W,CHIP,CS22202JB07
     1 P3V3_AUX @T6G_MB_LIB.T6G(SCH_1):P3V3_AUX    I48 @T6G_MB_LIB.T6G(SCH_1):PAGE252
     2 SMB_INA230_3V3AUX_SDA @T6G_MB_LIB.T6G(SCH_1):SMB_INA230_3V3AUX_SDA    I48 @T6G_MB_LIB.T6G(SCH_1):PAGE252

R3397 Q_RES_0402LF-33.2,1%,1/16W,CHIP,CS03322FB03
     1 GPU_NVS_PWR_BRAKE_N_R @T6G_MB_LIB.T6G(SCH_1):GPU_NVS_PWR_BRAKE_N_R    I37 @T6G_MB_LIB.T6G(SCH_1):PAGE255
     2 GPU_NVS_PWR_BRAKE_N_BUF @T6G_MB_LIB.T6G(SCH_1):GPU_NVS_PWR_BRAKE_N_BUF    I37 @T6G_MB_LIB.T6G(SCH_1):PAGE255

R3428 Q_RES_0402LF-100K,1%,1/16W,EMPTY,CS41002FB09
     1 GPU_FPGA_THERM_OVERT_N @T6G_MB_LIB.T6G(SCH_1):GPU_FPGA_THERM_OVERT_N    I17 @T6G_MB_LIB.T6G(SCH_1):PAGE299
     2    GND @T6G_MB_LIB.T6G(SCH_1):GND    I17 @T6G_MB_LIB.T6G(SCH_1):PAGE299

R3429 Q_RES_0402LF-100K,1%,1/16W,EMPTY,CS41002FB09
     1 P3V3_AUX @T6G_MB_LIB.T6G(SCH_1):P3V3_AUX   I130 @T6G_MB_LIB.T6G(SCH_1):PAGE299
     2 GPU_BASE_HMC_READY @T6G_MB_LIB.T6G(SCH_1):GPU_BASE_HMC_READY   I130 @T6G_MB_LIB.T6G(SCH_1):PAGE299

R3430 Q_RES_0402LF-100K,1%,1/16W,EMPTY,CS41002FB09
     1 GPU_FPGA_OVERT_N @T6G_MB_LIB.T6G(SCH_1):GPU_FPGA_OVERT_N     I3 @T6G_MB_LIB.T6G(SCH_1):PAGE299
     2    GND @T6G_MB_LIB.T6G(SCH_1):GND     I3 @T6G_MB_LIB.T6G(SCH_1):PAGE299

R3431 Q_RES_0402LF-100K,1%,1/16W,EMPTY,CS41002FB09
     1 GPU_HMC_PRSNT_N @T6G_MB_LIB.T6G(SCH_1):GPU_HMC_PRSNT_N   I133 @T6G_MB_LIB.T6G(SCH_1):PAGE299
     2    GND @T6G_MB_LIB.T6G(SCH_1):GND   I133 @T6G_MB_LIB.T6G(SCH_1):PAGE299

R3432 Q_RES_0402LF-4.7K,5%,1/16W,CHIP,CS24702JB10
     1 P3V3_AUX @T6G_MB_LIB.T6G(SCH_1):P3V3_AUX    I53 @T6G_MB_LIB.T6G(SCH_1):PAGE299
     2 GPU_FPGA_THERM_OVERT @T6G_MB_LIB.T6G(SCH_1):GPU_FPGA_THERM_OVERT    I53 @T6G_MB_LIB.T6G(SCH_1):PAGE299

R3433 Q_RES_0402LF-4.7K,5%,1/16W,CHIP,CS24702JB10
     1 P3V3_AUX @T6G_MB_LIB.T6G(SCH_1):P3V3_AUX    I49 @T6G_MB_LIB.T6G(SCH_1):PAGE299
     2 GPU_BASE_HMC_READY_N @T6G_MB_LIB.T6G(SCH_1):GPU_BASE_HMC_READY_N    I49 @T6G_MB_LIB.T6G(SCH_1):PAGE299

R3434 Q_RES_0402LF-4.7K,5%,1/16W,CHIP,CS24702JB10
     1 P3V3_AUX @T6G_MB_LIB.T6G(SCH_1):P3V3_AUX    I39 @T6G_MB_LIB.T6G(SCH_1):PAGE299
     2 GPU_HMC_PRSNT @T6G_MB_LIB.T6G(SCH_1):GPU_HMC_PRSNT    I39 @T6G_MB_LIB.T6G(SCH_1):PAGE299

R3435 Q_RES_0402LF-4.7K,5%,1/16W,CHIP,CS24702JB10
     1 P3V3_AUX @T6G_MB_LIB.T6G(SCH_1):P3V3_AUX    I23 @T6G_MB_LIB.T6G(SCH_1):PAGE299
     2 GPU_FPGA_OVERT @T6G_MB_LIB.T6G(SCH_1):GPU_FPGA_OVERT    I23 @T6G_MB_LIB.T6G(SCH_1):PAGE299

R3436 Q_RES_0402LF-100K,1%,1/16W,CHIP,CS41002FB09
     1 P3V3_AUX @T6G_MB_LIB.T6G(SCH_1):P3V3_AUX    I45 @T6G_MB_LIB.T6G(SCH_1):PAGE299
     2 GPU_HMC_PRSNT_ISO_N @T6G_MB_LIB.T6G(SCH_1):GPU_HMC_PRSNT_ISO_N    I45 @T6G_MB_LIB.T6G(SCH_1):PAGE299

R3437 Q_RES_0402LF-100K,1%,1/16W,CHIP,CS41002FB09
     1 P3V3_AUX @T6G_MB_LIB.T6G(SCH_1):P3V3_AUX    I27 @T6G_MB_LIB.T6G(SCH_1):PAGE299
     2 GPU_FPGA_OVERT_ISO_N @T6G_MB_LIB.T6G(SCH_1):GPU_FPGA_OVERT_ISO_N    I27 @T6G_MB_LIB.T6G(SCH_1):PAGE299

R3438 Q_RES_0402LF-100K,1%,1/16W,CHIP,CS41002FB09
     1 P3V3_AUX @T6G_MB_LIB.T6G(SCH_1):P3V3_AUX    I55 @T6G_MB_LIB.T6G(SCH_1):PAGE299
     2 GPU_BASE_HMC_READY_ISO @T6G_MB_LIB.T6G(SCH_1):GPU_BASE_HMC_READY_ISO    I55 @T6G_MB_LIB.T6G(SCH_1):PAGE299

R3439 Q_RES_0402LF-100K,1%,1/16W,CHIP,CS41002FB09
     1 P3V3_AUX @T6G_MB_LIB.T6G(SCH_1):P3V3_AUX    I59 @T6G_MB_LIB.T6G(SCH_1):PAGE299
     2 GPU_FPGA_THERM_OVERT_ISO_N @T6G_MB_LIB.T6G(SCH_1):GPU_FPGA_THERM_OVERT_ISO_N    I59 @T6G_MB_LIB.T6G(SCH_1):PAGE299

R3440 Q_RES_0402LF-0,5%,1/16W,EMPTY,CS00002JB13
     1 GPU_BASE_ID0 @T6G_MB_LIB.T6G(SCH_1):GPU_BASE_ID0    I65 @T6G_MB_LIB.T6G(SCH_1):PAGE330
     2    GND @T6G_MB_LIB.T6G(SCH_1):GND    I65 @T6G_MB_LIB.T6G(SCH_1):PAGE330

R3441 Q_RES_0402LF-0,5%,1/16W,CHIP,CS00002JB13
     1 GPU_BASE_ID1 @T6G_MB_LIB.T6G(SCH_1):GPU_BASE_ID1    I64 @T6G_MB_LIB.T6G(SCH_1):PAGE330
     2    GND @T6G_MB_LIB.T6G(SCH_1):GND    I64 @T6G_MB_LIB.T6G(SCH_1):PAGE330

R3442 Q_RES_0402LF-0,5%,1/16W,CHIP,CS00002JB13
     1 GPU_PEX_STRAP0 @T6G_MB_LIB.T6G(SCH_1):GPU_PEX_STRAP0    I67 @T6G_MB_LIB.T6G(SCH_1):PAGE330
     2    GND @T6G_MB_LIB.T6G(SCH_1):GND    I67 @T6G_MB_LIB.T6G(SCH_1):PAGE330

R3443 Q_RES_0402LF-0,5%,1/16W,CHIP,CS00002JB13
     1 GPU_PEX_STRAP1 @T6G_MB_LIB.T6G(SCH_1):GPU_PEX_STRAP1    I66 @T6G_MB_LIB.T6G(SCH_1):PAGE330
     2    GND @T6G_MB_LIB.T6G(SCH_1):GND    I66 @T6G_MB_LIB.T6G(SCH_1):PAGE330

R3448 Q_RES_0402LF-4.7K,5%,1/16W,EMPTY,CS24702JB10
     1 P3V3_AUX @T6G_MB_LIB.T6G(SCH_1):P3V3_AUX   I168 @T6G_MB_LIB.T6G(SCH_1):PAGE334
     2 GPU_FPGA_BOOT_EN @T6G_MB_LIB.T6G(SCH_1):GPU_FPGA_BOOT_EN   I168 @T6G_MB_LIB.T6G(SCH_1):PAGE334

R3449 Q_RES_0402LF-100K,1%,1/16W,CHIP,CS41002FB09
     1 GPU_FPGA_BOOT_EN @T6G_MB_LIB.T6G(SCH_1):GPU_FPGA_BOOT_EN   I170 @T6G_MB_LIB.T6G(SCH_1):PAGE334
     2    GND @T6G_MB_LIB.T6G(SCH_1):GND   I170 @T6G_MB_LIB.T6G(SCH_1):PAGE334

R3451 Q_RES_0402LF-4.7K,5%,1/16W,EMPTY,CS24702JB10
     1 P3V3_AUX @T6G_MB_LIB.T6G(SCH_1):P3V3_AUX   I127 @T6G_MB_LIB.T6G(SCH_1):PAGE334
     2 GPU_BASE_STBY_EN @T6G_MB_LIB.T6G(SCH_1):GPU_BASE_STBY_EN   I127 @T6G_MB_LIB.T6G(SCH_1):PAGE334

R3452 Q_RES_0402LF-100K,1%,1/16W,CHIP,CS41002FB09
     1 GPU_BASE_STBY_EN @T6G_MB_LIB.T6G(SCH_1):GPU_BASE_STBY_EN    I95 @T6G_MB_LIB.T6G(SCH_1):PAGE334
     2    GND @T6G_MB_LIB.T6G(SCH_1):GND    I95 @T6G_MB_LIB.T6G(SCH_1):PAGE334

R3453 Q_RES_0402LF-100K,1%,1/16W,EMPTY,CS41002FB09
     1 P3V3_AUX @T6G_MB_LIB.T6G(SCH_1):P3V3_AUX   I164 @T6G_MB_LIB.T6G(SCH_1):PAGE334
     2 GPU_FPGA_BOOT_EN_BUF_R @T6G_MB_LIB.T6G(SCH_1):GPU_FPGA_BOOT_EN_BUF_R   I164 @T6G_MB_LIB.T6G(SCH_1):PAGE334

R3454 Q_RES_0402LF-1K,1%,1/16W,CHIP,CS21002FB06
     1 GPU_FPGA_BOOT_EN_BUF_R @T6G_MB_LIB.T6G(SCH_1):GPU_FPGA_BOOT_EN_BUF_R   I165 @T6G_MB_LIB.T6G(SCH_1):PAGE334
     2    GND @T6G_MB_LIB.T6G(SCH_1):GND   I165 @T6G_MB_LIB.T6G(SCH_1):PAGE334

R3455 Q_RES_0402LF-10K,1%,1/16W,CHIP,CS31002FB08
     1 RST_PERST_2_SWB_BUF_R_N @T6G_MB_LIB.T6G(SCH_1):RST_PERST_2_SWB_BUF_R_N   I139 @T6G_MB_LIB.T6G(SCH_1):PAGE334
     2    GND @T6G_MB_LIB.T6G(SCH_1):GND   I139 @T6G_MB_LIB.T6G(SCH_1):PAGE334

R3456 Q_RES_0402LF-100K,1%,1/16W,EMPTY,CS41002FB09
     1 P3V3_AUX @T6G_MB_LIB.T6G(SCH_1):P3V3_AUX   I124 @T6G_MB_LIB.T6G(SCH_1):PAGE334
     2 GPU_BASE_STBY_EN_BUF_R @T6G_MB_LIB.T6G(SCH_1):GPU_BASE_STBY_EN_BUF_R   I124 @T6G_MB_LIB.T6G(SCH_1):PAGE334

R3457 Q_RES_0402LF-10K,1%,1/16W,CHIP,CS31002FB08
     1 GPU_BASE_STBY_EN_BUF_R @T6G_MB_LIB.T6G(SCH_1):GPU_BASE_STBY_EN_BUF_R   I123 @T6G_MB_LIB.T6G(SCH_1):PAGE334
     2    GND @T6G_MB_LIB.T6G(SCH_1):GND   I123 @T6G_MB_LIB.T6G(SCH_1):PAGE334

R3459 Q_RES_0402LF-1K,1%,1/16W,CHIP,CS21002FB06
     1 P3V3_AUX @T6G_MB_LIB.T6G(SCH_1):P3V3_AUX    I75 @T6G_MB_LIB.T6G(SCH_1):PAGE255
     2 GPU_NVS_PWR_BRAKE_N @T6G_MB_LIB.T6G(SCH_1):GPU_NVS_PWR_BRAKE_N    I75 @T6G_MB_LIB.T6G(SCH_1):PAGE255

R3460 Q_RES_0402LF-100K,1%,1/16W,EMPTY,CS41002FB09
     1 GPU_NVS_PWR_BRAKE_N @T6G_MB_LIB.T6G(SCH_1):GPU_NVS_PWR_BRAKE_N    I31 @T6G_MB_LIB.T6G(SCH_1):PAGE255
     2    GND @T6G_MB_LIB.T6G(SCH_1):GND    I31 @T6G_MB_LIB.T6G(SCH_1):PAGE255

R3461 Q_RES_0402LF-54.9K,1%,1/16W,CHIP,CS35492FB03
     1 P3V3_AUX @T6G_MB_LIB.T6G(SCH_1):P3V3_AUX    I35 @T6G_MB_LIB.T6G(SCH_1):PAGE255
     2 GPU_NVS_PWR_BRAKE_N_R @T6G_MB_LIB.T6G(SCH_1):GPU_NVS_PWR_BRAKE_N_R    I35 @T6G_MB_LIB.T6G(SCH_1):PAGE255

R3462 Q_RES_0402LF-100K,1%,1/16W,EMPTY,CS41002FB09
     1 GPU_NVS_PWR_BRAKE_N_R @T6G_MB_LIB.T6G(SCH_1):GPU_NVS_PWR_BRAKE_N_R    I33 @T6G_MB_LIB.T6G(SCH_1):PAGE255
     2    GND @T6G_MB_LIB.T6G(SCH_1):GND    I33 @T6G_MB_LIB.T6G(SCH_1):PAGE255

R3463 Q_RES_0402LF-54.9K,1%,1/16W,CHIP,CS35492FB03
     1 GPU_BASE_HMC_READY @T6G_MB_LIB.T6G(SCH_1):GPU_BASE_HMC_READY   I131 @T6G_MB_LIB.T6G(SCH_1):PAGE299
     2    GND @T6G_MB_LIB.T6G(SCH_1):GND   I131 @T6G_MB_LIB.T6G(SCH_1):PAGE299

R3464 Q_RES_0402LF-54.9K,1%,1/16W,CHIP,CS35492FB03
     1 P3V3_AUX @T6G_MB_LIB.T6G(SCH_1):P3V3_AUX   I134 @T6G_MB_LIB.T6G(SCH_1):PAGE299
     2 GPU_FPGA_OVERT_N @T6G_MB_LIB.T6G(SCH_1):GPU_FPGA_OVERT_N   I134 @T6G_MB_LIB.T6G(SCH_1):PAGE299

R3465 Q_RES_0402LF-10K,1%,1/16W,CHIP,CS31002FB08
     1 P3V3_AUX @T6G_MB_LIB.T6G(SCH_1):P3V3_AUX   I132 @T6G_MB_LIB.T6G(SCH_1):PAGE299
     2 GPU_HMC_PRSNT_N @T6G_MB_LIB.T6G(SCH_1):GPU_HMC_PRSNT_N   I132 @T6G_MB_LIB.T6G(SCH_1):PAGE299

R3466 Q_RES_0402LF-10K,1%,1/16W,CHIP,CS31002FB08
     1 RST_PERST_1_SWB_BUF_R_N @T6G_MB_LIB.T6G(SCH_1):RST_PERST_1_SWB_BUF_R_N   I184 @T6G_MB_LIB.T6G(SCH_1):PAGE334
     2    GND @T6G_MB_LIB.T6G(SCH_1):GND   I184 @T6G_MB_LIB.T6G(SCH_1):PAGE334

R3467 Q_RES_0402LF-10K,1%,1/16W,CHIP,CS31002FB08
     1 RST_PERST_0_SWB_BUF_R_N @T6G_MB_LIB.T6G(SCH_1):RST_PERST_0_SWB_BUF_R_N   I181 @T6G_MB_LIB.T6G(SCH_1):PAGE334
     2    GND @T6G_MB_LIB.T6G(SCH_1):GND   I181 @T6G_MB_LIB.T6G(SCH_1):PAGE334

R3468 Q_RES_0402LF-49.9,1%,1/16W,CHIP,CS04992FB07
     1 RST_PERST_1_SWB_BUF_R_N @T6G_MB_LIB.T6G(SCH_1):RST_PERST_1_SWB_BUF_R_N   I183 @T6G_MB_LIB.T6G(SCH_1):PAGE334
     2 RST_PERST_1_SWB_BUF_N @T6G_MB_LIB.T6G(SCH_1):RST_PERST_1_SWB_BUF_N   I183 @T6G_MB_LIB.T6G(SCH_1):PAGE334

R3469 Q_RES_0402LF-49.9,1%,1/16W,CHIP,CS04992FB07
     1 RST_PERST_0_SWB_BUF_R_N @T6G_MB_LIB.T6G(SCH_1):RST_PERST_0_SWB_BUF_R_N   I180 @T6G_MB_LIB.T6G(SCH_1):PAGE334
     2 RST_PERST_0_SWB_BUF_N @T6G_MB_LIB.T6G(SCH_1):RST_PERST_0_SWB_BUF_N   I180 @T6G_MB_LIB.T6G(SCH_1):PAGE334

R3470 Q_RES_0402LF-1K,1%,1/16W,CHIP,CS21002FB06
     1 P3V3_AUX @T6G_MB_LIB.T6G(SCH_1):P3V3_AUX   I202 @T6G_MB_LIB.T6G(SCH_1):PAGE299
     2 GPU_WP_HW_CTRL_N @T6G_MB_LIB.T6G(SCH_1):GPU_WP_HW_CTRL_N   I202 @T6G_MB_LIB.T6G(SCH_1):PAGE299

R3471 Q_RES_0402LF-10K,1%,1/16W,EMPTY,CS31002FB08
     1 GPU_WP_HW_CTRL_N @T6G_MB_LIB.T6G(SCH_1):GPU_WP_HW_CTRL_N   I187 @T6G_MB_LIB.T6G(SCH_1):PAGE299
     2    GND @T6G_MB_LIB.T6G(SCH_1):GND   I187 @T6G_MB_LIB.T6G(SCH_1):PAGE299

R3472 Q_RES_0402LF-0,5%,1/16W,EMPTY,CS00002JB13
     1    GND @T6G_MB_LIB.T6G(SCH_1):GND   I198 @T6G_MB_LIB.T6G(SCH_1):PAGE299
     2 GPU_WP_HW_CTRL_ISO_N @T6G_MB_LIB.T6G(SCH_1):GPU_WP_HW_CTRL_ISO_N   I198 @T6G_MB_LIB.T6G(SCH_1):PAGE299

R3473 Q_RES_0402LF-100K,1%,1/16W,EMPTY,CS41002FB09
     1 GPU_PRSNT_N @T6G_MB_LIB.T6G(SCH_1):GPU_PRSNT_N   I163 @T6G_MB_LIB.T6G(SCH_1):PAGE299
     2    GND @T6G_MB_LIB.T6G(SCH_1):GND   I163 @T6G_MB_LIB.T6G(SCH_1):PAGE299

R3474 Q_RES_0402LF-4.7K,5%,1/16W,CHIP,CS24702JB10
     1 P3V3_AUX @T6G_MB_LIB.T6G(SCH_1):P3V3_AUX   I158 @T6G_MB_LIB.T6G(SCH_1):PAGE299
     2 GPU_PRSNT @T6G_MB_LIB.T6G(SCH_1):GPU_PRSNT   I158 @T6G_MB_LIB.T6G(SCH_1):PAGE299

R3475 Q_RES_0402LF-100K,1%,1/16W,CHIP,CS41002FB09
     1 P3V3_AUX @T6G_MB_LIB.T6G(SCH_1):P3V3_AUX   I154 @T6G_MB_LIB.T6G(SCH_1):PAGE299
     2 GPU_PRSNT_N_ISO @T6G_MB_LIB.T6G(SCH_1):GPU_PRSNT_N_ISO   I154 @T6G_MB_LIB.T6G(SCH_1):PAGE299

R3476 Q_RES_0402LF-33.2,1%,1/16W,CHIP,CS03322FB03
     1 GPU_FPGA_THERM_OVERT_ISO_R_N @T6G_MB_LIB.T6G(SCH_1):GPU_FPGA_THERM_OVERT_ISO_R_N   I250 @T6G_MB_LIB.T6G(SCH_1):PAGE80
     2 GPU_FPGA_THERM_OVERT_ISO_N @T6G_MB_LIB.T6G(SCH_1):GPU_FPGA_THERM_OVERT_ISO_N   I250 @T6G_MB_LIB.T6G(SCH_1):PAGE80

R3477 Q_RES_0402LF-33.2,1%,1/16W,CHIP,CS03322FB03
     1 GPU_NVS_PWR_BRAKE_N @T6G_MB_LIB.T6G(SCH_1):GPU_NVS_PWR_BRAKE_N   I286 @T6G_MB_LIB.T6G(SCH_1):PAGE80
     2 GPU_NVS_PWR_BRAKE_R_N @T6G_MB_LIB.T6G(SCH_1):GPU_NVS_PWR_BRAKE_R_N   I286 @T6G_MB_LIB.T6G(SCH_1):PAGE80

R3478 Q_RES_0402LF-33.2,1%,1/16W,CHIP,CS03322FB03
     1 GPU_FPGA_EROT_RST_N @T6G_MB_LIB.T6G(SCH_1):GPU_FPGA_EROT_RST_N   I288 @T6G_MB_LIB.T6G(SCH_1):PAGE80
     2 GPU_FPGA_EROT_RST_R_N @T6G_MB_LIB.T6G(SCH_1):GPU_FPGA_EROT_RST_R_N   I288 @T6G_MB_LIB.T6G(SCH_1):PAGE80

R3479 Q_RES_0402LF-33.2,1%,1/16W,CHIP,CS03322FB03
     1 GPU_BASE_STBY_EN_R @T6G_MB_LIB.T6G(SCH_1):GPU_BASE_STBY_EN_R   I281 @T6G_MB_LIB.T6G(SCH_1):PAGE80
     2 GPU_BASE_STBY_EN @T6G_MB_LIB.T6G(SCH_1):GPU_BASE_STBY_EN   I281 @T6G_MB_LIB.T6G(SCH_1):PAGE80

R3480 Q_RES_0402LF-33.2,1%,1/16W,CHIP,CS03322FB03
     1 GPU_BASE_HMC_READY_ISO_R @T6G_MB_LIB.T6G(SCH_1):GPU_BASE_HMC_READY_ISO_R   I247 @T6G_MB_LIB.T6G(SCH_1):PAGE80
     2 GPU_BASE_HMC_READY_ISO @T6G_MB_LIB.T6G(SCH_1):GPU_BASE_HMC_READY_ISO   I247 @T6G_MB_LIB.T6G(SCH_1):PAGE80

R3481 Q_RES_0402LF-33.2,1%,1/16W,CHIP,CS03322FB03
     1 GPU_HMC_PRSNT_ISO_R_N @T6G_MB_LIB.T6G(SCH_1):GPU_HMC_PRSNT_ISO_R_N   I251 @T6G_MB_LIB.T6G(SCH_1):PAGE80
     2 GPU_HMC_PRSNT_ISO_N @T6G_MB_LIB.T6G(SCH_1):GPU_HMC_PRSNT_ISO_N   I251 @T6G_MB_LIB.T6G(SCH_1):PAGE80

R3482 Q_RES_0402LF-33.2,1%,1/16W,CHIP,CS03322FB03
     1 GPU_FPGA_BOOT_EN_R @T6G_MB_LIB.T6G(SCH_1):GPU_FPGA_BOOT_EN_R   I278 @T6G_MB_LIB.T6G(SCH_1):PAGE80
     2 GPU_FPGA_BOOT_EN @T6G_MB_LIB.T6G(SCH_1):GPU_FPGA_BOOT_EN   I278 @T6G_MB_LIB.T6G(SCH_1):PAGE80

R3483 Q_RES_0402LF-33.2,1%,1/16W,CHIP,CS03322FB03
     1 GPU_FPGA_EROT_RECOV_N @T6G_MB_LIB.T6G(SCH_1):GPU_FPGA_EROT_RECOV_N   I290 @T6G_MB_LIB.T6G(SCH_1):PAGE80
     2 GPU_FPGA_EROT_RECOV_R_N @T6G_MB_LIB.T6G(SCH_1):GPU_FPGA_EROT_RECOV_R_N   I290 @T6G_MB_LIB.T6G(SCH_1):PAGE80

R3484 Q_RES_0402LF-33.2,1%,1/16W,CHIP,CS03322FB03
     1 GPU_FPGA_OVERT_ISO_R_N @T6G_MB_LIB.T6G(SCH_1):GPU_FPGA_OVERT_ISO_R_N   I254 @T6G_MB_LIB.T6G(SCH_1):PAGE80
     2 GPU_FPGA_OVERT_ISO_N @T6G_MB_LIB.T6G(SCH_1):GPU_FPGA_OVERT_ISO_N   I254 @T6G_MB_LIB.T6G(SCH_1):PAGE80

R3485 Q_RES_0402LF-33.2,1%,1/16W,CHIP,CS03322FB03
     1 GPU_WP_HW_CTRL_R_N @T6G_MB_LIB.T6G(SCH_1):GPU_WP_HW_CTRL_R_N   I255 @T6G_MB_LIB.T6G(SCH_1):PAGE80
     2 GPU_WP_HW_CTRL_N @T6G_MB_LIB.T6G(SCH_1):GPU_WP_HW_CTRL_N   I255 @T6G_MB_LIB.T6G(SCH_1):PAGE80

R3486 Q_RES_0402LF-33.2,1%,1/16W,CHIP,CS03322FB03
     1 GPU_PRSNT_N_ISO_R @T6G_MB_LIB.T6G(SCH_1):GPU_PRSNT_N_ISO_R   I258 @T6G_MB_LIB.T6G(SCH_1):PAGE80
     2 GPU_PRSNT_N_ISO @T6G_MB_LIB.T6G(SCH_1):GPU_PRSNT_N_ISO   I258 @T6G_MB_LIB.T6G(SCH_1):PAGE80

R3487 Q_RES_0402LF-10K,1%,1/16W,CHIP,CS31002FB08
     1 P3V3_AUX @T6G_MB_LIB.T6G(SCH_1):P3V3_AUX   I166 @T6G_MB_LIB.T6G(SCH_1):PAGE299
     2 GPU_PRSNT_N @T6G_MB_LIB.T6G(SCH_1):GPU_PRSNT_N   I166 @T6G_MB_LIB.T6G(SCH_1):PAGE299

R3488 Q_RES_0402LF-1K,1%,1/16W,CHIP,CS21002FB06
     1 P3V3_AUX @T6G_MB_LIB.T6G(SCH_1):P3V3_AUX    I40 @T6G_MB_LIB.T6G(SCH_1):PAGE255
     2 GPU_FPGA_EROT_RST_N @T6G_MB_LIB.T6G(SCH_1):GPU_FPGA_EROT_RST_N    I40 @T6G_MB_LIB.T6G(SCH_1):PAGE255

R3489 Q_RES_0402LF-100K,1%,1/16W,EMPTY,CS41002FB09
     1 GPU_FPGA_EROT_RST_N @T6G_MB_LIB.T6G(SCH_1):GPU_FPGA_EROT_RST_N    I42 @T6G_MB_LIB.T6G(SCH_1):PAGE255
     2    GND @T6G_MB_LIB.T6G(SCH_1):GND    I42 @T6G_MB_LIB.T6G(SCH_1):PAGE255

R3490 Q_RES_0402LF-1K,1%,1/16W,CHIP,CS21002FB06
     1 P3V3_AUX @T6G_MB_LIB.T6G(SCH_1):P3V3_AUX    I57 @T6G_MB_LIB.T6G(SCH_1):PAGE255
     2 GPU_FPGA_EROT_RECOV_N @T6G_MB_LIB.T6G(SCH_1):GPU_FPGA_EROT_RECOV_N    I57 @T6G_MB_LIB.T6G(SCH_1):PAGE255

R3491 Q_RES_0402LF-100K,1%,1/16W,EMPTY,CS41002FB09
     1 GPU_FPGA_EROT_RECOV_N @T6G_MB_LIB.T6G(SCH_1):GPU_FPGA_EROT_RECOV_N    I70 @T6G_MB_LIB.T6G(SCH_1):PAGE255
     2    GND @T6G_MB_LIB.T6G(SCH_1):GND    I70 @T6G_MB_LIB.T6G(SCH_1):PAGE255

R3492 Q_RES_0402LF-54.9K,1%,1/16W,CHIP,CS35492FB03
     1 P3V3_AUX @T6G_MB_LIB.T6G(SCH_1):P3V3_AUX    I47 @T6G_MB_LIB.T6G(SCH_1):PAGE255
     2 GPU_FPGA_EROT_RST_BUF_R_N @T6G_MB_LIB.T6G(SCH_1):GPU_FPGA_EROT_RST_BUF_R_N    I47 @T6G_MB_LIB.T6G(SCH_1):PAGE255

R3493 Q_RES_0402LF-100K,1%,1/16W,EMPTY,CS41002FB09
     1 GPU_FPGA_EROT_RST_BUF_R_N @T6G_MB_LIB.T6G(SCH_1):GPU_FPGA_EROT_RST_BUF_R_N    I48 @T6G_MB_LIB.T6G(SCH_1):PAGE255
     2    GND @T6G_MB_LIB.T6G(SCH_1):GND    I48 @T6G_MB_LIB.T6G(SCH_1):PAGE255

R3494 Q_RES_0402LF-54.9K,1%,1/16W,CHIP,CS35492FB03
     1 P3V3_AUX @T6G_MB_LIB.T6G(SCH_1):P3V3_AUX    I55 @T6G_MB_LIB.T6G(SCH_1):PAGE255
     2 GPU_FPGA_EROT_RECOV_BUF_R_N @T6G_MB_LIB.T6G(SCH_1):GPU_FPGA_EROT_RECOV_BUF_R_N    I55 @T6G_MB_LIB.T6G(SCH_1):PAGE255

R3495 Q_RES_0402LF-100K,1%,1/16W,EMPTY,CS41002FB09
     1 GPU_FPGA_EROT_RECOV_BUF_R_N @T6G_MB_LIB.T6G(SCH_1):GPU_FPGA_EROT_RECOV_BUF_R_N    I62 @T6G_MB_LIB.T6G(SCH_1):PAGE255
     2    GND @T6G_MB_LIB.T6G(SCH_1):GND    I62 @T6G_MB_LIB.T6G(SCH_1):PAGE255

R3496 Q_RES_0402LF-33.2,1%,1/16W,CHIP,CS03322FB03
     1 GPU_FPGA_EROT_RST_BUF_R_N @T6G_MB_LIB.T6G(SCH_1):GPU_FPGA_EROT_RST_BUF_R_N    I45 @T6G_MB_LIB.T6G(SCH_1):PAGE255
     2 GPU_FPGA_EROT_RST_BUF_N @T6G_MB_LIB.T6G(SCH_1):GPU_FPGA_EROT_RST_BUF_N    I45 @T6G_MB_LIB.T6G(SCH_1):PAGE255

R3497 Q_RES_0402LF-33.2,1%,1/16W,CHIP,CS03322FB03
     1 GPU_FPGA_EROT_RECOV_BUF_R_N @T6G_MB_LIB.T6G(SCH_1):GPU_FPGA_EROT_RECOV_BUF_R_N    I53 @T6G_MB_LIB.T6G(SCH_1):PAGE255
     2 GPU_FPGA_EROT_RECOV_BUF_N @T6G_MB_LIB.T6G(SCH_1):GPU_FPGA_EROT_RECOV_BUF_N    I53 @T6G_MB_LIB.T6G(SCH_1):PAGE255

R3498 Q_RES_0402LF-54.9K,1%,1/16W,CHIP,CS35492FB03
     1 P3V3_AUX @T6G_MB_LIB.T6G(SCH_1):P3V3_AUX   I167 @T6G_MB_LIB.T6G(SCH_1):PAGE299
     2 GPU_FPGA_THERM_OVERT_N @T6G_MB_LIB.T6G(SCH_1):GPU_FPGA_THERM_OVERT_N   I167 @T6G_MB_LIB.T6G(SCH_1):PAGE299

R3499 Q_RES_0402LF-0,5%,1/16W,CHIP,CS00002JB13
     1 GPU_BASE_ID1 @T6G_MB_LIB.T6G(SCH_1):GPU_BASE_ID1    I57 @T6G_MB_LIB.T6G(SCH_1):PAGE246
     2 GPU_BASE_ID1_R @T6G_MB_LIB.T6G(SCH_1):GPU_BASE_ID1_R    I57 @T6G_MB_LIB.T6G(SCH_1):PAGE246

R3500 Q_RES_0402LF-4.7K,5%,1/16W,CHIP,CS24702JB10
     1 P3V3_OCP_SFF @T6G_MB_LIB.T6G(SCH_1):P3V3_OCP_SFF    I27 @T6G_MB_LIB.T6G(SCH_1):PAGE248
     2 SMB_OCP_SFF_3V3AUX_BUF_SCL @T6G_MB_LIB.T6G(SCH_1):SMB_OCP_SFF_3V3AUX_BUF_SCL    I27 @T6G_MB_LIB.T6G(SCH_1):PAGE248

R3501 Q_RES_0402LF-4.7K,5%,1/16W,CHIP,CS24702JB10
     1 P3V3_OCP_SFF @T6G_MB_LIB.T6G(SCH_1):P3V3_OCP_SFF    I31 @T6G_MB_LIB.T6G(SCH_1):PAGE248
     2 SMB_OCP_SFF_3V3AUX_BUF_SDA @T6G_MB_LIB.T6G(SCH_1):SMB_OCP_SFF_3V3AUX_BUF_SDA    I31 @T6G_MB_LIB.T6G(SCH_1):PAGE248

R3502 Q_RES_0402LF-100K,1%,1/16W,EMPTY,CS41002FB09
     1 GPU_FPGA_EROT_FATALERR_N @T6G_MB_LIB.T6G(SCH_1):GPU_FPGA_EROT_FATALERR_N   I181 @T6G_MB_LIB.T6G(SCH_1):PAGE299
     2    GND @T6G_MB_LIB.T6G(SCH_1):GND   I181 @T6G_MB_LIB.T6G(SCH_1):PAGE299

R3503 Q_RES_0402LF-4.7K,5%,1/16W,CHIP,CS24702JB10
     1 P3V3_AUX @T6G_MB_LIB.T6G(SCH_1):P3V3_AUX   I177 @T6G_MB_LIB.T6G(SCH_1):PAGE299
     2 GPU_FPGA_EROT_FATALERR @T6G_MB_LIB.T6G(SCH_1):GPU_FPGA_EROT_FATALERR   I177 @T6G_MB_LIB.T6G(SCH_1):PAGE299

R3504 Q_RES_0402LF-100K,1%,1/16W,CHIP,CS41002FB09
     1 P3V3_AUX @T6G_MB_LIB.T6G(SCH_1):P3V3_AUX   I174 @T6G_MB_LIB.T6G(SCH_1):PAGE299
     2 GPU_FPGA_EROT_FATALERR_ISO_N @T6G_MB_LIB.T6G(SCH_1):GPU_FPGA_EROT_FATALERR_ISO_N   I174 @T6G_MB_LIB.T6G(SCH_1):PAGE299

R3505 Q_RES_0402LF-33.2,1%,1/16W,CHIP,CS03322FB03
     1 GPU_FPGA_EROT_FATALERR_ISO_R_N @T6G_MB_LIB.T6G(SCH_1):GPU_FPGA_EROT_FATALERR_ISO_R_N   I259 @T6G_MB_LIB.T6G(SCH_1):PAGE80
     2 GPU_FPGA_EROT_FATALERR_ISO_N @T6G_MB_LIB.T6G(SCH_1):GPU_FPGA_EROT_FATALERR_ISO_N   I259 @T6G_MB_LIB.T6G(SCH_1):PAGE80

R3506 Q_RES_0402LF-4.7K,5%,1/16W,EMPTY,CS24702JB10
     1 P3V3_AUX @T6G_MB_LIB.T6G(SCH_1):P3V3_AUX   I193 @T6G_MB_LIB.T6G(SCH_1):PAGE256
     2 GPU_FPGA_RST_R_N @T6G_MB_LIB.T6G(SCH_1):GPU_FPGA_RST_R_N   I193 @T6G_MB_LIB.T6G(SCH_1):PAGE256

R3507 Q_RES_0402LF-10K,1%,1/16W,CHIP,CS31002FB08
     1 GPU_FPGA_RST_R_N @T6G_MB_LIB.T6G(SCH_1):GPU_FPGA_RST_R_N   I192 @T6G_MB_LIB.T6G(SCH_1):PAGE256
     2    GND @T6G_MB_LIB.T6G(SCH_1):GND   I192 @T6G_MB_LIB.T6G(SCH_1):PAGE256

R3508 Q_RES_0402LF-54.9K,1%,1/16W,CHIP,CS35492FB03
     1 FM_GPU_PWR_EN_R1 @T6G_MB_LIB.T6G(SCH_1):FM_GPU_PWR_EN_R1   I194 @T6G_MB_LIB.T6G(SCH_1):PAGE256
     2    GND @T6G_MB_LIB.T6G(SCH_1):GND   I194 @T6G_MB_LIB.T6G(SCH_1):PAGE256

R3509 Q_RES_0402LF-10K,1%,1/16W,CHIP,CS31002FB08
     1 GPU_FPGA_RST_R1_BUF_N @T6G_MB_LIB.T6G(SCH_1):GPU_FPGA_RST_R1_BUF_N   I191 @T6G_MB_LIB.T6G(SCH_1):PAGE256
     2    GND @T6G_MB_LIB.T6G(SCH_1):GND   I191 @T6G_MB_LIB.T6G(SCH_1):PAGE256

R3510 Q_RES_0402LF-54.9K,1%,1/16W,CHIP,CS35492FB03
     1 P3V3_AUX @T6G_MB_LIB.T6G(SCH_1):P3V3_AUX   I176 @T6G_MB_LIB.T6G(SCH_1):PAGE333
     2 FM_SMB_1_ALERT_GPU_N @T6G_MB_LIB.T6G(SCH_1):FM_SMB_1_ALERT_GPU_N   I176 @T6G_MB_LIB.T6G(SCH_1):PAGE333

R3511 Q_RES_0402LF-54.9K,1%,1/16W,CHIP,CS35492FB03
     1 GPU_FPGA_READY @T6G_MB_LIB.T6G(SCH_1):GPU_FPGA_READY   I172 @T6G_MB_LIB.T6G(SCH_1):PAGE333
     2    GND @T6G_MB_LIB.T6G(SCH_1):GND   I172 @T6G_MB_LIB.T6G(SCH_1):PAGE333

R3512 Q_RES_0402LF-100K,1%,1/16W,EMPTY,CS41002FB09
     1 P3V3_AUX @T6G_MB_LIB.T6G(SCH_1):P3V3_AUX   I174 @T6G_MB_LIB.T6G(SCH_1):PAGE333
     2 FM_GPU_PWRGD @T6G_MB_LIB.T6G(SCH_1):FM_GPU_PWRGD   I174 @T6G_MB_LIB.T6G(SCH_1):PAGE333

R3513 Q_RES_0402LF-54.9K,1%,1/16W,CHIP,CS35492FB03
     1 FM_GPU_PWRGD @T6G_MB_LIB.T6G(SCH_1):FM_GPU_PWRGD   I173 @T6G_MB_LIB.T6G(SCH_1):PAGE333
     2    GND @T6G_MB_LIB.T6G(SCH_1):GND   I173 @T6G_MB_LIB.T6G(SCH_1):PAGE333

R3514 Q_RES_0402LF-54.9K,1%,1/16W,CHIP,CS35492FB03
     1 P3V3_AUX @T6G_MB_LIB.T6G(SCH_1):P3V3_AUX   I175 @T6G_MB_LIB.T6G(SCH_1):PAGE333
     2 FM_SMB_2_ALERT_GPU_N @T6G_MB_LIB.T6G(SCH_1):FM_SMB_2_ALERT_GPU_N   I175 @T6G_MB_LIB.T6G(SCH_1):PAGE333

R3515 Q_RES_0402LF-49.9,1%,1/16W,CHIP,CS04992FB07
     1 FM_SWB_PWR_EN_R1_BUF @T6G_MB_LIB.T6G(SCH_1):FM_SWB_PWR_EN_R1_BUF   I193 @T6G_MB_LIB.T6G(SCH_1):PAGE334
     2 FM_SWB_PWR_EN_R_BUF @T6G_MB_LIB.T6G(SCH_1):FM_SWB_PWR_EN_R_BUF   I193 @T6G_MB_LIB.T6G(SCH_1):PAGE334

R3516 Q_RES_0402LF-0,5%,1/16W,CHIP,CS00002JB13
     1 GPU_BASE_ID0 @T6G_MB_LIB.T6G(SCH_1):GPU_BASE_ID0    I56 @T6G_MB_LIB.T6G(SCH_1):PAGE246
     2 GPU_BASE_ID0_R @T6G_MB_LIB.T6G(SCH_1):GPU_BASE_ID0_R    I56 @T6G_MB_LIB.T6G(SCH_1):PAGE246

R3517 Q_RES_0402LF-0,5%,1/16W,CHIP,CS00002JB13
     1 GPU_PEX_STRAP1 @T6G_MB_LIB.T6G(SCH_1):GPU_PEX_STRAP1    I55 @T6G_MB_LIB.T6G(SCH_1):PAGE246
     2 GPU_PEX_STRAP1_R @T6G_MB_LIB.T6G(SCH_1):GPU_PEX_STRAP1_R    I55 @T6G_MB_LIB.T6G(SCH_1):PAGE246

R3518 Q_RES_0402LF-0,5%,1/16W,CHIP,CS00002JB13
     1 GPU_PEX_STRAP0 @T6G_MB_LIB.T6G(SCH_1):GPU_PEX_STRAP0    I47 @T6G_MB_LIB.T6G(SCH_1):PAGE246
     2 GPU_PEX_STRAP0_R @T6G_MB_LIB.T6G(SCH_1):GPU_PEX_STRAP0_R    I47 @T6G_MB_LIB.T6G(SCH_1):PAGE246

R3519 Q_RES_0402LF-4.7K,5%,1/16W,CHIP,CS24702JB10
     1 P3V3_OCP_V3_2 @T6G_MB_LIB.T6G(SCH_1):P3V3_OCP_V3_2    I34 @T6G_MB_LIB.T6G(SCH_1):PAGE248
     2 SMB_OCP_V3_2_3V3AUX_BUF_SCL @T6G_MB_LIB.T6G(SCH_1):SMB_OCP_V3_2_3V3AUX_BUF_SCL    I34 @T6G_MB_LIB.T6G(SCH_1):PAGE248

R3520 Q_RES_0402LF-4.7K,5%,1/16W,CHIP,CS24702JB10
     1 P3V3_OCP_V3_2 @T6G_MB_LIB.T6G(SCH_1):P3V3_OCP_V3_2    I23 @T6G_MB_LIB.T6G(SCH_1):PAGE248
     2 SMB_OCP_V3_2_3V3AUX_BUF_SDA @T6G_MB_LIB.T6G(SCH_1):SMB_OCP_V3_2_3V3AUX_BUF_SDA    I23 @T6G_MB_LIB.T6G(SCH_1):PAGE248

R3521 Q_RES_0402LF-54.9K,1%,1/16W,CHIP,CS35492FB03
     1 P3V3_AUX @T6G_MB_LIB.T6G(SCH_1):P3V3_AUX    I36 @T6G_MB_LIB.T6G(SCH_1):PAGE249
     2 SMB_2_BMC_GPU_BUF_R_SCL @T6G_MB_LIB.T6G(SCH_1):SMB_2_BMC_GPU_BUF_R_SCL    I36 @T6G_MB_LIB.T6G(SCH_1):PAGE249

R3522 Q_RES_0402LF-54.9K,1%,1/16W,CHIP,CS35492FB03
     1 P3V3_AUX @T6G_MB_LIB.T6G(SCH_1):P3V3_AUX    I37 @T6G_MB_LIB.T6G(SCH_1):PAGE249
     2 SMB_2_BMC_GPU_BUF_R_SDA @T6G_MB_LIB.T6G(SCH_1):SMB_2_BMC_GPU_BUF_R_SDA    I37 @T6G_MB_LIB.T6G(SCH_1):PAGE249

R3523 Q_RES_0402LF-54.9K,1%,1/16W,CHIP,CS35492FB03
     1 P3V3_AUX @T6G_MB_LIB.T6G(SCH_1):P3V3_AUX    I80 @T6G_MB_LIB.T6G(SCH_1):PAGE249
     2 SMB_1_BMC_GPU_BUF_R_SCL @T6G_MB_LIB.T6G(SCH_1):SMB_1_BMC_GPU_BUF_R_SCL    I80 @T6G_MB_LIB.T6G(SCH_1):PAGE249

R3524 Q_RES_0402LF-54.9K,1%,1/16W,CHIP,CS35492FB03
     1 P3V3_AUX @T6G_MB_LIB.T6G(SCH_1):P3V3_AUX    I81 @T6G_MB_LIB.T6G(SCH_1):PAGE249
     2 SMB_1_BMC_GPU_BUF_R_SDA @T6G_MB_LIB.T6G(SCH_1):SMB_1_BMC_GPU_BUF_R_SDA    I81 @T6G_MB_LIB.T6G(SCH_1):PAGE249

R3525 Q_RES_0402LF-54.9K,1%,1/16W,CHIP,CS35492FB03
     1 P3V3_AUX @T6G_MB_LIB.T6G(SCH_1):P3V3_AUX   I184 @T6G_MB_LIB.T6G(SCH_1):PAGE299
     2 GPU_FPGA_EROT_FATALERR_N @T6G_MB_LIB.T6G(SCH_1):GPU_FPGA_EROT_FATALERR_N   I184 @T6G_MB_LIB.T6G(SCH_1):PAGE299

R3526 Q_RES_0402LF-0,5%,1/16W,CHIP,CS00002JB13
     1 SMB_PCIE0_3V3AUX_SCL_R5 @T6G_MB_LIB.T6G(SCH_1):SMB_PCIE0_3V3AUX_SCL_R5    I23 @T6G_MB_LIB.T6G(SCH_1):PAGE252
     2 SMB_SENSOR_E1S_3V3AUX_SCL @T6G_MB_LIB.T6G(SCH_1):SMB_SENSOR_E1S_3V3AUX_SCL    I23 @T6G_MB_LIB.T6G(SCH_1):PAGE252

R3527 Q_RES_0402LF-0,5%,1/16W,CHIP,CS00002JB13
     1 SMB_PCIE0_3V3AUX_SDA_R5 @T6G_MB_LIB.T6G(SCH_1):SMB_PCIE0_3V3AUX_SDA_R5    I24 @T6G_MB_LIB.T6G(SCH_1):PAGE252
     2 SMB_SENSOR_E1S_3V3AUX_SDA @T6G_MB_LIB.T6G(SCH_1):SMB_SENSOR_E1S_3V3AUX_SDA    I24 @T6G_MB_LIB.T6G(SCH_1):PAGE252

R3529 Q_RES_0402LF-10K,1%,1/16W,CHIP,CS31002FB08
     1 P3V3_AUX @T6G_MB_LIB.T6G(SCH_1):P3V3_AUX    I99 @T6G_MB_LIB.T6G(SCH_1):PAGE346
     2 SMB_PCIE_E1S_ISO_EN_R @T6G_MB_LIB.T6G(SCH_1):SMB_PCIE_E1S_ISO_EN_R    I99 @T6G_MB_LIB.T6G(SCH_1):PAGE346

R3530 Q_RES_0402LF-4.7K,5%,1/16W,CHIP,CS24702JB10
     1 P3V3_E1S_0 @T6G_MB_LIB.T6G(SCH_1):P3V3_E1S_0    I80 @T6G_MB_LIB.T6G(SCH_1):PAGE346
     2 SMB_E1S_3V3AUX_ISO_SCL_R @T6G_MB_LIB.T6G(SCH_1):SMB_E1S_3V3AUX_ISO_SCL_R    I80 @T6G_MB_LIB.T6G(SCH_1):PAGE346

R3531 Q_RES_0402LF-200K,1%,1/16W,EMPTY,CS42002FB05
     1 SMB_PCIE_E1S_ISO_EN @T6G_MB_LIB.T6G(SCH_1):SMB_PCIE_E1S_ISO_EN    I96 @T6G_MB_LIB.T6G(SCH_1):PAGE346
     2 SMB_PCIE_E1S_ISO_EN_R @T6G_MB_LIB.T6G(SCH_1):SMB_PCIE_E1S_ISO_EN_R    I96 @T6G_MB_LIB.T6G(SCH_1):PAGE346

R3532 Q_RES_0402LF-4.7K,5%,1/16W,CHIP,CS24702JB10
     1 P3V3_E1S_0 @T6G_MB_LIB.T6G(SCH_1):P3V3_E1S_0    I78 @T6G_MB_LIB.T6G(SCH_1):PAGE346
     2 SMB_E1S_3V3AUX_ISO_SDA_R @T6G_MB_LIB.T6G(SCH_1):SMB_E1S_3V3AUX_ISO_SDA_R    I78 @T6G_MB_LIB.T6G(SCH_1):PAGE346

R3533 Q_RES_0402LF-33.2,1%,1/16W,CHIP,CS03322FB03
     1 SMB_E1S_3V3AUX_ISO_SCL_R @T6G_MB_LIB.T6G(SCH_1):SMB_E1S_3V3AUX_ISO_SCL_R    I76 @T6G_MB_LIB.T6G(SCH_1):PAGE346
     2 SMB_E1S_3V3AUX_ISO_SCL @T6G_MB_LIB.T6G(SCH_1):SMB_E1S_3V3AUX_ISO_SCL    I76 @T6G_MB_LIB.T6G(SCH_1):PAGE346

R3534 Q_RES_0402LF-33.2,1%,1/16W,CHIP,CS03322FB03
     1 SMB_E1S_3V3AUX_ISO_SDA_R @T6G_MB_LIB.T6G(SCH_1):SMB_E1S_3V3AUX_ISO_SDA_R    I77 @T6G_MB_LIB.T6G(SCH_1):PAGE346
     2 SMB_E1S_3V3AUX_ISO_SDA @T6G_MB_LIB.T6G(SCH_1):SMB_E1S_3V3AUX_ISO_SDA    I77 @T6G_MB_LIB.T6G(SCH_1):PAGE346

R3535 Q_RES_0402LF-2.2K,5%,1/16W,CHIP,CS22202JB07
     1 P3V3_AUX @T6G_MB_LIB.T6G(SCH_1):P3V3_AUX    I44 @T6G_MB_LIB.T6G(SCH_1):PAGE252
     2 SMB_SENSOR_E1S_3V3AUX_SCL @T6G_MB_LIB.T6G(SCH_1):SMB_SENSOR_E1S_3V3AUX_SCL    I44 @T6G_MB_LIB.T6G(SCH_1):PAGE252

R3536 Q_RES_0402LF-2.2K,5%,1/16W,CHIP,CS22202JB07
     1 P3V3_AUX @T6G_MB_LIB.T6G(SCH_1):P3V3_AUX    I43 @T6G_MB_LIB.T6G(SCH_1):PAGE252
     2 SMB_SENSOR_E1S_3V3AUX_SDA @T6G_MB_LIB.T6G(SCH_1):SMB_SENSOR_E1S_3V3AUX_SDA    I43 @T6G_MB_LIB.T6G(SCH_1):PAGE252

R3553 Q_RES_0402LF-33.2,1%,1/16W,CHIP,CS03322FB03
     1 SMB_LM75_3_3V3AUX_SCL @T6G_MB_LIB.T6G(SCH_1):SMB_LM75_3_3V3AUX_SCL   I134 @T6G_MB_LIB.T6G(SCH_1):PAGE359
     2 SMB_LM75_3_3V3AUX_SCL_R1 @T6G_MB_LIB.T6G(SCH_1):SMB_LM75_3_3V3AUX_SCL_R1   I134 @T6G_MB_LIB.T6G(SCH_1):PAGE359

R3554 Q_RES_0402LF-33.2,1%,1/16W,CHIP,CS03322FB03
     1 SMB_LM75_3_3V3AUX_SDA @T6G_MB_LIB.T6G(SCH_1):SMB_LM75_3_3V3AUX_SDA   I136 @T6G_MB_LIB.T6G(SCH_1):PAGE359
     2 SMB_LM75_3_3V3AUX_SDA_R1 @T6G_MB_LIB.T6G(SCH_1):SMB_LM75_3_3V3AUX_SDA_R1   I136 @T6G_MB_LIB.T6G(SCH_1):PAGE359

R3559 Q_RES_0402LF-0,5%,1/16W,CHIP,CS00002JB13
     1 OCP_V3_2_P3V3_ADC_ALERT_R @T6G_MB_LIB.T6G(SCH_1):OCP_V3_2_P3V3_ADC_ALERT_R    I96 @T6G_MB_LIB.T6G(SCH_1):PAGE360
     2 OCP_V3_2_P3V3_P12V_ADC_R_ALERT @T6G_MB_LIB.T6G(SCH_1):OCP_V3_2_P3V3_P12V_ADC_R_ALERT    I96 @T6G_MB_LIB.T6G(SCH_1):PAGE360

R3560 Q_RES_0402LF-0,5%,1/16W,CHIP,CS00002JB13
     1 M2_0_P3V3_ADC_ALERT_R @T6G_MB_LIB.T6G(SCH_1):M2_0_P3V3_ADC_ALERT_R    I41 @T6G_MB_LIB.T6G(SCH_1):PAGE360
     2 M2_0_P3V3_ADC_ALERT @T6G_MB_LIB.T6G(SCH_1):M2_0_P3V3_ADC_ALERT    I41 @T6G_MB_LIB.T6G(SCH_1):PAGE360

R3561 Q_RES_0402LF-0,5%,1/16W,CHIP,CS00002JB13
     1 P12V_SCM_ADC_ALERT_R @T6G_MB_LIB.T6G(SCH_1):P12V_SCM_ADC_ALERT_R    I64 @T6G_MB_LIB.T6G(SCH_1):PAGE360
     2 P12V_SCM_ADC_ALERT @T6G_MB_LIB.T6G(SCH_1):P12V_SCM_ADC_ALERT    I64 @T6G_MB_LIB.T6G(SCH_1):PAGE360

R3563 Q_RES_0402LF-0,5%,1/16W,CHIP,CS00002JB13
     1 OCP_SFF_P3V3_ADC_ALERT_R @T6G_MB_LIB.T6G(SCH_1):OCP_SFF_P3V3_ADC_ALERT_R    I35 @T6G_MB_LIB.T6G(SCH_1):PAGE295
     2 OCP_SFF_P3V3_P12V_ADC_R_ALERT @T6G_MB_LIB.T6G(SCH_1):OCP_SFF_P3V3_P12V_ADC_R_ALERT    I35 @T6G_MB_LIB.T6G(SCH_1):PAGE295

R3568 Q_RES_0402LF-0,5%,1/16W,CHIP,CS00002JB13
     1 SMB_INA230_3_3V3AUX_SCL_R @T6G_MB_LIB.T6G(SCH_1):SMB_INA230_3_3V3AUX_SCL_R   I128 @T6G_MB_LIB.T6G(SCH_1):PAGE360
     2 SMB_INA230_3_3V3AUX_SCL_R1 @T6G_MB_LIB.T6G(SCH_1):SMB_INA230_3_3V3AUX_SCL_R1   I128 @T6G_MB_LIB.T6G(SCH_1):PAGE360

R3569 Q_RES_0402LF-0,5%,1/16W,CHIP,CS00002JB13
     1 SMB_INA230_3_3V3AUX_SDA_R @T6G_MB_LIB.T6G(SCH_1):SMB_INA230_3_3V3AUX_SDA_R   I127 @T6G_MB_LIB.T6G(SCH_1):PAGE360
     2 SMB_INA230_3_3V3AUX_SDA_R1 @T6G_MB_LIB.T6G(SCH_1):SMB_INA230_3_3V3AUX_SDA_R1   I127 @T6G_MB_LIB.T6G(SCH_1):PAGE360

R3570 Q_RES_0402LF-10,1%,1/16W,CHIP,CS01002FB07
     1 P3V3_OCP_V3_2_R @T6G_MB_LIB.T6G(SCH_1):P3V3_OCP_V3_2_R   I109 @T6G_MB_LIB.T6G(SCH_1):PAGE360
     2 VSENSE_P12V_INA230_3_INP @T6G_MB_LIB.T6G(SCH_1):VSENSE_P12V_INA230_3_INP   I109 @T6G_MB_LIB.T6G(SCH_1):PAGE360

R3571 Q_RES_0402LF-10,1%,1/16W,CHIP,CS01002FB07
     1 P3V3_OCP_V3_2 @T6G_MB_LIB.T6G(SCH_1):P3V3_OCP_V3_2   I110 @T6G_MB_LIB.T6G(SCH_1):PAGE360
     2 VSENSE_P12V_INA230_3_INN @T6G_MB_LIB.T6G(SCH_1):VSENSE_P12V_INA230_3_INN   I110 @T6G_MB_LIB.T6G(SCH_1):PAGE360

R3572 Q_RES_0402LF-0,5%,1/16W,CHIP,CS00002JB13
     1 SMB_INA230_4_3V3AUX_SCL_R @T6G_MB_LIB.T6G(SCH_1):SMB_INA230_4_3V3AUX_SCL_R   I130 @T6G_MB_LIB.T6G(SCH_1):PAGE360
     2 SMB_INA230_4_3V3AUX_SCL_R1 @T6G_MB_LIB.T6G(SCH_1):SMB_INA230_4_3V3AUX_SCL_R1   I130 @T6G_MB_LIB.T6G(SCH_1):PAGE360

R3573 Q_RES_0402LF-0,5%,1/16W,CHIP,CS00002JB13
     1 SMB_INA230_4_3V3AUX_SDA_R @T6G_MB_LIB.T6G(SCH_1):SMB_INA230_4_3V3AUX_SDA_R   I129 @T6G_MB_LIB.T6G(SCH_1):PAGE360
     2 SMB_INA230_4_3V3AUX_SDA_R1 @T6G_MB_LIB.T6G(SCH_1):SMB_INA230_4_3V3AUX_SDA_R1   I129 @T6G_MB_LIB.T6G(SCH_1):PAGE360

R3574 Q_RES_0402LF-10,1%,1/16W,CHIP,CS01002FB07
     1   P3V3 @T6G_MB_LIB.T6G(SCH_1):P3V3    I35 @T6G_MB_LIB.T6G(SCH_1):PAGE360
     2 VSENSE_P12V_INA230_4_INP @T6G_MB_LIB.T6G(SCH_1):VSENSE_P12V_INA230_4_INP    I35 @T6G_MB_LIB.T6G(SCH_1):PAGE360

R3575 Q_RES_0402LF-10,1%,1/16W,CHIP,CS01002FB07
     1 P3V3_M2_0 @T6G_MB_LIB.T6G(SCH_1):P3V3_M2_0    I33 @T6G_MB_LIB.T6G(SCH_1):PAGE360
     2 VSENSE_P12V_INA230_4_INN @T6G_MB_LIB.T6G(SCH_1):VSENSE_P12V_INA230_4_INN    I33 @T6G_MB_LIB.T6G(SCH_1):PAGE360

R3576 Q_RES_0402LF-0,5%,1/16W,CHIP,CS00002JB13
     1 SMB_INA230_5_3V3AUX_SCL_R @T6G_MB_LIB.T6G(SCH_1):SMB_INA230_5_3V3AUX_SCL_R   I131 @T6G_MB_LIB.T6G(SCH_1):PAGE360
     2 SMB_INA230_5_3V3AUX_SCL_R1 @T6G_MB_LIB.T6G(SCH_1):SMB_INA230_5_3V3AUX_SCL_R1   I131 @T6G_MB_LIB.T6G(SCH_1):PAGE360

R3577 Q_RES_0402LF-0,5%,1/16W,CHIP,CS00002JB13
     1 SMB_INA230_5_3V3AUX_SDA_R @T6G_MB_LIB.T6G(SCH_1):SMB_INA230_5_3V3AUX_SDA_R   I132 @T6G_MB_LIB.T6G(SCH_1):PAGE360
     2 SMB_INA230_5_3V3AUX_SDA_R1 @T6G_MB_LIB.T6G(SCH_1):SMB_INA230_5_3V3AUX_SDA_R1   I132 @T6G_MB_LIB.T6G(SCH_1):PAGE360

R3578 Q_RES_0402LF-10,1%,1/16W,CHIP,CS01002FB07
     1 P12V_SCM_R @T6G_MB_LIB.T6G(SCH_1):P12V_SCM_R    I58 @T6G_MB_LIB.T6G(SCH_1):PAGE360
     2 VSENSE_P12V_INA230_5_INP @T6G_MB_LIB.T6G(SCH_1):VSENSE_P12V_INA230_5_INP    I58 @T6G_MB_LIB.T6G(SCH_1):PAGE360

R3579 Q_RES_0402LF-10,1%,1/16W,CHIP,CS01002FB07
     1 P12V_SCM @T6G_MB_LIB.T6G(SCH_1):P12V_SCM    I56 @T6G_MB_LIB.T6G(SCH_1):PAGE360
     2 VSENSE_P12V_INA230_5_INN @T6G_MB_LIB.T6G(SCH_1):VSENSE_P12V_INA230_5_INN    I56 @T6G_MB_LIB.T6G(SCH_1):PAGE360

R3580 Q_RES_0402LF-0,5%,1/16W,CHIP,CS00002JB13
     1 SMB_INA230_3V3AUX_SCL_R @T6G_MB_LIB.T6G(SCH_1):SMB_INA230_3V3AUX_SCL_R    I69 @T6G_MB_LIB.T6G(SCH_1):PAGE252
     2 SMB_INA230_3V3AUX_SCL @T6G_MB_LIB.T6G(SCH_1):SMB_INA230_3V3AUX_SCL    I69 @T6G_MB_LIB.T6G(SCH_1):PAGE252

R3581 Q_RES_0402LF-0,5%,1/16W,CHIP,CS00002JB13
     1 SMB_INA230_3V3AUX_SDA_R @T6G_MB_LIB.T6G(SCH_1):SMB_INA230_3V3AUX_SDA_R    I68 @T6G_MB_LIB.T6G(SCH_1):PAGE252
     2 SMB_INA230_3V3AUX_SDA @T6G_MB_LIB.T6G(SCH_1):SMB_INA230_3V3AUX_SDA    I68 @T6G_MB_LIB.T6G(SCH_1):PAGE252

R3582 Q_RES_0402LF-2.2K,5%,1/16W,CHIP,CS22202JB07
     1 P3V3_AUX @T6G_MB_LIB.T6G(SCH_1):P3V3_AUX    I46 @T6G_MB_LIB.T6G(SCH_1):PAGE252
     2 SMB_IOEXP_3V3AUX_SCL @T6G_MB_LIB.T6G(SCH_1):SMB_IOEXP_3V3AUX_SCL    I46 @T6G_MB_LIB.T6G(SCH_1):PAGE252

R3583 Q_RES_0402LF-2.2K,5%,1/16W,CHIP,CS22202JB07
     1 P3V3_AUX @T6G_MB_LIB.T6G(SCH_1):P3V3_AUX    I45 @T6G_MB_LIB.T6G(SCH_1):PAGE252
     2 SMB_IOEXP_3V3AUX_SDA @T6G_MB_LIB.T6G(SCH_1):SMB_IOEXP_3V3AUX_SDA    I45 @T6G_MB_LIB.T6G(SCH_1):PAGE252

R3586 Q_RES_0402LF-33.2,1%,1/16W,CHIP,CS03322FB03
     1 SMB_INA230_3V3AUX_SCL @T6G_MB_LIB.T6G(SCH_1):SMB_INA230_3V3AUX_SCL    I12 @T6G_MB_LIB.T6G(SCH_1):PAGE253
     2 SMB_INA230_1_3V3AUX_SCL_R @T6G_MB_LIB.T6G(SCH_1):SMB_INA230_1_3V3AUX_SCL_R    I12 @T6G_MB_LIB.T6G(SCH_1):PAGE253

R3587 Q_RES_0402LF-33.2,1%,1/16W,CHIP,CS03322FB03
     1 SMB_INA230_3V3AUX_SDA @T6G_MB_LIB.T6G(SCH_1):SMB_INA230_3V3AUX_SDA    I11 @T6G_MB_LIB.T6G(SCH_1):PAGE253
     2 SMB_INA230_1_3V3AUX_SDA_R @T6G_MB_LIB.T6G(SCH_1):SMB_INA230_1_3V3AUX_SDA_R    I11 @T6G_MB_LIB.T6G(SCH_1):PAGE253

R3588 Q_RES_0402LF-33.2,1%,1/16W,CHIP,CS03322FB03
     1 SMB_INA230_3V3AUX_SCL @T6G_MB_LIB.T6G(SCH_1):SMB_INA230_3V3AUX_SCL    I10 @T6G_MB_LIB.T6G(SCH_1):PAGE253
     2 SMB_INA230_2_3V3AUX_SCL_R @T6G_MB_LIB.T6G(SCH_1):SMB_INA230_2_3V3AUX_SCL_R    I10 @T6G_MB_LIB.T6G(SCH_1):PAGE253

R3589 Q_RES_0402LF-33.2,1%,1/16W,CHIP,CS03322FB03
     1 SMB_INA230_3V3AUX_SDA @T6G_MB_LIB.T6G(SCH_1):SMB_INA230_3V3AUX_SDA     I9 @T6G_MB_LIB.T6G(SCH_1):PAGE253
     2 SMB_INA230_2_3V3AUX_SDA_R @T6G_MB_LIB.T6G(SCH_1):SMB_INA230_2_3V3AUX_SDA_R     I9 @T6G_MB_LIB.T6G(SCH_1):PAGE253

R3590 Q_RES_0402LF-33.2,1%,1/16W,CHIP,CS03322FB03
     1 SMB_INA230_3V3AUX_SCL @T6G_MB_LIB.T6G(SCH_1):SMB_INA230_3V3AUX_SCL     I8 @T6G_MB_LIB.T6G(SCH_1):PAGE253
     2 SMB_INA230_3_3V3AUX_SCL_R @T6G_MB_LIB.T6G(SCH_1):SMB_INA230_3_3V3AUX_SCL_R     I8 @T6G_MB_LIB.T6G(SCH_1):PAGE253

R3591 Q_RES_0402LF-33.2,1%,1/16W,CHIP,CS03322FB03
     1 SMB_INA230_3V3AUX_SDA @T6G_MB_LIB.T6G(SCH_1):SMB_INA230_3V3AUX_SDA     I7 @T6G_MB_LIB.T6G(SCH_1):PAGE253
     2 SMB_INA230_3_3V3AUX_SDA_R @T6G_MB_LIB.T6G(SCH_1):SMB_INA230_3_3V3AUX_SDA_R     I7 @T6G_MB_LIB.T6G(SCH_1):PAGE253

R3592 Q_RES_0402LF-33.2,1%,1/16W,CHIP,CS03322FB03
     1 SMB_INA230_3V3AUX_SCL @T6G_MB_LIB.T6G(SCH_1):SMB_INA230_3V3AUX_SCL     I4 @T6G_MB_LIB.T6G(SCH_1):PAGE253
     2 SMB_INA230_5_3V3AUX_SCL_R @T6G_MB_LIB.T6G(SCH_1):SMB_INA230_5_3V3AUX_SCL_R     I4 @T6G_MB_LIB.T6G(SCH_1):PAGE253

R3593 Q_RES_0402LF-33.2,1%,1/16W,CHIP,CS03322FB03
     1 SMB_INA230_3V3AUX_SDA @T6G_MB_LIB.T6G(SCH_1):SMB_INA230_3V3AUX_SDA     I3 @T6G_MB_LIB.T6G(SCH_1):PAGE253
     2 SMB_INA230_5_3V3AUX_SDA_R @T6G_MB_LIB.T6G(SCH_1):SMB_INA230_5_3V3AUX_SDA_R     I3 @T6G_MB_LIB.T6G(SCH_1):PAGE253

R3594 Q_RES_0402LF-33.2,1%,1/16W,CHIP,CS03322FB03
     1 SMB_INA230_3V3AUX_SCL @T6G_MB_LIB.T6G(SCH_1):SMB_INA230_3V3AUX_SCL     I6 @T6G_MB_LIB.T6G(SCH_1):PAGE253
     2 SMB_INA230_4_3V3AUX_SCL_R @T6G_MB_LIB.T6G(SCH_1):SMB_INA230_4_3V3AUX_SCL_R     I6 @T6G_MB_LIB.T6G(SCH_1):PAGE253

R3595 Q_RES_0402LF-33.2,1%,1/16W,CHIP,CS03322FB03
     1 SMB_INA230_3V3AUX_SDA @T6G_MB_LIB.T6G(SCH_1):SMB_INA230_3V3AUX_SDA     I5 @T6G_MB_LIB.T6G(SCH_1):PAGE253
     2 SMB_INA230_4_3V3AUX_SDA_R @T6G_MB_LIB.T6G(SCH_1):SMB_INA230_4_3V3AUX_SDA_R     I5 @T6G_MB_LIB.T6G(SCH_1):PAGE253

R3600 Q_RES_0402LF-0,5%,1/16W,CHIP,CS00002JB13
     1 SMB_INA230_1_3V3AUX_SCL_R @T6G_MB_LIB.T6G(SCH_1):SMB_INA230_1_3V3AUX_SCL_R   I152 @T6G_MB_LIB.T6G(SCH_1):PAGE295
     2 SMB_INA230_1_3V3AUX_SCL_R1 @T6G_MB_LIB.T6G(SCH_1):SMB_INA230_1_3V3AUX_SCL_R1   I152 @T6G_MB_LIB.T6G(SCH_1):PAGE295

R3601 Q_RES_0402LF-0,5%,1/16W,CHIP,CS00002JB13
     1 SMB_INA230_1_3V3AUX_SDA_R @T6G_MB_LIB.T6G(SCH_1):SMB_INA230_1_3V3AUX_SDA_R   I153 @T6G_MB_LIB.T6G(SCH_1):PAGE295
     2 SMB_INA230_1_3V3AUX_SDA_R1 @T6G_MB_LIB.T6G(SCH_1):SMB_INA230_1_3V3AUX_SDA_R1   I153 @T6G_MB_LIB.T6G(SCH_1):PAGE295

R3602 Q_RES_0402LF-10,1%,1/16W,CHIP,CS01002FB07
     1 P3V3_OCP_SFF_R @T6G_MB_LIB.T6G(SCH_1):P3V3_OCP_SFF_R    I41 @T6G_MB_LIB.T6G(SCH_1):PAGE295
     2 VSENSE_P3V3_INA230_1_INP @T6G_MB_LIB.T6G(SCH_1):VSENSE_P3V3_INA230_1_INP    I41 @T6G_MB_LIB.T6G(SCH_1):PAGE295

R3603 Q_RES_0402LF-10,1%,1/16W,CHIP,CS01002FB07
     1 P3V3_OCP_SFF @T6G_MB_LIB.T6G(SCH_1):P3V3_OCP_SFF    I43 @T6G_MB_LIB.T6G(SCH_1):PAGE295
     2 VSENSE_P3V3_INA230_1_INN @T6G_MB_LIB.T6G(SCH_1):VSENSE_P3V3_INA230_1_INN    I43 @T6G_MB_LIB.T6G(SCH_1):PAGE295

R3608 Q_RES_0402LF-4.7K,1%,1/16W,CHIP,CS24702FB06
     1    GND @T6G_MB_LIB.T6G(SCH_1):GND   I103 @T6G_MB_LIB.T6G(SCH_1):PAGE360
     2 INA230_3_A1 @T6G_MB_LIB.T6G(SCH_1):INA230_3_A1   I103 @T6G_MB_LIB.T6G(SCH_1):PAGE360

R3609 Q_RES_0402LF-4.7K,1%,1/16W,EMPTY,CS24702FB06
     1    GND @T6G_MB_LIB.T6G(SCH_1):GND   I104 @T6G_MB_LIB.T6G(SCH_1):PAGE360
     2 INA230_3_A0 @T6G_MB_LIB.T6G(SCH_1):INA230_3_A0   I104 @T6G_MB_LIB.T6G(SCH_1):PAGE360

R3610 Q_RES_0402LF-4.7K,1%,1/16W,EMPTY,CS24702FB06
     1    GND @T6G_MB_LIB.T6G(SCH_1):GND    I45 @T6G_MB_LIB.T6G(SCH_1):PAGE360
     2 INA230_4_A1 @T6G_MB_LIB.T6G(SCH_1):INA230_4_A1    I45 @T6G_MB_LIB.T6G(SCH_1):PAGE360

R3611 Q_RES_0402LF-4.7K,1%,1/16W,CHIP,CS24702FB06
     1    GND @T6G_MB_LIB.T6G(SCH_1):GND    I36 @T6G_MB_LIB.T6G(SCH_1):PAGE360
     2 INA230_4_A0 @T6G_MB_LIB.T6G(SCH_1):INA230_4_A0    I36 @T6G_MB_LIB.T6G(SCH_1):PAGE360

R3612 Q_RES_0402LF-4.7K,1%,1/16W,EMPTY,CS24702FB06
     1    GND @T6G_MB_LIB.T6G(SCH_1):GND    I68 @T6G_MB_LIB.T6G(SCH_1):PAGE360
     2 INA230_5_A1 @T6G_MB_LIB.T6G(SCH_1):INA230_5_A1    I68 @T6G_MB_LIB.T6G(SCH_1):PAGE360

R3613 Q_RES_0402LF-4.7K,1%,1/16W,EMPTY,CS24702FB06
     1    GND @T6G_MB_LIB.T6G(SCH_1):GND    I59 @T6G_MB_LIB.T6G(SCH_1):PAGE360
     2 INA230_5_A0 @T6G_MB_LIB.T6G(SCH_1):INA230_5_A0    I59 @T6G_MB_LIB.T6G(SCH_1):PAGE360

R3616 Q_RES_0402LF-4.7K,1%,1/16W,CHIP,CS24702FB06
     1    GND @T6G_MB_LIB.T6G(SCH_1):GND    I31 @T6G_MB_LIB.T6G(SCH_1):PAGE295
     2 INA230_1_A1 @T6G_MB_LIB.T6G(SCH_1):INA230_1_A1    I31 @T6G_MB_LIB.T6G(SCH_1):PAGE295

R3617 Q_RES_0402LF-4.7K,1%,1/16W,EMPTY,CS24702FB06
     1    GND @T6G_MB_LIB.T6G(SCH_1):GND    I40 @T6G_MB_LIB.T6G(SCH_1):PAGE295
     2 INA230_1_A0 @T6G_MB_LIB.T6G(SCH_1):INA230_1_A0    I40 @T6G_MB_LIB.T6G(SCH_1):PAGE295

R3620 Q_RES_0402LF-0,5%,1/16W,CHIP,CS00002JB13
     1 INA230_3_A0 @T6G_MB_LIB.T6G(SCH_1):INA230_3_A0   I100 @T6G_MB_LIB.T6G(SCH_1):PAGE360
     2 SMB_INA230_3_3V3AUX_SCL_R1 @T6G_MB_LIB.T6G(SCH_1):SMB_INA230_3_3V3AUX_SCL_R1   I100 @T6G_MB_LIB.T6G(SCH_1):PAGE360

R3621 Q_RES_0402LF-4.7K,1%,1/16W,EMPTY,CS24702FB06
     1 P3V3_AUX @T6G_MB_LIB.T6G(SCH_1):P3V3_AUX    I87 @T6G_MB_LIB.T6G(SCH_1):PAGE360
     2 INA230_4_A0 @T6G_MB_LIB.T6G(SCH_1):INA230_4_A0    I87 @T6G_MB_LIB.T6G(SCH_1):PAGE360

R3622 Q_RES_0402LF-4.7K,1%,1/16W,CHIP,CS24702FB06
     1 P3V3_AUX @T6G_MB_LIB.T6G(SCH_1):P3V3_AUX    I90 @T6G_MB_LIB.T6G(SCH_1):PAGE360
     2 INA230_5_A0 @T6G_MB_LIB.T6G(SCH_1):INA230_5_A0    I90 @T6G_MB_LIB.T6G(SCH_1):PAGE360

R3623 Q_RES_0402LF-4.7K,1%,1/16W,CHIP,CS24702FB06
     1 P3V3_AUX @T6G_MB_LIB.T6G(SCH_1):P3V3_AUX    I86 @T6G_MB_LIB.T6G(SCH_1):PAGE360
     2 INA230_4_A1 @T6G_MB_LIB.T6G(SCH_1):INA230_4_A1    I86 @T6G_MB_LIB.T6G(SCH_1):PAGE360

R3624 Q_RES_0402LF-4.7K,1%,1/16W,CHIP,CS24702FB06
     1 P3V3_AUX @T6G_MB_LIB.T6G(SCH_1):P3V3_AUX    I89 @T6G_MB_LIB.T6G(SCH_1):PAGE360
     2 INA230_5_A1 @T6G_MB_LIB.T6G(SCH_1):INA230_5_A1    I89 @T6G_MB_LIB.T6G(SCH_1):PAGE360

R3627 Q_RES_0402LF-4.7K,1%,1/16W,CHIP,CS24702FB06
     1 P3V3_AUX @T6G_MB_LIB.T6G(SCH_1):P3V3_AUX    I89 @T6G_MB_LIB.T6G(SCH_1):PAGE295
     2 INA230_1_A0 @T6G_MB_LIB.T6G(SCH_1):INA230_1_A0    I89 @T6G_MB_LIB.T6G(SCH_1):PAGE295

R3628 Q_RES_0402LF-4.7K,1%,1/16W,EMPTY,CS24702FB06
     1 P3V3_AUX @T6G_MB_LIB.T6G(SCH_1):P3V3_AUX    I88 @T6G_MB_LIB.T6G(SCH_1):PAGE295
     2 INA230_1_A1 @T6G_MB_LIB.T6G(SCH_1):INA230_1_A1    I88 @T6G_MB_LIB.T6G(SCH_1):PAGE295

R3630 Q_RES_0402LF-0,5%,1/16W,EMPTY,CS00002JB13
     1 P12V_OCP_V3_2_EN_R @T6G_MB_LIB.T6G(SCH_1):P12V_OCP_V3_2_EN_R    I73 @T6G_MB_LIB.T6G(SCH_1):PAGE344
     2 P12V_OCP_V3_2_EN_2_R3 @T6G_MB_LIB.T6G(SCH_1):P12V_OCP_V3_2_EN_2_R3    I73 @T6G_MB_LIB.T6G(SCH_1):PAGE344

R3631 Q_RES_0402LF-0,5%,1/16W,EMPTY,CS00002JB13
     1 P3V3_OCP_V3_2_EN_R @T6G_MB_LIB.T6G(SCH_1):P3V3_OCP_V3_2_EN_R    I74 @T6G_MB_LIB.T6G(SCH_1):PAGE344
     2 P3V3_OCP_EN_2 @T6G_MB_LIB.T6G(SCH_1):P3V3_OCP_EN_2    I74 @T6G_MB_LIB.T6G(SCH_1):PAGE344

R3633 Q_RES_2512LF-0.002,1%,2W,CHIP,CS+002AFR06
     1 P3V3_OCP_V3_2 @T6G_MB_LIB.T6G(SCH_1):P3V3_OCP_V3_2   I116 @T6G_MB_LIB.T6G(SCH_1):PAGE360
     2 P3V3_OCP_V3_2_R @T6G_MB_LIB.T6G(SCH_1):P3V3_OCP_V3_2_R   I116 @T6G_MB_LIB.T6G(SCH_1):PAGE360

R3634 Q_RES_2512LF-0.002,1%,2W,CHIP,CS+002AFR06
     1 P3V3_M2_0 @T6G_MB_LIB.T6G(SCH_1):P3V3_M2_0    I92 @T6G_MB_LIB.T6G(SCH_1):PAGE360
     2   P3V3 @T6G_MB_LIB.T6G(SCH_1):P3V3    I92 @T6G_MB_LIB.T6G(SCH_1):PAGE360

R3635 Q_RES_2512LF-0.002,1%,2W,CHIP,CS+002AFR06
     1 P12V_SCM @T6G_MB_LIB.T6G(SCH_1):P12V_SCM    I93 @T6G_MB_LIB.T6G(SCH_1):PAGE360
     2 P12V_SCM_R @T6G_MB_LIB.T6G(SCH_1):P12V_SCM_R    I93 @T6G_MB_LIB.T6G(SCH_1):PAGE360

R3645 Q_RES_2512LF-0.002,1%,2W,CHIP,CS+002AFR06
     1 P3V3_OCP_SFF @T6G_MB_LIB.T6G(SCH_1):P3V3_OCP_SFF    I93 @T6G_MB_LIB.T6G(SCH_1):PAGE295
     2 P3V3_OCP_SFF_R @T6G_MB_LIB.T6G(SCH_1):P3V3_OCP_SFF_R    I93 @T6G_MB_LIB.T6G(SCH_1):PAGE295

R3651 Q_RES_0402LF-0,5%,1/16W,CHIP,CS00002JB13
     1 USB2_P0_R_DP @T6G_MB_LIB.T6G(SCH_1):USB2_P0_R_DP   I138 @T6G_MB_LIB.T6G(SCH_1):PAGE358
     2 USB2_HOST_BMC_B_DP @T6G_MB_LIB.T6G(SCH_1):USB2_HOST_BMC_B_DP   I138 @T6G_MB_LIB.T6G(SCH_1):PAGE358

R3652 Q_RES_0402LF-0,5%,1/16W,CHIP,CS00002JB13
     1 USB2_P0_R_DN @T6G_MB_LIB.T6G(SCH_1):USB2_P0_R_DN   I137 @T6G_MB_LIB.T6G(SCH_1):PAGE358
     2 USB2_HOST_BMC_B_DN @T6G_MB_LIB.T6G(SCH_1):USB2_HOST_BMC_B_DN   I137 @T6G_MB_LIB.T6G(SCH_1):PAGE358

R3653 Q_RES_0402LF-680,1%,1/16W,CHIP,CS16802FB03
     1 USB_HUB_RREF @T6G_MB_LIB.T6G(SCH_1):USB_HUB_RREF   I139 @T6G_MB_LIB.T6G(SCH_1):PAGE358
     2    GND @T6G_MB_LIB.T6G(SCH_1):GND   I139 @T6G_MB_LIB.T6G(SCH_1):PAGE358

R3654 Q_RES_0402LF-33.2,1%,1/16W,CHIP,CS03322FB03
     1 RST_USB_HUB_N @T6G_MB_LIB.T6G(SCH_1):RST_USB_HUB_N   I155 @T6G_MB_LIB.T6G(SCH_1):PAGE358
     2 RST_USB_HUB_R_N @T6G_MB_LIB.T6G(SCH_1):RST_USB_HUB_R_N   I155 @T6G_MB_LIB.T6G(SCH_1):PAGE358

R3655 Q_RES_0402LF-0,5%,1/16W,CHIP,CS00002JB13
     1 P3V3_AUX @T6G_MB_LIB.T6G(SCH_1):P3V3_AUX   I161 @T6G_MB_LIB.T6G(SCH_1):PAGE358
     2 P3V3_AUX_USB_HUB @T6G_MB_LIB.T6G(SCH_1):P3V3_AUX_USB_HUB   I161 @T6G_MB_LIB.T6G(SCH_1):PAGE358

R3656 Q_RES_0402LF-10K,1%,1/16W,EMPTY,CS31002FB08
     1 P3V3_AUX @T6G_MB_LIB.T6G(SCH_1):P3V3_AUX   I194 @T6G_MB_LIB.T6G(SCH_1):PAGE358
     2 USB_HUB_OVCUR1 @T6G_MB_LIB.T6G(SCH_1):USB_HUB_OVCUR1   I194 @T6G_MB_LIB.T6G(SCH_1):PAGE358

R3657 Q_RES_0402LF-10K,1%,1/16W,EMPTY,CS31002FB08
     1 P3V3_AUX @T6G_MB_LIB.T6G(SCH_1):P3V3_AUX   I195 @T6G_MB_LIB.T6G(SCH_1):PAGE358
     2 USB_HUB_OVCUR2 @T6G_MB_LIB.T6G(SCH_1):USB_HUB_OVCUR2   I195 @T6G_MB_LIB.T6G(SCH_1):PAGE358

R3658 Q_RES_0402LF-10K,1%,1/16W,EMPTY,CS31002FB08
     1 P3V3_AUX @T6G_MB_LIB.T6G(SCH_1):P3V3_AUX   I196 @T6G_MB_LIB.T6G(SCH_1):PAGE358
     2 USB_HUB_OVCUR3 @T6G_MB_LIB.T6G(SCH_1):USB_HUB_OVCUR3   I196 @T6G_MB_LIB.T6G(SCH_1):PAGE358

R3659 Q_RES_0402LF-10K,1%,1/16W,EMPTY,CS31002FB08
     1 P3V3_AUX @T6G_MB_LIB.T6G(SCH_1):P3V3_AUX   I198 @T6G_MB_LIB.T6G(SCH_1):PAGE358
     2 USB_HUB_OVCUR4 @T6G_MB_LIB.T6G(SCH_1):USB_HUB_OVCUR4   I198 @T6G_MB_LIB.T6G(SCH_1):PAGE358

R3660 Q_RES_0402LF-10K,1%,1/16W,CHIP,CS31002FB08
     1 P3V3_AUX @T6G_MB_LIB.T6G(SCH_1):P3V3_AUX   I159 @T6G_MB_LIB.T6G(SCH_1):PAGE358
     2 RST_USB_HUB_R_N @T6G_MB_LIB.T6G(SCH_1):RST_USB_HUB_R_N   I159 @T6G_MB_LIB.T6G(SCH_1):PAGE358

R3661 Q_RES_0402LF-47K,0.1%,1/16W,EMPTY,CS34702BB05
     1    GND @T6G_MB_LIB.T6G(SCH_1):GND   I201 @T6G_MB_LIB.T6G(SCH_1):PAGE358
     2 RST_USB_HUB_R_N @T6G_MB_LIB.T6G(SCH_1):RST_USB_HUB_R_N   I201 @T6G_MB_LIB.T6G(SCH_1):PAGE358

R3662 Q_RES_0402LF-0,5%,1/16W,CHIP,CS00002JB13
     1 P3V3_AUX_USB_HUB @T6G_MB_LIB.T6G(SCH_1):P3V3_AUX_USB_HUB   I167 @T6G_MB_LIB.T6G(SCH_1):PAGE358
     2 USB_HUB_DVDD @T6G_MB_LIB.T6G(SCH_1):USB_HUB_DVDD   I167 @T6G_MB_LIB.T6G(SCH_1):PAGE358

R3663 Q_RES_0402LF-10K,1%,1/16W,CHIP,CS31002FB08
     1 P3V3_AUX @T6G_MB_LIB.T6G(SCH_1):P3V3_AUX   I186 @T6G_MB_LIB.T6G(SCH_1):PAGE358
     2 USB_HUB_PSELF @T6G_MB_LIB.T6G(SCH_1):USB_HUB_PSELF   I186 @T6G_MB_LIB.T6G(SCH_1):PAGE358

R3664 Q_RES_0402LF-10K,1%,1/16W,EMPTY,CS31002FB08
     1 USB_HUB_PSELF @T6G_MB_LIB.T6G(SCH_1):USB_HUB_PSELF   I187 @T6G_MB_LIB.T6G(SCH_1):PAGE358
     2    GND @T6G_MB_LIB.T6G(SCH_1):GND   I187 @T6G_MB_LIB.T6G(SCH_1):PAGE358

R3665 Q_RES_0402LF-100K,1%,1/16W,CHIP,CS41002FB09
     1 USB_HUB_PGANG @T6G_MB_LIB.T6G(SCH_1):USB_HUB_PGANG   I182 @T6G_MB_LIB.T6G(SCH_1):PAGE358
     2    GND @T6G_MB_LIB.T6G(SCH_1):GND   I182 @T6G_MB_LIB.T6G(SCH_1):PAGE358

R3666 Q_RES_0402LF-0,5%,1/16W,CHIP,CS00002JB13
     1 USB_HUB_TEST @T6G_MB_LIB.T6G(SCH_1):USB_HUB_TEST   I199 @T6G_MB_LIB.T6G(SCH_1):PAGE358
     2    GND @T6G_MB_LIB.T6G(SCH_1):GND   I199 @T6G_MB_LIB.T6G(SCH_1):PAGE358

R3667 Q_RES_0402LF-1K,1%,1/16W,EMPTY,CS21002FB06
     1 P3V3_AUX @T6G_MB_LIB.T6G(SCH_1):P3V3_AUX    I66 @T6G_MB_LIB.T6G(SCH_1):PAGE369
     2 ADC128_A1 @T6G_MB_LIB.T6G(SCH_1):ADC128_A1    I66 @T6G_MB_LIB.T6G(SCH_1):PAGE369

R3668 Q_RES_0402LF-1K,1%,1/16W,CHIP,CS21002FB06
     1 ADC128_A1 @T6G_MB_LIB.T6G(SCH_1):ADC128_A1    I38 @T6G_MB_LIB.T6G(SCH_1):PAGE369
     2    GND @T6G_MB_LIB.T6G(SCH_1):GND    I38 @T6G_MB_LIB.T6G(SCH_1):PAGE369

R3669 Q_RES_0402LF-1K,1%,1/16W,EMPTY,CS21002FB06
     1 P3V3_AUX @T6G_MB_LIB.T6G(SCH_1):P3V3_AUX    I68 @T6G_MB_LIB.T6G(SCH_1):PAGE369
     2 ADC128_A0 @T6G_MB_LIB.T6G(SCH_1):ADC128_A0    I68 @T6G_MB_LIB.T6G(SCH_1):PAGE369

R3670 Q_RES_0402LF-1K,1%,1/16W,CHIP,CS21002FB06
     1 ADC128_A0 @T6G_MB_LIB.T6G(SCH_1):ADC128_A0    I40 @T6G_MB_LIB.T6G(SCH_1):PAGE369
     2    GND @T6G_MB_LIB.T6G(SCH_1):GND    I40 @T6G_MB_LIB.T6G(SCH_1):PAGE369

R3671 Q_RES_0402LF-0,5%,1/16W,CHIP,CS00002JB13
     1 SMB_SCM_2_R4_SDA @T6G_MB_LIB.T6G(SCH_1):SMB_SCM_2_R4_SDA   I149 @T6G_MB_LIB.T6G(SCH_1):PAGE369
     2 SMB_SEN_TIC_3V3AUX_SDA @T6G_MB_LIB.T6G(SCH_1):SMB_SEN_TIC_3V3AUX_SDA   I149 @T6G_MB_LIB.T6G(SCH_1):PAGE369

R3672 Q_RES_0402LF-0,5%,1/16W,CHIP,CS00002JB13
     1 SMB_SCM_2_R4_SCL @T6G_MB_LIB.T6G(SCH_1):SMB_SCM_2_R4_SCL   I150 @T6G_MB_LIB.T6G(SCH_1):PAGE369
     2 SMB_SEN_TIC_3V3AUX_SCL @T6G_MB_LIB.T6G(SCH_1):SMB_SEN_TIC_3V3AUX_SCL   I150 @T6G_MB_LIB.T6G(SCH_1):PAGE369

R3679 Q_RES_0402LF-0,5%,1/16W,EMPTY,CS00002JB13
     1 P12V_AUX_ADC @T6G_MB_LIB.T6G(SCH_1):P12V_AUX_ADC    I10 @T6G_MB_LIB.T6G(SCH_1):PAGE369
     2 P12V_AUX_ADC_MAM @T6G_MB_LIB.T6G(SCH_1):P12V_AUX_ADC_MAM    I10 @T6G_MB_LIB.T6G(SCH_1):PAGE369

R3680 Q_RES_0402LF-0,5%,1/16W,CHIP,CS00002JB13
     1 P12V_AUX_ADC @T6G_MB_LIB.T6G(SCH_1):P12V_AUX_ADC     I9 @T6G_MB_LIB.T6G(SCH_1):PAGE369
     2 P12V_AUX_ADC_TIC @T6G_MB_LIB.T6G(SCH_1):P12V_AUX_ADC_TIC     I9 @T6G_MB_LIB.T6G(SCH_1):PAGE369

R3681 Q_RES_0402LF-0,5%,1/16W,EMPTY,CS00002JB13
     1 P3V3_AUX_ADC @T6G_MB_LIB.T6G(SCH_1):P3V3_AUX_ADC    I30 @T6G_MB_LIB.T6G(SCH_1):PAGE369
     2 P3V3_AUX_ADC_MAM @T6G_MB_LIB.T6G(SCH_1):P3V3_AUX_ADC_MAM    I30 @T6G_MB_LIB.T6G(SCH_1):PAGE369

R3682 Q_RES_0402LF-0,5%,1/16W,CHIP,CS00002JB13
     1 P3V3_AUX_ADC @T6G_MB_LIB.T6G(SCH_1):P3V3_AUX_ADC    I27 @T6G_MB_LIB.T6G(SCH_1):PAGE369
     2 P3V3_AUX_ADC_TIC @T6G_MB_LIB.T6G(SCH_1):P3V3_AUX_ADC_TIC    I27 @T6G_MB_LIB.T6G(SCH_1):PAGE369

R3683 Q_RES_0402LF-0,5%,1/16W,EMPTY,CS00002JB13
     1 P3V3_ADC @T6G_MB_LIB.T6G(SCH_1):P3V3_ADC    I23 @T6G_MB_LIB.T6G(SCH_1):PAGE369
     2 P3V3_ADC_MAM @T6G_MB_LIB.T6G(SCH_1):P3V3_ADC_MAM    I23 @T6G_MB_LIB.T6G(SCH_1):PAGE369

R3684 Q_RES_0402LF-0,5%,1/16W,CHIP,CS00002JB13
     1 P3V3_ADC @T6G_MB_LIB.T6G(SCH_1):P3V3_ADC    I22 @T6G_MB_LIB.T6G(SCH_1):PAGE369
     2 P3V3_ADC_TIC @T6G_MB_LIB.T6G(SCH_1):P3V3_ADC_TIC    I22 @T6G_MB_LIB.T6G(SCH_1):PAGE369

R3685 Q_RES_0402LF-0,5%,1/16W,EMPTY,CS00002JB13
     1 P5V_ADC @T6G_MB_LIB.T6G(SCH_1):P5V_ADC    I18 @T6G_MB_LIB.T6G(SCH_1):PAGE369
     2 P5V_ADC_MAM @T6G_MB_LIB.T6G(SCH_1):P5V_ADC_MAM    I18 @T6G_MB_LIB.T6G(SCH_1):PAGE369

R3686 Q_RES_0402LF-0,5%,1/16W,CHIP,CS00002JB13
     1 P5V_ADC @T6G_MB_LIB.T6G(SCH_1):P5V_ADC    I16 @T6G_MB_LIB.T6G(SCH_1):PAGE369
     2 P5V_ADC_TIC @T6G_MB_LIB.T6G(SCH_1):P5V_ADC_TIC    I16 @T6G_MB_LIB.T6G(SCH_1):PAGE369

R3687 Q_RES_0402LF-0,5%,1/16W,EMPTY,CS00002JB13
     1 P1V581_PDB_ADC @T6G_MB_LIB.T6G(SCH_1):P1V581_PDB_ADC    I42 @T6G_MB_LIB.T6G(SCH_1):PAGE369
     2 P3V3_PDB_AUX_ADC_MAM @T6G_MB_LIB.T6G(SCH_1):P3V3_PDB_AUX_ADC_MAM    I42 @T6G_MB_LIB.T6G(SCH_1):PAGE369

R3688 Q_RES_0402LF-0,5%,1/16W,CHIP,CS00002JB13
     1 P1V581_PDB_ADC @T6G_MB_LIB.T6G(SCH_1):P1V581_PDB_ADC    I41 @T6G_MB_LIB.T6G(SCH_1):PAGE369
     2 P3V3_PDB_AUX_ADC_TIC @T6G_MB_LIB.T6G(SCH_1):P3V3_PDB_AUX_ADC_TIC    I41 @T6G_MB_LIB.T6G(SCH_1):PAGE369

R3689 Q_RES_0402LF-4.7K,1%,1/16W,EMPTY,CS24702FB06
     1 P3V3_ADC128_VCC @T6G_MB_LIB.T6G(SCH_1):P3V3_ADC128_VCC   I131 @T6G_MB_LIB.T6G(SCH_1):PAGE369
     2 ADC128_VREF @T6G_MB_LIB.T6G(SCH_1):ADC128_VREF   I131 @T6G_MB_LIB.T6G(SCH_1):PAGE369

R3690 Q_RES_0402LF-4.7K,1%,1/16W,EMPTY,CS24702FB06
     1 ADC128_VREF @T6G_MB_LIB.T6G(SCH_1):ADC128_VREF   I130 @T6G_MB_LIB.T6G(SCH_1):PAGE369
     2    GND @T6G_MB_LIB.T6G(SCH_1):GND   I130 @T6G_MB_LIB.T6G(SCH_1):PAGE369

R3703 Q_RES_0402LF-10K,1%,1/16W,EMPTY,CS31002FB08
     1 P3V3_AUX @T6G_MB_LIB.T6G(SCH_1):P3V3_AUX     I7 @T6G_MB_LIB.T6G(SCH_1):PAGE251
     2 PCA9548_PCIE0_ADDR2 @T6G_MB_LIB.T6G(SCH_1):PCA9548_PCIE0_ADDR2     I7 @T6G_MB_LIB.T6G(SCH_1):PAGE251

R3704 Q_RES_0402LF-1K,1%,1/16W,CHIP,CS21002FB06
     1 PCA9548_PCIE0_ADDR2 @T6G_MB_LIB.T6G(SCH_1):PCA9548_PCIE0_ADDR2     I1 @T6G_MB_LIB.T6G(SCH_1):PAGE251
     2    GND @T6G_MB_LIB.T6G(SCH_1):GND     I1 @T6G_MB_LIB.T6G(SCH_1):PAGE251

R3705 Q_RES_0402LF-10K,1%,1/16W,EMPTY,CS31002FB08
     1 P3V3_AUX @T6G_MB_LIB.T6G(SCH_1):P3V3_AUX    I27 @T6G_MB_LIB.T6G(SCH_1):PAGE251
     2 RST_SMB_SWITCH_N @T6G_MB_LIB.T6G(SCH_1):RST_SMB_SWITCH_N    I27 @T6G_MB_LIB.T6G(SCH_1):PAGE251

R3706 Q_RES_0402LF-10K,1%,1/16W,EMPTY,CS31002FB08
     1 P3V3_AUX @T6G_MB_LIB.T6G(SCH_1):P3V3_AUX     I8 @T6G_MB_LIB.T6G(SCH_1):PAGE251
     2 PCA9548_PCIE0_ADDR1 @T6G_MB_LIB.T6G(SCH_1):PCA9548_PCIE0_ADDR1     I8 @T6G_MB_LIB.T6G(SCH_1):PAGE251

R3707 Q_RES_0402LF-1K,1%,1/16W,CHIP,CS21002FB06
     1 PCA9548_PCIE0_ADDR1 @T6G_MB_LIB.T6G(SCH_1):PCA9548_PCIE0_ADDR1     I4 @T6G_MB_LIB.T6G(SCH_1):PAGE251
     2    GND @T6G_MB_LIB.T6G(SCH_1):GND     I4 @T6G_MB_LIB.T6G(SCH_1):PAGE251

R3708 Q_RES_0402LF-10K,1%,1/16W,EMPTY,CS31002FB08
     1 P3V3_AUX @T6G_MB_LIB.T6G(SCH_1):P3V3_AUX    I10 @T6G_MB_LIB.T6G(SCH_1):PAGE251
     2 PCA9548_PCIE0_ADDR0 @T6G_MB_LIB.T6G(SCH_1):PCA9548_PCIE0_ADDR0    I10 @T6G_MB_LIB.T6G(SCH_1):PAGE251

R3709 Q_RES_0402LF-1K,1%,1/16W,CHIP,CS21002FB06
     1 PCA9548_PCIE0_ADDR0 @T6G_MB_LIB.T6G(SCH_1):PCA9548_PCIE0_ADDR0     I6 @T6G_MB_LIB.T6G(SCH_1):PAGE251
     2    GND @T6G_MB_LIB.T6G(SCH_1):GND     I6 @T6G_MB_LIB.T6G(SCH_1):PAGE251

R3710 Q_RES_0402LF-0,5%,1/16W,CHIP,CS00002JB13
     1 RST_SMB_SWITCH_N @T6G_MB_LIB.T6G(SCH_1):RST_SMB_SWITCH_N    I29 @T6G_MB_LIB.T6G(SCH_1):PAGE251
     2 PU_RST_SMB_PCIE2_N @T6G_MB_LIB.T6G(SCH_1):PU_RST_SMB_PCIE2_N    I29 @T6G_MB_LIB.T6G(SCH_1):PAGE251

R3711 Q_RES_0402LF-33.2,1%,1/16W,CHIP,CS03322FB03
     1 SMB_VR_SENSOR_3V3AUX_SCL @T6G_MB_LIB.T6G(SCH_1):SMB_VR_SENSOR_3V3AUX_SCL    I69 @T6G_MB_LIB.T6G(SCH_1):PAGE251
     2 SMB_VR_SENSOR_3V3AUX_SCL_R @T6G_MB_LIB.T6G(SCH_1):SMB_VR_SENSOR_3V3AUX_SCL_R    I69 @T6G_MB_LIB.T6G(SCH_1):PAGE251

R3712 Q_RES_0402LF-33.2,1%,1/16W,CHIP,CS03322FB03
     1 SMB_VR_SENSOR_3V3AUX_SDA @T6G_MB_LIB.T6G(SCH_1):SMB_VR_SENSOR_3V3AUX_SDA    I68 @T6G_MB_LIB.T6G(SCH_1):PAGE251
     2 SMB_VR_SENSOR_3V3AUX_SDA_R @T6G_MB_LIB.T6G(SCH_1):SMB_VR_SENSOR_3V3AUX_SDA_R    I68 @T6G_MB_LIB.T6G(SCH_1):PAGE251

R3713 Q_RES_0402LF-0,5%,1/16W,CHIP,CS00002JB13
     1 SMB_VR_3V3AUX_SCL_R6 @T6G_MB_LIB.T6G(SCH_1):SMB_VR_3V3AUX_SCL_R6    I33 @T6G_MB_LIB.T6G(SCH_1):PAGE251
     2 SMB_VR_3V3AUX_SCL @T6G_MB_LIB.T6G(SCH_1):SMB_VR_3V3AUX_SCL    I33 @T6G_MB_LIB.T6G(SCH_1):PAGE251

R3714 Q_RES_0402LF-0,5%,1/16W,CHIP,CS00002JB13
     1 SMB_VR_3V3AUX_SDA_R6 @T6G_MB_LIB.T6G(SCH_1):SMB_VR_3V3AUX_SDA_R6    I32 @T6G_MB_LIB.T6G(SCH_1):PAGE251
     2 SMB_VR_3V3AUX_SDA @T6G_MB_LIB.T6G(SCH_1):SMB_VR_3V3AUX_SDA    I32 @T6G_MB_LIB.T6G(SCH_1):PAGE251

R3715 Q_RES_0402LF-0,5%,1/16W,CHIP,CS00002JB13
     1 SMB_LM75_0_3V3AUX_SCL_R @T6G_MB_LIB.T6G(SCH_1):SMB_LM75_0_3V3AUX_SCL_R    I31 @T6G_MB_LIB.T6G(SCH_1):PAGE251
     2 SMB_LM75_0_3V3AUX_SCL @T6G_MB_LIB.T6G(SCH_1):SMB_LM75_0_3V3AUX_SCL    I31 @T6G_MB_LIB.T6G(SCH_1):PAGE251

R3716 Q_RES_0402LF-0,5%,1/16W,CHIP,CS00002JB13
     1 SMB_LM75_0_3V3AUX_SDA_R @T6G_MB_LIB.T6G(SCH_1):SMB_LM75_0_3V3AUX_SDA_R    I30 @T6G_MB_LIB.T6G(SCH_1):PAGE251
     2 SMB_LM75_0_3V3AUX_SDA @T6G_MB_LIB.T6G(SCH_1):SMB_LM75_0_3V3AUX_SDA    I30 @T6G_MB_LIB.T6G(SCH_1):PAGE251

R3717 Q_RES_0402LF-0,5%,1/16W,CHIP,CS00002JB13
     1 SMB_LM75_1_3V3AUX_SCL_R @T6G_MB_LIB.T6G(SCH_1):SMB_LM75_1_3V3AUX_SCL_R    I20 @T6G_MB_LIB.T6G(SCH_1):PAGE251
     2 SMB_LM75_1_3V3AUX_SCL @T6G_MB_LIB.T6G(SCH_1):SMB_LM75_1_3V3AUX_SCL    I20 @T6G_MB_LIB.T6G(SCH_1):PAGE251

R3718 Q_RES_0402LF-0,5%,1/16W,CHIP,CS00002JB13
     1 SMB_LM75_1_3V3AUX_SDA_R @T6G_MB_LIB.T6G(SCH_1):SMB_LM75_1_3V3AUX_SDA_R    I21 @T6G_MB_LIB.T6G(SCH_1):PAGE251
     2 SMB_LM75_1_3V3AUX_SDA @T6G_MB_LIB.T6G(SCH_1):SMB_LM75_1_3V3AUX_SDA    I21 @T6G_MB_LIB.T6G(SCH_1):PAGE251

R3719 Q_RES_0402LF-0,5%,1/16W,CHIP,CS00002JB13
     1 SMB_LM75_2_3V3AUX_SCL_R @T6G_MB_LIB.T6G(SCH_1):SMB_LM75_2_3V3AUX_SCL_R    I18 @T6G_MB_LIB.T6G(SCH_1):PAGE251
     2 SMB_LM75_2_3V3AUX_SCL @T6G_MB_LIB.T6G(SCH_1):SMB_LM75_2_3V3AUX_SCL    I18 @T6G_MB_LIB.T6G(SCH_1):PAGE251

R3720 Q_RES_0402LF-0,5%,1/16W,CHIP,CS00002JB13
     1 SMB_LM75_2_3V3AUX_SDA_R @T6G_MB_LIB.T6G(SCH_1):SMB_LM75_2_3V3AUX_SDA_R    I19 @T6G_MB_LIB.T6G(SCH_1):PAGE251
     2 SMB_LM75_2_3V3AUX_SDA @T6G_MB_LIB.T6G(SCH_1):SMB_LM75_2_3V3AUX_SDA    I19 @T6G_MB_LIB.T6G(SCH_1):PAGE251

R3721 Q_RES_0402LF-0,5%,1/16W,CHIP,CS00002JB13
     1 SMB_LM75_3_3V3AUX_SCL_R @T6G_MB_LIB.T6G(SCH_1):SMB_LM75_3_3V3AUX_SCL_R    I67 @T6G_MB_LIB.T6G(SCH_1):PAGE251
     2 SMB_LM75_3_3V3AUX_SCL @T6G_MB_LIB.T6G(SCH_1):SMB_LM75_3_3V3AUX_SCL    I67 @T6G_MB_LIB.T6G(SCH_1):PAGE251

R3722 Q_RES_0402LF-0,5%,1/16W,CHIP,CS00002JB13
     1 SMB_LM75_3_3V3AUX_SDA_R @T6G_MB_LIB.T6G(SCH_1):SMB_LM75_3_3V3AUX_SDA_R    I66 @T6G_MB_LIB.T6G(SCH_1):PAGE251
     2 SMB_LM75_3_3V3AUX_SDA @T6G_MB_LIB.T6G(SCH_1):SMB_LM75_3_3V3AUX_SDA    I66 @T6G_MB_LIB.T6G(SCH_1):PAGE251

R3723 Q_RES_0402LF-2.2K,5%,1/16W,CHIP,CS22202JB07
     1 P3V3_AUX @T6G_MB_LIB.T6G(SCH_1):P3V3_AUX    I53 @T6G_MB_LIB.T6G(SCH_1):PAGE251
     2 SMB_VR_3V3AUX_SCL @T6G_MB_LIB.T6G(SCH_1):SMB_VR_3V3AUX_SCL    I53 @T6G_MB_LIB.T6G(SCH_1):PAGE251

R3724 Q_RES_0402LF-2.2K,5%,1/16W,CHIP,CS22202JB07
     1 P3V3_AUX @T6G_MB_LIB.T6G(SCH_1):P3V3_AUX    I52 @T6G_MB_LIB.T6G(SCH_1):PAGE251
     2 SMB_VR_3V3AUX_SDA @T6G_MB_LIB.T6G(SCH_1):SMB_VR_3V3AUX_SDA    I52 @T6G_MB_LIB.T6G(SCH_1):PAGE251

R3725 Q_RES_0402LF-2.2K,5%,1/16W,CHIP,CS22202JB07
     1 P3V3_AUX @T6G_MB_LIB.T6G(SCH_1):P3V3_AUX    I50 @T6G_MB_LIB.T6G(SCH_1):PAGE251
     2 SMB_LM75_0_3V3AUX_SCL @T6G_MB_LIB.T6G(SCH_1):SMB_LM75_0_3V3AUX_SCL    I50 @T6G_MB_LIB.T6G(SCH_1):PAGE251

R3726 Q_RES_0402LF-2.2K,5%,1/16W,CHIP,CS22202JB07
     1 P3V3_AUX @T6G_MB_LIB.T6G(SCH_1):P3V3_AUX    I49 @T6G_MB_LIB.T6G(SCH_1):PAGE251
     2 SMB_LM75_0_3V3AUX_SDA @T6G_MB_LIB.T6G(SCH_1):SMB_LM75_0_3V3AUX_SDA    I49 @T6G_MB_LIB.T6G(SCH_1):PAGE251

R3727 Q_RES_0402LF-2.2K,5%,1/16W,CHIP,CS22202JB07
     1 P3V3_AUX @T6G_MB_LIB.T6G(SCH_1):P3V3_AUX    I48 @T6G_MB_LIB.T6G(SCH_1):PAGE251
     2 SMB_LM75_1_3V3AUX_SCL @T6G_MB_LIB.T6G(SCH_1):SMB_LM75_1_3V3AUX_SCL    I48 @T6G_MB_LIB.T6G(SCH_1):PAGE251

R3728 Q_RES_0402LF-2.2K,5%,1/16W,CHIP,CS22202JB07
     1 P3V3_AUX @T6G_MB_LIB.T6G(SCH_1):P3V3_AUX    I47 @T6G_MB_LIB.T6G(SCH_1):PAGE251
     2 SMB_LM75_1_3V3AUX_SDA @T6G_MB_LIB.T6G(SCH_1):SMB_LM75_1_3V3AUX_SDA    I47 @T6G_MB_LIB.T6G(SCH_1):PAGE251

R3729 Q_RES_0402LF-2.2K,5%,1/16W,CHIP,CS22202JB07
     1 P3V3_AUX @T6G_MB_LIB.T6G(SCH_1):P3V3_AUX    I44 @T6G_MB_LIB.T6G(SCH_1):PAGE251
     2 SMB_LM75_2_3V3AUX_SCL @T6G_MB_LIB.T6G(SCH_1):SMB_LM75_2_3V3AUX_SCL    I44 @T6G_MB_LIB.T6G(SCH_1):PAGE251

R3730 Q_RES_0402LF-2.2K,5%,1/16W,CHIP,CS22202JB07
     1 P3V3_AUX @T6G_MB_LIB.T6G(SCH_1):P3V3_AUX    I45 @T6G_MB_LIB.T6G(SCH_1):PAGE251
     2 SMB_LM75_2_3V3AUX_SDA @T6G_MB_LIB.T6G(SCH_1):SMB_LM75_2_3V3AUX_SDA    I45 @T6G_MB_LIB.T6G(SCH_1):PAGE251

R3731 Q_RES_0402LF-2.2K,5%,1/16W,CHIP,CS22202JB07
     1 P3V3_AUX @T6G_MB_LIB.T6G(SCH_1):P3V3_AUX    I43 @T6G_MB_LIB.T6G(SCH_1):PAGE251
     2 SMB_LM75_3_3V3AUX_SCL @T6G_MB_LIB.T6G(SCH_1):SMB_LM75_3_3V3AUX_SCL    I43 @T6G_MB_LIB.T6G(SCH_1):PAGE251

R3732 Q_RES_0402LF-2.2K,5%,1/16W,CHIP,CS22202JB07
     1 P3V3_AUX @T6G_MB_LIB.T6G(SCH_1):P3V3_AUX    I42 @T6G_MB_LIB.T6G(SCH_1):PAGE251
     2 SMB_LM75_3_3V3AUX_SDA @T6G_MB_LIB.T6G(SCH_1):SMB_LM75_3_3V3AUX_SDA    I42 @T6G_MB_LIB.T6G(SCH_1):PAGE251

R3751 Q_RES_0402LF-0,5%,1/16W,CHIP,CS00002JB13
     1 INA230_2_A0 @T6G_MB_LIB.T6G(SCH_1):INA230_2_A0   I146 @T6G_MB_LIB.T6G(SCH_1):PAGE295
     2 SMB_INA230_2_3V3AUX_SDA_R1 @T6G_MB_LIB.T6G(SCH_1):SMB_INA230_2_3V3AUX_SDA_R1   I146 @T6G_MB_LIB.T6G(SCH_1):PAGE295

R3752 Q_RES_0402LF-0,5%,1/16W,CHIP,CS00002JB13
     1 E1S_0_P3V3_ADC_ALERT_R @T6G_MB_LIB.T6G(SCH_1):E1S_0_P3V3_ADC_ALERT_R   I122 @T6G_MB_LIB.T6G(SCH_1):PAGE295
     2 E1S_0_P3V3_P12V_ADC_R_ALERT @T6G_MB_LIB.T6G(SCH_1):E1S_0_P3V3_P12V_ADC_R_ALERT   I122 @T6G_MB_LIB.T6G(SCH_1):PAGE295

R3754 Q_RES_0402LF-0,5%,1/16W,CHIP,CS00002JB13
     1 SMB_INA230_2_3V3AUX_SCL_R @T6G_MB_LIB.T6G(SCH_1):SMB_INA230_2_3V3AUX_SCL_R   I155 @T6G_MB_LIB.T6G(SCH_1):PAGE295
     2 SMB_INA230_2_3V3AUX_SCL_R1 @T6G_MB_LIB.T6G(SCH_1):SMB_INA230_2_3V3AUX_SCL_R1   I155 @T6G_MB_LIB.T6G(SCH_1):PAGE295

R3756 Q_RES_0402LF-0,5%,1/16W,CHIP,CS00002JB13
     1 SMB_INA230_2_3V3AUX_SDA_R @T6G_MB_LIB.T6G(SCH_1):SMB_INA230_2_3V3AUX_SDA_R   I154 @T6G_MB_LIB.T6G(SCH_1):PAGE295
     2 SMB_INA230_2_3V3AUX_SDA_R1 @T6G_MB_LIB.T6G(SCH_1):SMB_INA230_2_3V3AUX_SDA_R1   I154 @T6G_MB_LIB.T6G(SCH_1):PAGE295

R3758 Q_RES_0402LF-10,1%,1/16W,CHIP,CS01002FB07
     1 P3V3_E1S_0_R @T6G_MB_LIB.T6G(SCH_1):P3V3_E1S_0_R   I132 @T6G_MB_LIB.T6G(SCH_1):PAGE295
     2 VSENSE_P3V3_INA230_2_INP @T6G_MB_LIB.T6G(SCH_1):VSENSE_P3V3_INA230_2_INP   I132 @T6G_MB_LIB.T6G(SCH_1):PAGE295

R3760 Q_RES_0402LF-10,1%,1/16W,CHIP,CS01002FB07
     1 P3V3_E1S_0 @T6G_MB_LIB.T6G(SCH_1):P3V3_E1S_0   I134 @T6G_MB_LIB.T6G(SCH_1):PAGE295
     2 VSENSE_P3V3_INA230_2_INN @T6G_MB_LIB.T6G(SCH_1):VSENSE_P3V3_INA230_2_INN   I134 @T6G_MB_LIB.T6G(SCH_1):PAGE295

R3763 Q_RES_0402LF-4.7K,1%,1/16W,CHIP,CS24702FB06
     1    GND @T6G_MB_LIB.T6G(SCH_1):GND   I136 @T6G_MB_LIB.T6G(SCH_1):PAGE295
     2 INA230_2_A1 @T6G_MB_LIB.T6G(SCH_1):INA230_2_A1   I136 @T6G_MB_LIB.T6G(SCH_1):PAGE295

R3764 Q_RES_0402LF-4.7K,1%,1/16W,EMPTY,CS24702FB06
     1    GND @T6G_MB_LIB.T6G(SCH_1):GND   I135 @T6G_MB_LIB.T6G(SCH_1):PAGE295
     2 INA230_2_A0 @T6G_MB_LIB.T6G(SCH_1):INA230_2_A0   I135 @T6G_MB_LIB.T6G(SCH_1):PAGE295

R3767 Q_RES_2512LF-0.002,1%,2W,CHIP,CS+002AFR06
     1 P3V3_E1S_0 @T6G_MB_LIB.T6G(SCH_1):P3V3_E1S_0   I144 @T6G_MB_LIB.T6G(SCH_1):PAGE295
     2 P3V3_E1S_0_R @T6G_MB_LIB.T6G(SCH_1):P3V3_E1S_0_R   I144 @T6G_MB_LIB.T6G(SCH_1):PAGE295

R3770 Q_RES_0402LF-0,5%,1/16W,CHIP,CS00002JB13
     1 GPU_PRSNT @T6G_MB_LIB.T6G(SCH_1):GPU_PRSNT    I34 @T6G_MB_LIB.T6G(SCH_1):PAGE364
     2 GPU_PRSNT_R @T6G_MB_LIB.T6G(SCH_1):GPU_PRSNT_R    I34 @T6G_MB_LIB.T6G(SCH_1):PAGE364

R3771 Q_RES_0402LF-10K,1%,1/16W,CHIP,CS31002FB08
     1 P3V3_AUX @T6G_MB_LIB.T6G(SCH_1):P3V3_AUX     I7 @T6G_MB_LIB.T6G(SCH_1):PAGE297
     2 E1S_0_PWRDIS @T6G_MB_LIB.T6G(SCH_1):E1S_0_PWRDIS     I7 @T6G_MB_LIB.T6G(SCH_1):PAGE297

R3772 Q_RES_0402LF-0,5%,1/16W,CHIP,CS00002JB13
     1 RST_SMB_BUF_E1S_0_N @T6G_MB_LIB.T6G(SCH_1):RST_SMB_BUF_E1S_0_N    I38 @T6G_MB_LIB.T6G(SCH_1):PAGE297
     2 RST_SMB_E1S_0_N @T6G_MB_LIB.T6G(SCH_1):RST_SMB_E1S_0_N    I38 @T6G_MB_LIB.T6G(SCH_1):PAGE297

R3773 Q_RES_0402LF-4.7K,5%,1/16W,EMPTY,CS24702JB10
     1 P3V3_AUX @T6G_MB_LIB.T6G(SCH_1):P3V3_AUX   I106 @T6G_MB_LIB.T6G(SCH_1):PAGE297
     2 RST_SMB_E1S_0_N @T6G_MB_LIB.T6G(SCH_1):RST_SMB_E1S_0_N   I106 @T6G_MB_LIB.T6G(SCH_1):PAGE297

R3775 Q_RES_0402LF-0,5%,1/16W,CHIP,CS00002JB13
     1 FM_SMB_RST_E1S_0_R_N @T6G_MB_LIB.T6G(SCH_1):FM_SMB_RST_E1S_0_R_N     I2 @T6G_MB_LIB.T6G(SCH_1):PAGE297
     2 RST_SMB_E1S_N @T6G_MB_LIB.T6G(SCH_1):RST_SMB_E1S_N     I2 @T6G_MB_LIB.T6G(SCH_1):PAGE297

R3776 Q_RES_0402LF-0,5%,1/16W,CHIP,CS00002JB13
     1 FM_UARTSW_MSB_N @T6G_MB_LIB.T6G(SCH_1):FM_UARTSW_MSB_N    I27 @T6G_MB_LIB.T6G(SCH_1):PAGE348
     2 FM_UARTSW_MSB_R @T6G_MB_LIB.T6G(SCH_1):FM_UARTSW_MSB_R    I27 @T6G_MB_LIB.T6G(SCH_1):PAGE348

R3777 Q_RES_0402LF-0,5%,1/16W,CHIP,CS00002JB13
     1 FM_UARTSW_LSB_N @T6G_MB_LIB.T6G(SCH_1):FM_UARTSW_LSB_N    I25 @T6G_MB_LIB.T6G(SCH_1):PAGE348
     2 FM_UARTSW_LSB_R @T6G_MB_LIB.T6G(SCH_1):FM_UARTSW_LSB_R    I25 @T6G_MB_LIB.T6G(SCH_1):PAGE348

R3778 Q_RES_0402LF-0,5%,1/16W,CHIP,CS00002JB13
     1 FM_SOL_UART_CH_SEL_R @T6G_MB_LIB.T6G(SCH_1):FM_SOL_UART_CH_SEL_R   I169 @T6G_MB_LIB.T6G(SCH_1):PAGE348
     2 FM_SOL_UART_CH_SEL @T6G_MB_LIB.T6G(SCH_1):FM_SOL_UART_CH_SEL   I169 @T6G_MB_LIB.T6G(SCH_1):PAGE348

R3779 Q_RES_0402LF-0,5%,1/16W,CHIP,CS00002JB13
     1 RST_PERST_E1S_0_N @T6G_MB_LIB.T6G(SCH_1):RST_PERST_E1S_0_N    I30 @T6G_MB_LIB.T6G(SCH_1):PAGE297
     2 RST_PCIE_E1S_PERST_N @T6G_MB_LIB.T6G(SCH_1):RST_PCIE_E1S_PERST_N    I30 @T6G_MB_LIB.T6G(SCH_1):PAGE297

R3783 Q_RES_0402LF-100K,1%,1/16W,EMPTY,CS41002FB09
     1 P3V3_AUX @T6G_MB_LIB.T6G(SCH_1):P3V3_AUX   I131 @T6G_MB_LIB.T6G(SCH_1):PAGE338
     2 OCP_V3_1_P3V3_PWRGD @T6G_MB_LIB.T6G(SCH_1):OCP_V3_1_P3V3_PWRGD   I131 @T6G_MB_LIB.T6G(SCH_1):PAGE338

R3784 Q_RES_0402LF-0,5%,1/16W,CHIP,CS00002JB13
     1 P12V_OCP_UV_1_R @T6G_MB_LIB.T6G(SCH_1):P12V_OCP_UV_1_R    I40 @T6G_MB_LIB.T6G(SCH_1):PAGE338
     2 P12V_OCP_UV_1 @T6G_MB_LIB.T6G(SCH_1):P12V_OCP_UV_1    I40 @T6G_MB_LIB.T6G(SCH_1):PAGE338

R3785 Q_RES_0402LF-0,5%,1/16W,CHIP,CS00002JB13
     1 P3V3_OCP_UV_1_R1 @T6G_MB_LIB.T6G(SCH_1):P3V3_OCP_UV_1_R1    I61 @T6G_MB_LIB.T6G(SCH_1):PAGE338
     2 P3V3_OCP_UV_1 @T6G_MB_LIB.T6G(SCH_1):P3V3_OCP_UV_1    I61 @T6G_MB_LIB.T6G(SCH_1):PAGE338

R3794 Q_RES_0402LF-0,5%,1/16W,EMPTY,CS00002JB13
     1 P3V3_OCP_PWRGD_1 @T6G_MB_LIB.T6G(SCH_1):P3V3_OCP_PWRGD_1   I132 @T6G_MB_LIB.T6G(SCH_1):PAGE338
     2 OCP_V3_1_P3V3_PWRGD @T6G_MB_LIB.T6G(SCH_1):OCP_V3_1_P3V3_PWRGD   I132 @T6G_MB_LIB.T6G(SCH_1):PAGE338

R3796 Q_RES_0402LF-100K,1%,1/16W,CHIP,CS41002FB09
     1 P3V3_AUX @T6G_MB_LIB.T6G(SCH_1):P3V3_AUX   I101 @T6G_MB_LIB.T6G(SCH_1):PAGE338
     2 P3V3_OCP_FAULT_1 @T6G_MB_LIB.T6G(SCH_1):P3V3_OCP_FAULT_1   I101 @T6G_MB_LIB.T6G(SCH_1):PAGE338

R3797 Q_RES_0402LF-100K,1%,1/16W,CHIP,CS41002FB09
     1 P3V3_AUX @T6G_MB_LIB.T6G(SCH_1):P3V3_AUX    I85 @T6G_MB_LIB.T6G(SCH_1):PAGE338
     2 HP_LVC3_OCP_V3_1_P12V_PWRGD @T6G_MB_LIB.T6G(SCH_1):HP_LVC3_OCP_V3_1_P12V_PWRGD    I85 @T6G_MB_LIB.T6G(SCH_1):PAGE338

R3799 Q_RES_0402LF-100K,1%,1/16W,CHIP,CS41002FB09
     1 P3V3_AUX @T6G_MB_LIB.T6G(SCH_1):P3V3_AUX    I83 @T6G_MB_LIB.T6G(SCH_1):PAGE338
     2 P12V_OCP_FAULT_1 @T6G_MB_LIB.T6G(SCH_1):P12V_OCP_FAULT_1    I83 @T6G_MB_LIB.T6G(SCH_1):PAGE338

R3807 Q_RES_0402LF-0,5%,1/16W,CHIP,CS00002JB13
     1 P3V3_OCP_UV_2_R1 @T6G_MB_LIB.T6G(SCH_1):P3V3_OCP_UV_2_R1    I50 @T6G_MB_LIB.T6G(SCH_1):PAGE343
     2 P3V3_OCP_UV_2 @T6G_MB_LIB.T6G(SCH_1):P3V3_OCP_UV_2    I50 @T6G_MB_LIB.T6G(SCH_1):PAGE343

R3816 Q_RES_0402LF-100K,1%,1/16W,CHIP,CS41002FB09
     1 P3V3_AUX @T6G_MB_LIB.T6G(SCH_1):P3V3_AUX    I79 @T6G_MB_LIB.T6G(SCH_1):PAGE343
     2 P12V_OCP_FAULT_2 @T6G_MB_LIB.T6G(SCH_1):P12V_OCP_FAULT_2    I79 @T6G_MB_LIB.T6G(SCH_1):PAGE343

R3825 Q_RES_0402LF-100K,1%,1/16W,CHIP,CS41002FB09
     1 P3V3_AUX @T6G_MB_LIB.T6G(SCH_1):P3V3_AUX    I80 @T6G_MB_LIB.T6G(SCH_1):PAGE343
     2 HP_LVC3_OCP_V3_2_P12V_PWRGD @T6G_MB_LIB.T6G(SCH_1):HP_LVC3_OCP_V3_2_P12V_PWRGD    I80 @T6G_MB_LIB.T6G(SCH_1):PAGE343

R3826 Q_RES_0402LF-100K,1%,1/16W,EMPTY,CS41002FB09
     1 P3V3_AUX @T6G_MB_LIB.T6G(SCH_1):P3V3_AUX   I128 @T6G_MB_LIB.T6G(SCH_1):PAGE343
     2 OCP_V3_2_P3V3_PWRGD @T6G_MB_LIB.T6G(SCH_1):OCP_V3_2_P3V3_PWRGD   I128 @T6G_MB_LIB.T6G(SCH_1):PAGE343

R3827 Q_RES_0402LF-0,5%,1/16W,CHIP,CS00002JB13
     1 P12V_OCP_UV_2_R @T6G_MB_LIB.T6G(SCH_1):P12V_OCP_UV_2_R    I33 @T6G_MB_LIB.T6G(SCH_1):PAGE343
     2 P12V_OCP_UV_2 @T6G_MB_LIB.T6G(SCH_1):P12V_OCP_UV_2    I33 @T6G_MB_LIB.T6G(SCH_1):PAGE343

R3831 Q_RES_0402LF-0,5%,1/16W,CHIP,CS00002JB13
     1 P12V_OCP_PWRGD_2 @T6G_MB_LIB.T6G(SCH_1):P12V_OCP_PWRGD_2    I77 @T6G_MB_LIB.T6G(SCH_1):PAGE343
     2 HP_LVC3_OCP_V3_2_P12V_PWRGD @T6G_MB_LIB.T6G(SCH_1):HP_LVC3_OCP_V3_2_P12V_PWRGD    I77 @T6G_MB_LIB.T6G(SCH_1):PAGE343

R3832 Q_RES_0402LF-0,5%,1/16W,EMPTY,CS00002JB13
     1 P3V3_OCP_PWRGD_2 @T6G_MB_LIB.T6G(SCH_1):P3V3_OCP_PWRGD_2   I127 @T6G_MB_LIB.T6G(SCH_1):PAGE343
     2 OCP_V3_2_P3V3_PWRGD @T6G_MB_LIB.T6G(SCH_1):OCP_V3_2_P3V3_PWRGD   I127 @T6G_MB_LIB.T6G(SCH_1):PAGE343

R3833 Q_RES_0402LF-100K,1%,1/16W,CHIP,CS41002FB09
     1 P3V3_AUX @T6G_MB_LIB.T6G(SCH_1):P3V3_AUX   I107 @T6G_MB_LIB.T6G(SCH_1):PAGE343
     2 P3V3_OCP_FAULT_2 @T6G_MB_LIB.T6G(SCH_1):P3V3_OCP_FAULT_2   I107 @T6G_MB_LIB.T6G(SCH_1):PAGE343

R3834 Q_RES_0402LF-0,5%,1/16W,EMPTY,CS00002JB13
     1 P12V_OCP_SFF_EN_R @T6G_MB_LIB.T6G(SCH_1):P12V_OCP_SFF_EN_R   I128 @T6G_MB_LIB.T6G(SCH_1):PAGE339
     2 P12V_OCP_EN_1_R2 @T6G_MB_LIB.T6G(SCH_1):P12V_OCP_EN_1_R2   I128 @T6G_MB_LIB.T6G(SCH_1):PAGE339

R3836 Q_RES_0402LF-10K,1%,1/16W,CHIP,CS31002FB08
     1 P3V3_AUX @T6G_MB_LIB.T6G(SCH_1):P3V3_AUX    I43 @T6G_MB_LIB.T6G(SCH_1):PAGE350
     2 HP_LVC3_SCM_HSC_PWRGD_R @T6G_MB_LIB.T6G(SCH_1):HP_LVC3_SCM_HSC_PWRGD_R    I43 @T6G_MB_LIB.T6G(SCH_1):PAGE350

R3845 Q_RES_0402LF-0,5%,1/16W,EMPTY,CS00002JB13
     1 P3V3_OCP_SFF_EN_R @T6G_MB_LIB.T6G(SCH_1):P3V3_OCP_SFF_EN_R   I131 @T6G_MB_LIB.T6G(SCH_1):PAGE339
     2 P3V3_OCP_EN_1_R2 @T6G_MB_LIB.T6G(SCH_1):P3V3_OCP_EN_1_R2   I131 @T6G_MB_LIB.T6G(SCH_1):PAGE339

R3848 Q_RES_0402LF-10K,1%,1/16W,CHIP,CS31002FB08
     1 P3V3_AUX @T6G_MB_LIB.T6G(SCH_1):P3V3_AUX    I27 @T6G_MB_LIB.T6G(SCH_1):PAGE344
     2 HP_LVC3_OCP_V3_2_P12V_PWRGD @T6G_MB_LIB.T6G(SCH_1):HP_LVC3_OCP_V3_2_P12V_PWRGD    I27 @T6G_MB_LIB.T6G(SCH_1):PAGE344

R3858 Q_RES_0402LF-33.2,1%,1/16W,CHIP,CS03322FB03
     1 SMB_OCP_V3_2_3V3AUX_SDA @T6G_MB_LIB.T6G(SCH_1):SMB_OCP_V3_2_3V3AUX_SDA    I96 @T6G_MB_LIB.T6G(SCH_1):PAGE348
     2 SMB_OCP_V3_2_3V3AUX_SDA_R0 @T6G_MB_LIB.T6G(SCH_1):SMB_OCP_V3_2_3V3AUX_SDA_R0    I96 @T6G_MB_LIB.T6G(SCH_1):PAGE348

R3859 Q_RES_0402LF-0,5%,1/16W,EMPTY,CS00002JB13
     1 P12V_OCP_V3_2_ISENSE_MAM_MAM @T6G_MB_LIB.T6G(SCH_1):P12V_OCP_V3_2_ISENSE_MAM_MAM   I107 @T6G_MB_LIB.T6G(SCH_1):PAGE369
     2 P12V_OCP_V3_2_ISENSE_MAM @T6G_MB_LIB.T6G(SCH_1):P12V_OCP_V3_2_ISENSE_MAM   I107 @T6G_MB_LIB.T6G(SCH_1):PAGE369

R3860 Q_RES_0402LF-0,5%,1/16W,EMPTY,CS00002JB13
     1 P12V_OCP_V3_2_ISENSE_MPS_MAM @T6G_MB_LIB.T6G(SCH_1):P12V_OCP_V3_2_ISENSE_MPS_MAM    I83 @T6G_MB_LIB.T6G(SCH_1):PAGE369
     2 P12V_OCP_V3_2_ISENSE_MAM @T6G_MB_LIB.T6G(SCH_1):P12V_OCP_V3_2_ISENSE_MAM    I83 @T6G_MB_LIB.T6G(SCH_1):PAGE369

R3861 Q_RES_0402LF-0,5%,1/16W,CHIP,CS00002JB13
     1 P12V_OCP_V3_2_ISENSE_MAM_TIC @T6G_MB_LIB.T6G(SCH_1):P12V_OCP_V3_2_ISENSE_MAM_TIC    I82 @T6G_MB_LIB.T6G(SCH_1):PAGE369
     2 P12V_OCP_V3_2_ISENSE_TIC @T6G_MB_LIB.T6G(SCH_1):P12V_OCP_V3_2_ISENSE_TIC    I82 @T6G_MB_LIB.T6G(SCH_1):PAGE369

R3862 Q_RES_0402LF-0,5%,1/16W,EMPTY,CS00002JB13
     1 P12V_OCP_V3_2_ISENSE_MPS_TIC @T6G_MB_LIB.T6G(SCH_1):P12V_OCP_V3_2_ISENSE_MPS_TIC    I81 @T6G_MB_LIB.T6G(SCH_1):PAGE369
     2 P12V_OCP_V3_2_ISENSE_TIC @T6G_MB_LIB.T6G(SCH_1):P12V_OCP_V3_2_ISENSE_TIC    I81 @T6G_MB_LIB.T6G(SCH_1):PAGE369

R3863 Q_RES_0402LF-0,5%,1/16W,EMPTY,CS00002JB13
     1 P12V_OCP_SFF_ISENSE_MAM_MAM @T6G_MB_LIB.T6G(SCH_1):P12V_OCP_SFF_ISENSE_MAM_MAM   I115 @T6G_MB_LIB.T6G(SCH_1):PAGE369
     2 P12V_OCP_SFF_ISENSE_MAM @T6G_MB_LIB.T6G(SCH_1):P12V_OCP_SFF_ISENSE_MAM   I115 @T6G_MB_LIB.T6G(SCH_1):PAGE369

R3864 Q_RES_0402LF-0,5%,1/16W,EMPTY,CS00002JB13
     1 P12V_OCP_SFF_ISENSE_MPS_MAM @T6G_MB_LIB.T6G(SCH_1):P12V_OCP_SFF_ISENSE_MPS_MAM   I110 @T6G_MB_LIB.T6G(SCH_1):PAGE369
     2 P12V_OCP_SFF_ISENSE_MAM @T6G_MB_LIB.T6G(SCH_1):P12V_OCP_SFF_ISENSE_MAM   I110 @T6G_MB_LIB.T6G(SCH_1):PAGE369

R3865 Q_RES_0402LF-0,5%,1/16W,CHIP,CS00002JB13
     1 P12V_OCP_SFF_ISENSE_MAM_TIC @T6G_MB_LIB.T6G(SCH_1):P12V_OCP_SFF_ISENSE_MAM_TIC   I109 @T6G_MB_LIB.T6G(SCH_1):PAGE369
     2 P12V_OCP_SFF_ISENSE_TIC @T6G_MB_LIB.T6G(SCH_1):P12V_OCP_SFF_ISENSE_TIC   I109 @T6G_MB_LIB.T6G(SCH_1):PAGE369

R3866 Q_RES_0402LF-0,5%,1/16W,EMPTY,CS00002JB13
     1 P12V_OCP_SFF_ISENSE_MPS_TIC @T6G_MB_LIB.T6G(SCH_1):P12V_OCP_SFF_ISENSE_MPS_TIC   I108 @T6G_MB_LIB.T6G(SCH_1):PAGE369
     2 P12V_OCP_SFF_ISENSE_TIC @T6G_MB_LIB.T6G(SCH_1):P12V_OCP_SFF_ISENSE_TIC   I108 @T6G_MB_LIB.T6G(SCH_1):PAGE369

R3867 Q_RES_0402LF-0,5%,1/16W,EMPTY,CS00002JB13
     1 P12V_OCP_SENSE_2 @T6G_MB_LIB.T6G(SCH_1):P12V_OCP_SENSE_2    I74 @T6G_MB_LIB.T6G(SCH_1):PAGE343
     2 P12V_OCP_V3_2_ISENSE_MAM_MAM @T6G_MB_LIB.T6G(SCH_1):P12V_OCP_V3_2_ISENSE_MAM_MAM    I74 @T6G_MB_LIB.T6G(SCH_1):PAGE343

R3868 Q_RES_0402LF-0,5%,1/16W,CHIP,CS00002JB13
     1 P12V_OCP_SENSE_2 @T6G_MB_LIB.T6G(SCH_1):P12V_OCP_SENSE_2    I73 @T6G_MB_LIB.T6G(SCH_1):PAGE343
     2 P12V_OCP_V3_2_ISENSE_MAM_TIC @T6G_MB_LIB.T6G(SCH_1):P12V_OCP_V3_2_ISENSE_MAM_TIC    I73 @T6G_MB_LIB.T6G(SCH_1):PAGE343

R3869 Q_RES_0402LF-0,5%,1/16W,EMPTY,CS00002JB13
     1 P12V_OCP_SENSE_1 @T6G_MB_LIB.T6G(SCH_1):P12V_OCP_SENSE_1    I82 @T6G_MB_LIB.T6G(SCH_1):PAGE338
     2 P12V_OCP_SFF_ISENSE_MAM_MAM @T6G_MB_LIB.T6G(SCH_1):P12V_OCP_SFF_ISENSE_MAM_MAM    I82 @T6G_MB_LIB.T6G(SCH_1):PAGE338

R3870 Q_RES_0402LF-0,5%,1/16W,CHIP,CS00002JB13
     1 P12V_OCP_SENSE_1 @T6G_MB_LIB.T6G(SCH_1):P12V_OCP_SENSE_1    I80 @T6G_MB_LIB.T6G(SCH_1):PAGE338
     2 P12V_OCP_SFF_ISENSE_MAM_TIC @T6G_MB_LIB.T6G(SCH_1):P12V_OCP_SFF_ISENSE_MAM_TIC    I80 @T6G_MB_LIB.T6G(SCH_1):PAGE338

R3871 Q_RES_0402LF-0,5%,1/16W,CHIP,CS00002JB13
     1 P12V_OCP_IMON_1 @T6G_MB_LIB.T6G(SCH_1):P12V_OCP_IMON_1    I85 @T6G_MB_LIB.T6G(SCH_1):PAGE339
     2 P12V_OCP_SFF_ISENSE_MPS_MAM @T6G_MB_LIB.T6G(SCH_1):P12V_OCP_SFF_ISENSE_MPS_MAM    I85 @T6G_MB_LIB.T6G(SCH_1):PAGE339

R3872 Q_RES_0402LF-0,5%,1/16W,EMPTY,CS00002JB13
     1 P12V_OCP_IMON_1 @T6G_MB_LIB.T6G(SCH_1):P12V_OCP_IMON_1    I84 @T6G_MB_LIB.T6G(SCH_1):PAGE339
     2 P12V_OCP_SFF_ISENSE_MPS_TIC @T6G_MB_LIB.T6G(SCH_1):P12V_OCP_SFF_ISENSE_MPS_TIC    I84 @T6G_MB_LIB.T6G(SCH_1):PAGE339

R3873 Q_RES_0402LF-0,5%,1/16W,CHIP,CS00002JB13
     1 P12V_OCP_IMON_2 @T6G_MB_LIB.T6G(SCH_1):P12V_OCP_IMON_2    I23 @T6G_MB_LIB.T6G(SCH_1):PAGE344
     2 P12V_OCP_V3_2_ISENSE_MPS_MAM @T6G_MB_LIB.T6G(SCH_1):P12V_OCP_V3_2_ISENSE_MPS_MAM    I23 @T6G_MB_LIB.T6G(SCH_1):PAGE344

R3874 Q_RES_0402LF-0,5%,1/16W,EMPTY,CS00002JB13
     1 P12V_OCP_IMON_2 @T6G_MB_LIB.T6G(SCH_1):P12V_OCP_IMON_2    I22 @T6G_MB_LIB.T6G(SCH_1):PAGE344
     2 P12V_OCP_V3_2_ISENSE_MPS_TIC @T6G_MB_LIB.T6G(SCH_1):P12V_OCP_V3_2_ISENSE_MPS_TIC    I22 @T6G_MB_LIB.T6G(SCH_1):PAGE344

R3907 Q_RES_0402LF-33K,1%,1/16W,CHIP,CS33302FB00
     1 PDB_PRSNT_R_N @T6G_MB_LIB.T6G(SCH_1):PDB_PRSNT_R_N    I10 @T6G_MB_LIB.T6G(SCH_1):PAGE372
     2    GND @T6G_MB_LIB.T6G(SCH_1):GND    I10 @T6G_MB_LIB.T6G(SCH_1):PAGE372

R3909 Q_RES_0402LF-33.2,1%,1/16W,CHIP,CS03322FB03
     1 SMB_SML1_PMBUS_HSC_SCL @T6G_MB_LIB.T6G(SCH_1):SMB_SML1_PMBUS_HSC_SCL    I37 @T6G_MB_LIB.T6G(SCH_1):PAGE267
     2 SMB_SML1_PMBUS_HSC_L_SCL @T6G_MB_LIB.T6G(SCH_1):SMB_SML1_PMBUS_HSC_L_SCL    I37 @T6G_MB_LIB.T6G(SCH_1):PAGE267

R3923 Q_RES_0402LF-63.4K,1%,1/16W,CHIP,CS36342FB04
     1 P12V_PSU_FUSE @T6G_MB_LIB.T6G(SCH_1):P12V_PSU_FUSE    I16 @T6G_MB_LIB.T6G(SCH_1):PAGE372
     2 PDB_PRSNT_R_N @T6G_MB_LIB.T6G(SCH_1):PDB_PRSNT_R_N    I16 @T6G_MB_LIB.T6G(SCH_1):PAGE372

R3924 Q_RES_0402LF-0,5%,1/16W,CHIP,CS00002JB13
     1 IRQ_SML1_PMBUS_ALERT_N @T6G_MB_LIB.T6G(SCH_1):IRQ_SML1_PMBUS_ALERT_N    I24 @T6G_MB_LIB.T6G(SCH_1):PAGE267
     2 IRQ_SML1_PMBUS_ALERT @T6G_MB_LIB.T6G(SCH_1):IRQ_SML1_PMBUS_ALERT    I24 @T6G_MB_LIB.T6G(SCH_1):PAGE267

R3925 Q_RES_0402LF-1K,1%,1/16W,CHIP,CS21002FB06
     1 IRQ_SML1_PMBUS_ALERT @T6G_MB_LIB.T6G(SCH_1):IRQ_SML1_PMBUS_ALERT    I34 @T6G_MB_LIB.T6G(SCH_1):PAGE267
     2 P3V3_AUX @T6G_MB_LIB.T6G(SCH_1):P3V3_AUX    I34 @T6G_MB_LIB.T6G(SCH_1):PAGE267

R3933 Q_RES_0402LF-16.9K,1%,1/16W,CHIP,CS31692FB03
     1 P12V_AUX @T6G_MB_LIB.T6G(SCH_1):P12V_AUX    I63 @T6G_MB_LIB.T6G(SCH_1):PAGE267
     2 MB0_P12V_STBY_PWRGD @T6G_MB_LIB.T6G(SCH_1):MB0_P12V_STBY_PWRGD    I63 @T6G_MB_LIB.T6G(SCH_1):PAGE267

R3934 Q_RES_0402LF-22,1%,1/16W,CHIP,CS02202FB02
     1 HSC_D_OC_R @T6G_MB_LIB.T6G(SCH_1):HSC_D_OC_R    I80 @T6G_MB_LIB.T6G(SCH_1):PAGE267
     2 HSC_D_OC @T6G_MB_LIB.T6G(SCH_1):HSC_D_OC    I80 @T6G_MB_LIB.T6G(SCH_1):PAGE267

R3936 Q_RES_0402LF-4.7K,1%,1/16W,CHIP,CS24702FB06
     1 HSC_VDD @T6G_MB_LIB.T6G(SCH_1):HSC_VDD    I91 @T6G_MB_LIB.T6G(SCH_1):PAGE267
     2 HSC_D_OC @T6G_MB_LIB.T6G(SCH_1):HSC_D_OC    I91 @T6G_MB_LIB.T6G(SCH_1):PAGE267

R3939 Q_RES_0402LF-0,5%,1/16W,EMPTY,CS00002JB13
     1 P12V_E1S_0_ISENSE_MAM_MAM @T6G_MB_LIB.T6G(SCH_1):P12V_E1S_0_ISENSE_MAM_MAM    I80 @T6G_MB_LIB.T6G(SCH_1):PAGE369
     2 P12V_E1S_0_ISENSE_MAM @T6G_MB_LIB.T6G(SCH_1):P12V_E1S_0_ISENSE_MAM    I80 @T6G_MB_LIB.T6G(SCH_1):PAGE369

R3940 Q_RES_0402LF-0,5%,1/16W,EMPTY,CS00002JB13
     1 P12V_E1S_0_ISENSE_MPS_MAM @T6G_MB_LIB.T6G(SCH_1):P12V_E1S_0_ISENSE_MPS_MAM    I79 @T6G_MB_LIB.T6G(SCH_1):PAGE369
     2 P12V_E1S_0_ISENSE_MAM @T6G_MB_LIB.T6G(SCH_1):P12V_E1S_0_ISENSE_MAM    I79 @T6G_MB_LIB.T6G(SCH_1):PAGE369

R3941 Q_RES_0402LF-0,5%,1/16W,CHIP,CS00002JB13
     1 P12V_E1S_0_ISENSE_MAM_TIC @T6G_MB_LIB.T6G(SCH_1):P12V_E1S_0_ISENSE_MAM_TIC    I74 @T6G_MB_LIB.T6G(SCH_1):PAGE369
     2 P12V_E1S_0_ISENSE_TIC @T6G_MB_LIB.T6G(SCH_1):P12V_E1S_0_ISENSE_TIC    I74 @T6G_MB_LIB.T6G(SCH_1):PAGE369

R3942 Q_RES_0402LF-0,5%,1/16W,EMPTY,CS00002JB13
     1 P12V_E1S_0_ISENSE_MPS_TIC @T6G_MB_LIB.T6G(SCH_1):P12V_E1S_0_ISENSE_MPS_TIC    I73 @T6G_MB_LIB.T6G(SCH_1):PAGE369
     2 P12V_E1S_0_ISENSE_TIC @T6G_MB_LIB.T6G(SCH_1):P12V_E1S_0_ISENSE_TIC    I73 @T6G_MB_LIB.T6G(SCH_1):PAGE369

R3943 Q_RES_0402LF-0,5%,1/16W,CHIP,CS00002JB13
     1 E1S_0_P12V_EN @T6G_MB_LIB.T6G(SCH_1):E1S_0_P12V_EN    I19 @T6G_MB_LIB.T6G(SCH_1):PAGE323
     2 P12V_E1S_EN_0_R2 @T6G_MB_LIB.T6G(SCH_1):P12V_E1S_EN_0_R2    I19 @T6G_MB_LIB.T6G(SCH_1):PAGE323

R3946 Q_RES_0402LF-0,5%,1/16W,CHIP,CS00002JB13
     1 E1S_0_P3V3_EN @T6G_MB_LIB.T6G(SCH_1):E1S_0_P3V3_EN     I5 @T6G_MB_LIB.T6G(SCH_1):PAGE323
     2 P3V3_E1S_EN_0_R2 @T6G_MB_LIB.T6G(SCH_1):P3V3_E1S_EN_0_R2     I5 @T6G_MB_LIB.T6G(SCH_1):PAGE323

R3948 Q_RES_0402LF-10K,1%,1/16W,CHIP,CS31002FB08
     1 P3V3_AUX @T6G_MB_LIB.T6G(SCH_1):P3V3_AUX    I37 @T6G_MB_LIB.T6G(SCH_1):PAGE323
     2 HP_LVC3_E1S_0_HSC_PWRGD @T6G_MB_LIB.T6G(SCH_1):HP_LVC3_E1S_0_HSC_PWRGD    I37 @T6G_MB_LIB.T6G(SCH_1):PAGE323

R3955 Q_RES_0402LF-0,5%,1/16W,CHIP,CS00002JB13
     1 P12V_E1S_IMON_0 @T6G_MB_LIB.T6G(SCH_1):P12V_E1S_IMON_0    I48 @T6G_MB_LIB.T6G(SCH_1):PAGE323
     2 P12V_E1S_0_ISENSE_MPS_MAM @T6G_MB_LIB.T6G(SCH_1):P12V_E1S_0_ISENSE_MPS_MAM    I48 @T6G_MB_LIB.T6G(SCH_1):PAGE323

R3956 Q_RES_0402LF-0,5%,1/16W,EMPTY,CS00002JB13
     1 P12V_E1S_IMON_0 @T6G_MB_LIB.T6G(SCH_1):P12V_E1S_IMON_0    I47 @T6G_MB_LIB.T6G(SCH_1):PAGE323
     2 P12V_E1S_0_ISENSE_MPS_TIC @T6G_MB_LIB.T6G(SCH_1):P12V_E1S_0_ISENSE_MPS_TIC    I47 @T6G_MB_LIB.T6G(SCH_1):PAGE323

R3958 Q_RES_0402LF-0,5%,1/16W,CHIP,CS00002JB13
     1 P12V_E1S_UV_0_R @T6G_MB_LIB.T6G(SCH_1):P12V_E1S_UV_0_R    I29 @T6G_MB_LIB.T6G(SCH_1):PAGE324
     2 P12V_E1S_UV_0 @T6G_MB_LIB.T6G(SCH_1):P12V_E1S_UV_0    I29 @T6G_MB_LIB.T6G(SCH_1):PAGE324

R3959 Q_RES_0402LF-0,5%,1/16W,CHIP,CS00002JB13
     1 P3V3_E1S_UV_0_R @T6G_MB_LIB.T6G(SCH_1):P3V3_E1S_UV_0_R    I18 @T6G_MB_LIB.T6G(SCH_1):PAGE324
     2 P3V3_E1S_UV_0 @T6G_MB_LIB.T6G(SCH_1):P3V3_E1S_UV_0    I18 @T6G_MB_LIB.T6G(SCH_1):PAGE324

R3972 Q_RES_0402LF-0,5%,1/16W,CHIP,CS00002JB13
     1 P12V_E1S_PWRGD_0 @T6G_MB_LIB.T6G(SCH_1):P12V_E1S_PWRGD_0    I71 @T6G_MB_LIB.T6G(SCH_1):PAGE324
     2 HP_LVC3_E1S_0_HSC_PWRGD @T6G_MB_LIB.T6G(SCH_1):HP_LVC3_E1S_0_HSC_PWRGD    I71 @T6G_MB_LIB.T6G(SCH_1):PAGE324

R3973 Q_RES_0402LF-0,5%,1/16W,CHIP,CS00002JB13
     1 P3V3_E1S_PWRGD_0 @T6G_MB_LIB.T6G(SCH_1):P3V3_E1S_PWRGD_0    I48 @T6G_MB_LIB.T6G(SCH_1):PAGE324
     2 P3V3_E1S_PWRGD_0_R @T6G_MB_LIB.T6G(SCH_1):P3V3_E1S_PWRGD_0_R    I48 @T6G_MB_LIB.T6G(SCH_1):PAGE324

R3974 Q_RES_0402LF-0,5%,1/16W,EMPTY,CS00002JB13
     1 P12V_E1S_SENSE_0 @T6G_MB_LIB.T6G(SCH_1):P12V_E1S_SENSE_0    I70 @T6G_MB_LIB.T6G(SCH_1):PAGE324
     2 P12V_E1S_0_ISENSE_MAM_MAM @T6G_MB_LIB.T6G(SCH_1):P12V_E1S_0_ISENSE_MAM_MAM    I70 @T6G_MB_LIB.T6G(SCH_1):PAGE324

R3975 Q_RES_0402LF-0,5%,1/16W,CHIP,CS00002JB13
     1 P12V_E1S_SENSE_0 @T6G_MB_LIB.T6G(SCH_1):P12V_E1S_SENSE_0    I87 @T6G_MB_LIB.T6G(SCH_1):PAGE324
     2 P12V_E1S_0_ISENSE_MAM_TIC @T6G_MB_LIB.T6G(SCH_1):P12V_E1S_0_ISENSE_MAM_TIC    I87 @T6G_MB_LIB.T6G(SCH_1):PAGE324

R3976 Q_RES_0402LF-100K,1%,1/16W,CHIP,CS41002FB09
     1 P3V3_AUX @T6G_MB_LIB.T6G(SCH_1):P3V3_AUX    I76 @T6G_MB_LIB.T6G(SCH_1):PAGE324
     2 P12V_E1S_FAULT_0 @T6G_MB_LIB.T6G(SCH_1):P12V_E1S_FAULT_0    I76 @T6G_MB_LIB.T6G(SCH_1):PAGE324

R3977 Q_RES_0402LF-100K,1%,1/16W,CHIP,CS41002FB09
     1 P3V3_AUX @T6G_MB_LIB.T6G(SCH_1):P3V3_AUX    I52 @T6G_MB_LIB.T6G(SCH_1):PAGE324
     2 P3V3_E1S_FAULT_0 @T6G_MB_LIB.T6G(SCH_1):P3V3_E1S_FAULT_0    I52 @T6G_MB_LIB.T6G(SCH_1):PAGE324

R3978 Q_RES_0402LF-100K,1%,1/16W,CHIP,CS41002FB09
     1 P3V3_AUX @T6G_MB_LIB.T6G(SCH_1):P3V3_AUX    I86 @T6G_MB_LIB.T6G(SCH_1):PAGE324
     2 HP_LVC3_E1S_0_HSC_PWRGD @T6G_MB_LIB.T6G(SCH_1):HP_LVC3_E1S_0_HSC_PWRGD    I86 @T6G_MB_LIB.T6G(SCH_1):PAGE324

R3979 Q_RES_0402LF-100K,1%,1/16W,CHIP,CS41002FB09
     1 P3V3_AUX @T6G_MB_LIB.T6G(SCH_1):P3V3_AUX    I54 @T6G_MB_LIB.T6G(SCH_1):PAGE324
     2 P3V3_E1S_PWRGD_0_R @T6G_MB_LIB.T6G(SCH_1):P3V3_E1S_PWRGD_0_R    I54 @T6G_MB_LIB.T6G(SCH_1):PAGE324

R3996 Q_RES_0402LF-0,5%,1/16W,CHIP,CS00002JB13
     1 VIRTUAL_RESEAT_FPGA_N @T6G_MB_LIB.T6G(SCH_1):VIRTUAL_RESEAT_FPGA_N    I17 @T6G_MB_LIB.T6G(SCH_1):PAGE350
     2 P12V_SCM_EN @T6G_MB_LIB.T6G(SCH_1):P12V_SCM_EN    I17 @T6G_MB_LIB.T6G(SCH_1):PAGE350

R3997 Q_RES_0402LF-0,5%,1/16W,CHIP,CS00002JB13
     1 P12V_SCM_UV_R @T6G_MB_LIB.T6G(SCH_1):P12V_SCM_UV_R    I27 @T6G_MB_LIB.T6G(SCH_1):PAGE350
     2 P12V_SCM_UV @T6G_MB_LIB.T6G(SCH_1):P12V_SCM_UV    I27 @T6G_MB_LIB.T6G(SCH_1):PAGE350

R3998 Q_RES_0402LF-0,5%,1/16W,CHIP,CS00002JB13
     1 P12V_SCM_EN @T6G_MB_LIB.T6G(SCH_1):P12V_SCM_EN    I14 @T6G_MB_LIB.T6G(SCH_1):PAGE350
     2 P12V_SCM_EN_R2 @T6G_MB_LIB.T6G(SCH_1):P12V_SCM_EN_R2    I14 @T6G_MB_LIB.T6G(SCH_1):PAGE350

R4013 Q_RES_0402LF-100K,1%,1/16W,CHIP,CS41002FB09
     1 P3V3_AUX @T6G_MB_LIB.T6G(SCH_1):P3V3_AUX    I76 @T6G_MB_LIB.T6G(SCH_1):PAGE350
     2 P12V_SCM_FAULT_R_N @T6G_MB_LIB.T6G(SCH_1):P12V_SCM_FAULT_R_N    I76 @T6G_MB_LIB.T6G(SCH_1):PAGE350

R4015 Q_RES_0402LF-100K,1%,1/16W,CHIP,CS41002FB09
     1 P3V3_AUX @T6G_MB_LIB.T6G(SCH_1):P3V3_AUX    I78 @T6G_MB_LIB.T6G(SCH_1):PAGE350
     2 HP_LVC3_SCM_HSC_PWRGD @T6G_MB_LIB.T6G(SCH_1):HP_LVC3_SCM_HSC_PWRGD    I78 @T6G_MB_LIB.T6G(SCH_1):PAGE350

R4058 Q_RES_0402LF-10K,1%,1/16W,CHIP,CS31002FB08
     1 P3V3_AUX @T6G_MB_LIB.T6G(SCH_1):P3V3_AUX    I13 @T6G_MB_LIB.T6G(SCH_1):PAGE330
     2 PRSNT_SWB_N @T6G_MB_LIB.T6G(SCH_1):PRSNT_SWB_N    I13 @T6G_MB_LIB.T6G(SCH_1):PAGE330

R4059 Q_RES_0402LF-0,5%,1/16W,EMPTY,CS00002JB13
     1 P12V_OCP_V3_2_EN_R @T6G_MB_LIB.T6G(SCH_1):P12V_OCP_V3_2_EN_R   I119 @T6G_MB_LIB.T6G(SCH_1):PAGE343
     2 P12V_OCP_EN_2_R @T6G_MB_LIB.T6G(SCH_1):P12V_OCP_EN_2_R   I119 @T6G_MB_LIB.T6G(SCH_1):PAGE343

R4060 Q_RES_0402LF-0,5%,1/16W,EMPTY,CS00002JB13
     1 P3V3_OCP_V3_2_EN_R @T6G_MB_LIB.T6G(SCH_1):P3V3_OCP_V3_2_EN_R   I122 @T6G_MB_LIB.T6G(SCH_1):PAGE343
     2 P3V3_OCP_EN_2_R @T6G_MB_LIB.T6G(SCH_1):P3V3_OCP_EN_2_R   I122 @T6G_MB_LIB.T6G(SCH_1):PAGE343

R4061 Q_RES_0402LF-0,5%,1/16W,EMPTY,CS00002JB13
     1 P12V_OCP_SFF_EN_R @T6G_MB_LIB.T6G(SCH_1):P12V_OCP_SFF_EN_R   I123 @T6G_MB_LIB.T6G(SCH_1):PAGE338
     2 P12V_OCP_EN_1_R @T6G_MB_LIB.T6G(SCH_1):P12V_OCP_EN_1_R   I123 @T6G_MB_LIB.T6G(SCH_1):PAGE338

R4062 Q_RES_0402LF-0,5%,1/16W,CHIP,CS00002JB13
     1 P12V_SCM_EN @T6G_MB_LIB.T6G(SCH_1):P12V_SCM_EN    I20 @T6G_MB_LIB.T6G(SCH_1):PAGE350
     2 P12V_SCM_EN_R @T6G_MB_LIB.T6G(SCH_1):P12V_SCM_EN_R    I20 @T6G_MB_LIB.T6G(SCH_1):PAGE350

R4063 Q_RES_0402LF-0,5%,1/16W,CHIP,CS00002JB13
     1 E1S_0_P3V3_EN @T6G_MB_LIB.T6G(SCH_1):E1S_0_P3V3_EN     I2 @T6G_MB_LIB.T6G(SCH_1):PAGE324
     2 P3V3_E1S_EN_0_R @T6G_MB_LIB.T6G(SCH_1):P3V3_E1S_EN_0_R     I2 @T6G_MB_LIB.T6G(SCH_1):PAGE324

R4064 Q_RES_0402LF-0,5%,1/16W,CHIP,CS00002JB13
     1 E1S_0_P12V_EN @T6G_MB_LIB.T6G(SCH_1):E1S_0_P12V_EN    I24 @T6G_MB_LIB.T6G(SCH_1):PAGE324
     2 P12V_E1S_EN_0_R @T6G_MB_LIB.T6G(SCH_1):P12V_E1S_EN_0_R    I24 @T6G_MB_LIB.T6G(SCH_1):PAGE324

R4065 Q_RES_0402LF-10K,1%,1/16W,CHIP,CS31002FB08
     1 P12V_AUX @T6G_MB_LIB.T6G(SCH_1):P12V_AUX    I17 @T6G_MB_LIB.T6G(SCH_1):PAGE343
     2 P12V_OCP_2_EN_G @T6G_MB_LIB.T6G(SCH_1):P12V_OCP_2_EN_G    I17 @T6G_MB_LIB.T6G(SCH_1):PAGE343

R4066 Q_RES_0402LF-4.7K,5%,1/16W,EMPTY,CS24702JB10
     1 P3V3_OCP_EN_2_R @T6G_MB_LIB.T6G(SCH_1):P3V3_OCP_EN_2_R   I121 @T6G_MB_LIB.T6G(SCH_1):PAGE343
     2    GND @T6G_MB_LIB.T6G(SCH_1):GND   I121 @T6G_MB_LIB.T6G(SCH_1):PAGE343

R4067 Q_RES_0402LF-10K,1%,1/16W,CHIP,CS31002FB08
     1 P12V_AUX @T6G_MB_LIB.T6G(SCH_1):P12V_AUX    I43 @T6G_MB_LIB.T6G(SCH_1):PAGE343
     2 P3V3_OCP_2_EN_G @T6G_MB_LIB.T6G(SCH_1):P3V3_OCP_2_EN_G    I43 @T6G_MB_LIB.T6G(SCH_1):PAGE343

R4068 Q_RES_0402LF-10K,1%,1/16W,CHIP,CS31002FB08
     1 P12V_AUX @T6G_MB_LIB.T6G(SCH_1):P12V_AUX    I17 @T6G_MB_LIB.T6G(SCH_1):PAGE338
     2 P12V_OCP_1_EN_G @T6G_MB_LIB.T6G(SCH_1):P12V_OCP_1_EN_G    I17 @T6G_MB_LIB.T6G(SCH_1):PAGE338

R4069 Q_RES_0402LF-4.7K,5%,1/16W,EMPTY,CS24702JB10
     1 P3V3_OCP_EN_1_R @T6G_MB_LIB.T6G(SCH_1):P3V3_OCP_EN_1_R   I127 @T6G_MB_LIB.T6G(SCH_1):PAGE338
     2    GND @T6G_MB_LIB.T6G(SCH_1):GND   I127 @T6G_MB_LIB.T6G(SCH_1):PAGE338

R4070 Q_RES_0402LF-10K,1%,1/16W,CHIP,CS31002FB08
     1 P12V_AUX @T6G_MB_LIB.T6G(SCH_1):P12V_AUX    I59 @T6G_MB_LIB.T6G(SCH_1):PAGE338
     2 P3V3_OCP_1_EN_G @T6G_MB_LIB.T6G(SCH_1):P3V3_OCP_1_EN_G    I59 @T6G_MB_LIB.T6G(SCH_1):PAGE338

R4071 Q_RES_0402LF-10K,1%,1/16W,CHIP,CS31002FB08
     1 P12V_AUX @T6G_MB_LIB.T6G(SCH_1):P12V_AUX    I25 @T6G_MB_LIB.T6G(SCH_1):PAGE350
     2 P12V_SCM_EN_G @T6G_MB_LIB.T6G(SCH_1):P12V_SCM_EN_G    I25 @T6G_MB_LIB.T6G(SCH_1):PAGE350

R4072 Q_RES_0402LF-10K,1%,1/16W,CHIP,CS31002FB08
     1 P12V_AUX @T6G_MB_LIB.T6G(SCH_1):P12V_AUX     I8 @T6G_MB_LIB.T6G(SCH_1):PAGE324
     2 P3V3_E1S_0_EN_G @T6G_MB_LIB.T6G(SCH_1):P3V3_E1S_0_EN_G     I8 @T6G_MB_LIB.T6G(SCH_1):PAGE324

R4073 Q_RES_0402LF-4.7K,5%,1/16W,CHIP,CS24702JB10
     1 P12V_E1S_EN_0_R @T6G_MB_LIB.T6G(SCH_1):P12V_E1S_EN_0_R    I11 @T6G_MB_LIB.T6G(SCH_1):PAGE324
     2    GND @T6G_MB_LIB.T6G(SCH_1):GND    I11 @T6G_MB_LIB.T6G(SCH_1):PAGE324

R4074 Q_RES_0402LF-10K,1%,1/16W,CHIP,CS31002FB08
     1 P12V_AUX @T6G_MB_LIB.T6G(SCH_1):P12V_AUX    I25 @T6G_MB_LIB.T6G(SCH_1):PAGE324
     2 P12V_E1S_0_EN_G @T6G_MB_LIB.T6G(SCH_1):P12V_E1S_0_EN_G    I25 @T6G_MB_LIB.T6G(SCH_1):PAGE324

R4075 Q_RES_0402LF-0,5%,1/16W,CHIP,CS00002JB13
     1 CLK_GEN2_BMC_RC_OE_N @T6G_MB_LIB.T6G(SCH_1):CLK_GEN2_BMC_RC_OE_N    I22 @T6G_MB_LIB.T6G(SCH_1):PAGE232
     2 CLK_GEN2_BMC_RC_OE_R3_N @T6G_MB_LIB.T6G(SCH_1):CLK_GEN2_BMC_RC_OE_R3_N    I22 @T6G_MB_LIB.T6G(SCH_1):PAGE232

R4076 Q_RES_0402LF-0,5%,1/16W,CHIP,CS00002JB13
     1 CLK_GEN2_GPU_FPGA_OE_OR_N @T6G_MB_LIB.T6G(SCH_1):CLK_GEN2_GPU_FPGA_OE_OR_N    I16 @T6G_MB_LIB.T6G(SCH_1):PAGE232
     2 CLK_GEN2_GPU_OE_N @T6G_MB_LIB.T6G(SCH_1):CLK_GEN2_GPU_OE_N    I16 @T6G_MB_LIB.T6G(SCH_1):PAGE232

R4077 Q_RES_0402LF-1,1%,1/16W,CHIP,CS-1002FB04
     1 VFG3P3_CLK_GEN @T6G_MB_LIB.T6G(SCH_1):VFG3P3_CLK_GEN    I43 @T6G_MB_LIB.T6G(SCH_1):PAGE232
     2 VFG_3P3A_CLK_GEN @T6G_MB_LIB.T6G(SCH_1):VFG_3P3A_CLK_GEN    I43 @T6G_MB_LIB.T6G(SCH_1):PAGE232

R4078 Q_RES_0402LF-10K,1%,1/16W,EMPTY,CS31002FB08
     1 P3V3_AUX @T6G_MB_LIB.T6G(SCH_1):P3V3_AUX    I47 @T6G_MB_LIB.T6G(SCH_1):PAGE232
     2 FG_SS_EN @T6G_MB_LIB.T6G(SCH_1):FG_SS_EN    I47 @T6G_MB_LIB.T6G(SCH_1):PAGE232

R4079 Q_RES_0402LF-10K,1%,1/16W,CHIP,CS31002FB08
     1 FG_SS_EN @T6G_MB_LIB.T6G(SCH_1):FG_SS_EN    I46 @T6G_MB_LIB.T6G(SCH_1):PAGE232
     2    GND @T6G_MB_LIB.T6G(SCH_1):GND    I46 @T6G_MB_LIB.T6G(SCH_1):PAGE232

R4080 Q_RES_0402LF-10K,1%,1/16W,CHIP,CS31002FB08
     1 P3V3_AUX @T6G_MB_LIB.T6G(SCH_1):P3V3_AUX    I59 @T6G_MB_LIB.T6G(SCH_1):PAGE232
     2 P3V3_PWRGD_CLKGEN @T6G_MB_LIB.T6G(SCH_1):P3V3_PWRGD_CLKGEN    I59 @T6G_MB_LIB.T6G(SCH_1):PAGE232

R4081 Q_RES_0402LF-10K,1%,1/16W,CHIP,CS31002FB08
     1 P3V3_AUX @T6G_MB_LIB.T6G(SCH_1):P3V3_AUX    I56 @T6G_MB_LIB.T6G(SCH_1):PAGE232
     2 CLK_GEN2_SMB_SADR @T6G_MB_LIB.T6G(SCH_1):CLK_GEN2_SMB_SADR    I56 @T6G_MB_LIB.T6G(SCH_1):PAGE232

R4082 Q_RES_0402LF-10K,1%,1/16W,EMPTY,CS31002FB08
     1 CLK_GEN2_SMB_SADR @T6G_MB_LIB.T6G(SCH_1):CLK_GEN2_SMB_SADR    I55 @T6G_MB_LIB.T6G(SCH_1):PAGE232
     2    GND @T6G_MB_LIB.T6G(SCH_1):GND    I55 @T6G_MB_LIB.T6G(SCH_1):PAGE232

R4087 Q_RES_0402LF-0,5%,1/16W,CHIP,CS00002JB13
     1 FW_RECOVERY_R @T6G_MB_LIB.T6G(SCH_1):FW_RECOVERY_R    I31 @T6G_MB_LIB.T6G(SCH_1):PAGE348
     2 FW_RECOVERY @T6G_MB_LIB.T6G(SCH_1):FW_RECOVERY    I31 @T6G_MB_LIB.T6G(SCH_1):PAGE348

R4090 Q_RES_0402LF-1K,1%,1/16W,CHIP,CS21002FB06
     1 P3V3_AUX @T6G_MB_LIB.T6G(SCH_1):P3V3_AUX   I124 @T6G_MB_LIB.T6G(SCH_1):PAGE360
     2 M2_0_P3V3_ADC_ALERT_R @T6G_MB_LIB.T6G(SCH_1):M2_0_P3V3_ADC_ALERT_R   I124 @T6G_MB_LIB.T6G(SCH_1):PAGE360

R4091 Q_RES_0402LF-1K,1%,1/16W,CHIP,CS21002FB06
     1 P3V3_AUX @T6G_MB_LIB.T6G(SCH_1):P3V3_AUX   I122 @T6G_MB_LIB.T6G(SCH_1):PAGE360
     2 P12V_SCM_ADC_ALERT_R @T6G_MB_LIB.T6G(SCH_1):P12V_SCM_ADC_ALERT_R   I122 @T6G_MB_LIB.T6G(SCH_1):PAGE360

R4092 Q_RES_0402LF-1K,1%,1/16W,CHIP,CS21002FB06
     1 P3V3_AUX @T6G_MB_LIB.T6G(SCH_1):P3V3_AUX   I126 @T6G_MB_LIB.T6G(SCH_1):PAGE360
     2 OCP_V3_2_P3V3_ADC_ALERT_R @T6G_MB_LIB.T6G(SCH_1):OCP_V3_2_P3V3_ADC_ALERT_R   I126 @T6G_MB_LIB.T6G(SCH_1):PAGE360

R4093 Q_RES_0402LF-1K,1%,1/16W,CHIP,CS21002FB06
     1 P3V3_AUX @T6G_MB_LIB.T6G(SCH_1):P3V3_AUX   I149 @T6G_MB_LIB.T6G(SCH_1):PAGE295
     2 E1S_0_P3V3_ADC_ALERT_R @T6G_MB_LIB.T6G(SCH_1):E1S_0_P3V3_ADC_ALERT_R   I149 @T6G_MB_LIB.T6G(SCH_1):PAGE295

R4094 Q_RES_0402LF-1K,1%,1/16W,CHIP,CS21002FB06
     1 P3V3_AUX @T6G_MB_LIB.T6G(SCH_1):P3V3_AUX   I151 @T6G_MB_LIB.T6G(SCH_1):PAGE295
     2 OCP_SFF_P3V3_ADC_ALERT_R @T6G_MB_LIB.T6G(SCH_1):OCP_SFF_P3V3_ADC_ALERT_R   I151 @T6G_MB_LIB.T6G(SCH_1):PAGE295

R4119 Q_RES_0402LF-54.9K,1%,1/16W,EMPTY,CS35492FB03
     1 P3V3_AUX @T6G_MB_LIB.T6G(SCH_1):P3V3_AUX    I23 @T6G_MB_LIB.T6G(SCH_1):PAGE332
     2 GPU_3V3IO_RSVD0_FFU @T6G_MB_LIB.T6G(SCH_1):GPU_3V3IO_RSVD0_FFU    I23 @T6G_MB_LIB.T6G(SCH_1):PAGE332

R4120 Q_RES_0402LF-100K,1%,1/16W,EMPTY,CS41002FB09
     1 GPU_3V3IO_RSVD0_FFU @T6G_MB_LIB.T6G(SCH_1):GPU_3V3IO_RSVD0_FFU    I22 @T6G_MB_LIB.T6G(SCH_1):PAGE332
     2    GND @T6G_MB_LIB.T6G(SCH_1):GND    I22 @T6G_MB_LIB.T6G(SCH_1):PAGE332

R4121 Q_RES_0402LF-10K,1%,1/16W,CHIP,CS31002FB08
     1 P3V3_AUX @T6G_MB_LIB.T6G(SCH_1):P3V3_AUX    I14 @T6G_MB_LIB.T6G(SCH_1):PAGE332
     2 PRSNT_CABLE_GPU_B3_N @T6G_MB_LIB.T6G(SCH_1):PRSNT_CABLE_GPU_B3_N    I14 @T6G_MB_LIB.T6G(SCH_1):PAGE332

R4122 Q_RES_0402LF-100K,1%,1/16W,EMPTY,CS41002FB09
     1 PRSNT_CABLE_GPU_B3_N @T6G_MB_LIB.T6G(SCH_1):PRSNT_CABLE_GPU_B3_N    I13 @T6G_MB_LIB.T6G(SCH_1):PAGE332
     2    GND @T6G_MB_LIB.T6G(SCH_1):GND    I13 @T6G_MB_LIB.T6G(SCH_1):PAGE332

R4123 Q_RES_0402LF-54.9K,1%,1/16W,EMPTY,CS35492FB03
     1 P3V3_AUX @T6G_MB_LIB.T6G(SCH_1):P3V3_AUX    I18 @T6G_MB_LIB.T6G(SCH_1):PAGE332
     2 GPU_3V3IO_RSVD1_FFU @T6G_MB_LIB.T6G(SCH_1):GPU_3V3IO_RSVD1_FFU    I18 @T6G_MB_LIB.T6G(SCH_1):PAGE332

R4124 Q_RES_0402LF-100K,1%,1/16W,EMPTY,CS41002FB09
     1 GPU_3V3IO_RSVD1_FFU @T6G_MB_LIB.T6G(SCH_1):GPU_3V3IO_RSVD1_FFU   I135 @T6G_MB_LIB.T6G(SCH_1):PAGE332
     2    GND @T6G_MB_LIB.T6G(SCH_1):GND   I135 @T6G_MB_LIB.T6G(SCH_1):PAGE332

R4125 Q_RES_0402LF-4.7K,5%,1/16W,CHIP,CS24702JB10
     1 P3V3_AUX @T6G_MB_LIB.T6G(SCH_1):P3V3_AUX    I39 @T6G_MB_LIB.T6G(SCH_1):PAGE332
     2 GPU_3V3IO_RSVD0_FFU_N @T6G_MB_LIB.T6G(SCH_1):GPU_3V3IO_RSVD0_FFU_N    I39 @T6G_MB_LIB.T6G(SCH_1):PAGE332

R4126 Q_RES_0402LF-4.7K,5%,1/16W,CHIP,CS24702JB10
     1 P3V3_AUX @T6G_MB_LIB.T6G(SCH_1):P3V3_AUX    I27 @T6G_MB_LIB.T6G(SCH_1):PAGE332
     2 PRSNT_CABLE_GPU_B3 @T6G_MB_LIB.T6G(SCH_1):PRSNT_CABLE_GPU_B3    I27 @T6G_MB_LIB.T6G(SCH_1):PAGE332

R4127 Q_RES_0402LF-4.7K,5%,1/16W,CHIP,CS24702JB10
     1 P3V3_AUX @T6G_MB_LIB.T6G(SCH_1):P3V3_AUX    I35 @T6G_MB_LIB.T6G(SCH_1):PAGE332
     2 GPU_3V3IO_RSVD1_FFU_N @T6G_MB_LIB.T6G(SCH_1):GPU_3V3IO_RSVD1_FFU_N    I35 @T6G_MB_LIB.T6G(SCH_1):PAGE332

R4128 Q_RES_0402LF-100K,1%,1/16W,CHIP,CS41002FB09
     1 P3V3_AUX @T6G_MB_LIB.T6G(SCH_1):P3V3_AUX   I104 @T6G_MB_LIB.T6G(SCH_1):PAGE332
     2 GPU_3V3IO_RSVD0_FFU_ISO @T6G_MB_LIB.T6G(SCH_1):GPU_3V3IO_RSVD0_FFU_ISO   I104 @T6G_MB_LIB.T6G(SCH_1):PAGE332

R4129 Q_RES_0402LF-100K,1%,1/16W,CHIP,CS41002FB09
     1 P3V3_AUX @T6G_MB_LIB.T6G(SCH_1):P3V3_AUX    I66 @T6G_MB_LIB.T6G(SCH_1):PAGE332
     2 PRSNT_CABLE_GPU_B3_ISO_N @T6G_MB_LIB.T6G(SCH_1):PRSNT_CABLE_GPU_B3_ISO_N    I66 @T6G_MB_LIB.T6G(SCH_1):PAGE332

R4130 Q_RES_0402LF-100K,1%,1/16W,CHIP,CS41002FB09
     1 P3V3_AUX @T6G_MB_LIB.T6G(SCH_1):P3V3_AUX    I70 @T6G_MB_LIB.T6G(SCH_1):PAGE332
     2 GPU_3V3IO_RSVD1_FFU_ISO @T6G_MB_LIB.T6G(SCH_1):GPU_3V3IO_RSVD1_FFU_ISO    I70 @T6G_MB_LIB.T6G(SCH_1):PAGE332

R4131 Q_RES_0402LF-54.9K,1%,1/16W,EMPTY,CS35492FB03
     1 P3V3_AUX @T6G_MB_LIB.T6G(SCH_1):P3V3_AUX    I97 @T6G_MB_LIB.T6G(SCH_1):PAGE332
     2 GPU_3V3IO_RSVD3_FFU @T6G_MB_LIB.T6G(SCH_1):GPU_3V3IO_RSVD3_FFU    I97 @T6G_MB_LIB.T6G(SCH_1):PAGE332

R4132 Q_RES_0402LF-100K,1%,1/16W,EMPTY,CS41002FB09
     1 GPU_3V3IO_RSVD3_FFU @T6G_MB_LIB.T6G(SCH_1):GPU_3V3IO_RSVD3_FFU    I96 @T6G_MB_LIB.T6G(SCH_1):PAGE332
     2    GND @T6G_MB_LIB.T6G(SCH_1):GND    I96 @T6G_MB_LIB.T6G(SCH_1):PAGE332

R4133 Q_RES_0402LF-54.9K,1%,1/16W,EMPTY,CS35492FB03
     1 P3V3_AUX @T6G_MB_LIB.T6G(SCH_1):P3V3_AUX    I82 @T6G_MB_LIB.T6G(SCH_1):PAGE332
     2 GPU_3V3IO_RSVD5_FFU @T6G_MB_LIB.T6G(SCH_1):GPU_3V3IO_RSVD5_FFU    I82 @T6G_MB_LIB.T6G(SCH_1):PAGE332

R4134 Q_RES_0402LF-100K,1%,1/16W,EMPTY,CS41002FB09
     1 GPU_3V3IO_RSVD5_FFU @T6G_MB_LIB.T6G(SCH_1):GPU_3V3IO_RSVD5_FFU    I81 @T6G_MB_LIB.T6G(SCH_1):PAGE332
     2    GND @T6G_MB_LIB.T6G(SCH_1):GND    I81 @T6G_MB_LIB.T6G(SCH_1):PAGE332

R4135 Q_RES_0402LF-10K,1%,1/16W,CHIP,CS31002FB08
     1 P3V3_AUX @T6G_MB_LIB.T6G(SCH_1):P3V3_AUX    I93 @T6G_MB_LIB.T6G(SCH_1):PAGE332
     2 PRSNT_CABLE_GPU_A2_N @T6G_MB_LIB.T6G(SCH_1):PRSNT_CABLE_GPU_A2_N    I93 @T6G_MB_LIB.T6G(SCH_1):PAGE332

R4136 Q_RES_0402LF-100K,1%,1/16W,EMPTY,CS41002FB09
     1 PRSNT_CABLE_GPU_A2_N @T6G_MB_LIB.T6G(SCH_1):PRSNT_CABLE_GPU_A2_N    I92 @T6G_MB_LIB.T6G(SCH_1):PAGE332
     2    GND @T6G_MB_LIB.T6G(SCH_1):GND    I92 @T6G_MB_LIB.T6G(SCH_1):PAGE332

R4137 Q_RES_0402LF-4.7K,5%,1/16W,CHIP,CS24702JB10
     1 P3V3_AUX @T6G_MB_LIB.T6G(SCH_1):P3V3_AUX   I107 @T6G_MB_LIB.T6G(SCH_1):PAGE332
     2 GPU_3V3IO_RSVD3_FFU_N @T6G_MB_LIB.T6G(SCH_1):GPU_3V3IO_RSVD3_FFU_N   I107 @T6G_MB_LIB.T6G(SCH_1):PAGE332

R4138 Q_RES_0402LF-4.7K,5%,1/16W,CHIP,CS24702JB10
     1 P3V3_AUX @T6G_MB_LIB.T6G(SCH_1):P3V3_AUX    I88 @T6G_MB_LIB.T6G(SCH_1):PAGE332
     2 GPU_3V3IO_RSVD5_FFU_N @T6G_MB_LIB.T6G(SCH_1):GPU_3V3IO_RSVD5_FFU_N    I88 @T6G_MB_LIB.T6G(SCH_1):PAGE332

R4139 Q_RES_0402LF-4.7K,5%,1/16W,CHIP,CS24702JB10
     1 P3V3_AUX @T6G_MB_LIB.T6G(SCH_1):P3V3_AUX    I99 @T6G_MB_LIB.T6G(SCH_1):PAGE332
     2 PRSNT_CABLE_GPU_A2 @T6G_MB_LIB.T6G(SCH_1):PRSNT_CABLE_GPU_A2    I99 @T6G_MB_LIB.T6G(SCH_1):PAGE332

R4140 Q_RES_0402LF-100K,1%,1/16W,CHIP,CS41002FB09
     1 P3V3_AUX @T6G_MB_LIB.T6G(SCH_1):P3V3_AUX   I131 @T6G_MB_LIB.T6G(SCH_1):PAGE332
     2 GPU_3V3IO_RSVD3_FFU_ISO @T6G_MB_LIB.T6G(SCH_1):GPU_3V3IO_RSVD3_FFU_ISO   I131 @T6G_MB_LIB.T6G(SCH_1):PAGE332

R4141 Q_RES_0402LF-100K,1%,1/16W,CHIP,CS41002FB09
     1 P3V3_AUX @T6G_MB_LIB.T6G(SCH_1):P3V3_AUX   I114 @T6G_MB_LIB.T6G(SCH_1):PAGE332
     2 GPU_3V3IO_RSVD5_FFU_ISO @T6G_MB_LIB.T6G(SCH_1):GPU_3V3IO_RSVD5_FFU_ISO   I114 @T6G_MB_LIB.T6G(SCH_1):PAGE332

R4142 Q_RES_0402LF-100K,1%,1/16W,CHIP,CS41002FB09
     1 P3V3_AUX @T6G_MB_LIB.T6G(SCH_1):P3V3_AUX   I122 @T6G_MB_LIB.T6G(SCH_1):PAGE332
     2 PRSNT_CABLE_GPU_A2_ISO_N @T6G_MB_LIB.T6G(SCH_1):PRSNT_CABLE_GPU_A2_ISO_N   I122 @T6G_MB_LIB.T6G(SCH_1):PAGE332

R4143 Q_RES_0402LF-33.2,1%,1/16W,CHIP,CS03322FB03
     1 GPU_3V3IO_RSVD0_FFU_ISO_R @T6G_MB_LIB.T6G(SCH_1):GPU_3V3IO_RSVD0_FFU_ISO_R   I231 @T6G_MB_LIB.T6G(SCH_1):PAGE80
     2 GPU_3V3IO_RSVD0_FFU_ISO @T6G_MB_LIB.T6G(SCH_1):GPU_3V3IO_RSVD0_FFU_ISO   I231 @T6G_MB_LIB.T6G(SCH_1):PAGE80

R4144 Q_RES_0402LF-33.2,1%,1/16W,CHIP,CS03322FB03
     1 GPU_3V3IO_RSVD1_FFU_ISO_R @T6G_MB_LIB.T6G(SCH_1):GPU_3V3IO_RSVD1_FFU_ISO_R   I233 @T6G_MB_LIB.T6G(SCH_1):PAGE80
     2 GPU_3V3IO_RSVD1_FFU_ISO @T6G_MB_LIB.T6G(SCH_1):GPU_3V3IO_RSVD1_FFU_ISO   I233 @T6G_MB_LIB.T6G(SCH_1):PAGE80

R4145 Q_RES_0402LF-33.2,1%,1/16W,CHIP,CS03322FB03
     1 PRSNT_CABLE_GPU_B3_ISO_R_N @T6G_MB_LIB.T6G(SCH_1):PRSNT_CABLE_GPU_B3_ISO_R_N   I121 @T6G_MB_LIB.T6G(SCH_1):PAGE79
     2 PRSNT_CABLE_GPU_B3_ISO_N @T6G_MB_LIB.T6G(SCH_1):PRSNT_CABLE_GPU_B3_ISO_N   I121 @T6G_MB_LIB.T6G(SCH_1):PAGE79

R4146 Q_RES_0402LF-33.2,1%,1/16W,CHIP,CS03322FB03
     1 GPU_3V3IO_RSVD3_FFU_ISO_R @T6G_MB_LIB.T6G(SCH_1):GPU_3V3IO_RSVD3_FFU_ISO_R   I122 @T6G_MB_LIB.T6G(SCH_1):PAGE79
     2 GPU_3V3IO_RSVD3_FFU_ISO @T6G_MB_LIB.T6G(SCH_1):GPU_3V3IO_RSVD3_FFU_ISO   I122 @T6G_MB_LIB.T6G(SCH_1):PAGE79

R4147 Q_RES_0402LF-33.2,1%,1/16W,CHIP,CS03322FB03
     1 PRSNT_CABLE_GPU_A2_ISO_R_N @T6G_MB_LIB.T6G(SCH_1):PRSNT_CABLE_GPU_A2_ISO_R_N   I240 @T6G_MB_LIB.T6G(SCH_1):PAGE80
     2 PRSNT_CABLE_GPU_A2_ISO_N @T6G_MB_LIB.T6G(SCH_1):PRSNT_CABLE_GPU_A2_ISO_N   I240 @T6G_MB_LIB.T6G(SCH_1):PAGE80

R4148 Q_RES_0402LF-33.2,1%,1/16W,CHIP,CS03322FB03
     1 GPU_3V3IO_RSVD5_FFU_ISO_R @T6G_MB_LIB.T6G(SCH_1):GPU_3V3IO_RSVD5_FFU_ISO_R   I242 @T6G_MB_LIB.T6G(SCH_1):PAGE80
     2 GPU_3V3IO_RSVD5_FFU_ISO @T6G_MB_LIB.T6G(SCH_1):GPU_3V3IO_RSVD5_FFU_ISO   I242 @T6G_MB_LIB.T6G(SCH_1):PAGE80

R4149 Q_RES_0402LF-33.2,1%,1/16W,CHIP,CS03322FB03
     1 SMB_1_PLD_3V3AUX_SCL @T6G_MB_LIB.T6G(SCH_1):SMB_1_PLD_3V3AUX_SCL    I89 @T6G_MB_LIB.T6G(SCH_1):PAGE349
     2 SMB_1_PLD_3V3AUX_SCL_R1 @T6G_MB_LIB.T6G(SCH_1):SMB_1_PLD_3V3AUX_SCL_R1    I89 @T6G_MB_LIB.T6G(SCH_1):PAGE349

R4150 Q_RES_0402LF-33.2,1%,1/16W,CHIP,CS03322FB03
     1 SMB_1_PLD_3V3AUX_SDA @T6G_MB_LIB.T6G(SCH_1):SMB_1_PLD_3V3AUX_SDA    I90 @T6G_MB_LIB.T6G(SCH_1):PAGE349
     2 SMB_1_PLD_3V3AUX_SDA_R1 @T6G_MB_LIB.T6G(SCH_1):SMB_1_PLD_3V3AUX_SDA_R1    I90 @T6G_MB_LIB.T6G(SCH_1):PAGE349

R4151 Q_RES_0402LF-33.2,1%,1/16W,CHIP,CS03322FB03
     1 SMB_1_PLD_3V3AUX_SCL @T6G_MB_LIB.T6G(SCH_1):SMB_1_PLD_3V3AUX_SCL    I83 @T6G_MB_LIB.T6G(SCH_1):PAGE349
     2 SMB_2_PLD_3V3AUX_SCL_R1 @T6G_MB_LIB.T6G(SCH_1):SMB_2_PLD_3V3AUX_SCL_R1    I83 @T6G_MB_LIB.T6G(SCH_1):PAGE349

R4152 Q_RES_0402LF-33.2,1%,1/16W,CHIP,CS03322FB03
     1 SMB_1_PLD_3V3AUX_SDA @T6G_MB_LIB.T6G(SCH_1):SMB_1_PLD_3V3AUX_SDA    I84 @T6G_MB_LIB.T6G(SCH_1):PAGE349
     2 SMB_2_PLD_3V3AUX_SDA_R1 @T6G_MB_LIB.T6G(SCH_1):SMB_2_PLD_3V3AUX_SDA_R1    I84 @T6G_MB_LIB.T6G(SCH_1):PAGE349

R4153 Q_RES_0402LF-10K,1%,1/16W,CHIP,CS31002FB08
     1 P3V3_AUX @T6G_MB_LIB.T6G(SCH_1):P3V3_AUX     I4 @T6G_MB_LIB.T6G(SCH_1):PAGE332
     2 PRSNT_CABLE_GPU_A1_N @T6G_MB_LIB.T6G(SCH_1):PRSNT_CABLE_GPU_A1_N     I4 @T6G_MB_LIB.T6G(SCH_1):PAGE332

R4154 Q_RES_0402LF-100K,1%,1/16W,EMPTY,CS41002FB09
     1 PRSNT_CABLE_GPU_A1_N @T6G_MB_LIB.T6G(SCH_1):PRSNT_CABLE_GPU_A1_N     I2 @T6G_MB_LIB.T6G(SCH_1):PAGE332
     2    GND @T6G_MB_LIB.T6G(SCH_1):GND     I2 @T6G_MB_LIB.T6G(SCH_1):PAGE332

R4155 Q_RES_0402LF-4.7K,5%,1/16W,CHIP,CS24702JB10
     1 P3V3_AUX @T6G_MB_LIB.T6G(SCH_1):P3V3_AUX     I8 @T6G_MB_LIB.T6G(SCH_1):PAGE332
     2 PRSNT_CABLE_GPU_A1 @T6G_MB_LIB.T6G(SCH_1):PRSNT_CABLE_GPU_A1     I8 @T6G_MB_LIB.T6G(SCH_1):PAGE332

R4156 Q_RES_0402LF-100K,1%,1/16W,CHIP,CS41002FB09
     1 P3V3_AUX @T6G_MB_LIB.T6G(SCH_1):P3V3_AUX    I48 @T6G_MB_LIB.T6G(SCH_1):PAGE332
     2 PRSNT_CABLE_GPU_A1_ISO_N @T6G_MB_LIB.T6G(SCH_1):PRSNT_CABLE_GPU_A1_ISO_N    I48 @T6G_MB_LIB.T6G(SCH_1):PAGE332

R4157 Q_RES_0402LF-33.2,1%,1/16W,CHIP,CS03322FB03
     1 PRSNT_CABLE_GPU_A1_ISO_R_N @T6G_MB_LIB.T6G(SCH_1):PRSNT_CABLE_GPU_A1_ISO_R_N   I246 @T6G_MB_LIB.T6G(SCH_1):PAGE80
     2 PRSNT_CABLE_GPU_A1_ISO_N @T6G_MB_LIB.T6G(SCH_1):PRSNT_CABLE_GPU_A1_ISO_N   I246 @T6G_MB_LIB.T6G(SCH_1):PAGE80

R4158 Q_RES_0402LF-54.9K,1%,1/16W,EMPTY,CS35492FB03
     1 P3V3_AUX @T6G_MB_LIB.T6G(SCH_1):P3V3_AUX    I14 @T6G_MB_LIB.T6G(SCH_1):PAGE331
     2 GPU_3V3IO_RSVD1 @T6G_MB_LIB.T6G(SCH_1):GPU_3V3IO_RSVD1    I14 @T6G_MB_LIB.T6G(SCH_1):PAGE331

R4159 Q_RES_0402LF-100K,1%,1/16W,EMPTY,CS41002FB09
     1 GPU_3V3IO_RSVD1 @T6G_MB_LIB.T6G(SCH_1):GPU_3V3IO_RSVD1    I13 @T6G_MB_LIB.T6G(SCH_1):PAGE331
     2    GND @T6G_MB_LIB.T6G(SCH_1):GND    I13 @T6G_MB_LIB.T6G(SCH_1):PAGE331

R4160 Q_RES_0402LF-54.9K,1%,1/16W,EMPTY,CS35492FB03
     1 P3V3_AUX @T6G_MB_LIB.T6G(SCH_1):P3V3_AUX     I4 @T6G_MB_LIB.T6G(SCH_1):PAGE331
     2 GPU_3V3IO_RSVD4 @T6G_MB_LIB.T6G(SCH_1):GPU_3V3IO_RSVD4     I4 @T6G_MB_LIB.T6G(SCH_1):PAGE331

R4161 Q_RES_0402LF-100K,1%,1/16W,EMPTY,CS41002FB09
     1 GPU_3V3IO_RSVD4 @T6G_MB_LIB.T6G(SCH_1):GPU_3V3IO_RSVD4     I2 @T6G_MB_LIB.T6G(SCH_1):PAGE331
     2    GND @T6G_MB_LIB.T6G(SCH_1):GND     I2 @T6G_MB_LIB.T6G(SCH_1):PAGE331

R4162 Q_RES_0402LF-54.9K,1%,1/16W,EMPTY,CS35492FB03
     1 P3V3_AUX @T6G_MB_LIB.T6G(SCH_1):P3V3_AUX     I9 @T6G_MB_LIB.T6G(SCH_1):PAGE331
     2 GPU_3V3IO_RSVD3 @T6G_MB_LIB.T6G(SCH_1):GPU_3V3IO_RSVD3     I9 @T6G_MB_LIB.T6G(SCH_1):PAGE331

R4163 Q_RES_0402LF-100K,1%,1/16W,EMPTY,CS41002FB09
     1 GPU_3V3IO_RSVD3 @T6G_MB_LIB.T6G(SCH_1):GPU_3V3IO_RSVD3     I8 @T6G_MB_LIB.T6G(SCH_1):PAGE331
     2    GND @T6G_MB_LIB.T6G(SCH_1):GND     I8 @T6G_MB_LIB.T6G(SCH_1):PAGE331

R4164 Q_RES_0402LF-4.7K,5%,1/16W,CHIP,CS24702JB10
     1 P3V3_AUX @T6G_MB_LIB.T6G(SCH_1):P3V3_AUX    I27 @T6G_MB_LIB.T6G(SCH_1):PAGE331
     2 GPU_3V3IO_RSVD1_N @T6G_MB_LIB.T6G(SCH_1):GPU_3V3IO_RSVD1_N    I27 @T6G_MB_LIB.T6G(SCH_1):PAGE331

R4165 Q_RES_0402LF-4.7K,5%,1/16W,CHIP,CS24702JB10
     1 P3V3_AUX @T6G_MB_LIB.T6G(SCH_1):P3V3_AUX    I18 @T6G_MB_LIB.T6G(SCH_1):PAGE331
     2 GPU_3V3IO_RSVD4_N @T6G_MB_LIB.T6G(SCH_1):GPU_3V3IO_RSVD4_N    I18 @T6G_MB_LIB.T6G(SCH_1):PAGE331

R4166 Q_RES_0402LF-4.7K,5%,1/16W,CHIP,CS24702JB10
     1 P3V3_AUX @T6G_MB_LIB.T6G(SCH_1):P3V3_AUX    I23 @T6G_MB_LIB.T6G(SCH_1):PAGE331
     2 GPU_3V3IO_RSVD3_N @T6G_MB_LIB.T6G(SCH_1):GPU_3V3IO_RSVD3_N    I23 @T6G_MB_LIB.T6G(SCH_1):PAGE331

R4167 Q_RES_0402LF-100K,1%,1/16W,CHIP,CS41002FB09
     1 P3V3_AUX @T6G_MB_LIB.T6G(SCH_1):P3V3_AUX    I47 @T6G_MB_LIB.T6G(SCH_1):PAGE331
     2 GPU_3V3IO_RSVD1_ISO @T6G_MB_LIB.T6G(SCH_1):GPU_3V3IO_RSVD1_ISO    I47 @T6G_MB_LIB.T6G(SCH_1):PAGE331

R4168 Q_RES_0402LF-100K,1%,1/16W,CHIP,CS41002FB09
     1 P3V3_AUX @T6G_MB_LIB.T6G(SCH_1):P3V3_AUX    I35 @T6G_MB_LIB.T6G(SCH_1):PAGE331
     2 GPU_3V3IO_RSVD4_ISO @T6G_MB_LIB.T6G(SCH_1):GPU_3V3IO_RSVD4_ISO    I35 @T6G_MB_LIB.T6G(SCH_1):PAGE331

R4169 Q_RES_0402LF-100K,1%,1/16W,CHIP,CS41002FB09
     1 P3V3_AUX @T6G_MB_LIB.T6G(SCH_1):P3V3_AUX    I39 @T6G_MB_LIB.T6G(SCH_1):PAGE331
     2 GPU_3V3IO_RSVD3_ISO @T6G_MB_LIB.T6G(SCH_1):GPU_3V3IO_RSVD3_ISO    I39 @T6G_MB_LIB.T6G(SCH_1):PAGE331

R4170 Q_RES_0402LF-33.2,1%,1/16W,CHIP,CS03322FB03
     1 GPU_3V3IO_RSVD1_ISO_R @T6G_MB_LIB.T6G(SCH_1):GPU_3V3IO_RSVD1_ISO_R   I220 @T6G_MB_LIB.T6G(SCH_1):PAGE80
     2 GPU_3V3IO_RSVD1_ISO @T6G_MB_LIB.T6G(SCH_1):GPU_3V3IO_RSVD1_ISO   I220 @T6G_MB_LIB.T6G(SCH_1):PAGE80

R4171 Q_RES_0402LF-33.2,1%,1/16W,CHIP,CS03322FB03
     1 GPU_3V3IO_RSVD3_ISO_R @T6G_MB_LIB.T6G(SCH_1):GPU_3V3IO_RSVD3_ISO_R   I223 @T6G_MB_LIB.T6G(SCH_1):PAGE80
     2 GPU_3V3IO_RSVD3_ISO @T6G_MB_LIB.T6G(SCH_1):GPU_3V3IO_RSVD3_ISO   I223 @T6G_MB_LIB.T6G(SCH_1):PAGE80

R4172 Q_RES_0402LF-33.2,1%,1/16W,CHIP,CS03322FB03
     1 GPU_3V3IO_RSVD4_ISO_R @T6G_MB_LIB.T6G(SCH_1):GPU_3V3IO_RSVD4_ISO_R   I224 @T6G_MB_LIB.T6G(SCH_1):PAGE80
     2 GPU_3V3IO_RSVD4_ISO @T6G_MB_LIB.T6G(SCH_1):GPU_3V3IO_RSVD4_ISO   I224 @T6G_MB_LIB.T6G(SCH_1):PAGE80

R4173 Q_RES_0402LF-100K,1%,1/16W,EMPTY,CS41002FB09
     1 P3V3_AUX @T6G_MB_LIB.T6G(SCH_1):P3V3_AUX   I204 @T6G_MB_LIB.T6G(SCH_1):PAGE256
     2 UART_BMC_BIC_R_BUF_RX @T6G_MB_LIB.T6G(SCH_1):UART_BMC_BIC_R_BUF_RX   I204 @T6G_MB_LIB.T6G(SCH_1):PAGE256

R4178 Q_RES_0402LF-33.2,1%,1/16W,CHIP,CS03322FB03
     1 SMB_LM75_2_3V3AUX_SCL @T6G_MB_LIB.T6G(SCH_1):SMB_LM75_2_3V3AUX_SCL   I114 @T6G_MB_LIB.T6G(SCH_1):PAGE359
     2 SMB_LM75_2_3V3AUX_SCL_R1 @T6G_MB_LIB.T6G(SCH_1):SMB_LM75_2_3V3AUX_SCL_R1   I114 @T6G_MB_LIB.T6G(SCH_1):PAGE359

R4179 Q_RES_0402LF-33.2,1%,1/16W,CHIP,CS03322FB03
     1 SMB_LM75_1_3V3AUX_SCL @T6G_MB_LIB.T6G(SCH_1):SMB_LM75_1_3V3AUX_SCL   I109 @T6G_MB_LIB.T6G(SCH_1):PAGE359
     2 SMB_LM75_1_3V3AUX_SCL_R1 @T6G_MB_LIB.T6G(SCH_1):SMB_LM75_1_3V3AUX_SCL_R1   I109 @T6G_MB_LIB.T6G(SCH_1):PAGE359

R4180 Q_RES_0402LF-33.2,1%,1/16W,CHIP,CS03322FB03
     1 SMB_LM75_0_3V3AUX_SCL @T6G_MB_LIB.T6G(SCH_1):SMB_LM75_0_3V3AUX_SCL    I77 @T6G_MB_LIB.T6G(SCH_1):PAGE359
     2 SMB_LM75_0_3V3AUX_SCL_R1 @T6G_MB_LIB.T6G(SCH_1):SMB_LM75_0_3V3AUX_SCL_R1    I77 @T6G_MB_LIB.T6G(SCH_1):PAGE359

R4181 Q_RES_0402LF-33.2,1%,1/16W,CHIP,CS03322FB03
     1 SMB_LM75_2_3V3AUX_SDA @T6G_MB_LIB.T6G(SCH_1):SMB_LM75_2_3V3AUX_SDA   I116 @T6G_MB_LIB.T6G(SCH_1):PAGE359
     2 SMB_LM75_2_3V3AUX_SDA_R1 @T6G_MB_LIB.T6G(SCH_1):SMB_LM75_2_3V3AUX_SDA_R1   I116 @T6G_MB_LIB.T6G(SCH_1):PAGE359

R4182 Q_RES_0402LF-33.2,1%,1/16W,CHIP,CS03322FB03
     1 SMB_LM75_1_3V3AUX_SDA @T6G_MB_LIB.T6G(SCH_1):SMB_LM75_1_3V3AUX_SDA   I107 @T6G_MB_LIB.T6G(SCH_1):PAGE359
     2 SMB_LM75_1_3V3AUX_SDA_R1 @T6G_MB_LIB.T6G(SCH_1):SMB_LM75_1_3V3AUX_SDA_R1   I107 @T6G_MB_LIB.T6G(SCH_1):PAGE359

R4183 Q_RES_0402LF-33.2,1%,1/16W,CHIP,CS03322FB03
     1 SMB_LM75_0_3V3AUX_SDA @T6G_MB_LIB.T6G(SCH_1):SMB_LM75_0_3V3AUX_SDA    I78 @T6G_MB_LIB.T6G(SCH_1):PAGE359
     2 SMB_LM75_0_3V3AUX_SDA_R1 @T6G_MB_LIB.T6G(SCH_1):SMB_LM75_0_3V3AUX_SDA_R1    I78 @T6G_MB_LIB.T6G(SCH_1):PAGE359

R4184 Q_RES_0402LF-1K,1%,1/16W,EMPTY,CS21002FB06
     1 P3V3_AUX @T6G_MB_LIB.T6G(SCH_1):P3V3_AUX   I142 @T6G_MB_LIB.T6G(SCH_1):PAGE359
     2 U273_3_ADD2 @T6G_MB_LIB.T6G(SCH_1):U273_3_ADD2   I142 @T6G_MB_LIB.T6G(SCH_1):PAGE359

R4185 Q_RES_0402LF-1K,1%,1/16W,CHIP,CS21002FB06
     1 U273_3_ADD2 @T6G_MB_LIB.T6G(SCH_1):U273_3_ADD2   I141 @T6G_MB_LIB.T6G(SCH_1):PAGE359
     2    GND @T6G_MB_LIB.T6G(SCH_1):GND   I141 @T6G_MB_LIB.T6G(SCH_1):PAGE359

R4186 Q_RES_0402LF-1K,1%,1/16W,EMPTY,CS21002FB06
     1 P3V3_AUX @T6G_MB_LIB.T6G(SCH_1):P3V3_AUX   I122 @T6G_MB_LIB.T6G(SCH_1):PAGE359
     2 U272_2_ADD2 @T6G_MB_LIB.T6G(SCH_1):U272_2_ADD2   I122 @T6G_MB_LIB.T6G(SCH_1):PAGE359

R4187 Q_RES_0402LF-1K,1%,1/16W,CHIP,CS21002FB06
     1 U272_2_ADD2 @T6G_MB_LIB.T6G(SCH_1):U272_2_ADD2   I121 @T6G_MB_LIB.T6G(SCH_1):PAGE359
     2    GND @T6G_MB_LIB.T6G(SCH_1):GND   I121 @T6G_MB_LIB.T6G(SCH_1):PAGE359

R4188 Q_RES_0402LF-1K,1%,1/16W,EMPTY,CS21002FB06
     1 P3V3_AUX @T6G_MB_LIB.T6G(SCH_1):P3V3_AUX   I101 @T6G_MB_LIB.T6G(SCH_1):PAGE359
     2 U271_1_ADD2 @T6G_MB_LIB.T6G(SCH_1):U271_1_ADD2   I101 @T6G_MB_LIB.T6G(SCH_1):PAGE359

R4189 Q_RES_0402LF-1K,1%,1/16W,CHIP,CS21002FB06
     1 U271_1_ADD2 @T6G_MB_LIB.T6G(SCH_1):U271_1_ADD2   I102 @T6G_MB_LIB.T6G(SCH_1):PAGE359
     2    GND @T6G_MB_LIB.T6G(SCH_1):GND   I102 @T6G_MB_LIB.T6G(SCH_1):PAGE359

R4190 Q_RES_0402LF-1K,1%,1/16W,EMPTY,CS21002FB06
     1 P3V3_AUX @T6G_MB_LIB.T6G(SCH_1):P3V3_AUX    I91 @T6G_MB_LIB.T6G(SCH_1):PAGE359
     2 U270_0_ADD2 @T6G_MB_LIB.T6G(SCH_1):U270_0_ADD2    I91 @T6G_MB_LIB.T6G(SCH_1):PAGE359

R4191 Q_RES_0402LF-1K,1%,1/16W,CHIP,CS21002FB06
     1 U270_0_ADD2 @T6G_MB_LIB.T6G(SCH_1):U270_0_ADD2    I89 @T6G_MB_LIB.T6G(SCH_1):PAGE359
     2    GND @T6G_MB_LIB.T6G(SCH_1):GND    I89 @T6G_MB_LIB.T6G(SCH_1):PAGE359

R4192 Q_RES_0402LF-1K,1%,1/16W,EMPTY,CS21002FB06
     1 P3V3_AUX @T6G_MB_LIB.T6G(SCH_1):P3V3_AUX   I148 @T6G_MB_LIB.T6G(SCH_1):PAGE359
     2 U273_3_ADD1 @T6G_MB_LIB.T6G(SCH_1):U273_3_ADD1   I148 @T6G_MB_LIB.T6G(SCH_1):PAGE359

R4193 Q_RES_0402LF-1K,1%,1/16W,CHIP,CS21002FB06
     1 U273_3_ADD1 @T6G_MB_LIB.T6G(SCH_1):U273_3_ADD1   I145 @T6G_MB_LIB.T6G(SCH_1):PAGE359
     2    GND @T6G_MB_LIB.T6G(SCH_1):GND   I145 @T6G_MB_LIB.T6G(SCH_1):PAGE359

R4194 Q_RES_0402LF-1K,1%,1/16W,EMPTY,CS21002FB06
     1 P3V3_AUX @T6G_MB_LIB.T6G(SCH_1):P3V3_AUX   I128 @T6G_MB_LIB.T6G(SCH_1):PAGE359
     2 U272_2_ADD1 @T6G_MB_LIB.T6G(SCH_1):U272_2_ADD1   I128 @T6G_MB_LIB.T6G(SCH_1):PAGE359

R4195 Q_RES_0402LF-1K,1%,1/16W,CHIP,CS21002FB06
     1 U272_2_ADD1 @T6G_MB_LIB.T6G(SCH_1):U272_2_ADD1   I125 @T6G_MB_LIB.T6G(SCH_1):PAGE359
     2    GND @T6G_MB_LIB.T6G(SCH_1):GND   I125 @T6G_MB_LIB.T6G(SCH_1):PAGE359

R4196 Q_RES_0402LF-1K,1%,1/16W,EMPTY,CS21002FB06
     1 P3V3_AUX @T6G_MB_LIB.T6G(SCH_1):P3V3_AUX    I95 @T6G_MB_LIB.T6G(SCH_1):PAGE359
     2 U271_1_ADD1 @T6G_MB_LIB.T6G(SCH_1):U271_1_ADD1    I95 @T6G_MB_LIB.T6G(SCH_1):PAGE359

R4197 Q_RES_0402LF-1K,1%,1/16W,CHIP,CS21002FB06
     1 U271_1_ADD1 @T6G_MB_LIB.T6G(SCH_1):U271_1_ADD1    I98 @T6G_MB_LIB.T6G(SCH_1):PAGE359
     2    GND @T6G_MB_LIB.T6G(SCH_1):GND    I98 @T6G_MB_LIB.T6G(SCH_1):PAGE359

R4198 Q_RES_0402LF-1K,1%,1/16W,EMPTY,CS21002FB06
     1 P3V3_AUX @T6G_MB_LIB.T6G(SCH_1):P3V3_AUX    I82 @T6G_MB_LIB.T6G(SCH_1):PAGE359
     2 U270_0_ADD1 @T6G_MB_LIB.T6G(SCH_1):U270_0_ADD1    I82 @T6G_MB_LIB.T6G(SCH_1):PAGE359

R4199 Q_RES_0402LF-1K,1%,1/16W,CHIP,CS21002FB06
     1 U270_0_ADD1 @T6G_MB_LIB.T6G(SCH_1):U270_0_ADD1    I81 @T6G_MB_LIB.T6G(SCH_1):PAGE359
     2    GND @T6G_MB_LIB.T6G(SCH_1):GND    I81 @T6G_MB_LIB.T6G(SCH_1):PAGE359

R4200 Q_RES_0402LF-1K,1%,1/16W,EMPTY,CS21002FB06
     1 P3V3_AUX @T6G_MB_LIB.T6G(SCH_1):P3V3_AUX   I149 @T6G_MB_LIB.T6G(SCH_1):PAGE359
     2 U273_3_ADD0 @T6G_MB_LIB.T6G(SCH_1):U273_3_ADD0   I149 @T6G_MB_LIB.T6G(SCH_1):PAGE359

R4201 Q_RES_0402LF-1K,1%,1/16W,CHIP,CS21002FB06
     1 U273_3_ADD0 @T6G_MB_LIB.T6G(SCH_1):U273_3_ADD0   I147 @T6G_MB_LIB.T6G(SCH_1):PAGE359
     2    GND @T6G_MB_LIB.T6G(SCH_1):GND   I147 @T6G_MB_LIB.T6G(SCH_1):PAGE359

R4202 Q_RES_0402LF-1K,1%,1/16W,EMPTY,CS21002FB06
     1 P3V3_AUX @T6G_MB_LIB.T6G(SCH_1):P3V3_AUX   I129 @T6G_MB_LIB.T6G(SCH_1):PAGE359
     2 U272_2_ADD0 @T6G_MB_LIB.T6G(SCH_1):U272_2_ADD0   I129 @T6G_MB_LIB.T6G(SCH_1):PAGE359

R4203 Q_RES_0402LF-1K,1%,1/16W,CHIP,CS21002FB06
     1 U272_2_ADD0 @T6G_MB_LIB.T6G(SCH_1):U272_2_ADD0   I127 @T6G_MB_LIB.T6G(SCH_1):PAGE359
     2    GND @T6G_MB_LIB.T6G(SCH_1):GND   I127 @T6G_MB_LIB.T6G(SCH_1):PAGE359

R4204 Q_RES_0402LF-1K,1%,1/16W,EMPTY,CS21002FB06
     1 P3V3_AUX @T6G_MB_LIB.T6G(SCH_1):P3V3_AUX    I94 @T6G_MB_LIB.T6G(SCH_1):PAGE359
     2 U271_1_ADD0 @T6G_MB_LIB.T6G(SCH_1):U271_1_ADD0    I94 @T6G_MB_LIB.T6G(SCH_1):PAGE359

R4205 Q_RES_0402LF-1K,1%,1/16W,CHIP,CS21002FB06
     1 U271_1_ADD0 @T6G_MB_LIB.T6G(SCH_1):U271_1_ADD0    I96 @T6G_MB_LIB.T6G(SCH_1):PAGE359
     2    GND @T6G_MB_LIB.T6G(SCH_1):GND    I96 @T6G_MB_LIB.T6G(SCH_1):PAGE359

R4206 Q_RES_0402LF-1K,1%,1/16W,EMPTY,CS21002FB06
     1 P3V3_AUX @T6G_MB_LIB.T6G(SCH_1):P3V3_AUX    I86 @T6G_MB_LIB.T6G(SCH_1):PAGE359
     2 U270_0_ADD0 @T6G_MB_LIB.T6G(SCH_1):U270_0_ADD0    I86 @T6G_MB_LIB.T6G(SCH_1):PAGE359

R4207 Q_RES_0402LF-1K,1%,1/16W,CHIP,CS21002FB06
     1 U270_0_ADD0 @T6G_MB_LIB.T6G(SCH_1):U270_0_ADD0    I85 @T6G_MB_LIB.T6G(SCH_1):PAGE359
     2    GND @T6G_MB_LIB.T6G(SCH_1):GND    I85 @T6G_MB_LIB.T6G(SCH_1):PAGE359

R4208 Q_RES_0402LF-200K,1%,1/16W,EMPTY,CS42002FB05
     1 P3V3_AUX @T6G_MB_LIB.T6G(SCH_1):P3V3_AUX   I171 @T6G_MB_LIB.T6G(SCH_1):PAGE359
     2 FM_THERMAL_ALERT_N @T6G_MB_LIB.T6G(SCH_1):FM_THERMAL_ALERT_N   I171 @T6G_MB_LIB.T6G(SCH_1):PAGE359

R4209 Q_RES_0402LF-200K,1%,1/16W,EMPTY,CS42002FB05
     1 P3V3_AUX @T6G_MB_LIB.T6G(SCH_1):P3V3_AUX   I169 @T6G_MB_LIB.T6G(SCH_1):PAGE359
     2 FM_THERMAL_ALERT_N @T6G_MB_LIB.T6G(SCH_1):FM_THERMAL_ALERT_N   I169 @T6G_MB_LIB.T6G(SCH_1):PAGE359

R4210 Q_RES_0402LF-200K,1%,1/16W,EMPTY,CS42002FB05
     1 P3V3_AUX @T6G_MB_LIB.T6G(SCH_1):P3V3_AUX   I170 @T6G_MB_LIB.T6G(SCH_1):PAGE359
     2 FM_THERMAL_ALERT_N @T6G_MB_LIB.T6G(SCH_1):FM_THERMAL_ALERT_N   I170 @T6G_MB_LIB.T6G(SCH_1):PAGE359

R4211 Q_RES_0402LF-200K,1%,1/16W,CHIP,CS42002FB05
     1 P3V3_AUX @T6G_MB_LIB.T6G(SCH_1):P3V3_AUX   I168 @T6G_MB_LIB.T6G(SCH_1):PAGE359
     2 FM_THERMAL_ALERT_N @T6G_MB_LIB.T6G(SCH_1):FM_THERMAL_ALERT_N   I168 @T6G_MB_LIB.T6G(SCH_1):PAGE359

R4212 Q_RES_0402LF-0,5%,1/16W,CHIP,CS00002JB13
     1 FM_THERMAL_ALERT_N @T6G_MB_LIB.T6G(SCH_1):FM_THERMAL_ALERT_N   I135 @T6G_MB_LIB.T6G(SCH_1):PAGE359
     2 FM_LM75_3_ALERT_N @T6G_MB_LIB.T6G(SCH_1):FM_LM75_3_ALERT_N   I135 @T6G_MB_LIB.T6G(SCH_1):PAGE359

R4213 Q_RES_0402LF-0,5%,1/16W,CHIP,CS00002JB13
     1 FM_THERMAL_ALERT_N @T6G_MB_LIB.T6G(SCH_1):FM_THERMAL_ALERT_N   I115 @T6G_MB_LIB.T6G(SCH_1):PAGE359
     2 FM_LM75_2_ALERT_N @T6G_MB_LIB.T6G(SCH_1):FM_LM75_2_ALERT_N   I115 @T6G_MB_LIB.T6G(SCH_1):PAGE359

R4214 Q_RES_0402LF-0,5%,1/16W,CHIP,CS00002JB13
     1 FM_THERMAL_ALERT_N @T6G_MB_LIB.T6G(SCH_1):FM_THERMAL_ALERT_N   I108 @T6G_MB_LIB.T6G(SCH_1):PAGE359
     2 FM_G751_1_ALERT_N @T6G_MB_LIB.T6G(SCH_1):FM_G751_1_ALERT_N   I108 @T6G_MB_LIB.T6G(SCH_1):PAGE359

R4215 Q_RES_0402LF-0,5%,1/16W,CHIP,CS00002JB13
     1 FM_THERMAL_ALERT_N @T6G_MB_LIB.T6G(SCH_1):FM_THERMAL_ALERT_N    I79 @T6G_MB_LIB.T6G(SCH_1):PAGE359
     2 FM_G751_0_ALERT_N @T6G_MB_LIB.T6G(SCH_1):FM_G751_0_ALERT_N    I79 @T6G_MB_LIB.T6G(SCH_1):PAGE359

R4264 Q_RES_0402LF-4.7K,5%,1/16W,CHIP,CS24702JB10
     1 P3V3_AUX @T6G_MB_LIB.T6G(SCH_1):P3V3_AUX    I47 @T6G_MB_LIB.T6G(SCH_1):PAGE364
     2 PWRGD_P3V3_AUX_PDB_BUF_R @T6G_MB_LIB.T6G(SCH_1):PWRGD_P3V3_AUX_PDB_BUF_R    I47 @T6G_MB_LIB.T6G(SCH_1):PAGE364

R4265 Q_RES_0402LF-4.7K,5%,1/16W,EMPTY,CS24702JB10
     1 PWRGD_P3V3_AUX_PDB_BUF_R @T6G_MB_LIB.T6G(SCH_1):PWRGD_P3V3_AUX_PDB_BUF_R    I43 @T6G_MB_LIB.T6G(SCH_1):PAGE364
     2    GND @T6G_MB_LIB.T6G(SCH_1):GND    I43 @T6G_MB_LIB.T6G(SCH_1):PAGE364

R4266 Q_RES_0402LF-33.2,1%,1/16W,CHIP,CS03322FB03
     1 PWRGD_P3V3_AUX_PDB_BUF_R @T6G_MB_LIB.T6G(SCH_1):PWRGD_P3V3_AUX_PDB_BUF_R    I48 @T6G_MB_LIB.T6G(SCH_1):PAGE364
     2 PWRGD_P3V3_AUX_PDB_BUF @T6G_MB_LIB.T6G(SCH_1):PWRGD_P3V3_AUX_PDB_BUF    I48 @T6G_MB_LIB.T6G(SCH_1):PAGE364

R4268 Q_RES_0402LF-0,5%,1/16W,CHIP,CS00002JB13
     1 PWRGD_P3V3_AUX_PDB @T6G_MB_LIB.T6G(SCH_1):PWRGD_P3V3_AUX_PDB    I41 @T6G_MB_LIB.T6G(SCH_1):PAGE364
     2 PWRGD_P3V3_AUX_PDB_R @T6G_MB_LIB.T6G(SCH_1):PWRGD_P3V3_AUX_PDB_R    I41 @T6G_MB_LIB.T6G(SCH_1):PAGE364

R4269 Q_RES_0402LF-2.2K,5%,1/16W,EMPTY,CS22202JB07
     1 P3V3_AUX @T6G_MB_LIB.T6G(SCH_1):P3V3_AUX    I41 @T6G_MB_LIB.T6G(SCH_1):PAGE251
     2 SMB_VR_SENSOR_3V3AUX_SCL @T6G_MB_LIB.T6G(SCH_1):SMB_VR_SENSOR_3V3AUX_SCL    I41 @T6G_MB_LIB.T6G(SCH_1):PAGE251

R4270 Q_RES_0402LF-2.2K,5%,1/16W,EMPTY,CS22202JB07
     1 P3V3_AUX @T6G_MB_LIB.T6G(SCH_1):P3V3_AUX    I40 @T6G_MB_LIB.T6G(SCH_1):PAGE251
     2 SMB_VR_SENSOR_3V3AUX_SDA @T6G_MB_LIB.T6G(SCH_1):SMB_VR_SENSOR_3V3AUX_SDA    I40 @T6G_MB_LIB.T6G(SCH_1):PAGE251

R4303 Q_RES_0402LF-0,5%,1/16W,CHIP,CS00002JB13
     1 CLK_100M_CPU0_CLK12_R_DP @T6G_MB_LIB.T6G(SCH_1):CLK_100M_CPU0_CLK12_R_DP   I191 @T6G_MB_LIB.T6G(SCH_1):PAGE28
     2 CLK_100M_CPU0_CLK12_DP @T6G_MB_LIB.T6G(SCH_1):CLK_100M_CPU0_CLK12_DP   I191 @T6G_MB_LIB.T6G(SCH_1):PAGE28

R4304 Q_RES_0402LF-0,5%,1/16W,CHIP,CS00002JB13
     1 CLK_100M_CPU0_CLK12_R_DN @T6G_MB_LIB.T6G(SCH_1):CLK_100M_CPU0_CLK12_R_DN   I192 @T6G_MB_LIB.T6G(SCH_1):PAGE28
     2 CLK_100M_CPU0_CLK12_DN @T6G_MB_LIB.T6G(SCH_1):CLK_100M_CPU0_CLK12_DN   I192 @T6G_MB_LIB.T6G(SCH_1):PAGE28

R4305 Q_RES_0402LF-0,5%,1/16W,CHIP,CS00002JB13
     1 CLK_100M_CPU1_CLK12_R_DP @T6G_MB_LIB.T6G(SCH_1):CLK_100M_CPU1_CLK12_R_DP   I327 @T6G_MB_LIB.T6G(SCH_1):PAGE55
     2 CLK_100M_CPU1_CLK12_DP @T6G_MB_LIB.T6G(SCH_1):CLK_100M_CPU1_CLK12_DP   I327 @T6G_MB_LIB.T6G(SCH_1):PAGE55

R4306 Q_RES_0402LF-0,5%,1/16W,CHIP,CS00002JB13
     1 CLK_100M_CPU1_CLK12_R_DN @T6G_MB_LIB.T6G(SCH_1):CLK_100M_CPU1_CLK12_R_DN   I326 @T6G_MB_LIB.T6G(SCH_1):PAGE55
     2 CLK_100M_CPU1_CLK12_DN @T6G_MB_LIB.T6G(SCH_1):CLK_100M_CPU1_CLK12_DN   I326 @T6G_MB_LIB.T6G(SCH_1):PAGE55

R4419 Q_RES_0402LF-49.9,1%,1/16W,EMPTY,CS04992FB07
     1 USB2_HOST_BMC_B_DP @T6G_MB_LIB.T6G(SCH_1):USB2_HOST_BMC_B_DP   I203 @T6G_MB_LIB.T6G(SCH_1):PAGE358
     2    GND @T6G_MB_LIB.T6G(SCH_1):GND   I203 @T6G_MB_LIB.T6G(SCH_1):PAGE358

R4420 Q_RES_0402LF-49.9,1%,1/16W,EMPTY,CS04992FB07
     1 USB2_HOST_BMC_B_DN @T6G_MB_LIB.T6G(SCH_1):USB2_HOST_BMC_B_DN   I202 @T6G_MB_LIB.T6G(SCH_1):PAGE358
     2    GND @T6G_MB_LIB.T6G(SCH_1):GND   I202 @T6G_MB_LIB.T6G(SCH_1):PAGE358

R4450 Q_RES_0402LF-0,5%,1/16W,CHIP,CS00002JB13
     1 USB_CPU0_HUB1_VBUS_DS @T6G_MB_LIB.T6G(SCH_1):USB_CPU0_HUB1_VBUS_DS    I27 @T6G_MB_LIB.T6G(SCH_1):PAGE153
     2 P5V_AUX @T6G_MB_LIB.T6G(SCH_1):P5V_AUX    I27 @T6G_MB_LIB.T6G(SCH_1):PAGE153

R4451 Q_RES_0402LF-33.2,1%,1/16W,CHIP,CS03322FB03
     1 RST_USB_HUB_N @T6G_MB_LIB.T6G(SCH_1):RST_USB_HUB_N    I20 @T6G_MB_LIB.T6G(SCH_1):PAGE153
     2 RST_USB_CPU0_HUB1_R_N @T6G_MB_LIB.T6G(SCH_1):RST_USB_CPU0_HUB1_R_N    I20 @T6G_MB_LIB.T6G(SCH_1):PAGE153

R4452 Q_RES_0402LF-10K,1%,1/16W,EMPTY,CS31002FB08
     1 P3V3_AUX @T6G_MB_LIB.T6G(SCH_1):P3V3_AUX    I93 @T6G_MB_LIB.T6G(SCH_1):PAGE153
     2 RST_USB_CPU0_HUB1_R_N @T6G_MB_LIB.T6G(SCH_1):RST_USB_CPU0_HUB1_R_N    I93 @T6G_MB_LIB.T6G(SCH_1):PAGE153

R4453 Q_RES_0402LF-47K,0.1%,1/16W,EMPTY,CS34702BB05
     1 RST_USB_CPU0_HUB1_R_N @T6G_MB_LIB.T6G(SCH_1):RST_USB_CPU0_HUB1_R_N    I23 @T6G_MB_LIB.T6G(SCH_1):PAGE153
     2    GND @T6G_MB_LIB.T6G(SCH_1):GND    I23 @T6G_MB_LIB.T6G(SCH_1):PAGE153

R4475 Q_RES_0603LF-1,1%,1/10W,CHIP,CS-1003F900
     1 P3V3_9ZXL045_P0 @T6G_MB_LIB.T6G(SCH_1):P3V3_9ZXL045_P0     I6 @T6G_MB_LIB.T6G(SCH_1):PAGE160
     2 P3V3_9ZXL045_P0_VDDR @T6G_MB_LIB.T6G(SCH_1):P3V3_9ZXL045_P0_VDDR     I6 @T6G_MB_LIB.T6G(SCH_1):PAGE160

R4476 Q_RES_0402LF-10K,1%,1/16W,CHIP,CS31002FB08
     1 P3V3_AUX @T6G_MB_LIB.T6G(SCH_1):P3V3_AUX    I73 @T6G_MB_LIB.T6G(SCH_1):PAGE160
     2 FM_9ZXL045_P0_DEV_EN @T6G_MB_LIB.T6G(SCH_1):FM_9ZXL045_P0_DEV_EN    I73 @T6G_MB_LIB.T6G(SCH_1):PAGE160

R4482 Q_RES_0402LF-49.9,1%,1/16W,EMPTY,CS04992FB07
     1 USB2_HOST_BMC_B_BUF_DP @T6G_MB_LIB.T6G(SCH_1):USB2_HOST_BMC_B_BUF_DP   I208 @T6G_MB_LIB.T6G(SCH_1):PAGE358
     2    GND @T6G_MB_LIB.T6G(SCH_1):GND   I208 @T6G_MB_LIB.T6G(SCH_1):PAGE358

R4483 Q_RES_0402LF-49.9,1%,1/16W,EMPTY,CS04992FB07
     1 USB2_HOST_BMC_B_BUF_DN @T6G_MB_LIB.T6G(SCH_1):USB2_HOST_BMC_B_BUF_DN   I206 @T6G_MB_LIB.T6G(SCH_1):PAGE358
     2    GND @T6G_MB_LIB.T6G(SCH_1):GND   I206 @T6G_MB_LIB.T6G(SCH_1):PAGE358

R4489 Q_RES_0402LF-4.75K,1%,1/16W,CHIP,CS24752FB03
     1 P3V3_AUX @T6G_MB_LIB.T6G(SCH_1):P3V3_AUX     I3 @T6G_MB_LIB.T6G(SCH_1):PAGE160
     2 CLK_9ZXL045_P0_SADR0 @T6G_MB_LIB.T6G(SCH_1):CLK_9ZXL045_P0_SADR0     I3 @T6G_MB_LIB.T6G(SCH_1):PAGE160

R4490 Q_RES_0402LF-4.75K,1%,1/16W,EMPTY,CS24752FB03
     1 CLK_9ZXL045_P0_SADR0 @T6G_MB_LIB.T6G(SCH_1):CLK_9ZXL045_P0_SADR0     I2 @T6G_MB_LIB.T6G(SCH_1):PAGE160
     2    GND @T6G_MB_LIB.T6G(SCH_1):GND     I2 @T6G_MB_LIB.T6G(SCH_1):PAGE160

R4491 Q_RES_0402LF-10K,1%,1/16W,CHIP,CS31002FB08
     1 P3V3_AUX @T6G_MB_LIB.T6G(SCH_1):P3V3_AUX    I31 @T6G_MB_LIB.T6G(SCH_1):PAGE160
     2 CLK_9ZXL045_P0_HIBW @T6G_MB_LIB.T6G(SCH_1):CLK_9ZXL045_P0_HIBW    I31 @T6G_MB_LIB.T6G(SCH_1):PAGE160

R4492 Q_RES_0402LF-10K,1%,1/16W,CHIP,CS31002FB08
     1 CLK_9ZXL045_P0_HIBW @T6G_MB_LIB.T6G(SCH_1):CLK_9ZXL045_P0_HIBW    I29 @T6G_MB_LIB.T6G(SCH_1):PAGE160
     2    GND @T6G_MB_LIB.T6G(SCH_1):GND    I29 @T6G_MB_LIB.T6G(SCH_1):PAGE160

R4493 Q_RES_0603LF-1,1%,1/10W,CHIP,CS-1003F900
     1 P3V3_9ZXL045_P0 @T6G_MB_LIB.T6G(SCH_1):P3V3_9ZXL045_P0    I27 @T6G_MB_LIB.T6G(SCH_1):PAGE160
     2 P3V3_9ZXL045_P0_VDDA @T6G_MB_LIB.T6G(SCH_1):P3V3_9ZXL045_P0_VDDA    I27 @T6G_MB_LIB.T6G(SCH_1):PAGE160

R4501 Q_RES_0402LF-0,5%,1/16W,CHIP,CS00002JB13
     1 CLK_GEN2_XTAL_IN_R @T6G_MB_LIB.T6G(SCH_1):CLK_GEN2_XTAL_IN_R    I31 @T6G_MB_LIB.T6G(SCH_1):PAGE232
     2 CLK_GEN2_XTAL_IN @T6G_MB_LIB.T6G(SCH_1):CLK_GEN2_XTAL_IN    I31 @T6G_MB_LIB.T6G(SCH_1):PAGE232

R4506 Q_RES_0402LF-33.2,1%,1/16W,CHIP,CS03322FB03
     1 SMB_CPU0_CPU1_SEC_SCL @T6G_MB_LIB.T6G(SCH_1):SMB_CPU0_CPU1_SEC_SCL   I191 @T6G_MB_LIB.T6G(SCH_1):PAGE348
     2 SMB_CPU0_CPU1_SEC_SCL_R @T6G_MB_LIB.T6G(SCH_1):SMB_CPU0_CPU1_SEC_SCL_R   I191 @T6G_MB_LIB.T6G(SCH_1):PAGE348

R4507 Q_RES_0402LF-33.2,1%,1/16W,CHIP,CS03322FB03
     1 SMB_CPU0_CPU1_SEC_SDA @T6G_MB_LIB.T6G(SCH_1):SMB_CPU0_CPU1_SEC_SDA   I190 @T6G_MB_LIB.T6G(SCH_1):PAGE348
     2 SMB_CPU0_CPU1_SEC_SDA_R @T6G_MB_LIB.T6G(SCH_1):SMB_CPU0_CPU1_SEC_SDA_R   I190 @T6G_MB_LIB.T6G(SCH_1):PAGE348

R4508 Q_RES_0402LF-33.2,1%,1/16W,CHIP,CS03322FB03
     1 SMB_1_PLD_3V3AUX_SCL @T6G_MB_LIB.T6G(SCH_1):SMB_1_PLD_3V3AUX_SCL    I88 @T6G_MB_LIB.T6G(SCH_1):PAGE348
     2 SMB_1_PLD_3V3AUX_SCL_R3 @T6G_MB_LIB.T6G(SCH_1):SMB_1_PLD_3V3AUX_SCL_R3    I88 @T6G_MB_LIB.T6G(SCH_1):PAGE348

R4509 Q_RES_0402LF-33.2,1%,1/16W,CHIP,CS03322FB03
     1 SMB_1_PLD_3V3AUX_SDA @T6G_MB_LIB.T6G(SCH_1):SMB_1_PLD_3V3AUX_SDA    I87 @T6G_MB_LIB.T6G(SCH_1):PAGE348
     2 SMB_1_PLD_3V3AUX_SDA_R3 @T6G_MB_LIB.T6G(SCH_1):SMB_1_PLD_3V3AUX_SDA_R3    I87 @T6G_MB_LIB.T6G(SCH_1):PAGE348

R4514 Q_RES_0402LF-4.7K,1%,1/16W,EMPTY,CS24702FB06
     1 CLK_GEN2_GPU_FPGA_OE_R2_N @T6G_MB_LIB.T6G(SCH_1):CLK_GEN2_GPU_FPGA_OE_R2_N     I8 @T6G_MB_LIB.T6G(SCH_1):PAGE232
     2    GND @T6G_MB_LIB.T6G(SCH_1):GND     I8 @T6G_MB_LIB.T6G(SCH_1):PAGE232

R4515 Q_RES_0402LF-100K,1%,1/16W,CHIP,CS41002FB09
     1 P3V3_AUX @T6G_MB_LIB.T6G(SCH_1):P3V3_AUX   I200 @T6G_MB_LIB.T6G(SCH_1):PAGE256
     2 UART_BMC_BIC_RX @T6G_MB_LIB.T6G(SCH_1):UART_BMC_BIC_RX   I200 @T6G_MB_LIB.T6G(SCH_1):PAGE256

R4518 Q_RES_0402LF-10K,1%,1/16W,CHIP,CS31002FB08
     1 FM_9ZXL045_P0_2_OE_N @T6G_MB_LIB.T6G(SCH_1):FM_9ZXL045_P0_2_OE_N    I52 @T6G_MB_LIB.T6G(SCH_1):PAGE160
     2    GND @T6G_MB_LIB.T6G(SCH_1):GND    I52 @T6G_MB_LIB.T6G(SCH_1):PAGE160

R4519 Q_RES_0402LF-10K,1%,1/16W,CHIP,CS31002FB08
     1 FM_9ZXL045_P0_1_OE_N @T6G_MB_LIB.T6G(SCH_1):FM_9ZXL045_P0_1_OE_N    I53 @T6G_MB_LIB.T6G(SCH_1):PAGE160
     2    GND @T6G_MB_LIB.T6G(SCH_1):GND    I53 @T6G_MB_LIB.T6G(SCH_1):PAGE160

R4520 Q_RES_0402LF-10K,1%,1/16W,CHIP,CS31002FB08
     1 FM_9ZXL045_P0_0_OE_N @T6G_MB_LIB.T6G(SCH_1):FM_9ZXL045_P0_0_OE_N    I55 @T6G_MB_LIB.T6G(SCH_1):PAGE160
     2    GND @T6G_MB_LIB.T6G(SCH_1):GND    I55 @T6G_MB_LIB.T6G(SCH_1):PAGE160

R4521 Q_RES_0402LF-1K,1%,1/16W,CHIP,CS21002FB06
     1 P3V3_AUX @T6G_MB_LIB.T6G(SCH_1):P3V3_AUX    I73 @T6G_MB_LIB.T6G(SCH_1):PAGE232
     2 CLK_GEN2_BMC_RC_OE_N @T6G_MB_LIB.T6G(SCH_1):CLK_GEN2_BMC_RC_OE_N    I73 @T6G_MB_LIB.T6G(SCH_1):PAGE232

R4532 Q_RES_0402LF-10K,1%,1/16W,CHIP,CS31002FB08
     1 P3V3_AUX @T6G_MB_LIB.T6G(SCH_1):P3V3_AUX    I75 @T6G_MB_LIB.T6G(SCH_1):PAGE339
     2 HP_LVC3_OCP_V3_1_P12V_PWRGD @T6G_MB_LIB.T6G(SCH_1):HP_LVC3_OCP_V3_1_P12V_PWRGD    I75 @T6G_MB_LIB.T6G(SCH_1):PAGE339

R4535 Q_RES_0402LF-0,5%,1/16W,CHIP,CS00002JB13
     1 CLK_100M_CPU0_CLK01_R_DP @T6G_MB_LIB.T6G(SCH_1):CLK_100M_CPU0_CLK01_R_DP   I160 @T6G_MB_LIB.T6G(SCH_1):PAGE28
     2 CLK_100M_CPU0_CLK01_DP @T6G_MB_LIB.T6G(SCH_1):CLK_100M_CPU0_CLK01_DP   I160 @T6G_MB_LIB.T6G(SCH_1):PAGE28

R4536 Q_RES_0402LF-0,5%,1/16W,CHIP,CS00002JB13
     1 CLK_100M_CPU0_CLK01_R_DN @T6G_MB_LIB.T6G(SCH_1):CLK_100M_CPU0_CLK01_R_DN   I161 @T6G_MB_LIB.T6G(SCH_1):PAGE28
     2 CLK_100M_CPU0_CLK01_DN @T6G_MB_LIB.T6G(SCH_1):CLK_100M_CPU0_CLK01_DN   I161 @T6G_MB_LIB.T6G(SCH_1):PAGE28

R4537 Q_RES_0402LF-0,5%,1/16W,CHIP,CS00002JB13
     1 FM_P2E_EN_N @T6G_MB_LIB.T6G(SCH_1):FM_P2E_EN_N    I67 @T6G_MB_LIB.T6G(SCH_1):PAGE110
     2 CLK_GEN2_GPU_FPGA_OE_OR_N @T6G_MB_LIB.T6G(SCH_1):CLK_GEN2_GPU_FPGA_OE_OR_N    I67 @T6G_MB_LIB.T6G(SCH_1):PAGE110

R4543 Q_RES_0402LF-1K,1%,1/16W,CHIP,CS21002FB06
     1 P3V3_AUX @T6G_MB_LIB.T6G(SCH_1):P3V3_AUX    I85 @T6G_MB_LIB.T6G(SCH_1):PAGE331
     2 HGX_DETECT_N @T6G_MB_LIB.T6G(SCH_1):HGX_DETECT_N    I85 @T6G_MB_LIB.T6G(SCH_1):PAGE331

R4544 Q_RES_0402LF-100K,1%,1/16W,EMPTY,CS41002FB09
     1 HGX_DETECT_N @T6G_MB_LIB.T6G(SCH_1):HGX_DETECT_N    I62 @T6G_MB_LIB.T6G(SCH_1):PAGE331
     2    GND @T6G_MB_LIB.T6G(SCH_1):GND    I62 @T6G_MB_LIB.T6G(SCH_1):PAGE331

R4545 Q_RES_0402LF-4.7K,5%,1/16W,CHIP,CS24702JB10
     1 P3V3_AUX @T6G_MB_LIB.T6G(SCH_1):P3V3_AUX    I57 @T6G_MB_LIB.T6G(SCH_1):PAGE331
     2 HGX_DETECT @T6G_MB_LIB.T6G(SCH_1):HGX_DETECT    I57 @T6G_MB_LIB.T6G(SCH_1):PAGE331

R4546 Q_RES_0402LF-100K,1%,1/16W,EMPTY,CS41002FB09
     1 P3V3_AUX @T6G_MB_LIB.T6G(SCH_1):P3V3_AUX   I110 @T6G_MB_LIB.T6G(SCH_1):PAGE331
     2 HGX_DETECT_N_ISO @T6G_MB_LIB.T6G(SCH_1):HGX_DETECT_N_ISO   I110 @T6G_MB_LIB.T6G(SCH_1):PAGE331

R4547 Q_RES_0402LF-100K,1%,1/16W,EMPTY,CS41002FB09
     1 P3V3_AUX @T6G_MB_LIB.T6G(SCH_1):P3V3_AUX    I89 @T6G_MB_LIB.T6G(SCH_1):PAGE331
     2 SWB_HSC_EN @T6G_MB_LIB.T6G(SCH_1):SWB_HSC_EN    I89 @T6G_MB_LIB.T6G(SCH_1):PAGE331

R4548 Q_RES_0402LF-100K,1%,1/16W,CHIP,CS41002FB09
     1 SWB_HSC_EN @T6G_MB_LIB.T6G(SCH_1):SWB_HSC_EN    I87 @T6G_MB_LIB.T6G(SCH_1):PAGE331
     2    GND @T6G_MB_LIB.T6G(SCH_1):GND    I87 @T6G_MB_LIB.T6G(SCH_1):PAGE331

R4549 Q_RES_0402LF-4.7K,5%,1/16W,EMPTY,CS24702JB10
     1 P3V3_AUX @T6G_MB_LIB.T6G(SCH_1):P3V3_AUX    I98 @T6G_MB_LIB.T6G(SCH_1):PAGE331
     2 SWB_HSC_EN_BUF_R @T6G_MB_LIB.T6G(SCH_1):SWB_HSC_EN_BUF_R    I98 @T6G_MB_LIB.T6G(SCH_1):PAGE331

R4550 Q_RES_0402LF-49.9,1%,1/16W,CHIP,CS04992FB07
     1 SWB_HSC_EN_BUF_R @T6G_MB_LIB.T6G(SCH_1):SWB_HSC_EN_BUF_R    I97 @T6G_MB_LIB.T6G(SCH_1):PAGE331
     2 SWB_HSC_EN_BUF @T6G_MB_LIB.T6G(SCH_1):SWB_HSC_EN_BUF    I97 @T6G_MB_LIB.T6G(SCH_1):PAGE331

R4551 Q_RES_0402LF-54.9K,1%,1/16W,EMPTY,CS35492FB03
     1 P3V3_AUX @T6G_MB_LIB.T6G(SCH_1):P3V3_AUX    I51 @T6G_MB_LIB.T6G(SCH_1):PAGE364
     2 HPDB_HSC_PWRGD @T6G_MB_LIB.T6G(SCH_1):HPDB_HSC_PWRGD    I51 @T6G_MB_LIB.T6G(SCH_1):PAGE364

R4552 Q_RES_0402LF-100K,1%,1/16W,CHIP,CS41002FB09
     1 HPDB_HSC_PWRGD @T6G_MB_LIB.T6G(SCH_1):HPDB_HSC_PWRGD    I50 @T6G_MB_LIB.T6G(SCH_1):PAGE364
     2    GND @T6G_MB_LIB.T6G(SCH_1):GND    I50 @T6G_MB_LIB.T6G(SCH_1):PAGE364

R4553 Q_RES_0402LF-4.7K,5%,1/16W,CHIP,CS24702JB10
     1 P3V3_AUX @T6G_MB_LIB.T6G(SCH_1):P3V3_AUX    I55 @T6G_MB_LIB.T6G(SCH_1):PAGE364
     2 HPDB_HSC_PWRGD_N @T6G_MB_LIB.T6G(SCH_1):HPDB_HSC_PWRGD_N    I55 @T6G_MB_LIB.T6G(SCH_1):PAGE364

R4554 Q_RES_0402LF-100K,1%,1/16W,CHIP,CS41002FB09
     1 P3V3_AUX @T6G_MB_LIB.T6G(SCH_1):P3V3_AUX    I59 @T6G_MB_LIB.T6G(SCH_1):PAGE364
     2 HPDB_HSC_PWRGD_ISO @T6G_MB_LIB.T6G(SCH_1):HPDB_HSC_PWRGD_ISO    I59 @T6G_MB_LIB.T6G(SCH_1):PAGE364

R4555 Q_RES_0402LF-4.7K,5%,1/16W,EMPTY,CS24702JB10
     1 SWB_HSC_EN_BUF_R @T6G_MB_LIB.T6G(SCH_1):SWB_HSC_EN_BUF_R    I99 @T6G_MB_LIB.T6G(SCH_1):PAGE331
     2    GND @T6G_MB_LIB.T6G(SCH_1):GND    I99 @T6G_MB_LIB.T6G(SCH_1):PAGE331

R4556 Q_RES_0402LF-33.2,1%,1/16W,CHIP,CS03322FB03
     1 HGX_DETECT_N_R @T6G_MB_LIB.T6G(SCH_1):HGX_DETECT_N_R   I226 @T6G_MB_LIB.T6G(SCH_1):PAGE80
     2 HGX_DETECT_N @T6G_MB_LIB.T6G(SCH_1):HGX_DETECT_N   I226 @T6G_MB_LIB.T6G(SCH_1):PAGE80

R4557 Q_RES_0402LF-33.2,1%,1/16W,CHIP,CS03322FB03
     1 HPDB_HSC_PWRGD_ISO @T6G_MB_LIB.T6G(SCH_1):HPDB_HSC_PWRGD_ISO   I301 @T6G_MB_LIB.T6G(SCH_1):PAGE80
     2 HPDB_HSC_PWRGD_ISO_R @T6G_MB_LIB.T6G(SCH_1):HPDB_HSC_PWRGD_ISO_R   I301 @T6G_MB_LIB.T6G(SCH_1):PAGE80

R4558 Q_RES_0402LF-33.2,1%,1/16W,CHIP,CS03322FB03
     1 SWB_HSC_EN_R @T6G_MB_LIB.T6G(SCH_1):SWB_HSC_EN_R   I228 @T6G_MB_LIB.T6G(SCH_1):PAGE80
     2 SWB_HSC_EN @T6G_MB_LIB.T6G(SCH_1):SWB_HSC_EN   I228 @T6G_MB_LIB.T6G(SCH_1):PAGE80

R4559 Q_RES_0402LF-100K,1%,1/16W,CHIP,CS41002FB09
     1 SWB_HSC_PWRGD @T6G_MB_LIB.T6G(SCH_1):SWB_HSC_PWRGD    I54 @T6G_MB_LIB.T6G(SCH_1):PAGE332
     2    GND @T6G_MB_LIB.T6G(SCH_1):GND    I54 @T6G_MB_LIB.T6G(SCH_1):PAGE332

R4560 Q_RES_0402LF-4.7K,5%,1/16W,CHIP,CS24702JB10
     1 P3V3_AUX @T6G_MB_LIB.T6G(SCH_1):P3V3_AUX    I62 @T6G_MB_LIB.T6G(SCH_1):PAGE332
     2 SWB_HSC_PWRGD_N @T6G_MB_LIB.T6G(SCH_1):SWB_HSC_PWRGD_N    I62 @T6G_MB_LIB.T6G(SCH_1):PAGE332

R4561 Q_RES_0402LF-100K,1%,1/16W,CHIP,CS41002FB09
     1 P3V3_AUX @T6G_MB_LIB.T6G(SCH_1):P3V3_AUX   I110 @T6G_MB_LIB.T6G(SCH_1):PAGE332
     2 SWB_HSC_PWRGD_ISO @T6G_MB_LIB.T6G(SCH_1):SWB_HSC_PWRGD_ISO   I110 @T6G_MB_LIB.T6G(SCH_1):PAGE332

R4562 Q_RES_0402LF-100K,1%,1/16W,EMPTY,CS41002FB09
     1 P3V3_AUX @T6G_MB_LIB.T6G(SCH_1):P3V3_AUX    I55 @T6G_MB_LIB.T6G(SCH_1):PAGE332
     2 SWB_HSC_PWRGD @T6G_MB_LIB.T6G(SCH_1):SWB_HSC_PWRGD    I55 @T6G_MB_LIB.T6G(SCH_1):PAGE332

R4563 Q_RES_0402LF-33.2,1%,1/16W,CHIP,CS03322FB03
     1 SWB_HSC_PWRGD_ISO_R @T6G_MB_LIB.T6G(SCH_1):SWB_HSC_PWRGD_ISO_R   I243 @T6G_MB_LIB.T6G(SCH_1):PAGE80
     2 SWB_HSC_PWRGD_ISO @T6G_MB_LIB.T6G(SCH_1):SWB_HSC_PWRGD_ISO   I243 @T6G_MB_LIB.T6G(SCH_1):PAGE80

R4567 Q_RES_0402LF-5.11K,1%,1/16W,CHIP,CS25112FB04
     1 P3V3_PDB_AUX_ADC @T6G_MB_LIB.T6G(SCH_1):P3V3_PDB_AUX_ADC     I8 @T6G_MB_LIB.T6G(SCH_1):PAGE369
     2 P1V581_PDB_ADC @T6G_MB_LIB.T6G(SCH_1):P1V581_PDB_ADC     I8 @T6G_MB_LIB.T6G(SCH_1):PAGE369

R4568 Q_RES_0402LF-4.7K,1%,1/16W,CHIP,CS24702FB06
     1 P1V581_PDB_ADC @T6G_MB_LIB.T6G(SCH_1):P1V581_PDB_ADC     I7 @T6G_MB_LIB.T6G(SCH_1):PAGE369
     2    GND @T6G_MB_LIB.T6G(SCH_1):GND     I7 @T6G_MB_LIB.T6G(SCH_1):PAGE369

R4569 Q_RES_0402LF-0,5%,1/16W,EMPTY,CS00002JB13
     1 GPU_3V3IO_RSVD1 @T6G_MB_LIB.T6G(SCH_1):GPU_3V3IO_RSVD1   I107 @T6G_MB_LIB.T6G(SCH_1):PAGE331
     2 GPU_3V3IO_RSVD1_ISO @T6G_MB_LIB.T6G(SCH_1):GPU_3V3IO_RSVD1_ISO   I107 @T6G_MB_LIB.T6G(SCH_1):PAGE331

R4570 Q_RES_0402LF-0,5%,1/16W,EMPTY,CS00002JB13
     1 GPU_3V3IO_RSVD3 @T6G_MB_LIB.T6G(SCH_1):GPU_3V3IO_RSVD3   I109 @T6G_MB_LIB.T6G(SCH_1):PAGE331
     2 GPU_3V3IO_RSVD3_ISO @T6G_MB_LIB.T6G(SCH_1):GPU_3V3IO_RSVD3_ISO   I109 @T6G_MB_LIB.T6G(SCH_1):PAGE331

R4571 Q_RES_0402LF-0,5%,1/16W,EMPTY,CS00002JB13
     1 GPU_3V3IO_RSVD4 @T6G_MB_LIB.T6G(SCH_1):GPU_3V3IO_RSVD4   I108 @T6G_MB_LIB.T6G(SCH_1):PAGE331
     2 GPU_3V3IO_RSVD4_ISO @T6G_MB_LIB.T6G(SCH_1):GPU_3V3IO_RSVD4_ISO   I108 @T6G_MB_LIB.T6G(SCH_1):PAGE331

R4572 Q_RES_0402LF-0,5%,1/16W,EMPTY,CS00002JB13
     1 GPU_3V3IO_RSVD1_FFU @T6G_MB_LIB.T6G(SCH_1):GPU_3V3IO_RSVD1_FFU    I41 @T6G_MB_LIB.T6G(SCH_1):PAGE332
     2 GPU_3V3IO_RSVD1_FFU_ISO @T6G_MB_LIB.T6G(SCH_1):GPU_3V3IO_RSVD1_FFU_ISO    I41 @T6G_MB_LIB.T6G(SCH_1):PAGE332

R4573 Q_RES_0402LF-0,5%,1/16W,EMPTY,CS00002JB13
     1 PRSNT_CABLE_GPU_B3_N @T6G_MB_LIB.T6G(SCH_1):PRSNT_CABLE_GPU_B3_N    I33 @T6G_MB_LIB.T6G(SCH_1):PAGE332
     2 PRSNT_CABLE_GPU_B3_ISO_N @T6G_MB_LIB.T6G(SCH_1):PRSNT_CABLE_GPU_B3_ISO_N    I33 @T6G_MB_LIB.T6G(SCH_1):PAGE332

R4574 Q_RES_0402LF-0,5%,1/16W,EMPTY,CS00002JB13
     1 PRSNT_CABLE_GPU_A1_N @T6G_MB_LIB.T6G(SCH_1):PRSNT_CABLE_GPU_A1_N    I31 @T6G_MB_LIB.T6G(SCH_1):PAGE332
     2 PRSNT_CABLE_GPU_A1_ISO_N @T6G_MB_LIB.T6G(SCH_1):PRSNT_CABLE_GPU_A1_ISO_N    I31 @T6G_MB_LIB.T6G(SCH_1):PAGE332

R4575 Q_RES_0402LF-0,5%,1/16W,EMPTY,CS00002JB13
     1 GPU_3V3IO_RSVD0_FFU @T6G_MB_LIB.T6G(SCH_1):GPU_3V3IO_RSVD0_FFU    I44 @T6G_MB_LIB.T6G(SCH_1):PAGE332
     2 GPU_3V3IO_RSVD0_FFU_ISO @T6G_MB_LIB.T6G(SCH_1):GPU_3V3IO_RSVD0_FFU_ISO    I44 @T6G_MB_LIB.T6G(SCH_1):PAGE332

R4576 Q_RES_0402LF-0,5%,1/16W,EMPTY,CS00002JB13
     1 GPU_3V3IO_RSVD5_FFU @T6G_MB_LIB.T6G(SCH_1):GPU_3V3IO_RSVD5_FFU    I91 @T6G_MB_LIB.T6G(SCH_1):PAGE332
     2 GPU_3V3IO_RSVD5_FFU_ISO @T6G_MB_LIB.T6G(SCH_1):GPU_3V3IO_RSVD5_FFU_ISO    I91 @T6G_MB_LIB.T6G(SCH_1):PAGE332

R4577 Q_RES_0402LF-0,5%,1/16W,EMPTY,CS00002JB13
     1 GPU_3V3IO_RSVD3_FFU @T6G_MB_LIB.T6G(SCH_1):GPU_3V3IO_RSVD3_FFU   I109 @T6G_MB_LIB.T6G(SCH_1):PAGE332
     2 GPU_3V3IO_RSVD3_FFU_ISO @T6G_MB_LIB.T6G(SCH_1):GPU_3V3IO_RSVD3_FFU_ISO   I109 @T6G_MB_LIB.T6G(SCH_1):PAGE332

R4578 Q_RES_0402LF-0,5%,1/16W,EMPTY,CS00002JB13
     1 PRSNT_CABLE_GPU_A2_N @T6G_MB_LIB.T6G(SCH_1):PRSNT_CABLE_GPU_A2_N   I103 @T6G_MB_LIB.T6G(SCH_1):PAGE332
     2 PRSNT_CABLE_GPU_A2_ISO_N @T6G_MB_LIB.T6G(SCH_1):PRSNT_CABLE_GPU_A2_ISO_N   I103 @T6G_MB_LIB.T6G(SCH_1):PAGE332

R4601 Q_RES_0402LF-0,5%,1/16W,CHIP,CS00002JB13
     1 CLK_50M_NCSI_OCP_SFF_ISO @T6G_MB_LIB.T6G(SCH_1):CLK_50M_NCSI_OCP_SFF_ISO    I29 @T6G_MB_LIB.T6G(SCH_1):PAGE337
     2 CLK_50M_NCSI_OCP_SFF_ISO_R @T6G_MB_LIB.T6G(SCH_1):CLK_50M_NCSI_OCP_SFF_ISO_R    I29 @T6G_MB_LIB.T6G(SCH_1):PAGE337

R4602 Q_RES_0402LF-0,5%,1/16W,CHIP,CS00002JB13
     1 CLK_50M_NCSI_OCP_V3_2_ISO @T6G_MB_LIB.T6G(SCH_1):CLK_50M_NCSI_OCP_V3_2_ISO    I36 @T6G_MB_LIB.T6G(SCH_1):PAGE342
     2 CLK_50M_NCSI_OCP_V3_2_ISO_R @T6G_MB_LIB.T6G(SCH_1):CLK_50M_NCSI_OCP_V3_2_ISO_R    I36 @T6G_MB_LIB.T6G(SCH_1):PAGE342

R4603 Q_RES_0402LF-10K,1%,1/16W,CHIP,CS31002FB08
     1 SMB_BMC_GPU_EN @T6G_MB_LIB.T6G(SCH_1):SMB_BMC_GPU_EN    I23 @T6G_MB_LIB.T6G(SCH_1):PAGE249
     2    GND @T6G_MB_LIB.T6G(SCH_1):GND    I23 @T6G_MB_LIB.T6G(SCH_1):PAGE249

R4604 Q_RES_0402LF-4.7K,5%,1/16W,CHIP,CS24702JB10
     1 P3V3_AUX @T6G_MB_LIB.T6G(SCH_1):P3V3_AUX     I5 @T6G_MB_LIB.T6G(SCH_1):PAGE368
     2 PWRGD_PS_PWROK_PLD_N @T6G_MB_LIB.T6G(SCH_1):PWRGD_PS_PWROK_PLD_N     I5 @T6G_MB_LIB.T6G(SCH_1):PAGE368

R4605 Q_RES_0402LF-1K,1%,1/16W,CHIP,CS21002FB06
     1 P3V3_AUX @T6G_MB_LIB.T6G(SCH_1):P3V3_AUX    I11 @T6G_MB_LIB.T6G(SCH_1):PAGE368
     2 PWRGD_PS_PWROK_PLD_ISO @T6G_MB_LIB.T6G(SCH_1):PWRGD_PS_PWROK_PLD_ISO    I11 @T6G_MB_LIB.T6G(SCH_1):PAGE368

R4608 Q_RES_0402LF-33.2,1%,1/16W,CHIP,CS03322FB03
     1 GPU_FPGA_RST_R_N @T6G_MB_LIB.T6G(SCH_1):GPU_FPGA_RST_R_N   I295 @T6G_MB_LIB.T6G(SCH_1):PAGE80
     2 GPU_FPGA_RST_N @T6G_MB_LIB.T6G(SCH_1):GPU_FPGA_RST_N   I295 @T6G_MB_LIB.T6G(SCH_1):PAGE80

R4620 Q_RES_0402LF-1K,1%,1/16W,EMPTY,CS21002FB06
     1 P3V3_AUX @T6G_MB_LIB.T6G(SCH_1):P3V3_AUX    I46 @T6G_MB_LIB.T6G(SCH_1):PAGE372
     2 IRQ_UV_DETECT_N @T6G_MB_LIB.T6G(SCH_1):IRQ_UV_DETECT_N    I46 @T6G_MB_LIB.T6G(SCH_1):PAGE372

R4638 Q_RES_1206LF-243,1%,1/4W,CHIP,CS12436F201
     1    P5V @T6G_MB_LIB.T6G(SCH_1):P5V    I45 @T6G_MB_LIB.T6G(SCH_1):PAGE273
     2 VR_P5V_EN_D @T6G_MB_LIB.T6G(SCH_1):VR_P5V_EN_D    I45 @T6G_MB_LIB.T6G(SCH_1):PAGE273

R4639 Q_RES_1206LF-243,1%,1/4W,CHIP,CS12436F201
     1    P5V @T6G_MB_LIB.T6G(SCH_1):P5V    I74 @T6G_MB_LIB.T6G(SCH_1):PAGE273
     2 VR_P5V_EN_D @T6G_MB_LIB.T6G(SCH_1):VR_P5V_EN_D    I74 @T6G_MB_LIB.T6G(SCH_1):PAGE273

R4640 Q_RES_1206LF-243,1%,1/4W,CHIP,CS12436F201
     1    P5V @T6G_MB_LIB.T6G(SCH_1):P5V    I75 @T6G_MB_LIB.T6G(SCH_1):PAGE273
     2 VR_P5V_EN_D @T6G_MB_LIB.T6G(SCH_1):VR_P5V_EN_D    I75 @T6G_MB_LIB.T6G(SCH_1):PAGE273

R4641 Q_RES_1206LF-243,1%,1/4W,CHIP,CS12436F201
     1    P5V @T6G_MB_LIB.T6G(SCH_1):P5V    I76 @T6G_MB_LIB.T6G(SCH_1):PAGE273
     2 VR_P5V_EN_D @T6G_MB_LIB.T6G(SCH_1):VR_P5V_EN_D    I76 @T6G_MB_LIB.T6G(SCH_1):PAGE273

R4809 Q_RES_0402LF-0,5%,1/16W,CHIP,CS00002JB13
     1 TP_CHASI @T6G_MB_LIB.T6G(SCH_1):TP_CHASI   I220 @T6G_MB_LIB.T6G(SCH_1):PAGE348
     2    GND @T6G_MB_LIB.T6G(SCH_1):GND   I220 @T6G_MB_LIB.T6G(SCH_1):PAGE348

R4901 Q_RES_0402LF-82K,1%,1/16W,CHIP,CS38202FB01
     1 P12V_PSU_FUSE @T6G_MB_LIB.T6G(SCH_1):P12V_PSU_FUSE    I19 @T6G_MB_LIB.T6G(SCH_1):PAGE372
     2 HSC_EN @T6G_MB_LIB.T6G(SCH_1):HSC_EN    I19 @T6G_MB_LIB.T6G(SCH_1):PAGE372

R5004 Q_RES_0402LF-10K,1%,1/16W,CHIP,CS31002FB08
     1 SMB_APML_CPU1_R_SDA @T6G_MB_LIB.T6G(SCH_1):SMB_APML_CPU1_R_SDA    I27 @T6G_MB_LIB.T6G(SCH_1):PAGE138
     2    GND @T6G_MB_LIB.T6G(SCH_1):GND    I27 @T6G_MB_LIB.T6G(SCH_1):PAGE138

R5006 Q_RES_0402LF-1K,1%,1/16W,EMPTY,CS21002FB06
     1 PVDD11_S3_P0 @T6G_MB_LIB.T6G(SCH_1):PVDD11_S3_P0   I145 @T6G_MB_LIB.T6G(SCH_1):PAGE136
     2 I3C_SPD_DDRAF_CPU0_LVC1_SCL @T6G_MB_LIB.T6G(SCH_1):I3C_SPD_DDRAF_CPU0_LVC1_SCL   I145 @T6G_MB_LIB.T6G(SCH_1):PAGE136

R5007 Q_RES_0402LF-1K,1%,1/16W,EMPTY,CS21002FB06
     1 PVDD11_S3_P0 @T6G_MB_LIB.T6G(SCH_1):PVDD11_S3_P0   I147 @T6G_MB_LIB.T6G(SCH_1):PAGE136
     2 I3C_SPD_DDRAF_CPU0_LVC1_SDA @T6G_MB_LIB.T6G(SCH_1):I3C_SPD_DDRAF_CPU0_LVC1_SDA   I147 @T6G_MB_LIB.T6G(SCH_1):PAGE136

R5008 Q_RES_0402LF-1K,1%,1/16W,EMPTY,CS21002FB06
     1 PVDD11_S3_P0 @T6G_MB_LIB.T6G(SCH_1):PVDD11_S3_P0   I148 @T6G_MB_LIB.T6G(SCH_1):PAGE136
     2 I3C_SPD_DDRGL_CPU0_LVC1_SCL @T6G_MB_LIB.T6G(SCH_1):I3C_SPD_DDRGL_CPU0_LVC1_SCL   I148 @T6G_MB_LIB.T6G(SCH_1):PAGE136

R5009 Q_RES_0402LF-1K,1%,1/16W,EMPTY,CS21002FB06
     1 PVDD11_S3_P0 @T6G_MB_LIB.T6G(SCH_1):PVDD11_S3_P0   I150 @T6G_MB_LIB.T6G(SCH_1):PAGE136
     2 I3C_SPD_DDRGL_CPU0_LVC1_SDA @T6G_MB_LIB.T6G(SCH_1):I3C_SPD_DDRGL_CPU0_LVC1_SDA   I150 @T6G_MB_LIB.T6G(SCH_1):PAGE136

R5010 Q_RES_0402LF-1K,1%,1/16W,EMPTY,CS21002FB06
     1 PVDD11_S3_P1 @T6G_MB_LIB.T6G(SCH_1):PVDD11_S3_P1   I151 @T6G_MB_LIB.T6G(SCH_1):PAGE136
     2 I3C_SPD_DDRAF_CPU1_LVC1_SCL @T6G_MB_LIB.T6G(SCH_1):I3C_SPD_DDRAF_CPU1_LVC1_SCL   I151 @T6G_MB_LIB.T6G(SCH_1):PAGE136

R5011 Q_RES_0402LF-1K,1%,1/16W,EMPTY,CS21002FB06
     1 PVDD11_S3_P1 @T6G_MB_LIB.T6G(SCH_1):PVDD11_S3_P1   I152 @T6G_MB_LIB.T6G(SCH_1):PAGE136
     2 I3C_SPD_DDRAF_CPU1_LVC1_SDA @T6G_MB_LIB.T6G(SCH_1):I3C_SPD_DDRAF_CPU1_LVC1_SDA   I152 @T6G_MB_LIB.T6G(SCH_1):PAGE136

R5012 Q_RES_0402LF-1K,1%,1/16W,EMPTY,CS21002FB06
     1 PVDD11_S3_P1 @T6G_MB_LIB.T6G(SCH_1):PVDD11_S3_P1   I156 @T6G_MB_LIB.T6G(SCH_1):PAGE136
     2 I3C_SPD_DDRGL_CPU1_LVC1_SCL @T6G_MB_LIB.T6G(SCH_1):I3C_SPD_DDRGL_CPU1_LVC1_SCL   I156 @T6G_MB_LIB.T6G(SCH_1):PAGE136

R5013 Q_RES_0402LF-1K,1%,1/16W,EMPTY,CS21002FB06
     1 PVDD11_S3_P1 @T6G_MB_LIB.T6G(SCH_1):PVDD11_S3_P1   I154 @T6G_MB_LIB.T6G(SCH_1):PAGE136
     2 I3C_SPD_DDRGL_CPU1_LVC1_SDA @T6G_MB_LIB.T6G(SCH_1):I3C_SPD_DDRGL_CPU1_LVC1_SDA   I154 @T6G_MB_LIB.T6G(SCH_1):PAGE136

R5014 Q_RES_0402LF-1K,1%,1/16W,EMPTY,CS21002FB06
     1 PVDD11_S3_P0 @T6G_MB_LIB.T6G(SCH_1):PVDD11_S3_P0   I159 @T6G_MB_LIB.T6G(SCH_1):PAGE136
     2 I3C_SCM_0_R_SCL @T6G_MB_LIB.T6G(SCH_1):I3C_SCM_0_R_SCL   I159 @T6G_MB_LIB.T6G(SCH_1):PAGE136

R5015 Q_RES_0402LF-1K,1%,1/16W,EMPTY,CS21002FB06
     1 PVDD11_S3_P0 @T6G_MB_LIB.T6G(SCH_1):PVDD11_S3_P0   I157 @T6G_MB_LIB.T6G(SCH_1):PAGE136
     2 I3C_SCM_0_R_SDA @T6G_MB_LIB.T6G(SCH_1):I3C_SCM_0_R_SDA   I157 @T6G_MB_LIB.T6G(SCH_1):PAGE136

R5016 Q_RES_0402LF-1K,1%,1/16W,EMPTY,CS21002FB06
     1 PVDD11_S3_P0 @T6G_MB_LIB.T6G(SCH_1):PVDD11_S3_P0   I162 @T6G_MB_LIB.T6G(SCH_1):PAGE136
     2 I3C_SCM_1_R_SCL @T6G_MB_LIB.T6G(SCH_1):I3C_SCM_1_R_SCL   I162 @T6G_MB_LIB.T6G(SCH_1):PAGE136

R5017 Q_RES_0402LF-1K,1%,1/16W,EMPTY,CS21002FB06
     1 PVDD11_S3_P0 @T6G_MB_LIB.T6G(SCH_1):PVDD11_S3_P0   I161 @T6G_MB_LIB.T6G(SCH_1):PAGE136
     2 I3C_SCM_1_R_SDA @T6G_MB_LIB.T6G(SCH_1):I3C_SCM_1_R_SDA   I161 @T6G_MB_LIB.T6G(SCH_1):PAGE136

R5018 Q_RES_0402LF-1K,1%,1/16W,EMPTY,CS21002FB06
     1 PVDD11_S3_P1 @T6G_MB_LIB.T6G(SCH_1):PVDD11_S3_P1   I163 @T6G_MB_LIB.T6G(SCH_1):PAGE136
     2 I3C_SCM_2_R_SCL @T6G_MB_LIB.T6G(SCH_1):I3C_SCM_2_R_SCL   I163 @T6G_MB_LIB.T6G(SCH_1):PAGE136

R5019 Q_RES_0402LF-1K,1%,1/16W,EMPTY,CS21002FB06
     1 PVDD11_S3_P1 @T6G_MB_LIB.T6G(SCH_1):PVDD11_S3_P1   I164 @T6G_MB_LIB.T6G(SCH_1):PAGE136
     2 I3C_SCM_2_R_SDA @T6G_MB_LIB.T6G(SCH_1):I3C_SCM_2_R_SDA   I164 @T6G_MB_LIB.T6G(SCH_1):PAGE136

R5020 Q_RES_0402LF-1K,1%,1/16W,EMPTY,CS21002FB06
     1 PVDD11_S3_P1 @T6G_MB_LIB.T6G(SCH_1):PVDD11_S3_P1   I167 @T6G_MB_LIB.T6G(SCH_1):PAGE136
     2 I3C_SCM_3_R_SCL @T6G_MB_LIB.T6G(SCH_1):I3C_SCM_3_R_SCL   I167 @T6G_MB_LIB.T6G(SCH_1):PAGE136

R5021 Q_RES_0402LF-1K,1%,1/16W,EMPTY,CS21002FB06
     1 PVDD11_S3_P1 @T6G_MB_LIB.T6G(SCH_1):PVDD11_S3_P1   I166 @T6G_MB_LIB.T6G(SCH_1):PAGE136
     2 I3C_SCM_3_R_SDA @T6G_MB_LIB.T6G(SCH_1):I3C_SCM_3_R_SDA   I166 @T6G_MB_LIB.T6G(SCH_1):PAGE136

R5026 Q_RES_0402LF-4.7K,5%,1/16W,EMPTY,CS24702JB10
     1    GND @T6G_MB_LIB.T6G(SCH_1):GND    I40 @T6G_MB_LIB.T6G(SCH_1):PAGE28
     2 FM_SMM_CRASHDUMP @T6G_MB_LIB.T6G(SCH_1):FM_SMM_CRASHDUMP    I40 @T6G_MB_LIB.T6G(SCH_1):PAGE28

R5027 Q_RES_0402LF-4.7K,5%,1/16W,EMPTY,CS24702JB10
     1    GND @T6G_MB_LIB.T6G(SCH_1):GND    I59 @T6G_MB_LIB.T6G(SCH_1):PAGE28
     2 IRQ_SMI_ACTIVE_N @T6G_MB_LIB.T6G(SCH_1):IRQ_SMI_ACTIVE_N    I59 @T6G_MB_LIB.T6G(SCH_1):PAGE28

R5028 Q_RES_0402LF-4.7K,5%,1/16W,EMPTY,CS24702JB10
     1    GND @T6G_MB_LIB.T6G(SCH_1):GND    I60 @T6G_MB_LIB.T6G(SCH_1):PAGE28
     2 IRQ_BMC_SMI_N @T6G_MB_LIB.T6G(SCH_1):IRQ_BMC_SMI_N    I60 @T6G_MB_LIB.T6G(SCH_1):PAGE28

R5029 Q_RES_0402LF-4.7K,5%,1/16W,EMPTY,CS24702JB10
     1    GND @T6G_MB_LIB.T6G(SCH_1):GND    I62 @T6G_MB_LIB.T6G(SCH_1):PAGE28
     2 IRQ_TPM_SPI_R_N @T6G_MB_LIB.T6G(SCH_1):IRQ_TPM_SPI_R_N    I62 @T6G_MB_LIB.T6G(SCH_1):PAGE28

R5030 Q_RES_0402LF-4.7K,5%,1/16W,EMPTY,CS24702JB10
     1    GND @T6G_MB_LIB.T6G(SCH_1):GND   I334 @T6G_MB_LIB.T6G(SCH_1):PAGE55
     2 FM_BMC_TPM_PRES_N @T6G_MB_LIB.T6G(SCH_1):FM_BMC_TPM_PRES_N   I334 @T6G_MB_LIB.T6G(SCH_1):PAGE55

R5031 Q_RES_0402LF-4.7K,5%,1/16W,EMPTY,CS24702JB10
     1    GND @T6G_MB_LIB.T6G(SCH_1):GND   I331 @T6G_MB_LIB.T6G(SCH_1):PAGE55
     2 FM_BMC_READY_N @T6G_MB_LIB.T6G(SCH_1):FM_BMC_READY_N   I331 @T6G_MB_LIB.T6G(SCH_1):PAGE55

R5032 Q_RES_0402LF-4.7K,5%,1/16W,EMPTY,CS24702JB10
     1    GND @T6G_MB_LIB.T6G(SCH_1):GND   I330 @T6G_MB_LIB.T6G(SCH_1):PAGE55
     2 IRQ_CPU_BMC_NMI_N @T6G_MB_LIB.T6G(SCH_1):IRQ_CPU_BMC_NMI_N   I330 @T6G_MB_LIB.T6G(SCH_1):PAGE55

R5051 Q_RES_0402LF-0,5%,1/16W,EMPTY,CS00002JB13
     1 P3V3_RTC_AUX @T6G_MB_LIB.T6G(SCH_1):P3V3_RTC_AUX   I101 @T6G_MB_LIB.T6G(SCH_1):PAGE156
     2 P1V5_BAT_IN @T6G_MB_LIB.T6G(SCH_1):P1V5_BAT_IN   I101 @T6G_MB_LIB.T6G(SCH_1):PAGE156

R5052 Q_RES_0402LF-0,5%,1/16W,CHIP,CS00002JB13
     1 P3V3_RTC_AUX_R @T6G_MB_LIB.T6G(SCH_1):P3V3_RTC_AUX_R   I100 @T6G_MB_LIB.T6G(SCH_1):PAGE156
     2 P3V3_RTC_AUX @T6G_MB_LIB.T6G(SCH_1):P3V3_RTC_AUX   I100 @T6G_MB_LIB.T6G(SCH_1):PAGE156

R5053 Q_RES_0402LF-1K,1%,1/16W,EMPTY,CS21002FB06
     1 P1V5_BAT_OUT @T6G_MB_LIB.T6G(SCH_1):P1V5_BAT_OUT   I120 @T6G_MB_LIB.T6G(SCH_1):PAGE156
     2 P1V5_BAT_OUT_R @T6G_MB_LIB.T6G(SCH_1):P1V5_BAT_OUT_R   I120 @T6G_MB_LIB.T6G(SCH_1):PAGE156

R5054 Q_RES_0402LF-0,5%,1/16W,CHIP,CS00002JB13
     1 P3V3_RTC_AUX_R @T6G_MB_LIB.T6G(SCH_1):P3V3_RTC_AUX_R   I122 @T6G_MB_LIB.T6G(SCH_1):PAGE156
     2 P1V5_BAT_OUT_R @T6G_MB_LIB.T6G(SCH_1):P1V5_BAT_OUT_R   I122 @T6G_MB_LIB.T6G(SCH_1):PAGE156

R5055 Q_RES_0402LF-10K,5%,1/16W,CHIP,CS31002JB08
     1 P1V5_BAT @T6G_MB_LIB.T6G(SCH_1):P1V5_BAT   I427 @T6G_MB_LIB.T6G(SCH_1):PAGE27
     2 CPU0_RTC_LDO_SELECT @T6G_MB_LIB.T6G(SCH_1):CPU0_RTC_LDO_SELECT   I427 @T6G_MB_LIB.T6G(SCH_1):PAGE27

R5056 Q_RES_0402LF-10K,5%,1/16W,EMPTY,CS31002JB08
     1 CPU0_RTC_LDO_SELECT @T6G_MB_LIB.T6G(SCH_1):CPU0_RTC_LDO_SELECT   I428 @T6G_MB_LIB.T6G(SCH_1):PAGE27
     2    GND @T6G_MB_LIB.T6G(SCH_1):GND   I428 @T6G_MB_LIB.T6G(SCH_1):PAGE27

R5071 Q_RES_0402LF-100,1%,1/16W,CHIP,CS11002FB07
     1 P1V8_AUX @T6G_MB_LIB.T6G(SCH_1):P1V8_AUX    I34 @T6G_MB_LIB.T6G(SCH_1):PAGE144
     2 FM_FORCE_ALL_PWRON_ON @T6G_MB_LIB.T6G(SCH_1):FM_FORCE_ALL_PWRON_ON    I34 @T6G_MB_LIB.T6G(SCH_1):PAGE144

R5099 Q_RES_0402LF-0,5%,1/16W,CHIP,CS00002JB13
     1 FPGA_DEBUG_SW_SPARE @T6G_MB_LIB.T6G(SCH_1):FPGA_DEBUG_SW_SPARE    I35 @T6G_MB_LIB.T6G(SCH_1):PAGE80
     2 FM_FPGA_DEBUG_SW_SPARE @T6G_MB_LIB.T6G(SCH_1):FM_FPGA_DEBUG_SW_SPARE    I35 @T6G_MB_LIB.T6G(SCH_1):PAGE80

R5101 Q_RES_0402LF-10K,5%,1/16W,CHIP,CS31002JB08
     1 P3V3_AUX @T6G_MB_LIB.T6G(SCH_1):P3V3_AUX    I97 @T6G_MB_LIB.T6G(SCH_1):PAGE156
     2 P3V3_STBY_R @T6G_MB_LIB.T6G(SCH_1):P3V3_STBY_R    I97 @T6G_MB_LIB.T6G(SCH_1):PAGE156

R5102 Q_RES_0402LF-49.9,1%,1/16W,CHIP,CS04992FB07
     1 XTAL_CPU0_X48M_X2 @T6G_MB_LIB.T6G(SCH_1):XTAL_CPU0_X48M_X2   I195 @T6G_MB_LIB.T6G(SCH_1):PAGE28
     2 XTAL_CPU0_X48M_X2_R @T6G_MB_LIB.T6G(SCH_1):XTAL_CPU0_X48M_X2_R   I195 @T6G_MB_LIB.T6G(SCH_1):PAGE28

R5103 Q_RES_0402LF-49.9,1%,1/16W,CHIP,CS04992FB07
     1 XTAL_CPU1_X48M_X2 @T6G_MB_LIB.T6G(SCH_1):XTAL_CPU1_X48M_X2   I386 @T6G_MB_LIB.T6G(SCH_1):PAGE55
     2 XTAL_CPU1_X48M_X2_R @T6G_MB_LIB.T6G(SCH_1):XTAL_CPU1_X48M_X2_R   I386 @T6G_MB_LIB.T6G(SCH_1):PAGE55

R5234 Q_RES_0402LF-0,5%,1/16W,CHIP,CS00002JB13
     1 USB2_HUB_BUF_SWB_R_DP @T6G_MB_LIB.T6G(SCH_1):USB2_HUB_BUF_SWB_R_DP    I91 @T6G_MB_LIB.T6G(SCH_1):PAGE358
     2 USB2_HUB_BUF_SWB_DP @T6G_MB_LIB.T6G(SCH_1):USB2_HUB_BUF_SWB_DP    I91 @T6G_MB_LIB.T6G(SCH_1):PAGE358

R5236 Q_RES_0402LF-0,5%,1/16W,CHIP,CS00002JB13
     1 USB2_HUB_BUF_SWB_R_DN @T6G_MB_LIB.T6G(SCH_1):USB2_HUB_BUF_SWB_R_DN    I90 @T6G_MB_LIB.T6G(SCH_1):PAGE358
     2 USB2_HUB_BUF_SWB_DN @T6G_MB_LIB.T6G(SCH_1):USB2_HUB_BUF_SWB_DN    I90 @T6G_MB_LIB.T6G(SCH_1):PAGE358

R5238 Q_RES_0402LF-3.9K,5%,1/16W,EMPTY,CS23902JB04
     1 PD_U5201_EQ @T6G_MB_LIB.T6G(SCH_1):PD_U5201_EQ    I83 @T6G_MB_LIB.T6G(SCH_1):PAGE358
     2    GND @T6G_MB_LIB.T6G(SCH_1):GND    I83 @T6G_MB_LIB.T6G(SCH_1):PAGE358

R5377 Q_RES_0402LF-0,5%,1/16W,CHIP,CS00002JB13
     1 HDD_ACTIVITY_BUF_N @T6G_MB_LIB.T6G(SCH_1):HDD_ACTIVITY_BUF_N    I62 @T6G_MB_LIB.T6G(SCH_1):PAGE345
     2 PU_BUFFER_HDD_ACTIVITY @T6G_MB_LIB.T6G(SCH_1):PU_BUFFER_HDD_ACTIVITY    I62 @T6G_MB_LIB.T6G(SCH_1):PAGE345

R5487 Q_RES_0402LF-0,5%,1/16W,EMPTY,CS00002JB13
     1 P3V3_OCP_SFF_EN_R @T6G_MB_LIB.T6G(SCH_1):P3V3_OCP_SFF_EN_R   I126 @T6G_MB_LIB.T6G(SCH_1):PAGE338
     2 P3V3_OCP_EN_1_R @T6G_MB_LIB.T6G(SCH_1):P3V3_OCP_EN_1_R   I126 @T6G_MB_LIB.T6G(SCH_1):PAGE338

R6000 Q_RES_0402LF-0,5%,1/16W,CHIP,CS00002JB13
     1 I3C_SCM_0_SCL @T6G_MB_LIB.T6G(SCH_1):I3C_SCM_0_SCL   I123 @T6G_MB_LIB.T6G(SCH_1):PAGE348
     2 I3C_SCM_0_R_SCL @T6G_MB_LIB.T6G(SCH_1):I3C_SCM_0_R_SCL   I123 @T6G_MB_LIB.T6G(SCH_1):PAGE348

R6001 Q_RES_0402LF-0,5%,1/16W,CHIP,CS00002JB13
     1 I3C_SCM_0_SDA @T6G_MB_LIB.T6G(SCH_1):I3C_SCM_0_SDA   I124 @T6G_MB_LIB.T6G(SCH_1):PAGE348
     2 I3C_SCM_0_R_SDA @T6G_MB_LIB.T6G(SCH_1):I3C_SCM_0_R_SDA   I124 @T6G_MB_LIB.T6G(SCH_1):PAGE348

R6002 Q_RES_0402LF-0,5%,1/16W,CHIP,CS00002JB13
     1 I3C_SCM_1_SCL @T6G_MB_LIB.T6G(SCH_1):I3C_SCM_1_SCL   I122 @T6G_MB_LIB.T6G(SCH_1):PAGE348
     2 I3C_SCM_1_R_SCL @T6G_MB_LIB.T6G(SCH_1):I3C_SCM_1_R_SCL   I122 @T6G_MB_LIB.T6G(SCH_1):PAGE348

R6003 Q_RES_0402LF-0,5%,1/16W,CHIP,CS00002JB13
     1 I3C_SCM_1_SDA @T6G_MB_LIB.T6G(SCH_1):I3C_SCM_1_SDA   I121 @T6G_MB_LIB.T6G(SCH_1):PAGE348
     2 I3C_SCM_1_R_SDA @T6G_MB_LIB.T6G(SCH_1):I3C_SCM_1_R_SDA   I121 @T6G_MB_LIB.T6G(SCH_1):PAGE348

R6004 Q_RES_0402LF-0,5%,1/16W,CHIP,CS00002JB13
     1 I3C_SCM_2_SCL @T6G_MB_LIB.T6G(SCH_1):I3C_SCM_2_SCL   I120 @T6G_MB_LIB.T6G(SCH_1):PAGE348
     2 I3C_SCM_2_R_SCL @T6G_MB_LIB.T6G(SCH_1):I3C_SCM_2_R_SCL   I120 @T6G_MB_LIB.T6G(SCH_1):PAGE348

R6005 Q_RES_0402LF-0,5%,1/16W,CHIP,CS00002JB13
     1 I3C_SCM_2_SDA @T6G_MB_LIB.T6G(SCH_1):I3C_SCM_2_SDA   I118 @T6G_MB_LIB.T6G(SCH_1):PAGE348
     2 I3C_SCM_2_R_SDA @T6G_MB_LIB.T6G(SCH_1):I3C_SCM_2_R_SDA   I118 @T6G_MB_LIB.T6G(SCH_1):PAGE348

R6006 Q_RES_0402LF-0,5%,1/16W,CHIP,CS00002JB13
     1 I3C_SCM_3_SCL @T6G_MB_LIB.T6G(SCH_1):I3C_SCM_3_SCL   I117 @T6G_MB_LIB.T6G(SCH_1):PAGE348
     2 I3C_SCM_3_R_SCL @T6G_MB_LIB.T6G(SCH_1):I3C_SCM_3_R_SCL   I117 @T6G_MB_LIB.T6G(SCH_1):PAGE348

R6007 Q_RES_0402LF-0,5%,1/16W,CHIP,CS00002JB13
     1 I3C_SCM_3_SDA @T6G_MB_LIB.T6G(SCH_1):I3C_SCM_3_SDA   I119 @T6G_MB_LIB.T6G(SCH_1):PAGE348
     2 I3C_SCM_3_R_SDA @T6G_MB_LIB.T6G(SCH_1):I3C_SCM_3_R_SDA   I119 @T6G_MB_LIB.T6G(SCH_1):PAGE348

R6008 Q_RES_0402LF-0,5%,1/16W,CHIP,CS00002JB13
     1 SGPIO_SCM_DO_<0> @T6G_MB_LIB.T6G(SCH_1):SGPIO_SCM_DO_(0)   I135 @T6G_MB_LIB.T6G(SCH_1):PAGE348
     2 SGPIO_SCM_DO_R_<0> @T6G_MB_LIB.T6G(SCH_1):SGPIO_SCM_DO_R_(0)   I135 @T6G_MB_LIB.T6G(SCH_1):PAGE348

R6009 Q_RES_0402LF-0,5%,1/16W,CHIP,CS00002JB13
     1 SGPIO_SCM_CLK_<0> @T6G_MB_LIB.T6G(SCH_1):SGPIO_SCM_CLK_(0)   I134 @T6G_MB_LIB.T6G(SCH_1):PAGE348
     2 SGPIO_SCM_CLK_R_<0> @T6G_MB_LIB.T6G(SCH_1):SGPIO_SCM_CLK_R_(0)   I134 @T6G_MB_LIB.T6G(SCH_1):PAGE348

R6010 Q_RES_0402LF-0,5%,1/16W,CHIP,CS00002JB13
     1 SGPIO_SCM_DI_<0> @T6G_MB_LIB.T6G(SCH_1):SGPIO_SCM_DI_(0)   I133 @T6G_MB_LIB.T6G(SCH_1):PAGE348
     2 SGPIO_SCM_DI_R_<0> @T6G_MB_LIB.T6G(SCH_1):SGPIO_SCM_DI_R_(0)   I133 @T6G_MB_LIB.T6G(SCH_1):PAGE348

R6011 Q_RES_0402LF-0,5%,1/16W,CHIP,CS00002JB13
     1 SGPIO_SCM_LD_<0> @T6G_MB_LIB.T6G(SCH_1):SGPIO_SCM_LD_(0)   I132 @T6G_MB_LIB.T6G(SCH_1):PAGE348
     2 SGPIO_SCM_LD_R_<0> @T6G_MB_LIB.T6G(SCH_1):SGPIO_SCM_LD_R_(0)   I132 @T6G_MB_LIB.T6G(SCH_1):PAGE348

R6012 Q_RES_0402LF-0,5%,1/16W,CHIP,CS00002JB13
     1 SGPIO_SCM_DO_<1> @T6G_MB_LIB.T6G(SCH_1):SGPIO_SCM_DO_(1)   I131 @T6G_MB_LIB.T6G(SCH_1):PAGE348
     2 SGPIO_SCM_DO_R_<1> @T6G_MB_LIB.T6G(SCH_1):SGPIO_SCM_DO_R_(1)   I131 @T6G_MB_LIB.T6G(SCH_1):PAGE348

R6013 Q_RES_0402LF-0,5%,1/16W,CHIP,CS00002JB13
     1 SGPIO_SCM_CLK_<1> @T6G_MB_LIB.T6G(SCH_1):SGPIO_SCM_CLK_(1)   I130 @T6G_MB_LIB.T6G(SCH_1):PAGE348
     2 SGPIO_SCM_CLK_R_<1> @T6G_MB_LIB.T6G(SCH_1):SGPIO_SCM_CLK_R_(1)   I130 @T6G_MB_LIB.T6G(SCH_1):PAGE348

R6014 Q_RES_0402LF-0,5%,1/16W,CHIP,CS00002JB13
     1 SGPIO_SCM_DI_<1> @T6G_MB_LIB.T6G(SCH_1):SGPIO_SCM_DI_(1)   I128 @T6G_MB_LIB.T6G(SCH_1):PAGE348
     2 SGPIO_SCM_DI_R_<1> @T6G_MB_LIB.T6G(SCH_1):SGPIO_SCM_DI_R_(1)   I128 @T6G_MB_LIB.T6G(SCH_1):PAGE348

R6015 Q_RES_0402LF-0,5%,1/16W,CHIP,CS00002JB13
     1 SGPIO_SCM_LD_<1> @T6G_MB_LIB.T6G(SCH_1):SGPIO_SCM_LD_(1)   I129 @T6G_MB_LIB.T6G(SCH_1):PAGE348
     2 SGPIO_SCM_LD_R_<1> @T6G_MB_LIB.T6G(SCH_1):SGPIO_SCM_LD_R_(1)   I129 @T6G_MB_LIB.T6G(SCH_1):PAGE348

R6016 Q_RES_0402LF-2K,5%,1/16W,EMPTY,TMP_QCS22002JB29
     1 P3V3_AUX @T6G_MB_LIB.T6G(SCH_1):P3V3_AUX    I29 @T6G_MB_LIB.T6G(SCH_1):PAGE349
     2 SGPIO_SCM_DO_<0> @T6G_MB_LIB.T6G(SCH_1):SGPIO_SCM_DO_(0)    I29 @T6G_MB_LIB.T6G(SCH_1):PAGE349

R6017 Q_RES_0402LF-2K,5%,1/16W,EMPTY,TMP_QCS22002JB29
     1 P3V3_AUX @T6G_MB_LIB.T6G(SCH_1):P3V3_AUX    I28 @T6G_MB_LIB.T6G(SCH_1):PAGE349
     2 SGPIO_SCM_CLK_<0> @T6G_MB_LIB.T6G(SCH_1):SGPIO_SCM_CLK_(0)    I28 @T6G_MB_LIB.T6G(SCH_1):PAGE349

R6018 Q_RES_0402LF-2K,5%,1/16W,EMPTY,TMP_QCS22002JB29
     1 P3V3_AUX @T6G_MB_LIB.T6G(SCH_1):P3V3_AUX    I27 @T6G_MB_LIB.T6G(SCH_1):PAGE349
     2 SGPIO_SCM_DI_<0> @T6G_MB_LIB.T6G(SCH_1):SGPIO_SCM_DI_(0)    I27 @T6G_MB_LIB.T6G(SCH_1):PAGE349

R6019 Q_RES_0402LF-2K,5%,1/16W,EMPTY,TMP_QCS22002JB29
     1 P3V3_AUX @T6G_MB_LIB.T6G(SCH_1):P3V3_AUX    I25 @T6G_MB_LIB.T6G(SCH_1):PAGE349
     2 SGPIO_SCM_LD_<0> @T6G_MB_LIB.T6G(SCH_1):SGPIO_SCM_LD_(0)    I25 @T6G_MB_LIB.T6G(SCH_1):PAGE349

R6020 Q_RES_0402LF-2K,5%,1/16W,EMPTY,TMP_QCS22002JB29
     1 P3V3_AUX @T6G_MB_LIB.T6G(SCH_1):P3V3_AUX    I24 @T6G_MB_LIB.T6G(SCH_1):PAGE349
     2 SGPIO_SCM_DO_<1> @T6G_MB_LIB.T6G(SCH_1):SGPIO_SCM_DO_(1)    I24 @T6G_MB_LIB.T6G(SCH_1):PAGE349

R6021 Q_RES_0402LF-2K,5%,1/16W,EMPTY,TMP_QCS22002JB29
     1 P3V3_AUX @T6G_MB_LIB.T6G(SCH_1):P3V3_AUX    I22 @T6G_MB_LIB.T6G(SCH_1):PAGE349
     2 SGPIO_SCM_CLK_<1> @T6G_MB_LIB.T6G(SCH_1):SGPIO_SCM_CLK_(1)    I22 @T6G_MB_LIB.T6G(SCH_1):PAGE349

R6022 Q_RES_0402LF-2K,5%,1/16W,EMPTY,TMP_QCS22002JB29
     1 P3V3_AUX @T6G_MB_LIB.T6G(SCH_1):P3V3_AUX    I23 @T6G_MB_LIB.T6G(SCH_1):PAGE349
     2 SGPIO_SCM_DI_<1> @T6G_MB_LIB.T6G(SCH_1):SGPIO_SCM_DI_(1)    I23 @T6G_MB_LIB.T6G(SCH_1):PAGE349

R6023 Q_RES_0402LF-2K,5%,1/16W,EMPTY,TMP_QCS22002JB29
     1 P3V3_AUX @T6G_MB_LIB.T6G(SCH_1):P3V3_AUX    I21 @T6G_MB_LIB.T6G(SCH_1):PAGE349
     2 SGPIO_SCM_LD_<1> @T6G_MB_LIB.T6G(SCH_1):SGPIO_SCM_LD_(1)    I21 @T6G_MB_LIB.T6G(SCH_1):PAGE349

R6024 Q_RES_0402LF-4.7K,5%,1/16W,EMPTY,CS24702JB10
     1 P3V3_AUX @T6G_MB_LIB.T6G(SCH_1):P3V3_AUX    I20 @T6G_MB_LIB.T6G(SCH_1):PAGE349
     2 SGPIO_SCM_INTR_N @T6G_MB_LIB.T6G(SCH_1):SGPIO_SCM_INTR_N    I20 @T6G_MB_LIB.T6G(SCH_1):PAGE349

R6025 Q_RES_0402LF-0,5%,1/16W,CHIP,CS00002JB13
     1 SGPIO_SCM_RESET_N @T6G_MB_LIB.T6G(SCH_1):SGPIO_SCM_RESET_N    I43 @T6G_MB_LIB.T6G(SCH_1):PAGE348
     2 SGPIO_SCM_RESET_R_N @T6G_MB_LIB.T6G(SCH_1):SGPIO_SCM_RESET_R_N    I43 @T6G_MB_LIB.T6G(SCH_1):PAGE348

R6026 Q_RES_0402LF-0,5%,1/16W,CHIP,CS00002JB13
     1 SGPIO_SCM_INTR_N @T6G_MB_LIB.T6G(SCH_1):SGPIO_SCM_INTR_N    I42 @T6G_MB_LIB.T6G(SCH_1):PAGE348
     2 SGPIO_SCM_INTR_R1_N @T6G_MB_LIB.T6G(SCH_1):SGPIO_SCM_INTR_R1_N    I42 @T6G_MB_LIB.T6G(SCH_1):PAGE348

R6027 Q_RES_0402LF-4.7K,5%,1/16W,EMPTY,CS24702JB10
     1 SGPIO_SCM_RESET_N @T6G_MB_LIB.T6G(SCH_1):SGPIO_SCM_RESET_N    I32 @T6G_MB_LIB.T6G(SCH_1):PAGE349
     2    GND @T6G_MB_LIB.T6G(SCH_1):GND    I32 @T6G_MB_LIB.T6G(SCH_1):PAGE349

R6028 Q_RES_0402LF-0,5%,1/16W,CHIP,CS00002JB13
     1 FM_LPC_ESPI_SEL @T6G_MB_LIB.T6G(SCH_1):FM_LPC_ESPI_SEL   I174 @T6G_MB_LIB.T6G(SCH_1):PAGE348
     2    GND @T6G_MB_LIB.T6G(SCH_1):GND   I174 @T6G_MB_LIB.T6G(SCH_1):PAGE348

R6029 Q_RES_0402LF-33,5%,1/16W,CHIP,CS03302JB10
     1 CLK_GEN2_BMC_RC_OE_N @T6G_MB_LIB.T6G(SCH_1):CLK_GEN2_BMC_RC_OE_N    I65 @T6G_MB_LIB.T6G(SCH_1):PAGE79
     2 CLK_GEN2_BMC_RC_OE_R_N @T6G_MB_LIB.T6G(SCH_1):CLK_GEN2_BMC_RC_OE_R_N    I65 @T6G_MB_LIB.T6G(SCH_1):PAGE79

R6030 Q_RES_0402LF-33,5%,1/16W,CHIP,CS03302JB10
     1 CLK_GEN2_GPU_FPGA_OE_N @T6G_MB_LIB.T6G(SCH_1):CLK_GEN2_GPU_FPGA_OE_N    I64 @T6G_MB_LIB.T6G(SCH_1):PAGE79
     2 CLK_GEN2_GPU_FPGA_OE_R_N @T6G_MB_LIB.T6G(SCH_1):CLK_GEN2_GPU_FPGA_OE_R_N    I64 @T6G_MB_LIB.T6G(SCH_1):PAGE79

R6031 Q_RES_0402LF-33,5%,1/16W,CHIP,CS03302JB10
     1 VIRTUAL_RESEAT_FPGA_N @T6G_MB_LIB.T6G(SCH_1):VIRTUAL_RESEAT_FPGA_N    I55 @T6G_MB_LIB.T6G(SCH_1):PAGE79
     2 VIRTUAL_RESEAT_FPGA_R_N @T6G_MB_LIB.T6G(SCH_1):VIRTUAL_RESEAT_FPGA_R_N    I55 @T6G_MB_LIB.T6G(SCH_1):PAGE79

R6032 Q_RES_0402LF-0,5%,1/16W,CHIP,CS00002JB13
     1 JTAG_SCM_DBREQ_N @T6G_MB_LIB.T6G(SCH_1):JTAG_SCM_DBREQ_N    I28 @T6G_MB_LIB.T6G(SCH_1):PAGE348
     2 SCM_HDT_DBREQ_N @T6G_MB_LIB.T6G(SCH_1):SCM_HDT_DBREQ_N    I28 @T6G_MB_LIB.T6G(SCH_1):PAGE348

R6033 Q_RES_0402LF-0,5%,1/16W,CHIP,CS00002JB13
     1 RST_MB_STBY_N @T6G_MB_LIB.T6G(SCH_1):RST_MB_STBY_N    I30 @T6G_MB_LIB.T6G(SCH_1):PAGE348
     2 RST_MB_STBY_R_N @T6G_MB_LIB.T6G(SCH_1):RST_MB_STBY_R_N    I30 @T6G_MB_LIB.T6G(SCH_1):PAGE348

R6034 Q_RES_0402LF-1K,1%,1/16W,CHIP,CS21002FB06
     1 P3V3_AUX @T6G_MB_LIB.T6G(SCH_1):P3V3_AUX    I18 @T6G_MB_LIB.T6G(SCH_1):PAGE348
     2 SCM_ROT_CPU_RST_R_N @T6G_MB_LIB.T6G(SCH_1):SCM_ROT_CPU_RST_R_N    I18 @T6G_MB_LIB.T6G(SCH_1):PAGE348

R6035 Q_RES_0402LF-4.7K,5%,1/16W,EMPTY,CS24702JB10
     1 SCM_ROT_CPU_RST_R_N @T6G_MB_LIB.T6G(SCH_1):SCM_ROT_CPU_RST_R_N    I17 @T6G_MB_LIB.T6G(SCH_1):PAGE348
     2    GND @T6G_MB_LIB.T6G(SCH_1):GND    I17 @T6G_MB_LIB.T6G(SCH_1):PAGE348

R6036 Q_RES_0402LF-2K,1%,1/16W,EMPTY,CS22002FB07
     1 SMB_1_PLD_3V3AUX_SCL @T6G_MB_LIB.T6G(SCH_1):SMB_1_PLD_3V3AUX_SCL   I131 @T6G_MB_LIB.T6G(SCH_1):PAGE349
     2 P3V3_AUX @T6G_MB_LIB.T6G(SCH_1):P3V3_AUX   I131 @T6G_MB_LIB.T6G(SCH_1):PAGE349

R6037 Q_RES_0402LF-2K,1%,1/16W,EMPTY,CS22002FB07
     1 SMB_1_PLD_3V3AUX_SDA @T6G_MB_LIB.T6G(SCH_1):SMB_1_PLD_3V3AUX_SDA   I132 @T6G_MB_LIB.T6G(SCH_1):PAGE349
     2 P3V3_AUX @T6G_MB_LIB.T6G(SCH_1):P3V3_AUX   I132 @T6G_MB_LIB.T6G(SCH_1):PAGE349

R6038 Q_RES_0402LF-0,5%,1/16W,CHIP,CS00002JB13
     1 UV_ALERT_N @T6G_MB_LIB.T6G(SCH_1):UV_ALERT_N    I21 @T6G_MB_LIB.T6G(SCH_1):PAGE79
     2 IRQ_UV_DETECT_N @T6G_MB_LIB.T6G(SCH_1):IRQ_UV_DETECT_N    I21 @T6G_MB_LIB.T6G(SCH_1):PAGE79

R6039 Q_RES_0402LF-0,5%,1/16W,CHIP,CS00002JB13
     1 OC_ALERT_N @T6G_MB_LIB.T6G(SCH_1):OC_ALERT_N    I20 @T6G_MB_LIB.T6G(SCH_1):PAGE79
     2 HSC_D_OC @T6G_MB_LIB.T6G(SCH_1):HSC_D_OC    I20 @T6G_MB_LIB.T6G(SCH_1):PAGE79

R6040 Q_RES_0402LF-10K,5%,1/16W,CHIP,CS31002JB08
     1 P1V8_AUX @T6G_MB_LIB.T6G(SCH_1):P1V8_AUX    I70 @T6G_MB_LIB.T6G(SCH_1):PAGE144
     2 PU_FPGA_DEBUG_LED_CTRL @T6G_MB_LIB.T6G(SCH_1):PU_FPGA_DEBUG_LED_CTRL    I70 @T6G_MB_LIB.T6G(SCH_1):PAGE144

R6041 Q_RES_0402LF-100K,1%,1/16W,CHIP,CS41002FB09
     1    GND @T6G_MB_LIB.T6G(SCH_1):GND    I69 @T6G_MB_LIB.T6G(SCH_1):PAGE144
     2 FPGA_DEBUG_LED_CTRL @T6G_MB_LIB.T6G(SCH_1):FPGA_DEBUG_LED_CTRL    I69 @T6G_MB_LIB.T6G(SCH_1):PAGE144

R6042 Q_RES_0402LF-10K,5%,1/16W,CHIP,CS31002JB08
     1 P3V3_AUX @T6G_MB_LIB.T6G(SCH_1):P3V3_AUX    I62 @T6G_MB_LIB.T6G(SCH_1):PAGE144
     2 PU_FPGA_DEBUG_SW_SPARE @T6G_MB_LIB.T6G(SCH_1):PU_FPGA_DEBUG_SW_SPARE    I62 @T6G_MB_LIB.T6G(SCH_1):PAGE144

R6043 Q_RES_0402LF-100K,1%,1/16W,CHIP,CS41002FB09
     1    GND @T6G_MB_LIB.T6G(SCH_1):GND    I61 @T6G_MB_LIB.T6G(SCH_1):PAGE144
     2 FPGA_DEBUG_SW_SPARE @T6G_MB_LIB.T6G(SCH_1):FPGA_DEBUG_SW_SPARE    I61 @T6G_MB_LIB.T6G(SCH_1):PAGE144

R6044 Q_RES_0402LF-10K,5%,1/16W,CHIP,CS31002JB08
     1 FM_FORCE_ALL_PWRON @T6G_MB_LIB.T6G(SCH_1):FM_FORCE_ALL_PWRON    I33 @T6G_MB_LIB.T6G(SCH_1):PAGE144
     2    GND @T6G_MB_LIB.T6G(SCH_1):GND    I33 @T6G_MB_LIB.T6G(SCH_1):PAGE144

R6045 Q_RES_0402LF-4.7K,5%,1/16W,EMPTY,CS24702JB10
     1 P12V_OCP_EN_1_R @T6G_MB_LIB.T6G(SCH_1):P12V_OCP_EN_1_R   I130 @T6G_MB_LIB.T6G(SCH_1):PAGE338
     2    GND @T6G_MB_LIB.T6G(SCH_1):GND   I130 @T6G_MB_LIB.T6G(SCH_1):PAGE338

R6046 Q_RES_0402LF-100,1%,1/16W,CHIP,CS11002FB07
     1 HP_LVC3_OCP_SFF_PRSNT2_PLD_N @T6G_MB_LIB.T6G(SCH_1):HP_LVC3_OCP_SFF_PRSNT2_PLD_N    I64 @T6G_MB_LIB.T6G(SCH_1):PAGE80
     2 PRSNT_OCP_SFF_N @T6G_MB_LIB.T6G(SCH_1):PRSNT_OCP_SFF_N    I64 @T6G_MB_LIB.T6G(SCH_1):PAGE80

R6047 Q_RES_0402LF-0,5%,1/16W,CHIP,CS00002JB13
     1 PWRGD_P3V3_AUX @T6G_MB_LIB.T6G(SCH_1):PWRGD_P3V3_AUX    I34 @T6G_MB_LIB.T6G(SCH_1):PAGE80
     2 PWRGD_P3V3_AUX_R @T6G_MB_LIB.T6G(SCH_1):PWRGD_P3V3_AUX_R    I34 @T6G_MB_LIB.T6G(SCH_1):PAGE80

R6048 Q_RES_0402LF-0,5%,1/16W,CHIP,CS00002JB13
     1 HP_LVC3_E1S_0_HSC_PWRGD @T6G_MB_LIB.T6G(SCH_1):HP_LVC3_E1S_0_HSC_PWRGD    I28 @T6G_MB_LIB.T6G(SCH_1):PAGE80
     2 P12V_E1S_0_PWRGD @T6G_MB_LIB.T6G(SCH_1):P12V_E1S_0_PWRGD    I28 @T6G_MB_LIB.T6G(SCH_1):PAGE80

R6049 Q_RES_0402LF-4.7K,5%,1/16W,CHIP,CS24702JB10
     1 P3V3_E1S_EN_0_R @T6G_MB_LIB.T6G(SCH_1):P3V3_E1S_EN_0_R     I4 @T6G_MB_LIB.T6G(SCH_1):PAGE324
     2    GND @T6G_MB_LIB.T6G(SCH_1):GND     I4 @T6G_MB_LIB.T6G(SCH_1):PAGE324

R6050 Q_RES_0402LF-100K,1%,1/16W,EMPTY,CS41002FB09
     1 SW_P3V3_EN @T6G_MB_LIB.T6G(SCH_1):SW_P3V3_EN    I91 @T6G_MB_LIB.T6G(SCH_1):PAGE273
     2    GND @T6G_MB_LIB.T6G(SCH_1):GND    I91 @T6G_MB_LIB.T6G(SCH_1):PAGE273

R6051 Q_RES_0402LF-0,5%,1/16W,CHIP,CS00002JB13
     1 P12V_OCP_V3_1_PWRGD @T6G_MB_LIB.T6G(SCH_1):P12V_OCP_V3_1_PWRGD   I102 @T6G_MB_LIB.T6G(SCH_1):PAGE81
     2 P12V_OCP_V3_1_PLD_PWRGD @T6G_MB_LIB.T6G(SCH_1):P12V_OCP_V3_1_PLD_PWRGD   I102 @T6G_MB_LIB.T6G(SCH_1):PAGE81

R6052 Q_RES_0402LF-0,5%,1/16W,CHIP,CS00002JB13
     1 E1S_0_PRSNT_R_N @T6G_MB_LIB.T6G(SCH_1):E1S_0_PRSNT_R_N    I99 @T6G_MB_LIB.T6G(SCH_1):PAGE81
     2 E1S_0_PRSNT_N @T6G_MB_LIB.T6G(SCH_1):E1S_0_PRSNT_N    I99 @T6G_MB_LIB.T6G(SCH_1):PAGE81

R6053 Q_RES_0402LF-0,5%,1/16W,CHIP,CS00002JB13
     1 M2_SSD0_CLKREQ_EN_N @T6G_MB_LIB.T6G(SCH_1):M2_SSD0_CLKREQ_EN_N    I85 @T6G_MB_LIB.T6G(SCH_1):PAGE81
     2 FM_CLKREQ_M2_1_N @T6G_MB_LIB.T6G(SCH_1):FM_CLKREQ_M2_1_N    I85 @T6G_MB_LIB.T6G(SCH_1):PAGE81

R6054 Q_RES_0402LF-0,5%,1/16W,CHIP,CS00002JB13
     1 FM_OCP_SFF_PWR_GOOD @T6G_MB_LIB.T6G(SCH_1):FM_OCP_SFF_PWR_GOOD    I83 @T6G_MB_LIB.T6G(SCH_1):PAGE81
     2 PWRGD_OCP_SFF_PWR_GOOD @T6G_MB_LIB.T6G(SCH_1):PWRGD_OCP_SFF_PWR_GOOD    I83 @T6G_MB_LIB.T6G(SCH_1):PAGE81

R6055 Q_RES_0402LF-0,5%,1/16W,CHIP,CS00002JB13
     1 HP_LVC3_SCM_HSC_PWRGD @T6G_MB_LIB.T6G(SCH_1):HP_LVC3_SCM_HSC_PWRGD    I60 @T6G_MB_LIB.T6G(SCH_1):PAGE80
     2 P12V_SCM_PWRGD_R @T6G_MB_LIB.T6G(SCH_1):P12V_SCM_PWRGD_R    I60 @T6G_MB_LIB.T6G(SCH_1):PAGE80

R6056 Q_RES_0402LF-0,5%,1/16W,CHIP,CS00002JB13
     1 RST_PERST_OCP_V3_2_BUF2_N @T6G_MB_LIB.T6G(SCH_1):RST_PERST_OCP_V3_2_BUF2_N    I72 @T6G_MB_LIB.T6G(SCH_1):PAGE342
     2 RST_PERST0_OCP_V3_2_N @T6G_MB_LIB.T6G(SCH_1):RST_PERST0_OCP_V3_2_N    I72 @T6G_MB_LIB.T6G(SCH_1):PAGE342

R6057 Q_RES_0402LF-0,5%,1/16W,CHIP,CS00002JB13
     1 RST_PERST_OCP_V3_2_BUF2_N @T6G_MB_LIB.T6G(SCH_1):RST_PERST_OCP_V3_2_BUF2_N    I73 @T6G_MB_LIB.T6G(SCH_1):PAGE342
     2 RST_PERST1_OCP_V3_2_N @T6G_MB_LIB.T6G(SCH_1):RST_PERST1_OCP_V3_2_N    I73 @T6G_MB_LIB.T6G(SCH_1):PAGE342

R6058 Q_RES_0402LF-0,5%,1/16W,CHIP,CS00002JB13
     1 RST_PERST_OCP_V3_2_BUF2_N @T6G_MB_LIB.T6G(SCH_1):RST_PERST_OCP_V3_2_BUF2_N    I74 @T6G_MB_LIB.T6G(SCH_1):PAGE342
     2 RST_PERST2_OCP_V3_2_N @T6G_MB_LIB.T6G(SCH_1):RST_PERST2_OCP_V3_2_N    I74 @T6G_MB_LIB.T6G(SCH_1):PAGE342

R6059 Q_RES_0402LF-0,5%,1/16W,CHIP,CS00002JB13
     1 RST_PERST_OCP_V3_2_BUF2_N @T6G_MB_LIB.T6G(SCH_1):RST_PERST_OCP_V3_2_BUF2_N    I75 @T6G_MB_LIB.T6G(SCH_1):PAGE342
     2 RST_PERST3_OCP_V3_2_N @T6G_MB_LIB.T6G(SCH_1):RST_PERST3_OCP_V3_2_N    I75 @T6G_MB_LIB.T6G(SCH_1):PAGE342

R6060 Q_RES_0402LF-4.7K,5%,1/16W,EMPTY,CS24702JB10
     1 P12V_OCP_EN_2_R @T6G_MB_LIB.T6G(SCH_1):P12V_OCP_EN_2_R   I120 @T6G_MB_LIB.T6G(SCH_1):PAGE343
     2    GND @T6G_MB_LIB.T6G(SCH_1):GND   I120 @T6G_MB_LIB.T6G(SCH_1):PAGE343

R6061 Q_RES_0402LF-4.7K,5%,1/16W,EMPTY,CS24702JB10
     1 P12V_OCP_V3_2_EN_R @T6G_MB_LIB.T6G(SCH_1):P12V_OCP_V3_2_EN_R    I39 @T6G_MB_LIB.T6G(SCH_1):PAGE82
     2 P3V3_AUX @T6G_MB_LIB.T6G(SCH_1):P3V3_AUX    I39 @T6G_MB_LIB.T6G(SCH_1):PAGE82

R6062 Q_RES_0402LF-4.7K,5%,1/16W,EMPTY,CS24702JB10
     1 P3V3_OCP_V3_2_EN_R @T6G_MB_LIB.T6G(SCH_1):P3V3_OCP_V3_2_EN_R    I40 @T6G_MB_LIB.T6G(SCH_1):PAGE82
     2 P3V3_AUX @T6G_MB_LIB.T6G(SCH_1):P3V3_AUX    I40 @T6G_MB_LIB.T6G(SCH_1):PAGE82

R6063 Q_RES_0402LF-33,5%,1/16W,CHIP,CS03302JB10
     1 IRQ_OCP_V3_2_WAKE_BUF_N @T6G_MB_LIB.T6G(SCH_1):IRQ_OCP_V3_2_WAKE_BUF_N     I6 @T6G_MB_LIB.T6G(SCH_1):PAGE132
     2 IRQ_LVC3_WAKE_N @T6G_MB_LIB.T6G(SCH_1):IRQ_LVC3_WAKE_N     I6 @T6G_MB_LIB.T6G(SCH_1):PAGE132

R6064 Q_RES_0402LF-0,5%,1/16W,EMPTY,CS00002JB13
     1 UART_CPU0_SCM_LVC3_UART1_RX @T6G_MB_LIB.T6G(SCH_1):UART_CPU0_SCM_LVC3_UART1_RX   I177 @T6G_MB_LIB.T6G(SCH_1):PAGE348
     2 UART_CPU0_SCM_LVC3_UART1_R_RX @T6G_MB_LIB.T6G(SCH_1):UART_CPU0_SCM_LVC3_UART1_R_RX   I177 @T6G_MB_LIB.T6G(SCH_1):PAGE348

R6065 Q_RES_0402LF-0,5%,1/16W,EMPTY,CS00002JB13
     1 UART_CPU0_SCM_LVC3_UART1_R1_TX @T6G_MB_LIB.T6G(SCH_1):UART_CPU0_SCM_LVC3_UART1_R1_TX   I178 @T6G_MB_LIB.T6G(SCH_1):PAGE348
     2 UART_CPU0_SCM_LVC3_UART1_TX @T6G_MB_LIB.T6G(SCH_1):UART_CPU0_SCM_LVC3_UART1_TX   I178 @T6G_MB_LIB.T6G(SCH_1):PAGE348

R6066 Q_RES_0402LF-0,5%,1/16W,EMPTY,CS00002JB13
     1 JTAG_SCM_TDI_R @T6G_MB_LIB.T6G(SCH_1):JTAG_SCM_TDI_R   I150 @T6G_MB_LIB.T6G(SCH_1):PAGE349
     2 JTAG_SCM_TDI @T6G_MB_LIB.T6G(SCH_1):JTAG_SCM_TDI   I150 @T6G_MB_LIB.T6G(SCH_1):PAGE349

R6067 Q_RES_0402LF-0,5%,1/16W,CHIP,CS00002JB13
     1 JTAG_SCM_TDO_R @T6G_MB_LIB.T6G(SCH_1):JTAG_SCM_TDO_R   I159 @T6G_MB_LIB.T6G(SCH_1):PAGE349
     2 JTAG_SCM_TDI @T6G_MB_LIB.T6G(SCH_1):JTAG_SCM_TDI   I159 @T6G_MB_LIB.T6G(SCH_1):PAGE349

R6068 Q_RES_0402LF-0,5%,1/16W,EMPTY,CS00002JB13
     1 JTAG_SCM_TDO_R @T6G_MB_LIB.T6G(SCH_1):JTAG_SCM_TDO_R   I151 @T6G_MB_LIB.T6G(SCH_1):PAGE349
     2 JTAG_SCM_TDO @T6G_MB_LIB.T6G(SCH_1):JTAG_SCM_TDO   I151 @T6G_MB_LIB.T6G(SCH_1):PAGE349

R6069 Q_RES_0402LF-0,5%,1/16W,CHIP,CS00002JB13
     1 JTAG_SCM_TDI_R @T6G_MB_LIB.T6G(SCH_1):JTAG_SCM_TDI_R   I158 @T6G_MB_LIB.T6G(SCH_1):PAGE349
     2 JTAG_SCM_TDO @T6G_MB_LIB.T6G(SCH_1):JTAG_SCM_TDO   I158 @T6G_MB_LIB.T6G(SCH_1):PAGE349

R6070 Q_RES_0402LF-4.7K,5%,1/16W,EMPTY,CS24702JB10
     1 P3V3_AUX @T6G_MB_LIB.T6G(SCH_1):P3V3_AUX   I161 @T6G_MB_LIB.T6G(SCH_1):PAGE349
     2 JTAG_SCM_DBREQ_N @T6G_MB_LIB.T6G(SCH_1):JTAG_SCM_DBREQ_N   I161 @T6G_MB_LIB.T6G(SCH_1):PAGE349

R6071 Q_RES_0402LF-4.7K,5%,1/16W,EMPTY,CS24702JB10
     1 P3V3_AUX @T6G_MB_LIB.T6G(SCH_1):P3V3_AUX   I214 @T6G_MB_LIB.T6G(SCH_1):PAGE348
     2 PU_JTAG_DBP_BMC_PRDY_N @T6G_MB_LIB.T6G(SCH_1):PU_JTAG_DBP_BMC_PRDY_N   I214 @T6G_MB_LIB.T6G(SCH_1):PAGE348

R6073 Q_RES_0402LF-0,5%,1/16W,CHIP,CS00002JB13
     1 FM_PDB_BUF_EN_R_N @T6G_MB_LIB.T6G(SCH_1):FM_PDB_BUF_EN_R_N   I146 @T6G_MB_LIB.T6G(SCH_1):PAGE81
     2 FM_PDB_BUF_EN_N @T6G_MB_LIB.T6G(SCH_1):FM_PDB_BUF_EN_N   I146 @T6G_MB_LIB.T6G(SCH_1):PAGE81

R6074 Q_RES_0402LF-0,5%,1/16W,CHIP,CS00002JB13
     1 FM_THERMAL_ALERT_N @T6G_MB_LIB.T6G(SCH_1):FM_THERMAL_ALERT_N    I53 @T6G_MB_LIB.T6G(SCH_1):PAGE84
     2 FM_THERMAL_ALERT_R_N @T6G_MB_LIB.T6G(SCH_1):FM_THERMAL_ALERT_R_N    I53 @T6G_MB_LIB.T6G(SCH_1):PAGE84

R6075 Q_RES_0402LF-0,5%,1/16W,CHIP,CS00002JB13
     1 LED_HDD_ACTIVITY_B_N @T6G_MB_LIB.T6G(SCH_1):LED_HDD_ACTIVITY_B_N    I57 @T6G_MB_LIB.T6G(SCH_1):PAGE84
     2 LED_HDD_ACTIVITY_B_PLD_N @T6G_MB_LIB.T6G(SCH_1):LED_HDD_ACTIVITY_B_PLD_N    I57 @T6G_MB_LIB.T6G(SCH_1):PAGE84

R6076 Q_RES_0402LF-33,5%,1/16W,CHIP,CS03302JB10
     1 SMB_SCM_2_R3_SCL @T6G_MB_LIB.T6G(SCH_1):SMB_SCM_2_R3_SCL   I181 @T6G_MB_LIB.T6G(SCH_1):PAGE349
     2 SMB_SCM_2_R4_SCL @T6G_MB_LIB.T6G(SCH_1):SMB_SCM_2_R4_SCL   I181 @T6G_MB_LIB.T6G(SCH_1):PAGE349

R6077 Q_RES_0402LF-33,5%,1/16W,CHIP,CS03302JB10
     1 SMB_SCM_2_R3_SDA @T6G_MB_LIB.T6G(SCH_1):SMB_SCM_2_R3_SDA   I182 @T6G_MB_LIB.T6G(SCH_1):PAGE349
     2 SMB_SCM_2_R4_SDA @T6G_MB_LIB.T6G(SCH_1):SMB_SCM_2_R4_SDA   I182 @T6G_MB_LIB.T6G(SCH_1):PAGE349

R6078 Q_RES_0402LF-0,5%,1/16W,CHIP,CS00002JB13
     1 PWRGD_P3V3_AUX @T6G_MB_LIB.T6G(SCH_1):PWRGD_P3V3_AUX    I61 @T6G_MB_LIB.T6G(SCH_1):PAGE84
     2 PWRGD_P3V3_AUX_PDB @T6G_MB_LIB.T6G(SCH_1):PWRGD_P3V3_AUX_PDB    I61 @T6G_MB_LIB.T6G(SCH_1):PAGE84

R6081 Q_RES_0402LF-4.7K,5%,1/16W,CHIP,CS24702JB10
     1 PVDD11_S3_P0 @T6G_MB_LIB.T6G(SCH_1):PVDD11_S3_P0   I210 @T6G_MB_LIB.T6G(SCH_1):PAGE28
     2 SMB_CPU0_2_SCL @T6G_MB_LIB.T6G(SCH_1):SMB_CPU0_2_SCL   I210 @T6G_MB_LIB.T6G(SCH_1):PAGE28

R6082 Q_RES_0402LF-4.7K,5%,1/16W,CHIP,CS24702JB10
     1 PVDD11_S3_P0 @T6G_MB_LIB.T6G(SCH_1):PVDD11_S3_P0   I212 @T6G_MB_LIB.T6G(SCH_1):PAGE28
     2 SMB_CPU0_2_SDA @T6G_MB_LIB.T6G(SCH_1):SMB_CPU0_2_SDA   I212 @T6G_MB_LIB.T6G(SCH_1):PAGE28

R6083 Q_RES_0402LF-4.7K,5%,1/16W,CHIP,CS24702JB10
     1 PVDD11_S3_P0 @T6G_MB_LIB.T6G(SCH_1):PVDD11_S3_P0   I213 @T6G_MB_LIB.T6G(SCH_1):PAGE28
     2 SMB_CPU0_3_SCL @T6G_MB_LIB.T6G(SCH_1):SMB_CPU0_3_SCL   I213 @T6G_MB_LIB.T6G(SCH_1):PAGE28

R6084 Q_RES_0402LF-4.7K,5%,1/16W,CHIP,CS24702JB10
     1 PVDD11_S3_P0 @T6G_MB_LIB.T6G(SCH_1):PVDD11_S3_P0   I214 @T6G_MB_LIB.T6G(SCH_1):PAGE28
     2 SMB_CPU0_3_SDA @T6G_MB_LIB.T6G(SCH_1):SMB_CPU0_3_SDA   I214 @T6G_MB_LIB.T6G(SCH_1):PAGE28

R6085 Q_RES_0402LF-10K,1%,1/16W,CHIP,CS31002FB08
     1 P3V3_AUX @T6G_MB_LIB.T6G(SCH_1):P3V3_AUX   I298 @T6G_MB_LIB.T6G(SCH_1):PAGE80
     2 PU_SPI_PLD_CS_N @T6G_MB_LIB.T6G(SCH_1):PU_SPI_PLD_CS_N   I298 @T6G_MB_LIB.T6G(SCH_1):PAGE80

R6086 Q_RES_0402LF-10K,1%,1/16W,EMPTY,CS31002FB08
     1 PVDDIO_P0_EN_R @T6G_MB_LIB.T6G(SCH_1):PVDDIO_P0_EN_R   I129 @T6G_MB_LIB.T6G(SCH_1):PAGE175
     2    GND @T6G_MB_LIB.T6G(SCH_1):GND   I129 @T6G_MB_LIB.T6G(SCH_1):PAGE175

R6087 Q_RES_0402LF-10K,1%,1/16W,EMPTY,CS31002FB08
     1 PVDDCR_SOC_P1_EN_RC @T6G_MB_LIB.T6G(SCH_1):PVDDCR_SOC_P1_EN_RC   I135 @T6G_MB_LIB.T6G(SCH_1):PAGE185
     2    GND @T6G_MB_LIB.T6G(SCH_1):GND   I135 @T6G_MB_LIB.T6G(SCH_1):PAGE185

R6088 Q_RES_0402LF-10K,1%,1/16W,EMPTY,CS31002FB08
     1 PVDDIO_P1_EN_R @T6G_MB_LIB.T6G(SCH_1):PVDDIO_P1_EN_R   I130 @T6G_MB_LIB.T6G(SCH_1):PAGE192
     2    GND @T6G_MB_LIB.T6G(SCH_1):GND   I130 @T6G_MB_LIB.T6G(SCH_1):PAGE192

R6089 Q_RES_0402LF-10K,1%,1/16W,EMPTY,CS31002FB08
     1 PVDDCR_SOC_P0_EN_RC @T6G_MB_LIB.T6G(SCH_1):PVDDCR_SOC_P0_EN_RC   I136 @T6G_MB_LIB.T6G(SCH_1):PAGE168
     2    GND @T6G_MB_LIB.T6G(SCH_1):GND   I136 @T6G_MB_LIB.T6G(SCH_1):PAGE168

R6090 Q_RES_0402LF-4.7K,5%,1/16W,CHIP,CS24702JB10
     1 JTAG_SCM_PLD_TCK @T6G_MB_LIB.T6G(SCH_1):JTAG_SCM_PLD_TCK    I77 @T6G_MB_LIB.T6G(SCH_1):PAGE84
     2    GND @T6G_MB_LIB.T6G(SCH_1):GND    I77 @T6G_MB_LIB.T6G(SCH_1):PAGE84

R6092 Q_RES_0402LF-0,5%,1/16W,CHIP,CS00002JB13
     1 SCM_SYS_PWROK_R @T6G_MB_LIB.T6G(SCH_1):SCM_SYS_PWROK_R    I82 @T6G_MB_LIB.T6G(SCH_1):PAGE84
     2 SCM_SYS_PWROK_R1 @T6G_MB_LIB.T6G(SCH_1):SCM_SYS_PWROK_R1    I82 @T6G_MB_LIB.T6G(SCH_1):PAGE84

R6093 Q_RES_0402LF-0,5%,1/16W,CHIP,CS00002JB13
     1 SCM_SYS_PWROK_R @T6G_MB_LIB.T6G(SCH_1):SCM_SYS_PWROK_R    I84 @T6G_MB_LIB.T6G(SCH_1):PAGE84
     2 SCM_SYS_PWROK_R2 @T6G_MB_LIB.T6G(SCH_1):SCM_SYS_PWROK_R2    I84 @T6G_MB_LIB.T6G(SCH_1):PAGE84

R6094 Q_RES_0402LF-0,5%,1/16W,EMPTY,CS00002JB13
     1 E1S_0_PERST1_CLKREQ_R_N @T6G_MB_LIB.T6G(SCH_1):E1S_0_PERST1_CLKREQ_R_N   I128 @T6G_MB_LIB.T6G(SCH_1):PAGE79
     2 E1S_0_PERST1_CLKREQ_N @T6G_MB_LIB.T6G(SCH_1):E1S_0_PERST1_CLKREQ_N   I128 @T6G_MB_LIB.T6G(SCH_1):PAGE79

R6095 Q_RES_0402LF-0,5%,1/16W,CHIP,CS00002JB13
     1 IRQ_HSC_FAULT_BUF_R_N @T6G_MB_LIB.T6G(SCH_1):IRQ_HSC_FAULT_BUF_R_N   I112 @T6G_MB_LIB.T6G(SCH_1):PAGE79
     2 IRQ_HSC_FAULT_BUF_N @T6G_MB_LIB.T6G(SCH_1):IRQ_HSC_FAULT_BUF_N   I112 @T6G_MB_LIB.T6G(SCH_1):PAGE79

R6096 Q_RES_0402LF-0,5%,1/16W,CHIP,CS00002JB13
     1 FM_UV_ADR_TRIGGER_R_N @T6G_MB_LIB.T6G(SCH_1):FM_UV_ADR_TRIGGER_R_N   I115 @T6G_MB_LIB.T6G(SCH_1):PAGE79
     2 FM_UV_ADR_TRIGGER_N @T6G_MB_LIB.T6G(SCH_1):FM_UV_ADR_TRIGGER_N   I115 @T6G_MB_LIB.T6G(SCH_1):PAGE79

R6097 Q_RES_0402LF-0,5%,1/16W,CHIP,CS00002JB13
     1 MB0_P12V_STBY_PWRGD @T6G_MB_LIB.T6G(SCH_1):MB0_P12V_STBY_PWRGD    I40 @T6G_MB_LIB.T6G(SCH_1):PAGE244
     2 P5V_AUX_EN @T6G_MB_LIB.T6G(SCH_1):P5V_AUX_EN    I40 @T6G_MB_LIB.T6G(SCH_1):PAGE244

R6098 Q_RES_0402LF-10K,5%,1/16W,EMPTY,CS31002JB08
     1    GND @T6G_MB_LIB.T6G(SCH_1):GND    I99 @T6G_MB_LIB.T6G(SCH_1):PAGE75
     2 SPI_CPU0_CLK @T6G_MB_LIB.T6G(SCH_1):SPI_CPU0_CLK    I99 @T6G_MB_LIB.T6G(SCH_1):PAGE75

R6099 Q_RES_0402LF-0,5%,1/16W,CHIP,CS00002JB13
     1 PWRGD_P3V3_AUX_R1 @T6G_MB_LIB.T6G(SCH_1):PWRGD_P3V3_AUX_R1    I67 @T6G_MB_LIB.T6G(SCH_1):PAGE245
     2 PWRGD_P3V3_AUX @T6G_MB_LIB.T6G(SCH_1):PWRGD_P3V3_AUX    I67 @T6G_MB_LIB.T6G(SCH_1):PAGE245

R6100 Q_RES_0402LF-49.9,1%,1/16W,CHIP,CS04992FB07
     1 FM_BIOS_POST_CMPLT_BUF_R1_N @T6G_MB_LIB.T6G(SCH_1):FM_BIOS_POST_CMPLT_BUF_R1_N   I125 @T6G_MB_LIB.T6G(SCH_1):PAGE34
     2 FM_BIOS_POST_CMPLT_BUF_N @T6G_MB_LIB.T6G(SCH_1):FM_BIOS_POST_CMPLT_BUF_N   I125 @T6G_MB_LIB.T6G(SCH_1):PAGE34

R6101 Q_RES_0402LF-0,5%,1/16W,CHIP,CS00002JB13
     1 SCM_JTAG_MUX_S0 @T6G_MB_LIB.T6G(SCH_1):SCM_JTAG_MUX_S0   I375 @T6G_MB_LIB.T6G(SCH_1):PAGE148
     2 SCM_JTAG_MUX_S0_R1 @T6G_MB_LIB.T6G(SCH_1):SCM_JTAG_MUX_S0_R1   I375 @T6G_MB_LIB.T6G(SCH_1):PAGE148

R6102 Q_RES_0402LF-0,5%,1/16W,CHIP,CS00002JB13
     1 SCM_JTAG_MUX_S0 @T6G_MB_LIB.T6G(SCH_1):SCM_JTAG_MUX_S0   I376 @T6G_MB_LIB.T6G(SCH_1):PAGE148
     2 SCM_JTAG_MUX_S0_R2 @T6G_MB_LIB.T6G(SCH_1):SCM_JTAG_MUX_S0_R2   I376 @T6G_MB_LIB.T6G(SCH_1):PAGE148

R6103 Q_RES_0402LF-0,5%,1/16W,CHIP,CS00002JB13
     1 JTAG_CPUX_TDI_R1 @T6G_MB_LIB.T6G(SCH_1):JTAG_CPUX_TDI_R1    I76 @T6G_MB_LIB.T6G(SCH_1):PAGE150
     2 JTAG_CPUX_TDI @T6G_MB_LIB.T6G(SCH_1):JTAG_CPUX_TDI    I76 @T6G_MB_LIB.T6G(SCH_1):PAGE150

R6104 Q_RES_0402LF-0,5%,1/16W,CHIP,CS00002JB13
     1 JTAG_CPU0_BYPASS @T6G_MB_LIB.T6G(SCH_1):JTAG_CPU0_BYPASS    I48 @T6G_MB_LIB.T6G(SCH_1):PAGE151
     2 JTAG_CPU0_BYPASS_R1 @T6G_MB_LIB.T6G(SCH_1):JTAG_CPU0_BYPASS_R1    I48 @T6G_MB_LIB.T6G(SCH_1):PAGE151

R6105 Q_RES_0402LF-0,5%,1/16W,CHIP,CS00002JB13
     1 JTAG_CPU0_TDO_CPU1_TDI_R1 @T6G_MB_LIB.T6G(SCH_1):JTAG_CPU0_TDO_CPU1_TDI_R1    I49 @T6G_MB_LIB.T6G(SCH_1):PAGE151
     2 JTAG_CPU0_TDO_CPU1_TDI @T6G_MB_LIB.T6G(SCH_1):JTAG_CPU0_TDO_CPU1_TDI    I49 @T6G_MB_LIB.T6G(SCH_1):PAGE151

R6106 Q_RES_0402LF-10K,5%,1/16W,CHIP,CS31002JB08
     1 PVDD18_S5_P0 @T6G_MB_LIB.T6G(SCH_1):PVDD18_S5_P0    I81 @T6G_MB_LIB.T6G(SCH_1):PAGE144
     2 FM_PASSWORD_CLEAR_N @T6G_MB_LIB.T6G(SCH_1):FM_PASSWORD_CLEAR_N    I81 @T6G_MB_LIB.T6G(SCH_1):PAGE144

R6107 Q_RES_0402LF-10K,5%,1/16W,CHIP,CS31002JB08
     1 PVDD18_S5_P0 @T6G_MB_LIB.T6G(SCH_1):PVDD18_S5_P0    I83 @T6G_MB_LIB.T6G(SCH_1):PAGE144
     2 BIOS_DEBUG_MODE @T6G_MB_LIB.T6G(SCH_1):BIOS_DEBUG_MODE    I83 @T6G_MB_LIB.T6G(SCH_1):PAGE144

R6108 Q_RES_0402LF-0,5%,1/16W,CHIP,CS00002JB13
     1 HDT_HDR_TDO @T6G_MB_LIB.T6G(SCH_1):HDT_HDR_TDO   I159 @T6G_MB_LIB.T6G(SCH_1):PAGE149
     2 HDT_HDR_TDO_R @T6G_MB_LIB.T6G(SCH_1):HDT_HDR_TDO_R   I159 @T6G_MB_LIB.T6G(SCH_1):PAGE149

R6109 Q_RES_0402LF-0,5%,1/16W,CHIP,CS00002JB13
     1 JTAG_TDO @T6G_MB_LIB.T6G(SCH_1):JTAG_TDO    I78 @T6G_MB_LIB.T6G(SCH_1):PAGE150
     2 JTAG_TDO_R @T6G_MB_LIB.T6G(SCH_1):JTAG_TDO_R    I78 @T6G_MB_LIB.T6G(SCH_1):PAGE150

R6110 Q_RES_0402LF-0,5%,1/16W,CHIP,CS00002JB13
     1 JTAG_CPUX_TDO_R @T6G_MB_LIB.T6G(SCH_1):JTAG_CPUX_TDO_R    I50 @T6G_MB_LIB.T6G(SCH_1):PAGE151
     2 JTAG_CPUX_TDO @T6G_MB_LIB.T6G(SCH_1):JTAG_CPUX_TDO    I50 @T6G_MB_LIB.T6G(SCH_1):PAGE151

R6111 Q_RES_0402LF-0,5%,1/16W,CHIP,CS00002JB13
     1 JTAG_TDO_R1 @T6G_MB_LIB.T6G(SCH_1):JTAG_TDO_R1   I160 @T6G_MB_LIB.T6G(SCH_1):PAGE149
     2 JTAG_TDO @T6G_MB_LIB.T6G(SCH_1):JTAG_TDO   I160 @T6G_MB_LIB.T6G(SCH_1):PAGE149

R6112 Q_RES_0402LF-33.2,1%,1/16W,CHIP,CS03322FB03
     1 RST_PERST_CPU0_SWB_N @T6G_MB_LIB.T6G(SCH_1):RST_PERST_CPU0_SWB_N    I91 @T6G_MB_LIB.T6G(SCH_1):PAGE84
     2 RST_PERST_CPU0_SWB_R_N @T6G_MB_LIB.T6G(SCH_1):RST_PERST_CPU0_SWB_R_N    I91 @T6G_MB_LIB.T6G(SCH_1):PAGE84

R6113 Q_RES_0402LF-33.2,1%,1/16W,CHIP,CS03322FB03
     1 RST_PERST_CPU1_SWB_N @T6G_MB_LIB.T6G(SCH_1):RST_PERST_CPU1_SWB_N    I75 @T6G_MB_LIB.T6G(SCH_1):PAGE84
     2 RST_PERST_CPU1_SWB_R_N @T6G_MB_LIB.T6G(SCH_1):RST_PERST_CPU1_SWB_R_N    I75 @T6G_MB_LIB.T6G(SCH_1):PAGE84

R6114 Q_RES_0402LF-2K,1%,1/16W,CHIP,CS22002FB07
     1 RST_PERST_CPU0_SWB_N @T6G_MB_LIB.T6G(SCH_1):RST_PERST_CPU0_SWB_N   I137 @T6G_MB_LIB.T6G(SCH_1):PAGE82
     2    GND @T6G_MB_LIB.T6G(SCH_1):GND   I137 @T6G_MB_LIB.T6G(SCH_1):PAGE82

R6115 Q_RES_0402LF-2K,1%,1/16W,CHIP,CS22002FB07
     1 RST_PERST_CPU1_SWB_N @T6G_MB_LIB.T6G(SCH_1):RST_PERST_CPU1_SWB_N   I141 @T6G_MB_LIB.T6G(SCH_1):PAGE82
     2    GND @T6G_MB_LIB.T6G(SCH_1):GND   I141 @T6G_MB_LIB.T6G(SCH_1):PAGE82

R6116 Q_RES_0402LF-0,5%,1/16W,CHIP,CS00002JB13
     1 E1S_0_PERST1_CLKREQ_R_N @T6G_MB_LIB.T6G(SCH_1):E1S_0_PERST1_CLKREQ_R_N   I129 @T6G_MB_LIB.T6G(SCH_1):PAGE79
     2 E1S_0_PRSNT_N @T6G_MB_LIB.T6G(SCH_1):E1S_0_PRSNT_N   I129 @T6G_MB_LIB.T6G(SCH_1):PAGE79

R6117 Q_RES_0402LF-100,1%,1/16W,CHIP,CS11002FB07
     1 HP_LVC3_OCP_V3_2_PRSNT2_PLD_N @T6G_MB_LIB.T6G(SCH_1):HP_LVC3_OCP_V3_2_PRSNT2_PLD_N   I131 @T6G_MB_LIB.T6G(SCH_1):PAGE79
     2 PRSNT_OCP_V3_2_N @T6G_MB_LIB.T6G(SCH_1):PRSNT_OCP_V3_2_N   I131 @T6G_MB_LIB.T6G(SCH_1):PAGE79

R6118 Q_RES_0402LF-0,5%,1/16W,CHIP,CS00002JB13
     1 PWRGD_P5V_AUX_R3 @T6G_MB_LIB.T6G(SCH_1):PWRGD_P5V_AUX_R3   I103 @T6G_MB_LIB.T6G(SCH_1):PAGE84
     2 PWRGD_P5V_AUX_R2 @T6G_MB_LIB.T6G(SCH_1):PWRGD_P5V_AUX_R2   I103 @T6G_MB_LIB.T6G(SCH_1):PAGE84

R6119 Q_RES_0402LF-0,5%,1/16W,CHIP,CS00002JB13
     1 PWRGD_P3V3_AUX @T6G_MB_LIB.T6G(SCH_1):PWRGD_P3V3_AUX    I40 @T6G_MB_LIB.T6G(SCH_1):PAGE315
     2 P1V8_AUX_ENABLE @T6G_MB_LIB.T6G(SCH_1):P1V8_AUX_ENABLE    I40 @T6G_MB_LIB.T6G(SCH_1):PAGE315

R6120 Q_RES_0402LF-1K,1%,1/16W,CHIP,CS21002FB06
     1 PVDD18_S5_P0 @T6G_MB_LIB.T6G(SCH_1):PVDD18_S5_P0   I115 @T6G_MB_LIB.T6G(SCH_1):PAGE83
     2 FM_BOARD_SKU_ID4 @T6G_MB_LIB.T6G(SCH_1):FM_BOARD_SKU_ID4   I115 @T6G_MB_LIB.T6G(SCH_1):PAGE83

R6121 Q_RES_0402LF-1K,1%,1/16W,EMPTY,CS21002FB06
     1 PVDD18_S5_P0 @T6G_MB_LIB.T6G(SCH_1):PVDD18_S5_P0   I120 @T6G_MB_LIB.T6G(SCH_1):PAGE83
     2 FM_BOARD_SKU_ID3 @T6G_MB_LIB.T6G(SCH_1):FM_BOARD_SKU_ID3   I120 @T6G_MB_LIB.T6G(SCH_1):PAGE83

R6122 Q_RES_0402LF-1K,1%,1/16W,EMPTY,CS21002FB06
     1 PVDD18_S5_P0 @T6G_MB_LIB.T6G(SCH_1):PVDD18_S5_P0    I50 @T6G_MB_LIB.T6G(SCH_1):PAGE83
     2 FM_BOARD_SKU_ID2 @T6G_MB_LIB.T6G(SCH_1):FM_BOARD_SKU_ID2    I50 @T6G_MB_LIB.T6G(SCH_1):PAGE83

R6123 Q_RES_0402LF-1K,1%,1/16W,EMPTY,CS21002FB06
     1 PVDD18_S5_P0 @T6G_MB_LIB.T6G(SCH_1):PVDD18_S5_P0    I71 @T6G_MB_LIB.T6G(SCH_1):PAGE83
     2 FM_BOARD_SKU_ID1 @T6G_MB_LIB.T6G(SCH_1):FM_BOARD_SKU_ID1    I71 @T6G_MB_LIB.T6G(SCH_1):PAGE83

R6124 Q_RES_0402LF-1K,1%,1/16W,EMPTY,CS21002FB06
     1 PVDD18_S5_P0 @T6G_MB_LIB.T6G(SCH_1):PVDD18_S5_P0    I72 @T6G_MB_LIB.T6G(SCH_1):PAGE83
     2 FM_BOARD_SKU_ID0 @T6G_MB_LIB.T6G(SCH_1):FM_BOARD_SKU_ID0    I72 @T6G_MB_LIB.T6G(SCH_1):PAGE83

R6125 Q_RES_0402LF-1K,1%,1/16W,EMPTY,CS21002FB06
     1 FM_BOARD_SKU_ID4 @T6G_MB_LIB.T6G(SCH_1):FM_BOARD_SKU_ID4   I116 @T6G_MB_LIB.T6G(SCH_1):PAGE83
     2    GND @T6G_MB_LIB.T6G(SCH_1):GND   I116 @T6G_MB_LIB.T6G(SCH_1):PAGE83

R6126 Q_RES_0402LF-1K,1%,1/16W,CHIP,CS21002FB06
     1 FM_BOARD_SKU_ID3 @T6G_MB_LIB.T6G(SCH_1):FM_BOARD_SKU_ID3   I119 @T6G_MB_LIB.T6G(SCH_1):PAGE83
     2    GND @T6G_MB_LIB.T6G(SCH_1):GND   I119 @T6G_MB_LIB.T6G(SCH_1):PAGE83

R6127 Q_RES_0402LF-1K,1%,1/16W,CHIP,CS21002FB06
     1 FM_BOARD_SKU_ID2 @T6G_MB_LIB.T6G(SCH_1):FM_BOARD_SKU_ID2    I46 @T6G_MB_LIB.T6G(SCH_1):PAGE83
     2    GND @T6G_MB_LIB.T6G(SCH_1):GND    I46 @T6G_MB_LIB.T6G(SCH_1):PAGE83

R6128 Q_RES_0402LF-1K,1%,1/16W,CHIP,CS21002FB06
     1 FM_BOARD_SKU_ID1 @T6G_MB_LIB.T6G(SCH_1):FM_BOARD_SKU_ID1    I64 @T6G_MB_LIB.T6G(SCH_1):PAGE83
     2    GND @T6G_MB_LIB.T6G(SCH_1):GND    I64 @T6G_MB_LIB.T6G(SCH_1):PAGE83

R6129 Q_RES_0402LF-1K,1%,1/16W,CHIP,CS21002FB06
     1 FM_BOARD_SKU_ID0 @T6G_MB_LIB.T6G(SCH_1):FM_BOARD_SKU_ID0    I65 @T6G_MB_LIB.T6G(SCH_1):PAGE83
     2    GND @T6G_MB_LIB.T6G(SCH_1):GND    I65 @T6G_MB_LIB.T6G(SCH_1):PAGE83

R6130 Q_RES_0402LF-1K,1%,1/16W,CHIP,CS21002FB06
     1 PVDD18_S5_P0 @T6G_MB_LIB.T6G(SCH_1):PVDD18_S5_P0   I131 @T6G_MB_LIB.T6G(SCH_1):PAGE83
     2 FAB_REV_ID2 @T6G_MB_LIB.T6G(SCH_1):FAB_REV_ID2   I131 @T6G_MB_LIB.T6G(SCH_1):PAGE83

R6131 Q_RES_0402LF-1K,1%,1/16W,EMPTY,CS21002FB06
     1 PVDD18_S5_P0 @T6G_MB_LIB.T6G(SCH_1):PVDD18_S5_P0   I134 @T6G_MB_LIB.T6G(SCH_1):PAGE83
     2 FAB_REV_ID1 @T6G_MB_LIB.T6G(SCH_1):FAB_REV_ID1   I134 @T6G_MB_LIB.T6G(SCH_1):PAGE83

R6132 Q_RES_0402LF-1K,1%,1/16W,EMPTY,CS21002FB06
     1 PVDD18_S5_P0 @T6G_MB_LIB.T6G(SCH_1):PVDD18_S5_P0   I135 @T6G_MB_LIB.T6G(SCH_1):PAGE83
     2 FAB_REV_ID0 @T6G_MB_LIB.T6G(SCH_1):FAB_REV_ID0   I135 @T6G_MB_LIB.T6G(SCH_1):PAGE83

R6133 Q_RES_0402LF-1K,1%,1/16W,EMPTY,CS21002FB06
     1 FAB_REV_ID2 @T6G_MB_LIB.T6G(SCH_1):FAB_REV_ID2   I132 @T6G_MB_LIB.T6G(SCH_1):PAGE83
     2    GND @T6G_MB_LIB.T6G(SCH_1):GND   I132 @T6G_MB_LIB.T6G(SCH_1):PAGE83

R6134 Q_RES_0402LF-1K,1%,1/16W,CHIP,CS21002FB06
     1 FAB_REV_ID1 @T6G_MB_LIB.T6G(SCH_1):FAB_REV_ID1   I133 @T6G_MB_LIB.T6G(SCH_1):PAGE83
     2    GND @T6G_MB_LIB.T6G(SCH_1):GND   I133 @T6G_MB_LIB.T6G(SCH_1):PAGE83

R6135 Q_RES_0402LF-1K,1%,1/16W,CHIP,CS21002FB06
     1 FAB_REV_ID0 @T6G_MB_LIB.T6G(SCH_1):FAB_REV_ID0   I136 @T6G_MB_LIB.T6G(SCH_1):PAGE83
     2    GND @T6G_MB_LIB.T6G(SCH_1):GND   I136 @T6G_MB_LIB.T6G(SCH_1):PAGE83

R6136 Q_RES_0402LF-1K,1%,1/16W,CHIP,CS21002FB06
     1 P3V3_AUX @T6G_MB_LIB.T6G(SCH_1):P3V3_AUX   I117 @T6G_MB_LIB.T6G(SCH_1):PAGE83
     2 FM_BOARD_BMC_SKU_ID4 @T6G_MB_LIB.T6G(SCH_1):FM_BOARD_BMC_SKU_ID4   I117 @T6G_MB_LIB.T6G(SCH_1):PAGE83

R6137 Q_RES_0402LF-1K,1%,1/16W,EMPTY,CS21002FB06
     1 P3V3_AUX @T6G_MB_LIB.T6G(SCH_1):P3V3_AUX   I121 @T6G_MB_LIB.T6G(SCH_1):PAGE83
     2 FM_BOARD_BMC_SKU_ID3 @T6G_MB_LIB.T6G(SCH_1):FM_BOARD_BMC_SKU_ID3   I121 @T6G_MB_LIB.T6G(SCH_1):PAGE83

R6138 Q_RES_0402LF-1K,1%,1/16W,EMPTY,CS21002FB06
     1 P3V3_AUX @T6G_MB_LIB.T6G(SCH_1):P3V3_AUX    I39 @T6G_MB_LIB.T6G(SCH_1):PAGE83
     2 FM_BOARD_BMC_SKU_ID2 @T6G_MB_LIB.T6G(SCH_1):FM_BOARD_BMC_SKU_ID2    I39 @T6G_MB_LIB.T6G(SCH_1):PAGE83

R6139 Q_RES_0402LF-1K,1%,1/16W,EMPTY,CS21002FB06
     1 P3V3_AUX @T6G_MB_LIB.T6G(SCH_1):P3V3_AUX    I55 @T6G_MB_LIB.T6G(SCH_1):PAGE83
     2 FM_BOARD_BMC_SKU_ID1 @T6G_MB_LIB.T6G(SCH_1):FM_BOARD_BMC_SKU_ID1    I55 @T6G_MB_LIB.T6G(SCH_1):PAGE83

R6140 Q_RES_0402LF-1K,1%,1/16W,EMPTY,CS21002FB06
     1 P3V3_AUX @T6G_MB_LIB.T6G(SCH_1):P3V3_AUX    I56 @T6G_MB_LIB.T6G(SCH_1):PAGE83
     2 FM_BOARD_BMC_SKU_ID0 @T6G_MB_LIB.T6G(SCH_1):FM_BOARD_BMC_SKU_ID0    I56 @T6G_MB_LIB.T6G(SCH_1):PAGE83

R6141 Q_RES_0402LF-1K,1%,1/16W,EMPTY,CS21002FB06
     1 FM_BOARD_BMC_SKU_ID4 @T6G_MB_LIB.T6G(SCH_1):FM_BOARD_BMC_SKU_ID4   I118 @T6G_MB_LIB.T6G(SCH_1):PAGE83
     2    GND @T6G_MB_LIB.T6G(SCH_1):GND   I118 @T6G_MB_LIB.T6G(SCH_1):PAGE83

R6142 Q_RES_0402LF-1K,1%,1/16W,CHIP,CS21002FB06
     1 FM_BOARD_BMC_SKU_ID3 @T6G_MB_LIB.T6G(SCH_1):FM_BOARD_BMC_SKU_ID3   I122 @T6G_MB_LIB.T6G(SCH_1):PAGE83
     2    GND @T6G_MB_LIB.T6G(SCH_1):GND   I122 @T6G_MB_LIB.T6G(SCH_1):PAGE83

R6143 Q_RES_0402LF-1K,1%,1/16W,CHIP,CS21002FB06
     1 FM_BOARD_BMC_SKU_ID2 @T6G_MB_LIB.T6G(SCH_1):FM_BOARD_BMC_SKU_ID2    I36 @T6G_MB_LIB.T6G(SCH_1):PAGE83
     2    GND @T6G_MB_LIB.T6G(SCH_1):GND    I36 @T6G_MB_LIB.T6G(SCH_1):PAGE83

R6144 Q_RES_0402LF-1K,1%,1/16W,CHIP,CS21002FB06
     1 FM_BOARD_BMC_SKU_ID1 @T6G_MB_LIB.T6G(SCH_1):FM_BOARD_BMC_SKU_ID1    I52 @T6G_MB_LIB.T6G(SCH_1):PAGE83
     2    GND @T6G_MB_LIB.T6G(SCH_1):GND    I52 @T6G_MB_LIB.T6G(SCH_1):PAGE83

R6145 Q_RES_0402LF-1K,1%,1/16W,CHIP,CS21002FB06
     1 FM_BOARD_BMC_SKU_ID0 @T6G_MB_LIB.T6G(SCH_1):FM_BOARD_BMC_SKU_ID0    I54 @T6G_MB_LIB.T6G(SCH_1):PAGE83
     2    GND @T6G_MB_LIB.T6G(SCH_1):GND    I54 @T6G_MB_LIB.T6G(SCH_1):PAGE83

R6146 Q_RES_0402LF-1K,1%,1/16W,CHIP,CS21002FB06
     1 P1V8_AUX @T6G_MB_LIB.T6G(SCH_1):P1V8_AUX   I138 @T6G_MB_LIB.T6G(SCH_1):PAGE83
     2 FAB_BMC_REV_ID2 @T6G_MB_LIB.T6G(SCH_1):FAB_BMC_REV_ID2   I138 @T6G_MB_LIB.T6G(SCH_1):PAGE83

R6147 Q_RES_0402LF-1K,1%,1/16W,EMPTY,CS21002FB06
     1 P1V8_AUX @T6G_MB_LIB.T6G(SCH_1):P1V8_AUX   I140 @T6G_MB_LIB.T6G(SCH_1):PAGE83
     2 FAB_BMC_REV_ID1 @T6G_MB_LIB.T6G(SCH_1):FAB_BMC_REV_ID1   I140 @T6G_MB_LIB.T6G(SCH_1):PAGE83

R6148 Q_RES_0402LF-1K,1%,1/16W,EMPTY,CS21002FB06
     1 P1V8_AUX @T6G_MB_LIB.T6G(SCH_1):P1V8_AUX   I142 @T6G_MB_LIB.T6G(SCH_1):PAGE83
     2 FAB_BMC_REV_ID0 @T6G_MB_LIB.T6G(SCH_1):FAB_BMC_REV_ID0   I142 @T6G_MB_LIB.T6G(SCH_1):PAGE83

R6149 Q_RES_0402LF-1K,1%,1/16W,EMPTY,CS21002FB06
     1 FAB_BMC_REV_ID2 @T6G_MB_LIB.T6G(SCH_1):FAB_BMC_REV_ID2   I137 @T6G_MB_LIB.T6G(SCH_1):PAGE83
     2    GND @T6G_MB_LIB.T6G(SCH_1):GND   I137 @T6G_MB_LIB.T6G(SCH_1):PAGE83

R6150 Q_RES_0402LF-1K,1%,1/16W,CHIP,CS21002FB06
     1 FAB_BMC_REV_ID1 @T6G_MB_LIB.T6G(SCH_1):FAB_BMC_REV_ID1   I139 @T6G_MB_LIB.T6G(SCH_1):PAGE83
     2    GND @T6G_MB_LIB.T6G(SCH_1):GND   I139 @T6G_MB_LIB.T6G(SCH_1):PAGE83

R6151 Q_RES_0402LF-1K,1%,1/16W,CHIP,CS21002FB06
     1 FAB_BMC_REV_ID0 @T6G_MB_LIB.T6G(SCH_1):FAB_BMC_REV_ID0   I141 @T6G_MB_LIB.T6G(SCH_1):PAGE83
     2    GND @T6G_MB_LIB.T6G(SCH_1):GND   I141 @T6G_MB_LIB.T6G(SCH_1):PAGE83

R6152 Q_RES_0201LF-0,5%,1/20W,CHIP,CS00001JE10
     1 P2E_MB_BMC_TX_C_DP<0> @T6G_MB_LIB.T6G(SCH_1):P2E_MB_BMC_TX_C_DP(0)     I8 @T6G_MB_LIB.T6G(SCH_1):PAGE112
     2 P2E_MB_BMC_TX_C_R1_DP<0> @T6G_MB_LIB.T6G(SCH_1):P2E_MB_BMC_TX_C_R1_DP(0)     I8 @T6G_MB_LIB.T6G(SCH_1):PAGE112

R6153 Q_RES_0201LF-0,5%,1/20W,CHIP,CS00001JE10
     1 P2E_MB_BMC_TX_C_DN<0> @T6G_MB_LIB.T6G(SCH_1):P2E_MB_BMC_TX_C_DN(0)     I3 @T6G_MB_LIB.T6G(SCH_1):PAGE112
     2 P2E_MB_BMC_TX_C_R1_DN<0> @T6G_MB_LIB.T6G(SCH_1):P2E_MB_BMC_TX_C_R1_DN(0)     I3 @T6G_MB_LIB.T6G(SCH_1):PAGE112

R6154 Q_RES_0201LF-0,5%,1/20W,CHIP,CS00001JE10
     1 P2E_MB_BMC_TX_C_DP<0> @T6G_MB_LIB.T6G(SCH_1):P2E_MB_BMC_TX_C_DP(0)     I1 @T6G_MB_LIB.T6G(SCH_1):PAGE112
     2 P2E_MB_BMC_TX_C_R2_DP<0> @T6G_MB_LIB.T6G(SCH_1):P2E_MB_BMC_TX_C_R2_DP(0)     I1 @T6G_MB_LIB.T6G(SCH_1):PAGE112

R6155 Q_RES_0201LF-0,5%,1/20W,CHIP,CS00001JE10
     1 P2E_MB_BMC_TX_C_DN<0> @T6G_MB_LIB.T6G(SCH_1):P2E_MB_BMC_TX_C_DN(0)     I2 @T6G_MB_LIB.T6G(SCH_1):PAGE112
     2 P2E_MB_BMC_TX_C_R2_DN<0> @T6G_MB_LIB.T6G(SCH_1):P2E_MB_BMC_TX_C_R2_DN(0)     I2 @T6G_MB_LIB.T6G(SCH_1):PAGE112

R6156 Q_RES_0201LF-0,5%,1/20W,CHIP,CS00001JE10
     1 P2E_MB_BMC_RX_DP<0> @T6G_MB_LIB.T6G(SCH_1):P2E_MB_BMC_RX_DP(0)    I21 @T6G_MB_LIB.T6G(SCH_1):PAGE112
     2 P2E_MB_BMC_RX_R1_DP<0> @T6G_MB_LIB.T6G(SCH_1):P2E_MB_BMC_RX_R1_DP(0)    I21 @T6G_MB_LIB.T6G(SCH_1):PAGE112

R6157 Q_RES_0201LF-0,5%,1/20W,CHIP,CS00001JE10
     1 P2E_MB_BMC_RX_DN<0> @T6G_MB_LIB.T6G(SCH_1):P2E_MB_BMC_RX_DN(0)    I22 @T6G_MB_LIB.T6G(SCH_1):PAGE112
     2 P2E_MB_BMC_RX_R1_DN<0> @T6G_MB_LIB.T6G(SCH_1):P2E_MB_BMC_RX_R1_DN(0)    I22 @T6G_MB_LIB.T6G(SCH_1):PAGE112

R6158 Q_RES_0201LF-0,5%,1/20W,CHIP,CS00001JE10
     1 P2E_MB_BMC_RX_DP<0> @T6G_MB_LIB.T6G(SCH_1):P2E_MB_BMC_RX_DP(0)    I24 @T6G_MB_LIB.T6G(SCH_1):PAGE112
     2 P2E_MB_BMC_RX_R2_DP<0> @T6G_MB_LIB.T6G(SCH_1):P2E_MB_BMC_RX_R2_DP(0)    I24 @T6G_MB_LIB.T6G(SCH_1):PAGE112

R6159 Q_RES_0201LF-0,5%,1/20W,CHIP,CS00001JE10
     1 P2E_MB_BMC_RX_DN<0> @T6G_MB_LIB.T6G(SCH_1):P2E_MB_BMC_RX_DN(0)    I23 @T6G_MB_LIB.T6G(SCH_1):PAGE112
     2 P2E_MB_BMC_RX_R2_DN<0> @T6G_MB_LIB.T6G(SCH_1):P2E_MB_BMC_RX_R2_DN(0)    I23 @T6G_MB_LIB.T6G(SCH_1):PAGE112

R6160 Q_RES_0402LF-1K,1%,1/16W,CHIP,CS21002FB06
     1 PD_P2E_BUF2_ENSMB @T6G_MB_LIB.T6G(SCH_1):PD_P2E_BUF2_ENSMB    I12 @T6G_MB_LIB.T6G(SCH_1):PAGE111
     2    GND @T6G_MB_LIB.T6G(SCH_1):GND    I12 @T6G_MB_LIB.T6G(SCH_1):PAGE111

R6162 Q_RES_0402LF-0,5%,1/16W,CHIP,CS00002JB13
     1 FM_P2E_EN2_N @T6G_MB_LIB.T6G(SCH_1):FM_P2E_EN2_N    I23 @T6G_MB_LIB.T6G(SCH_1):PAGE111
     2 CLK_GEN2_GPU_FPGA_OE_OR_N @T6G_MB_LIB.T6G(SCH_1):CLK_GEN2_GPU_FPGA_OE_OR_N    I23 @T6G_MB_LIB.T6G(SCH_1):PAGE111

R6163 Q_RES_0402LF-1K,1%,1/16W,EMPTY,CS21002FB06
     1 P3V3_AUX @T6G_MB_LIB.T6G(SCH_1):P3V3_AUX    I39 @T6G_MB_LIB.T6G(SCH_1):PAGE111
     2 FM_P2E_BUF2_EQB1 @T6G_MB_LIB.T6G(SCH_1):FM_P2E_BUF2_EQB1    I39 @T6G_MB_LIB.T6G(SCH_1):PAGE111

R6164 Q_RES_0402LF-1K,1%,1/16W,CHIP,CS21002FB06
     1 FM_P2E_BUF2_EQB1 @T6G_MB_LIB.T6G(SCH_1):FM_P2E_BUF2_EQB1    I32 @T6G_MB_LIB.T6G(SCH_1):PAGE111
     2    GND @T6G_MB_LIB.T6G(SCH_1):GND    I32 @T6G_MB_LIB.T6G(SCH_1):PAGE111

R6165 Q_RES_0402LF-1K,1%,1/16W,EMPTY,CS21002FB06
     1 P3V3_AUX @T6G_MB_LIB.T6G(SCH_1):P3V3_AUX    I41 @T6G_MB_LIB.T6G(SCH_1):PAGE111
     2 FM_P2E_BUF2_EQB0 @T6G_MB_LIB.T6G(SCH_1):FM_P2E_BUF2_EQB0    I41 @T6G_MB_LIB.T6G(SCH_1):PAGE111

R6166 Q_RES_0402LF-1K,1%,1/16W,EMPTY,CS21002FB06
     1 FM_P2E_BUF2_EQB0 @T6G_MB_LIB.T6G(SCH_1):FM_P2E_BUF2_EQB0    I40 @T6G_MB_LIB.T6G(SCH_1):PAGE111
     2    GND @T6G_MB_LIB.T6G(SCH_1):GND    I40 @T6G_MB_LIB.T6G(SCH_1):PAGE111

R6167 Q_RES_0402LF-1K,1%,1/16W,EMPTY,CS21002FB06
     1 P3V3_AUX @T6G_MB_LIB.T6G(SCH_1):P3V3_AUX    I57 @T6G_MB_LIB.T6G(SCH_1):PAGE111
     2 FM_P2E_BUF2_VODB_DB @T6G_MB_LIB.T6G(SCH_1):FM_P2E_BUF2_VODB_DB    I57 @T6G_MB_LIB.T6G(SCH_1):PAGE111

R6168 Q_RES_0402LF-1K,1%,1/16W,CHIP,CS21002FB06
     1 FM_P2E_BUF2_VODB_DB @T6G_MB_LIB.T6G(SCH_1):FM_P2E_BUF2_VODB_DB    I58 @T6G_MB_LIB.T6G(SCH_1):PAGE111
     2    GND @T6G_MB_LIB.T6G(SCH_1):GND    I58 @T6G_MB_LIB.T6G(SCH_1):PAGE111

R6169 Q_RES_0402LF-1K,1%,1/16W,EMPTY,CS21002FB06
     1 P3V3_AUX @T6G_MB_LIB.T6G(SCH_1):P3V3_AUX    I53 @T6G_MB_LIB.T6G(SCH_1):PAGE111
     2 FM_P2E_BUF2_VODA_DB @T6G_MB_LIB.T6G(SCH_1):FM_P2E_BUF2_VODA_DB    I53 @T6G_MB_LIB.T6G(SCH_1):PAGE111

R6170 Q_RES_0402LF-1K,1%,1/16W,CHIP,CS21002FB06
     1 FM_P2E_BUF2_VODA_DB @T6G_MB_LIB.T6G(SCH_1):FM_P2E_BUF2_VODA_DB    I60 @T6G_MB_LIB.T6G(SCH_1):PAGE111
     2    GND @T6G_MB_LIB.T6G(SCH_1):GND    I60 @T6G_MB_LIB.T6G(SCH_1):PAGE111

R6171 Q_RES_0402LF-1K,1%,1/16W,EMPTY,CS21002FB06
     1 P3V3_AUX @T6G_MB_LIB.T6G(SCH_1):P3V3_AUX    I48 @T6G_MB_LIB.T6G(SCH_1):PAGE111
     2 FM_P2E_BUF2_EQA1 @T6G_MB_LIB.T6G(SCH_1):FM_P2E_BUF2_EQA1    I48 @T6G_MB_LIB.T6G(SCH_1):PAGE111

R6172 Q_RES_0402LF-1K,1%,1/16W,CHIP,CS21002FB06
     1 FM_P2E_BUF2_EQA1 @T6G_MB_LIB.T6G(SCH_1):FM_P2E_BUF2_EQA1    I49 @T6G_MB_LIB.T6G(SCH_1):PAGE111
     2    GND @T6G_MB_LIB.T6G(SCH_1):GND    I49 @T6G_MB_LIB.T6G(SCH_1):PAGE111

R6173 Q_RES_0402LF-1K,1%,1/16W,EMPTY,CS21002FB06
     1 P3V3_AUX @T6G_MB_LIB.T6G(SCH_1):P3V3_AUX    I44 @T6G_MB_LIB.T6G(SCH_1):PAGE111
     2 FM_P2E_BUF2_EQA0 @T6G_MB_LIB.T6G(SCH_1):FM_P2E_BUF2_EQA0    I44 @T6G_MB_LIB.T6G(SCH_1):PAGE111

R6174 Q_RES_0402LF-1K,1%,1/16W,EMPTY,CS21002FB06
     1 FM_P2E_BUF2_EQA0 @T6G_MB_LIB.T6G(SCH_1):FM_P2E_BUF2_EQA0    I45 @T6G_MB_LIB.T6G(SCH_1):PAGE111
     2    GND @T6G_MB_LIB.T6G(SCH_1):GND    I45 @T6G_MB_LIB.T6G(SCH_1):PAGE111

R6175 Q_RES_0402LF-1K,1%,1/16W,EMPTY,CS21002FB06
     1 P3V3_AUX @T6G_MB_LIB.T6G(SCH_1):P3V3_AUX    I63 @T6G_MB_LIB.T6G(SCH_1):PAGE111
     2 FM_P2E_BUF2_RXDET @T6G_MB_LIB.T6G(SCH_1):FM_P2E_BUF2_RXDET    I63 @T6G_MB_LIB.T6G(SCH_1):PAGE111

R6176 Q_RES_0402LF-1K,1%,1/16W,EMPTY,CS21002FB06
     1 FM_P2E_BUF2_RXDET @T6G_MB_LIB.T6G(SCH_1):FM_P2E_BUF2_RXDET    I64 @T6G_MB_LIB.T6G(SCH_1):PAGE111
     2    GND @T6G_MB_LIB.T6G(SCH_1):GND    I64 @T6G_MB_LIB.T6G(SCH_1):PAGE111

R6177 Q_RES_0402LF-1K,1%,1/16W,CHIP,CS21002FB06
     1 P3V3_AUX @T6G_MB_LIB.T6G(SCH_1):P3V3_AUX    I77 @T6G_MB_LIB.T6G(SCH_1):PAGE111
     2 FM_P2E_BUF2_SD_TH @T6G_MB_LIB.T6G(SCH_1):FM_P2E_BUF2_SD_TH    I77 @T6G_MB_LIB.T6G(SCH_1):PAGE111

R6178 Q_RES_0402LF-1K,1%,1/16W,EMPTY,CS21002FB06
     1 FM_P2E_BUF2_SD_TH @T6G_MB_LIB.T6G(SCH_1):FM_P2E_BUF2_SD_TH    I68 @T6G_MB_LIB.T6G(SCH_1):PAGE111
     2    GND @T6G_MB_LIB.T6G(SCH_1):GND    I68 @T6G_MB_LIB.T6G(SCH_1):PAGE111

R6179 Q_RES_0402LF-1K,1%,1/16W,CHIP,CS21002FB06
     1 P3V3_AUX @T6G_MB_LIB.T6G(SCH_1):P3V3_AUX    I78 @T6G_MB_LIB.T6G(SCH_1):PAGE111
     2 FM_P2E_BUF2_VOD_SEL @T6G_MB_LIB.T6G(SCH_1):FM_P2E_BUF2_VOD_SEL    I78 @T6G_MB_LIB.T6G(SCH_1):PAGE111

R6180 Q_RES_0402LF-1K,1%,1/16W,EMPTY,CS21002FB06
     1 FM_P2E_BUF2_VOD_SEL @T6G_MB_LIB.T6G(SCH_1):FM_P2E_BUF2_VOD_SEL    I73 @T6G_MB_LIB.T6G(SCH_1):PAGE111
     2    GND @T6G_MB_LIB.T6G(SCH_1):GND    I73 @T6G_MB_LIB.T6G(SCH_1):PAGE111

R6181 Q_RES_0402LF-4.7K,5%,1/16W,CHIP,CS24702JB10
     1 P3V3_AUX @T6G_MB_LIB.T6G(SCH_1):P3V3_AUX   I381 @T6G_MB_LIB.T6G(SCH_1):PAGE148
     2 PU_U212_EN_N @T6G_MB_LIB.T6G(SCH_1):PU_U212_EN_N   I381 @T6G_MB_LIB.T6G(SCH_1):PAGE148

R6182 Q_RES_0402LF-4.7K,5%,1/16W,CHIP,CS24702JB10
     1 P3V3_AUX @T6G_MB_LIB.T6G(SCH_1):P3V3_AUX   I384 @T6G_MB_LIB.T6G(SCH_1):PAGE148
     2 PU_U160_EN_N @T6G_MB_LIB.T6G(SCH_1):PU_U160_EN_N   I384 @T6G_MB_LIB.T6G(SCH_1):PAGE148

R6183 Q_RES_0402LF-0,5%,1/16W,CHIP,CS00002JB13
     1 FM_SEC_MUX_OE_N @T6G_MB_LIB.T6G(SCH_1):FM_SEC_MUX_OE_N   I164 @T6G_MB_LIB.T6G(SCH_1):PAGE81
     2 FM_SEC_MUX_OE_R_N @T6G_MB_LIB.T6G(SCH_1):FM_SEC_MUX_OE_R_N   I164 @T6G_MB_LIB.T6G(SCH_1):PAGE81

R6184 Q_RES_0402LF-0,5%,1/16W,CHIP,CS00002JB13
     1 FM_SEC_MUX_SEL @T6G_MB_LIB.T6G(SCH_1):FM_SEC_MUX_SEL   I165 @T6G_MB_LIB.T6G(SCH_1):PAGE81
     2 FM_SEC_MUX_R_SEL @T6G_MB_LIB.T6G(SCH_1):FM_SEC_MUX_R_SEL   I165 @T6G_MB_LIB.T6G(SCH_1):PAGE81

R6185 Q_RES_0402LF-10K,1%,1/16W,CHIP,CS31002FB08
     1 FM_SEC_MUX_OE_N @T6G_MB_LIB.T6G(SCH_1):FM_SEC_MUX_OE_N   I143 @T6G_MB_LIB.T6G(SCH_1):PAGE82
     2    GND @T6G_MB_LIB.T6G(SCH_1):GND   I143 @T6G_MB_LIB.T6G(SCH_1):PAGE82

R6186 Q_RES_0402LF-4.7K,5%,1/16W,EMPTY,CS24702JB10
     1 FM_SEC_MUX_OE_N @T6G_MB_LIB.T6G(SCH_1):FM_SEC_MUX_OE_N   I146 @T6G_MB_LIB.T6G(SCH_1):PAGE82
     2 P3V3_AUX @T6G_MB_LIB.T6G(SCH_1):P3V3_AUX   I146 @T6G_MB_LIB.T6G(SCH_1):PAGE82

R6187 Q_RES_0402LF-10K,1%,1/16W,EMPTY,CS31002FB08
     1 FM_SEC_MUX_SEL @T6G_MB_LIB.T6G(SCH_1):FM_SEC_MUX_SEL   I151 @T6G_MB_LIB.T6G(SCH_1):PAGE82
     2    GND @T6G_MB_LIB.T6G(SCH_1):GND   I151 @T6G_MB_LIB.T6G(SCH_1):PAGE82

R6188 Q_RES_0402LF-4.7K,5%,1/16W,EMPTY,CS24702JB10
     1 FM_SEC_MUX_SEL @T6G_MB_LIB.T6G(SCH_1):FM_SEC_MUX_SEL   I152 @T6G_MB_LIB.T6G(SCH_1):PAGE82
     2 P3V3_AUX @T6G_MB_LIB.T6G(SCH_1):P3V3_AUX   I152 @T6G_MB_LIB.T6G(SCH_1):PAGE82

R6190 Q_RES_0201LF-0,5%,1/20W,CHIP,CS00001JE10
     1 USB2_CPU0_P0_DP @T6G_MB_LIB.T6G(SCH_1):USB2_CPU0_P0_DP     I6 @T6G_MB_LIB.T6G(SCH_1):PAGE158
     2 USB2_CPU0_P0_R1_DP @T6G_MB_LIB.T6G(SCH_1):USB2_CPU0_P0_R1_DP     I6 @T6G_MB_LIB.T6G(SCH_1):PAGE158

R6191 Q_RES_0201LF-0,5%,1/20W,CHIP,CS00001JE10
     1 USB2_CPU0_P0_DN @T6G_MB_LIB.T6G(SCH_1):USB2_CPU0_P0_DN     I5 @T6G_MB_LIB.T6G(SCH_1):PAGE158
     2 USB2_CPU0_P0_R1_DN @T6G_MB_LIB.T6G(SCH_1):USB2_CPU0_P0_R1_DN     I5 @T6G_MB_LIB.T6G(SCH_1):PAGE158

R6192 Q_RES_0201LF-0,5%,1/20W,CHIP,CS00001JE10
     1 USB2_CPU0_P0_DP @T6G_MB_LIB.T6G(SCH_1):USB2_CPU0_P0_DP     I3 @T6G_MB_LIB.T6G(SCH_1):PAGE158
     2 USB2_CPU0_P0_R2_DP @T6G_MB_LIB.T6G(SCH_1):USB2_CPU0_P0_R2_DP     I3 @T6G_MB_LIB.T6G(SCH_1):PAGE158

R6193 Q_RES_0201LF-0,5%,1/20W,CHIP,CS00001JE10
     1 USB2_CPU0_P0_DN @T6G_MB_LIB.T6G(SCH_1):USB2_CPU0_P0_DN     I4 @T6G_MB_LIB.T6G(SCH_1):PAGE158
     2 USB2_CPU0_P0_R2_DN @T6G_MB_LIB.T6G(SCH_1):USB2_CPU0_P0_R2_DN     I4 @T6G_MB_LIB.T6G(SCH_1):PAGE158

R6194 Q_RES_0201LF-0,5%,1/20W,CHIP,CS00001JE10
     1 USB2_CPU0_P0_HUB1_R_DP @T6G_MB_LIB.T6G(SCH_1):USB2_CPU0_P0_HUB1_R_DP    I72 @T6G_MB_LIB.T6G(SCH_1):PAGE158
     2 USB2_HUB_EXT_DP @T6G_MB_LIB.T6G(SCH_1):USB2_HUB_EXT_DP    I72 @T6G_MB_LIB.T6G(SCH_1):PAGE158

R6195 Q_RES_0201LF-0,5%,1/20W,CHIP,CS00001JE10
     1 USB2_CPU0_P0_HUB1_R_DN @T6G_MB_LIB.T6G(SCH_1):USB2_CPU0_P0_HUB1_R_DN    I71 @T6G_MB_LIB.T6G(SCH_1):PAGE158
     2 USB2_HUB_EXT_DN @T6G_MB_LIB.T6G(SCH_1):USB2_HUB_EXT_DN    I71 @T6G_MB_LIB.T6G(SCH_1):PAGE158

R6196 Q_RES_0201LF-0,5%,1/20W,CHIP,CS00001JE10
     1 USB2_CPU0_P0_HUB2_R_DP @T6G_MB_LIB.T6G(SCH_1):USB2_CPU0_P0_HUB2_R_DP    I73 @T6G_MB_LIB.T6G(SCH_1):PAGE158
     2 USB2_HUB_EXT_DP @T6G_MB_LIB.T6G(SCH_1):USB2_HUB_EXT_DP    I73 @T6G_MB_LIB.T6G(SCH_1):PAGE158

R6197 Q_RES_0201LF-0,5%,1/20W,CHIP,CS00001JE10
     1 USB2_CPU0_P0_HUB2_R_DN @T6G_MB_LIB.T6G(SCH_1):USB2_CPU0_P0_HUB2_R_DN    I74 @T6G_MB_LIB.T6G(SCH_1):PAGE158
     2 USB2_HUB_EXT_DN @T6G_MB_LIB.T6G(SCH_1):USB2_HUB_EXT_DN    I74 @T6G_MB_LIB.T6G(SCH_1):PAGE158

R6200 Q_RES_0402LF-0,5%,1/16W,CHIP,CS00002JB13
     1 SMB_USB_CPU0_HUB1_SDA_R @T6G_MB_LIB.T6G(SCH_1):SMB_USB_CPU0_HUB1_SDA_R    I83 @T6G_MB_LIB.T6G(SCH_1):PAGE252
     2 SMB_USB_CPU0_HUB1_SDA @T6G_MB_LIB.T6G(SCH_1):SMB_USB_CPU0_HUB1_SDA    I83 @T6G_MB_LIB.T6G(SCH_1):PAGE252

R6201 Q_RES_0402LF-0,5%,1/16W,CHIP,CS00002JB13
     1 SMB_USB_CPU0_HUB1_SCL_R @T6G_MB_LIB.T6G(SCH_1):SMB_USB_CPU0_HUB1_SCL_R    I84 @T6G_MB_LIB.T6G(SCH_1):PAGE252
     2 SMB_USB_CPU0_HUB1_SCL @T6G_MB_LIB.T6G(SCH_1):SMB_USB_CPU0_HUB1_SCL    I84 @T6G_MB_LIB.T6G(SCH_1):PAGE252

R6202 Q_RES_0402LF-200,1%,1/16W,CHIP,CS12002FB06
     1    GND @T6G_MB_LIB.T6G(SCH_1):GND    I37 @T6G_MB_LIB.T6G(SCH_1):PAGE153
     2 USB_CPU0_HUB1_RREF_SS @T6G_MB_LIB.T6G(SCH_1):USB_CPU0_HUB1_RREF_SS    I37 @T6G_MB_LIB.T6G(SCH_1):PAGE153

R6203 Q_RES_0402LF-6.04K,1%,1/16W,CHIP,CS26042FB04
     1    GND @T6G_MB_LIB.T6G(SCH_1):GND    I39 @T6G_MB_LIB.T6G(SCH_1):PAGE153
     2 USB_CPU0_HUB1_RREF_USB2 @T6G_MB_LIB.T6G(SCH_1):USB_CPU0_HUB1_RREF_USB2    I39 @T6G_MB_LIB.T6G(SCH_1):PAGE153

R6204 Q_RES_0402LF-10K,1%,1/16W,CHIP,CS31002FB08
     1 P3V3_AUX @T6G_MB_LIB.T6G(SCH_1):P3V3_AUX    I41 @T6G_MB_LIB.T6G(SCH_1):PAGE153
     2 PU_CPU0_USB_HUB_PWR_EN @T6G_MB_LIB.T6G(SCH_1):PU_CPU0_USB_HUB_PWR_EN    I41 @T6G_MB_LIB.T6G(SCH_1):PAGE153

R6205 Q_RES_0402LF-10K,1%,1/16W,CHIP,CS31002FB08
     1 P3V3_AUX @T6G_MB_LIB.T6G(SCH_1):P3V3_AUX    I43 @T6G_MB_LIB.T6G(SCH_1):PAGE153
     2 PU_CPU0_USB_HUB_OVRCURR @T6G_MB_LIB.T6G(SCH_1):PU_CPU0_USB_HUB_OVRCURR    I43 @T6G_MB_LIB.T6G(SCH_1):PAGE153

R6206 Q_RES_0402LF-10K,1%,1/16W,CHIP,CS31002FB08
     1 P3V3_AUX @T6G_MB_LIB.T6G(SCH_1):P3V3_AUX    I44 @T6G_MB_LIB.T6G(SCH_1):PAGE153
     2 PU_CPU0_USB_HUB_RESERVED2 @T6G_MB_LIB.T6G(SCH_1):PU_CPU0_USB_HUB_RESERVED2    I44 @T6G_MB_LIB.T6G(SCH_1):PAGE153

R6207 Q_RES_0402LF-10K,1%,1/16W,CHIP,CS31002FB08
     1 P3V3_AUX @T6G_MB_LIB.T6G(SCH_1):P3V3_AUX    I45 @T6G_MB_LIB.T6G(SCH_1):PAGE153
     2 PU_CPU0_USB_HUB_RESERVED1 @T6G_MB_LIB.T6G(SCH_1):PU_CPU0_USB_HUB_RESERVED1    I45 @T6G_MB_LIB.T6G(SCH_1):PAGE153

R6208 Q_RES_0402LF-10K,1%,1/16W,CHIP,CS31002FB08
     1 P5V_AUX @T6G_MB_LIB.T6G(SCH_1):P5V_AUX    I47 @T6G_MB_LIB.T6G(SCH_1):PAGE153
     2 USB_CPU0_HUB1_VBUS_US @T6G_MB_LIB.T6G(SCH_1):USB_CPU0_HUB1_VBUS_US    I47 @T6G_MB_LIB.T6G(SCH_1):PAGE153

R6209 Q_RES_0402LF-10K,1%,1/16W,CHIP,CS31002FB08
     1 USB_CPU0_HUB1_VBUS_US @T6G_MB_LIB.T6G(SCH_1):USB_CPU0_HUB1_VBUS_US    I48 @T6G_MB_LIB.T6G(SCH_1):PAGE153
     2    GND @T6G_MB_LIB.T6G(SCH_1):GND    I48 @T6G_MB_LIB.T6G(SCH_1):PAGE153

R6210 Q_RES_0402LF-0,5%,1/16W,CHIP,CS00002JB13
     1 HSC_CSOUT @T6G_MB_LIB.T6G(SCH_1):HSC_CSOUT    I73 @T6G_MB_LIB.T6G(SCH_1):PAGE371
     2 HSC_D_OC @T6G_MB_LIB.T6G(SCH_1):HSC_D_OC    I73 @T6G_MB_LIB.T6G(SCH_1):PAGE371

R6211 Q_RES_0402LF-2.2K,5%,1/16W,CHIP,CS22202JB07
     1 P3V3_AUX @T6G_MB_LIB.T6G(SCH_1):P3V3_AUX    I89 @T6G_MB_LIB.T6G(SCH_1):PAGE252
     2 SMB_USB_CPU0_HUB1_SCL @T6G_MB_LIB.T6G(SCH_1):SMB_USB_CPU0_HUB1_SCL    I89 @T6G_MB_LIB.T6G(SCH_1):PAGE252

R6212 Q_RES_0402LF-2.2K,5%,1/16W,CHIP,CS22202JB07
     1 P3V3_AUX @T6G_MB_LIB.T6G(SCH_1):P3V3_AUX    I90 @T6G_MB_LIB.T6G(SCH_1):PAGE252
     2 SMB_USB_CPU0_HUB1_SDA @T6G_MB_LIB.T6G(SCH_1):SMB_USB_CPU0_HUB1_SDA    I90 @T6G_MB_LIB.T6G(SCH_1):PAGE252

R6213 Q_RES_0402LF-10K,1%,1/16W,CHIP,CS31002FB08
     1 P3V3_AUX @T6G_MB_LIB.T6G(SCH_1):P3V3_AUX    I87 @T6G_MB_LIB.T6G(SCH_1):PAGE153
     2 USB_CPU0_HUB1_MODE_SEL1 @T6G_MB_LIB.T6G(SCH_1):USB_CPU0_HUB1_MODE_SEL1    I87 @T6G_MB_LIB.T6G(SCH_1):PAGE153

R6214 Q_RES_0402LF-10K,1%,1/16W,EMPTY,CS31002FB08
     1 USB_CPU0_HUB1_MODE_SEL1 @T6G_MB_LIB.T6G(SCH_1):USB_CPU0_HUB1_MODE_SEL1    I88 @T6G_MB_LIB.T6G(SCH_1):PAGE153
     2    GND @T6G_MB_LIB.T6G(SCH_1):GND    I88 @T6G_MB_LIB.T6G(SCH_1):PAGE153

R6215 Q_RES_0402LF-10K,1%,1/16W,CHIP,CS31002FB08
     1 P3V3_AUX @T6G_MB_LIB.T6G(SCH_1):P3V3_AUX    I89 @T6G_MB_LIB.T6G(SCH_1):PAGE153
     2 USB_CPU0_HUB1_MODE_SEL0 @T6G_MB_LIB.T6G(SCH_1):USB_CPU0_HUB1_MODE_SEL0    I89 @T6G_MB_LIB.T6G(SCH_1):PAGE153

R6216 Q_RES_0402LF-10K,1%,1/16W,EMPTY,CS31002FB08
     1 USB_CPU0_HUB1_MODE_SEL0 @T6G_MB_LIB.T6G(SCH_1):USB_CPU0_HUB1_MODE_SEL0    I90 @T6G_MB_LIB.T6G(SCH_1):PAGE153
     2    GND @T6G_MB_LIB.T6G(SCH_1):GND    I90 @T6G_MB_LIB.T6G(SCH_1):PAGE153

R6217 Q_RES_0402LF-10K,1%,1/16W,EMPTY,CS31002FB08
     1 USB_CPU0_ADD_A0 @T6G_MB_LIB.T6G(SCH_1):USB_CPU0_ADD_A0    I68 @T6G_MB_LIB.T6G(SCH_1):PAGE153
     2    GND @T6G_MB_LIB.T6G(SCH_1):GND    I68 @T6G_MB_LIB.T6G(SCH_1):PAGE153

R6218 Q_RES_0402LF-10K,1%,1/16W,EMPTY,CS31002FB08
     1 P3V3_AUX @T6G_MB_LIB.T6G(SCH_1):P3V3_AUX    I69 @T6G_MB_LIB.T6G(SCH_1):PAGE153
     2 USB_CPU0_ADD_A1 @T6G_MB_LIB.T6G(SCH_1):USB_CPU0_ADD_A1    I69 @T6G_MB_LIB.T6G(SCH_1):PAGE153

R6219 Q_RES_0402LF-10K,1%,1/16W,CHIP,CS31002FB08
     1 USB_CPU0_ADD_A1 @T6G_MB_LIB.T6G(SCH_1):USB_CPU0_ADD_A1    I66 @T6G_MB_LIB.T6G(SCH_1):PAGE153
     2    GND @T6G_MB_LIB.T6G(SCH_1):GND    I66 @T6G_MB_LIB.T6G(SCH_1):PAGE153

R6220 Q_RES_0402LF-10K,1%,1/16W,EMPTY,CS31002FB08
     1 P3V3_AUX @T6G_MB_LIB.T6G(SCH_1):P3V3_AUX    I70 @T6G_MB_LIB.T6G(SCH_1):PAGE153
     2 USB_CPU0_ADD_A2 @T6G_MB_LIB.T6G(SCH_1):USB_CPU0_ADD_A2    I70 @T6G_MB_LIB.T6G(SCH_1):PAGE153

R6221 Q_RES_0402LF-10K,1%,1/16W,CHIP,CS31002FB08
     1 USB_CPU0_ADD_A2 @T6G_MB_LIB.T6G(SCH_1):USB_CPU0_ADD_A2    I67 @T6G_MB_LIB.T6G(SCH_1):PAGE153
     2    GND @T6G_MB_LIB.T6G(SCH_1):GND    I67 @T6G_MB_LIB.T6G(SCH_1):PAGE153

R6222 Q_RES_0402LF-10K,1%,1/16W,CHIP,CS31002FB08
     1 P3V3_AUX @T6G_MB_LIB.T6G(SCH_1):P3V3_AUX    I65 @T6G_MB_LIB.T6G(SCH_1):PAGE153
     2 USB_CPU0_ADD_A0 @T6G_MB_LIB.T6G(SCH_1):USB_CPU0_ADD_A0    I65 @T6G_MB_LIB.T6G(SCH_1):PAGE153

R6223 Q_RES_0402LF-1K,1%,1/16W,CHIP,CS21002FB06
     1 PD_USB_CPU0_WP @T6G_MB_LIB.T6G(SCH_1):PD_USB_CPU0_WP    I77 @T6G_MB_LIB.T6G(SCH_1):PAGE153
     2    GND @T6G_MB_LIB.T6G(SCH_1):GND    I77 @T6G_MB_LIB.T6G(SCH_1):PAGE153

R6224 Q_RES_0402LF-33.2,1%,1/16W,EMPTY,CS03322FB03
     1 SMB_USB_CPU0_HUB1_SCL @T6G_MB_LIB.T6G(SCH_1):SMB_USB_CPU0_HUB1_SCL    I84 @T6G_MB_LIB.T6G(SCH_1):PAGE153
     2 SMB_USB_CPU0_HUB1_SCL_R2 @T6G_MB_LIB.T6G(SCH_1):SMB_USB_CPU0_HUB1_SCL_R2    I84 @T6G_MB_LIB.T6G(SCH_1):PAGE153

R6225 Q_RES_0402LF-33.2,1%,1/16W,EMPTY,CS03322FB03
     1 SMB_USB_CPU0_HUB1_SDA @T6G_MB_LIB.T6G(SCH_1):SMB_USB_CPU0_HUB1_SDA    I83 @T6G_MB_LIB.T6G(SCH_1):PAGE153
     2 SMB_USB_CPU0_HUB1_SDA_R2 @T6G_MB_LIB.T6G(SCH_1):SMB_USB_CPU0_HUB1_SDA_R2    I83 @T6G_MB_LIB.T6G(SCH_1):PAGE153

R6226 Q_RES_0402LF-10K,1%,1/16W,EMPTY,CS31002FB08
     1 P3V3_AUX @T6G_MB_LIB.T6G(SCH_1):P3V3_AUX    I85 @T6G_MB_LIB.T6G(SCH_1):PAGE153
     2 SMB_USB_CPU0_HUB1_SCL_R2 @T6G_MB_LIB.T6G(SCH_1):SMB_USB_CPU0_HUB1_SCL_R2    I85 @T6G_MB_LIB.T6G(SCH_1):PAGE153

R6227 Q_RES_0402LF-10K,1%,1/16W,EMPTY,CS31002FB08
     1 P3V3_AUX @T6G_MB_LIB.T6G(SCH_1):P3V3_AUX    I86 @T6G_MB_LIB.T6G(SCH_1):PAGE153
     2 SMB_USB_CPU0_HUB1_SDA_R2 @T6G_MB_LIB.T6G(SCH_1):SMB_USB_CPU0_HUB1_SDA_R2    I86 @T6G_MB_LIB.T6G(SCH_1):PAGE153

R6228 Q_RES_0402LF-0,5%,1/16W,CHIP,CS00002JB13
     1 SMB_P12V_HSC_SDA_R @T6G_MB_LIB.T6G(SCH_1):SMB_P12V_HSC_SDA_R    I75 @T6G_MB_LIB.T6G(SCH_1):PAGE251
     2 SMB_P12V_HSC_SDA @T6G_MB_LIB.T6G(SCH_1):SMB_P12V_HSC_SDA    I75 @T6G_MB_LIB.T6G(SCH_1):PAGE251

R6229 Q_RES_0402LF-0,5%,1/16W,CHIP,CS00002JB13
     1 SMB_P12V_HSC_SCL_R @T6G_MB_LIB.T6G(SCH_1):SMB_P12V_HSC_SCL_R    I76 @T6G_MB_LIB.T6G(SCH_1):PAGE251
     2 SMB_P12V_HSC_SCL @T6G_MB_LIB.T6G(SCH_1):SMB_P12V_HSC_SCL    I76 @T6G_MB_LIB.T6G(SCH_1):PAGE251

R6230 Q_RES_0402LF-2.2K,5%,1/16W,CHIP,CS22202JB07
     1 P3V3_AUX @T6G_MB_LIB.T6G(SCH_1):P3V3_AUX    I45 @T6G_MB_LIB.T6G(SCH_1):PAGE371
     2 SMB_P12V_HSC_SDA @T6G_MB_LIB.T6G(SCH_1):SMB_P12V_HSC_SDA    I45 @T6G_MB_LIB.T6G(SCH_1):PAGE371

R6231 Q_RES_0402LF-2.2K,5%,1/16W,CHIP,CS22202JB07
     1 P3V3_AUX @T6G_MB_LIB.T6G(SCH_1):P3V3_AUX    I46 @T6G_MB_LIB.T6G(SCH_1):PAGE371
     2 SMB_P12V_HSC_SCL @T6G_MB_LIB.T6G(SCH_1):SMB_P12V_HSC_SCL    I46 @T6G_MB_LIB.T6G(SCH_1):PAGE371

R6232 Q_RES_0402LF-160K,1%,1/16W,EMPTY,CS41602FB05
     1 HSC_CSOUT @T6G_MB_LIB.T6G(SCH_1):HSC_CSOUT    I56 @T6G_MB_LIB.T6G(SCH_1):PAGE371
     2 A_HSC_LOW @T6G_MB_LIB.T6G(SCH_1):A_HSC_LOW    I56 @T6G_MB_LIB.T6G(SCH_1):PAGE371

R6233 Q_RES_0402LF-10K,1%,1/16W,EMPTY,CS31002FB08
     1 A_HSC_LOW @T6G_MB_LIB.T6G(SCH_1):A_HSC_LOW    I57 @T6G_MB_LIB.T6G(SCH_1):PAGE371
     2    GND @T6G_MB_LIB.T6G(SCH_1):GND    I57 @T6G_MB_LIB.T6G(SCH_1):PAGE371

R6234 Q_RES_0402LF-160K,1%,1/16W,EMPTY,CS41602FB05
     1 HSC_CSOUT @T6G_MB_LIB.T6G(SCH_1):HSC_CSOUT    I55 @T6G_MB_LIB.T6G(SCH_1):PAGE371
     2 A_HSC_HIGH @T6G_MB_LIB.T6G(SCH_1):A_HSC_HIGH    I55 @T6G_MB_LIB.T6G(SCH_1):PAGE371

R6235 Q_RES_0402LF-10K,1%,1/16W,EMPTY,CS31002FB08
     1 A_HSC_HIGH @T6G_MB_LIB.T6G(SCH_1):A_HSC_HIGH    I58 @T6G_MB_LIB.T6G(SCH_1):PAGE371
     2    GND @T6G_MB_LIB.T6G(SCH_1):GND    I58 @T6G_MB_LIB.T6G(SCH_1):PAGE371

R6236 Q_RES_0402LF-10K,1%,1/16W,EMPTY,CS31002FB08
     1 P3V3_AUX @T6G_MB_LIB.T6G(SCH_1):P3V3_AUX    I63 @T6G_MB_LIB.T6G(SCH_1):PAGE371
     2 A_HSC_LOW_GATE @T6G_MB_LIB.T6G(SCH_1):A_HSC_LOW_GATE    I63 @T6G_MB_LIB.T6G(SCH_1):PAGE371

R6237 Q_RES_0402LF-0,5%,1/16W,EMPTY,CS00002JB13
     1 A_HSC_LOW_GATE @T6G_MB_LIB.T6G(SCH_1):A_HSC_LOW_GATE    I66 @T6G_MB_LIB.T6G(SCH_1):PAGE371
     2    GND @T6G_MB_LIB.T6G(SCH_1):GND    I66 @T6G_MB_LIB.T6G(SCH_1):PAGE371

R6238 Q_RES_0402LF-0,5%,1/16W,EMPTY,CS00002JB13
     1 A_HSC_LOW_DRAIN @T6G_MB_LIB.T6G(SCH_1):A_HSC_LOW_DRAIN    I72 @T6G_MB_LIB.T6G(SCH_1):PAGE371
     2 HSC_D_OC @T6G_MB_LIB.T6G(SCH_1):HSC_D_OC    I72 @T6G_MB_LIB.T6G(SCH_1):PAGE371

R6239 Q_RES_0402LF-10K,1%,1/16W,CHIP,CS31002FB08
     1 P3V3_AUX @T6G_MB_LIB.T6G(SCH_1):P3V3_AUX    I70 @T6G_MB_LIB.T6G(SCH_1):PAGE371
     2 HSC_D_OC @T6G_MB_LIB.T6G(SCH_1):HSC_D_OC    I70 @T6G_MB_LIB.T6G(SCH_1):PAGE371

R6240 Q_RES_0402LF-0,5%,1/16W,CHIP,CS00002JB13
     1 PWRGD_P1V8_AUX_R @T6G_MB_LIB.T6G(SCH_1):PWRGD_P1V8_AUX_R    I40 @T6G_MB_LIB.T6G(SCH_1):PAGE380
     2 P1V2_AUX_ENABLE @T6G_MB_LIB.T6G(SCH_1):P1V2_AUX_ENABLE    I40 @T6G_MB_LIB.T6G(SCH_1):PAGE380

R6241 Q_RES_0402LF-0,5%,1/16W,CHIP,CS00002JB13
     1 PWRGD_P1V2_AUX @T6G_MB_LIB.T6G(SCH_1):PWRGD_P1V2_AUX    I44 @T6G_MB_LIB.T6G(SCH_1):PAGE380
     2 PWRGD_P1V2_AUX_R @T6G_MB_LIB.T6G(SCH_1):PWRGD_P1V2_AUX_R    I44 @T6G_MB_LIB.T6G(SCH_1):PAGE380

R6242 Q_RES_0402LF-0,5%,1/16W,CHIP,CS00002JB13
     1 P3V3_AUX @T6G_MB_LIB.T6G(SCH_1):P3V3_AUX     I2 @T6G_MB_LIB.T6G(SCH_1):PAGE315
     2 P1V8_AUX_VCC @T6G_MB_LIB.T6G(SCH_1):P1V8_AUX_VCC     I2 @T6G_MB_LIB.T6G(SCH_1):PAGE315

R6243 Q_RES_0402LF-10K,1%,1/16W,CHIP,CS31002FB08
     1 P3V3_AUX @T6G_MB_LIB.T6G(SCH_1):P3V3_AUX    I32 @T6G_MB_LIB.T6G(SCH_1):PAGE315
     2 PWRGD_P1V8_AUX @T6G_MB_LIB.T6G(SCH_1):PWRGD_P1V8_AUX    I32 @T6G_MB_LIB.T6G(SCH_1):PAGE315

R6244 Q_RES_0402LF-10K,1%,1/16W,CHIP,CS31002FB08
     1 P3V3_AUX @T6G_MB_LIB.T6G(SCH_1):P3V3_AUX    I19 @T6G_MB_LIB.T6G(SCH_1):PAGE380
     2 PWRGD_P1V2_AUX @T6G_MB_LIB.T6G(SCH_1):PWRGD_P1V2_AUX    I19 @T6G_MB_LIB.T6G(SCH_1):PAGE380

R6245 Q_RES_0402LF-0,5%,1/16W,CHIP,CS00002JB13
     1 P3V3_AUX @T6G_MB_LIB.T6G(SCH_1):P3V3_AUX    I38 @T6G_MB_LIB.T6G(SCH_1):PAGE380
     2 P1V2_AUX_VCC @T6G_MB_LIB.T6G(SCH_1):P1V2_AUX_VCC    I38 @T6G_MB_LIB.T6G(SCH_1):PAGE380

R6246 Q_RES_0402LF-130,1%,1/16W,CHIP,CS11302FB03
     1 LED_PWRGD_P1V2_AUX @T6G_MB_LIB.T6G(SCH_1):LED_PWRGD_P1V2_AUX    I45 @T6G_MB_LIB.T6G(SCH_1):PAGE254
     2 P3V3_AUX @T6G_MB_LIB.T6G(SCH_1):P3V3_AUX    I45 @T6G_MB_LIB.T6G(SCH_1):PAGE254

R6247 Q_RES_0402LF-4.7K,1%,1/16W,CHIP,CS24702FB06
     1 P3V3_AUX @T6G_MB_LIB.T6G(SCH_1):P3V3_AUX    I25 @T6G_MB_LIB.T6G(SCH_1):PAGE271
     2 HSC_TYPE_ADC_ALERT @T6G_MB_LIB.T6G(SCH_1):HSC_TYPE_ADC_ALERT    I25 @T6G_MB_LIB.T6G(SCH_1):PAGE271

R6250 Q_RES_0402LF-4.7K,1%,1/16W,CHIP,CS24702FB06
     1    GND @T6G_MB_LIB.T6G(SCH_1):GND    I30 @T6G_MB_LIB.T6G(SCH_1):PAGE271
     2 HSC_TYPE_ADC_A1 @T6G_MB_LIB.T6G(SCH_1):HSC_TYPE_ADC_A1    I30 @T6G_MB_LIB.T6G(SCH_1):PAGE271

R6251 Q_RES_0402LF-4.7K,1%,1/16W,EMPTY,CS24702FB06
     1    GND @T6G_MB_LIB.T6G(SCH_1):GND    I14 @T6G_MB_LIB.T6G(SCH_1):PAGE271
     2 HSC_TYPE_ADC_A0 @T6G_MB_LIB.T6G(SCH_1):HSC_TYPE_ADC_A0    I14 @T6G_MB_LIB.T6G(SCH_1):PAGE271

R6252 Q_RES_0402LF-33.2,1%,1/16W,CHIP,CS03322FB03
     1 SMB_LM75_0_3V3AUX_SCL @T6G_MB_LIB.T6G(SCH_1):SMB_LM75_0_3V3AUX_SCL     I9 @T6G_MB_LIB.T6G(SCH_1):PAGE271
     2 SMB_HSC_TYPE_ADC_SCL @T6G_MB_LIB.T6G(SCH_1):SMB_HSC_TYPE_ADC_SCL     I9 @T6G_MB_LIB.T6G(SCH_1):PAGE271

R6253 Q_RES_0402LF-33.2,1%,1/16W,CHIP,CS03322FB03
     1 SMB_LM75_0_3V3AUX_SDA @T6G_MB_LIB.T6G(SCH_1):SMB_LM75_0_3V3AUX_SDA    I10 @T6G_MB_LIB.T6G(SCH_1):PAGE271
     2 SMB_HSC_TYPE_ADC_SDA @T6G_MB_LIB.T6G(SCH_1):SMB_HSC_TYPE_ADC_SDA    I10 @T6G_MB_LIB.T6G(SCH_1):PAGE271

R6254 Q_RES_0402LF-0,5%,1/16W,CHIP,CS00002JB13
     1 HSC_TYPE_ADC_A0 @T6G_MB_LIB.T6G(SCH_1):HSC_TYPE_ADC_A0    I29 @T6G_MB_LIB.T6G(SCH_1):PAGE271
     2 SMB_HSC_TYPE_ADC_SDA @T6G_MB_LIB.T6G(SCH_1):SMB_HSC_TYPE_ADC_SDA    I29 @T6G_MB_LIB.T6G(SCH_1):PAGE271

R6257 Q_RES_0402LF-1M,1%,1/16W,CHIP,CS51002FB05
     1 XTAL_USB_CPU0_HUB2_XOUT @T6G_MB_LIB.T6G(SCH_1):XTAL_USB_CPU0_HUB2_XOUT   I160 @T6G_MB_LIB.T6G(SCH_1):PAGE157
     2 XTAL_USB_CPU0_HUB2_XIN @T6G_MB_LIB.T6G(SCH_1):XTAL_USB_CPU0_HUB2_XIN   I160 @T6G_MB_LIB.T6G(SCH_1):PAGE157

R6258 Q_RES_0402LF-4.7K,5%,1/16W,EMPTY,CS24702JB10
     1 P3V3_AUX @T6G_MB_LIB.T6G(SCH_1):P3V3_AUX   I164 @T6G_MB_LIB.T6G(SCH_1):PAGE155
     2 USB_HUB2_TI_PWRCTL2_MRP_VDD12 @T6G_MB_LIB.T6G(SCH_1):USB_HUB2_TI_PWRCTL2_MRP_VDD12   I164 @T6G_MB_LIB.T6G(SCH_1):PAGE155

R6259 Q_RES_0402LF-0,5%,1/16W,CHIP,CS00002JB13
     1 P1V2_CPU0_USB2_DVDD12 @T6G_MB_LIB.T6G(SCH_1):P1V2_CPU0_USB2_DVDD12   I166 @T6G_MB_LIB.T6G(SCH_1):PAGE155
     2 USB_HUB2_TI_PWRCTL2_MRP_VDD12 @T6G_MB_LIB.T6G(SCH_1):USB_HUB2_TI_PWRCTL2_MRP_VDD12   I166 @T6G_MB_LIB.T6G(SCH_1):PAGE155

R6260 Q_RES_0402LF-0,5%,1/16W,CHIP,CS00002JB13
     1 USB_HUB2_TI_VDD_MRP_USB3DN_TXDM1 @T6G_MB_LIB.T6G(SCH_1):USB_HUB2_TI_VDD_MRP_USB3DN_TXDM1   I170 @T6G_MB_LIB.T6G(SCH_1):PAGE157
     2 P1V2_CPU0_USB2_DVDD12 @T6G_MB_LIB.T6G(SCH_1):P1V2_CPU0_USB2_DVDD12   I170 @T6G_MB_LIB.T6G(SCH_1):PAGE157

R6261 Q_RES_0402LF-0,5%,1/16W,CHIP,CS00002JB13
     1 USB_HUB2_TI_USB_SSRXP_DN1_MRP_VDD12 @T6G_MB_LIB.T6G(SCH_1):USB_HUB2_TI_USB_SSRXP_DN1_MRP_VDD12   I134 @T6G_MB_LIB.T6G(SCH_1):PAGE155
     2 P1V2_CPU0_USB2_DVDD12 @T6G_MB_LIB.T6G(SCH_1):P1V2_CPU0_USB2_DVDD12   I134 @T6G_MB_LIB.T6G(SCH_1):PAGE155

R6262 Q_RES_0402LF-0,5%,1/16W,CHIP,CS00002JB13
     1 USB_HUB2_TI_VDD_MRP_USB3DN_RXDM1 @T6G_MB_LIB.T6G(SCH_1):USB_HUB2_TI_VDD_MRP_USB3DN_RXDM1   I134 @T6G_MB_LIB.T6G(SCH_1):PAGE157
     2 P1V2_CPU0_USB2_DVDD12 @T6G_MB_LIB.T6G(SCH_1):P1V2_CPU0_USB2_DVDD12   I134 @T6G_MB_LIB.T6G(SCH_1):PAGE157

R6263 Q_RES_0402LF-0,5%,1/16W,CHIP,CS00002JB13
     1 USB_HUB2_TI_USB_DP_DN3_MRP_VDD12 @T6G_MB_LIB.T6G(SCH_1):USB_HUB2_TI_USB_DP_DN3_MRP_VDD12   I155 @T6G_MB_LIB.T6G(SCH_1):PAGE155
     2 P1V2_CPU0_USB2_DVDD12 @T6G_MB_LIB.T6G(SCH_1):P1V2_CPU0_USB2_DVDD12   I155 @T6G_MB_LIB.T6G(SCH_1):PAGE155

R6264 Q_RES_0402LF-0,5%,1/16W,CHIP,CS00002JB13
     1 USB_HUB2_TI_USB_DM_DN3_MRP_VDD33 @T6G_MB_LIB.T6G(SCH_1):USB_HUB2_TI_USB_DM_DN3_MRP_VDD33   I151 @T6G_MB_LIB.T6G(SCH_1):PAGE155
     2 P3V3_AUX_CPU0_USB2_AVDD33 @T6G_MB_LIB.T6G(SCH_1):P3V3_AUX_CPU0_USB2_AVDD33   I151 @T6G_MB_LIB.T6G(SCH_1):PAGE155

R6265 Q_RES_0402LF-0,5%,1/16W,CHIP,CS00002JB13
     1 USB_HUB2_TI_VDD_MRP_USB3DN_TXDP3 @T6G_MB_LIB.T6G(SCH_1):USB_HUB2_TI_VDD_MRP_USB3DN_TXDP3   I145 @T6G_MB_LIB.T6G(SCH_1):PAGE157
     2 P1V2_CPU0_USB2_DVDD12 @T6G_MB_LIB.T6G(SCH_1):P1V2_CPU0_USB2_DVDD12   I145 @T6G_MB_LIB.T6G(SCH_1):PAGE157

R6266 Q_RES_0402LF-0,5%,1/16W,CHIP,CS00002JB13
     1 USB_HUB2_TI_USB_SSRXM_DN3_MRP_VDD12 @T6G_MB_LIB.T6G(SCH_1):USB_HUB2_TI_USB_SSRXM_DN3_MRP_VDD12   I136 @T6G_MB_LIB.T6G(SCH_1):PAGE155
     2 P1V2_CPU0_USB2_DVDD12 @T6G_MB_LIB.T6G(SCH_1):P1V2_CPU0_USB2_DVDD12   I136 @T6G_MB_LIB.T6G(SCH_1):PAGE155

R6267 Q_RES_0402LF-0,5%,1/16W,CHIP,CS00002JB13
     1 USB_HUB2_TI_VDD_MRP_USB3DN_TXDP4 @T6G_MB_LIB.T6G(SCH_1):USB_HUB2_TI_VDD_MRP_USB3DN_TXDP4   I122 @T6G_MB_LIB.T6G(SCH_1):PAGE157
     2 P1V2_CPU0_USB2_DVDD12 @T6G_MB_LIB.T6G(SCH_1):P1V2_CPU0_USB2_DVDD12   I122 @T6G_MB_LIB.T6G(SCH_1):PAGE157

R6268 Q_RES_0402LF-0,5%,1/16W,CHIP,CS00002JB13
     1 USB_HUB2_TI_USB_SSRXM_DN4_MRP_VDD12 @T6G_MB_LIB.T6G(SCH_1):USB_HUB2_TI_USB_SSRXM_DN4_MRP_VDD12   I149 @T6G_MB_LIB.T6G(SCH_1):PAGE155
     2 P1V2_CPU0_USB2_DVDD12 @T6G_MB_LIB.T6G(SCH_1):P1V2_CPU0_USB2_DVDD12   I149 @T6G_MB_LIB.T6G(SCH_1):PAGE155

R6269 Q_RES_0402LF-0,5%,1/16W,CHIP,CS00002JB13
     1 USB_HUB2_TI_VDD_MRP_USB3DN_RXDP4 @T6G_MB_LIB.T6G(SCH_1):USB_HUB2_TI_VDD_MRP_USB3DN_RXDP4   I136 @T6G_MB_LIB.T6G(SCH_1):PAGE157
     2 P1V2_CPU0_USB2_DVDD12 @T6G_MB_LIB.T6G(SCH_1):P1V2_CPU0_USB2_DVDD12   I136 @T6G_MB_LIB.T6G(SCH_1):PAGE157

R6270 Q_RES_0402LF-0,5%,1/16W,CHIP,CS00002JB13
     1 P3V3_AUX_CPU0_USB2_AVDD33 @T6G_MB_LIB.T6G(SCH_1):P3V3_AUX_CPU0_USB2_AVDD33   I143 @T6G_MB_LIB.T6G(SCH_1):PAGE155
     2 USB_HUB2_TI_PWRCTL3_MRP_VDD33 @T6G_MB_LIB.T6G(SCH_1):USB_HUB2_TI_PWRCTL3_MRP_VDD33   I143 @T6G_MB_LIB.T6G(SCH_1):PAGE155

R6271 Q_RES_0402LF-0,5%,1/16W,CHIP,CS00002JB13
     1 USB_HUB2_TI_USB_DP_DN1_MRP_CFG_STRAP @T6G_MB_LIB.T6G(SCH_1):USB_HUB2_TI_USB_DP_DN1_MRP_CFG_STRAP   I102 @T6G_MB_LIB.T6G(SCH_1):PAGE155
     2 USB_HUB2_MRP_CFG_STRAP @T6G_MB_LIB.T6G(SCH_1):USB_HUB2_MRP_CFG_STRAP   I102 @T6G_MB_LIB.T6G(SCH_1):PAGE155

R6272 Q_RES_0402LF-200K,1%,1/16W,CHIP,CS42002FB05
     1 USB_HUB2_MRP_CFG_STRAP @T6G_MB_LIB.T6G(SCH_1):USB_HUB2_MRP_CFG_STRAP   I105 @T6G_MB_LIB.T6G(SCH_1):PAGE155
     2    GND @T6G_MB_LIB.T6G(SCH_1):GND   I105 @T6G_MB_LIB.T6G(SCH_1):PAGE155

R6273 Q_RES_0402LF-200K,1%,1/16W,EMPTY,CS42002FB05
     1 P3V3_AUX @T6G_MB_LIB.T6G(SCH_1):P3V3_AUX   I104 @T6G_MB_LIB.T6G(SCH_1):PAGE155
     2 USB_HUB2_MRP_CFG_STRAP @T6G_MB_LIB.T6G(SCH_1):USB_HUB2_MRP_CFG_STRAP   I104 @T6G_MB_LIB.T6G(SCH_1):PAGE155

R6274 Q_RES_0402LF-0,5%,1/16W,CHIP,CS00002JB13
     1 USB_HUB2_TI_VDD33_MRP_PROG_FUNC7 @T6G_MB_LIB.T6G(SCH_1):USB_HUB2_TI_VDD33_MRP_PROG_FUNC7   I142 @T6G_MB_LIB.T6G(SCH_1):PAGE157
     2 P3V3_AUX_CPU0_USB2_AVDD33 @T6G_MB_LIB.T6G(SCH_1):P3V3_AUX_CPU0_USB2_AVDD33   I142 @T6G_MB_LIB.T6G(SCH_1):PAGE157

R6275 Q_RES_0402LF-0,5%,1/16W,CHIP,CS00002JB13
     1 USB_HUB2_TI_VDD33_MRP_PRT_CTL4_GANGPWR @T6G_MB_LIB.T6G(SCH_1):USB_HUB2_TI_VDD33_MRP_PRT_CTL4_GANGPWR   I131 @T6G_MB_LIB.T6G(SCH_1):PAGE157
     2 P3V3_AUX_CPU0_USB2_AVDD33 @T6G_MB_LIB.T6G(SCH_1):P3V3_AUX_CPU0_USB2_AVDD33   I131 @T6G_MB_LIB.T6G(SCH_1):PAGE157

R6276 Q_RES_0402LF-0,5%,1/16W,CHIP,CS00002JB13
     1 USB_HUB2_TI_VDD33_MRP_PRT_CTL4_GANGPWR @T6G_MB_LIB.T6G(SCH_1):USB_HUB2_TI_VDD33_MRP_PRT_CTL4_GANGPWR   I125 @T6G_MB_LIB.T6G(SCH_1):PAGE157
     2 USB_HUB2_MRP_PRT_CTL4_GANGPWR @T6G_MB_LIB.T6G(SCH_1):USB_HUB2_MRP_PRT_CTL4_GANGPWR   I125 @T6G_MB_LIB.T6G(SCH_1):PAGE157

R6277 Q_RES_0402LF-10K,1%,1/16W,EMPTY,CS31002FB08
     1 P3V3_AUX @T6G_MB_LIB.T6G(SCH_1):P3V3_AUX   I130 @T6G_MB_LIB.T6G(SCH_1):PAGE157
     2 USB_HUB2_MRP_PRT_CTL4_GANGPWR @T6G_MB_LIB.T6G(SCH_1):USB_HUB2_MRP_PRT_CTL4_GANGPWR   I130 @T6G_MB_LIB.T6G(SCH_1):PAGE157

R6278 Q_RES_0402LF-10K,1%,1/16W,EMPTY,CS31002FB08
     1 USB_HUB2_MRP_PRT_CTL4_GANGPWR @T6G_MB_LIB.T6G(SCH_1):USB_HUB2_MRP_PRT_CTL4_GANGPWR   I124 @T6G_MB_LIB.T6G(SCH_1):PAGE157
     2    GND @T6G_MB_LIB.T6G(SCH_1):GND   I124 @T6G_MB_LIB.T6G(SCH_1):PAGE157

R6279 Q_RES_0402LF-0,5%,1/16W,CHIP,CS00002JB13
     1 SMB_USB_CPU0_HUB1_SDA @T6G_MB_LIB.T6G(SCH_1):SMB_USB_CPU0_HUB1_SDA   I148 @T6G_MB_LIB.T6G(SCH_1):PAGE157
     2 SMB_USB_HUB2_TI_SDA_MRP_PRT_CTL2 @T6G_MB_LIB.T6G(SCH_1):SMB_USB_HUB2_TI_SDA_MRP_PRT_CTL2   I148 @T6G_MB_LIB.T6G(SCH_1):PAGE157

R6280 Q_RES_0402LF-0,5%,1/16W,CHIP,CS00002JB13
     1 SMB_USB_CPU0_HUB1_SCL @T6G_MB_LIB.T6G(SCH_1):SMB_USB_CPU0_HUB1_SCL   I146 @T6G_MB_LIB.T6G(SCH_1):PAGE157
     2 SMB_USB_HUB2_TI_SCL_MRP_PRT_CTL1 @T6G_MB_LIB.T6G(SCH_1):SMB_USB_HUB2_TI_SCL_MRP_PRT_CTL1   I146 @T6G_MB_LIB.T6G(SCH_1):PAGE157

R6281 Q_RES_0402LF-1K,1%,1/16W,EMPTY,CS21002FB06
     1 USB_HUB2_TI_SMBUSZ_MRP_PROG_FUNC2 @T6G_MB_LIB.T6G(SCH_1):USB_HUB2_TI_SMBUSZ_MRP_PROG_FUNC2   I139 @T6G_MB_LIB.T6G(SCH_1):PAGE157
     2    GND @T6G_MB_LIB.T6G(SCH_1):GND   I139 @T6G_MB_LIB.T6G(SCH_1):PAGE157

R6282 Q_RES_0402LF-1K,1%,1/16W,EMPTY,CS21002FB06
     1 P3V3_AUX @T6G_MB_LIB.T6G(SCH_1):P3V3_AUX   I138 @T6G_MB_LIB.T6G(SCH_1):PAGE157
     2 USB_HUB2_TI_SMBUSZ_MRP_PROG_FUNC2 @T6G_MB_LIB.T6G(SCH_1):USB_HUB2_TI_SMBUSZ_MRP_PROG_FUNC2   I138 @T6G_MB_LIB.T6G(SCH_1):PAGE157

R6283 Q_RES_0402LF-1K,1%,1/16W,EMPTY,CS21002FB06
     1 P3V3_AUX @T6G_MB_LIB.T6G(SCH_1):P3V3_AUX    I63 @T6G_MB_LIB.T6G(SCH_1):PAGE157
     2 USB_HUB2_TI_FULLPWRMGMTZ_MRP_PROG_FUNC3 @T6G_MB_LIB.T6G(SCH_1):USB_HUB2_TI_FULLPWRMGMTZ_MRP_PROG_FUNC3    I63 @T6G_MB_LIB.T6G(SCH_1):PAGE157

R6284 Q_RES_0402LF-10,1%,1/16W,CHIP,CS01002FB07
     1 USB_HUB2_TI_FULLPWRMGMTZ_MRP_PROG_FUNC3 @T6G_MB_LIB.T6G(SCH_1):USB_HUB2_TI_FULLPWRMGMTZ_MRP_PROG_FUNC3   I171 @T6G_MB_LIB.T6G(SCH_1):PAGE157
     2    GND @T6G_MB_LIB.T6G(SCH_1):GND   I171 @T6G_MB_LIB.T6G(SCH_1):PAGE157

R6285 Q_RES_0402LF-0,5%,1/16W,CHIP,CS00002JB13
     1 USB_HUB2_TI_PWRCTL_POL @T6G_MB_LIB.T6G(SCH_1):USB_HUB2_TI_PWRCTL_POL   I192 @T6G_MB_LIB.T6G(SCH_1):PAGE155
     2 USB_HUB2_TI_PWRCTL_POL_MRP_VBUS_DET @T6G_MB_LIB.T6G(SCH_1):USB_HUB2_TI_PWRCTL_POL_MRP_VBUS_DET   I192 @T6G_MB_LIB.T6G(SCH_1):PAGE155

R6286 Q_RES_0402LF-0,5%,1/16W,CHIP,CS00002JB13
     1 USB_HUB2_MRP_VBUS_DET @T6G_MB_LIB.T6G(SCH_1):USB_HUB2_MRP_VBUS_DET   I193 @T6G_MB_LIB.T6G(SCH_1):PAGE155
     2 USB_HUB2_TI_PWRCTL_POL_MRP_VBUS_DET @T6G_MB_LIB.T6G(SCH_1):USB_HUB2_TI_PWRCTL_POL_MRP_VBUS_DET   I193 @T6G_MB_LIB.T6G(SCH_1):PAGE155

R6287 Q_RES_0402LF-1K,1%,1/16W,CHIP,CS21002FB06
     1 P3V3_AUX @T6G_MB_LIB.T6G(SCH_1):P3V3_AUX   I197 @T6G_MB_LIB.T6G(SCH_1):PAGE155
     2 USB_HUB2_TI_PWRCTL_POL @T6G_MB_LIB.T6G(SCH_1):USB_HUB2_TI_PWRCTL_POL   I197 @T6G_MB_LIB.T6G(SCH_1):PAGE155

R6288 Q_RES_0402LF-1K,1%,1/16W,EMPTY,CS21002FB06
     1 USB_HUB2_TI_PWRCTL_POL @T6G_MB_LIB.T6G(SCH_1):USB_HUB2_TI_PWRCTL_POL   I198 @T6G_MB_LIB.T6G(SCH_1):PAGE155
     2    GND @T6G_MB_LIB.T6G(SCH_1):GND   I198 @T6G_MB_LIB.T6G(SCH_1):PAGE155

R6289 Q_RES_0402LF-10K,1%,1/16W,CHIP,CS31002FB08
     1 P3V3_AUX @T6G_MB_LIB.T6G(SCH_1):P3V3_AUX   I195 @T6G_MB_LIB.T6G(SCH_1):PAGE155
     2 USB_HUB2_MRP_VBUS_DET @T6G_MB_LIB.T6G(SCH_1):USB_HUB2_MRP_VBUS_DET   I195 @T6G_MB_LIB.T6G(SCH_1):PAGE155

R6290 Q_RES_0402LF-0,5%,1/16W,CHIP,CS00002JB13
     1 USB_HUB2_TI_GANGED_MRP_I2C_SLV_CFG0 @T6G_MB_LIB.T6G(SCH_1):USB_HUB2_TI_GANGED_MRP_I2C_SLV_CFG0    I76 @T6G_MB_LIB.T6G(SCH_1):PAGE157
     2 USB_HUB2_TI_GANGED @T6G_MB_LIB.T6G(SCH_1):USB_HUB2_TI_GANGED    I76 @T6G_MB_LIB.T6G(SCH_1):PAGE157

R6291 Q_RES_0402LF-0,5%,1/16W,CHIP,CS00002JB13
     1 USB_HUB2_TI_GANGED_MRP_I2C_SLV_CFG0 @T6G_MB_LIB.T6G(SCH_1):USB_HUB2_TI_GANGED_MRP_I2C_SLV_CFG0    I75 @T6G_MB_LIB.T6G(SCH_1):PAGE157
     2 USB_HUB2_MRP_I2C_SLV_CFG0 @T6G_MB_LIB.T6G(SCH_1):USB_HUB2_MRP_I2C_SLV_CFG0    I75 @T6G_MB_LIB.T6G(SCH_1):PAGE157

R6292 Q_RES_0402LF-1K,1%,1/16W,EMPTY,CS21002FB06
     1 P3V3_AUX @T6G_MB_LIB.T6G(SCH_1):P3V3_AUX    I77 @T6G_MB_LIB.T6G(SCH_1):PAGE157
     2 USB_HUB2_TI_GANGED @T6G_MB_LIB.T6G(SCH_1):USB_HUB2_TI_GANGED    I77 @T6G_MB_LIB.T6G(SCH_1):PAGE157

R6293 Q_RES_0402LF-4.7K,1%,1/16W,CHIP,CS24702FB06
     1 USB_HUB2_TI_GANGED @T6G_MB_LIB.T6G(SCH_1):USB_HUB2_TI_GANGED    I79 @T6G_MB_LIB.T6G(SCH_1):PAGE157
     2    GND @T6G_MB_LIB.T6G(SCH_1):GND    I79 @T6G_MB_LIB.T6G(SCH_1):PAGE157

R6294 Q_RES_0402LF-10K,1%,1/16W,CHIP,CS31002FB08
     1 P3V3_AUX @T6G_MB_LIB.T6G(SCH_1):P3V3_AUX    I81 @T6G_MB_LIB.T6G(SCH_1):PAGE157
     2 USB_HUB2_MRP_I2C_SLV_CFG0 @T6G_MB_LIB.T6G(SCH_1):USB_HUB2_MRP_I2C_SLV_CFG0    I81 @T6G_MB_LIB.T6G(SCH_1):PAGE157

R6295 Q_RES_0402LF-0,5%,1/16W,CHIP,CS00002JB13
     1 USB_HUB2_TI_OVERCCUR4 @T6G_MB_LIB.T6G(SCH_1):USB_HUB2_TI_OVERCCUR4   I182 @T6G_MB_LIB.T6G(SCH_1):PAGE155
     2 USB_HUB2_TI_OVERCUR4_MRP_I2C_SLV_CFG1 @T6G_MB_LIB.T6G(SCH_1):USB_HUB2_TI_OVERCUR4_MRP_I2C_SLV_CFG1   I182 @T6G_MB_LIB.T6G(SCH_1):PAGE155

R6296 Q_RES_0402LF-0,5%,1/16W,CHIP,CS00002JB13
     1 USB_HUB2_MRP_I2C_SLV_CFG1 @T6G_MB_LIB.T6G(SCH_1):USB_HUB2_MRP_I2C_SLV_CFG1   I183 @T6G_MB_LIB.T6G(SCH_1):PAGE155
     2 USB_HUB2_TI_OVERCUR4_MRP_I2C_SLV_CFG1 @T6G_MB_LIB.T6G(SCH_1):USB_HUB2_TI_OVERCUR4_MRP_I2C_SLV_CFG1   I183 @T6G_MB_LIB.T6G(SCH_1):PAGE155

R6297 Q_RES_0402LF-10K,1%,1/16W,CHIP,CS31002FB08
     1 P3V3_AUX @T6G_MB_LIB.T6G(SCH_1):P3V3_AUX   I185 @T6G_MB_LIB.T6G(SCH_1):PAGE155
     2 USB_HUB2_TI_OVERCCUR4 @T6G_MB_LIB.T6G(SCH_1):USB_HUB2_TI_OVERCCUR4   I185 @T6G_MB_LIB.T6G(SCH_1):PAGE155

R6298 Q_RES_0402LF-10K,1%,1/16W,CHIP,CS31002FB08
     1 P3V3_AUX @T6G_MB_LIB.T6G(SCH_1):P3V3_AUX   I187 @T6G_MB_LIB.T6G(SCH_1):PAGE155
     2 USB_HUB2_MRP_I2C_SLV_CFG1 @T6G_MB_LIB.T6G(SCH_1):USB_HUB2_MRP_I2C_SLV_CFG1   I187 @T6G_MB_LIB.T6G(SCH_1):PAGE155

R6299 Q_RES_0402LF-0,5%,1/16W,CHIP,CS00002JB13
     1 USB_HUB2_TI_OVERCUR3 @T6G_MB_LIB.T6G(SCH_1):USB_HUB2_TI_OVERCUR3   I180 @T6G_MB_LIB.T6G(SCH_1):PAGE155
     2 USB_HUB2_TI_OVERCUR3_MRP_CFG_BC_EN @T6G_MB_LIB.T6G(SCH_1):USB_HUB2_TI_OVERCUR3_MRP_CFG_BC_EN   I180 @T6G_MB_LIB.T6G(SCH_1):PAGE155

R6300 Q_RES_0402LF-0,5%,1/16W,CHIP,CS00002JB13
     1 USB_HUB2_MRP_CFG_BC_EN @T6G_MB_LIB.T6G(SCH_1):USB_HUB2_MRP_CFG_BC_EN   I181 @T6G_MB_LIB.T6G(SCH_1):PAGE155
     2 USB_HUB2_TI_OVERCUR3_MRP_CFG_BC_EN @T6G_MB_LIB.T6G(SCH_1):USB_HUB2_TI_OVERCUR3_MRP_CFG_BC_EN   I181 @T6G_MB_LIB.T6G(SCH_1):PAGE155

R6301 Q_RES_0402LF-10K,1%,1/16W,CHIP,CS31002FB08
     1 P3V3_AUX @T6G_MB_LIB.T6G(SCH_1):P3V3_AUX   I179 @T6G_MB_LIB.T6G(SCH_1):PAGE155
     2 USB_HUB2_TI_OVERCUR3 @T6G_MB_LIB.T6G(SCH_1):USB_HUB2_TI_OVERCUR3   I179 @T6G_MB_LIB.T6G(SCH_1):PAGE155

R6302 Q_RES_0402LF-200K,1%,1/16W,CHIP,CS42002FB05
     1 USB_HUB2_MRP_CFG_BC_EN @T6G_MB_LIB.T6G(SCH_1):USB_HUB2_MRP_CFG_BC_EN   I175 @T6G_MB_LIB.T6G(SCH_1):PAGE155
     2    GND @T6G_MB_LIB.T6G(SCH_1):GND   I175 @T6G_MB_LIB.T6G(SCH_1):PAGE155

R6303 Q_RES_0402LF-200K,1%,1/16W,EMPTY,CS42002FB05
     1 P3V3_AUX @T6G_MB_LIB.T6G(SCH_1):P3V3_AUX   I169 @T6G_MB_LIB.T6G(SCH_1):PAGE155
     2 USB_HUB2_MRP_CFG_BC_EN @T6G_MB_LIB.T6G(SCH_1):USB_HUB2_MRP_CFG_BC_EN   I169 @T6G_MB_LIB.T6G(SCH_1):PAGE155

R6304 Q_RES_0402LF-0,5%,1/16W,CHIP,CS00002JB13
     1 USB_HUB2_TI_HS_SUSPEND @T6G_MB_LIB.T6G(SCH_1):USB_HUB2_TI_HS_SUSPEND   I151 @T6G_MB_LIB.T6G(SCH_1):PAGE157
     2 USB_HUB2_TI_HS_SUSPEND_MRP_CFG_NON_REM @T6G_MB_LIB.T6G(SCH_1):USB_HUB2_TI_HS_SUSPEND_MRP_CFG_NON_REM   I151 @T6G_MB_LIB.T6G(SCH_1):PAGE157

R6305 Q_RES_0402LF-0,5%,1/16W,CHIP,CS00002JB13
     1 USB_HUB2_MRP_CFG_NON_REM @T6G_MB_LIB.T6G(SCH_1):USB_HUB2_MRP_CFG_NON_REM   I150 @T6G_MB_LIB.T6G(SCH_1):PAGE157
     2 USB_HUB2_TI_HS_SUSPEND_MRP_CFG_NON_REM @T6G_MB_LIB.T6G(SCH_1):USB_HUB2_TI_HS_SUSPEND_MRP_CFG_NON_REM   I150 @T6G_MB_LIB.T6G(SCH_1):PAGE157

R6306 Q_RES_0402LF-4.7K,1%,1/16W,CHIP,CS24702FB06
     1 P3V3_AUX @T6G_MB_LIB.T6G(SCH_1):P3V3_AUX   I155 @T6G_MB_LIB.T6G(SCH_1):PAGE157
     2 USB_HUB2_TI_HS_SUSPEND @T6G_MB_LIB.T6G(SCH_1):USB_HUB2_TI_HS_SUSPEND   I155 @T6G_MB_LIB.T6G(SCH_1):PAGE157

R6307 Q_RES_0402LF-4.7K,1%,1/16W,EMPTY,CS24702FB06
     1 USB_HUB2_TI_HS_SUSPEND @T6G_MB_LIB.T6G(SCH_1):USB_HUB2_TI_HS_SUSPEND   I156 @T6G_MB_LIB.T6G(SCH_1):PAGE157
     2    GND @T6G_MB_LIB.T6G(SCH_1):GND   I156 @T6G_MB_LIB.T6G(SCH_1):PAGE157

R6308 Q_RES_0402LF-200K,1%,1/16W,EMPTY,CS42002FB05
     1 P3V3_AUX @T6G_MB_LIB.T6G(SCH_1):P3V3_AUX   I153 @T6G_MB_LIB.T6G(SCH_1):PAGE157
     2 USB_HUB2_MRP_CFG_NON_REM @T6G_MB_LIB.T6G(SCH_1):USB_HUB2_MRP_CFG_NON_REM   I153 @T6G_MB_LIB.T6G(SCH_1):PAGE157

R6309 Q_RES_0402LF-200K,1%,1/16W,CHIP,CS42002FB05
     1 USB_HUB2_MRP_CFG_NON_REM @T6G_MB_LIB.T6G(SCH_1):USB_HUB2_MRP_CFG_NON_REM   I158 @T6G_MB_LIB.T6G(SCH_1):PAGE157
     2    GND @T6G_MB_LIB.T6G(SCH_1):GND   I158 @T6G_MB_LIB.T6G(SCH_1):PAGE157

R6310 Q_RES_0402LF-0,5%,1/16W,CHIP,CS00002JB13
     1 USB_HUB2_TI_OVERCUR1 @T6G_MB_LIB.T6G(SCH_1):USB_HUB2_TI_OVERCUR1   I202 @T6G_MB_LIB.T6G(SCH_1):PAGE155
     2 USB_HUB2_TI_OVERCUR1_MRP_PROG_FUNC4 @T6G_MB_LIB.T6G(SCH_1):USB_HUB2_TI_OVERCUR1_MRP_PROG_FUNC4   I202 @T6G_MB_LIB.T6G(SCH_1):PAGE155

R6311 Q_RES_0402LF-0,5%,1/16W,CHIP,CS00002JB13
     1 SMB_USB_CPU0_HUB1_SDA @T6G_MB_LIB.T6G(SCH_1):SMB_USB_CPU0_HUB1_SDA   I200 @T6G_MB_LIB.T6G(SCH_1):PAGE155
     2 USB_HUB2_TI_OVERCUR1_MRP_PROG_FUNC4 @T6G_MB_LIB.T6G(SCH_1):USB_HUB2_TI_OVERCUR1_MRP_PROG_FUNC4   I200 @T6G_MB_LIB.T6G(SCH_1):PAGE155

R6312 Q_RES_0402LF-10K,1%,1/16W,CHIP,CS31002FB08
     1 P3V3_AUX @T6G_MB_LIB.T6G(SCH_1):P3V3_AUX   I205 @T6G_MB_LIB.T6G(SCH_1):PAGE155
     2 USB_HUB2_TI_OVERCUR1 @T6G_MB_LIB.T6G(SCH_1):USB_HUB2_TI_OVERCUR1   I205 @T6G_MB_LIB.T6G(SCH_1):PAGE155

R6313 Q_RES_0402LF-0,5%,1/16W,CHIP,CS00002JB13
     1 USB_HUB2_TI_OVERCUR2 @T6G_MB_LIB.T6G(SCH_1):USB_HUB2_TI_OVERCUR2   I138 @T6G_MB_LIB.T6G(SCH_1):PAGE155
     2 USB_HUB2_TI_OVERCUR2_MRP_PROG_FUNC5 @T6G_MB_LIB.T6G(SCH_1):USB_HUB2_TI_OVERCUR2_MRP_PROG_FUNC5   I138 @T6G_MB_LIB.T6G(SCH_1):PAGE155

R6314 Q_RES_0402LF-0,5%,1/16W,CHIP,CS00002JB13
     1 SMB_USB_CPU0_HUB1_SCL @T6G_MB_LIB.T6G(SCH_1):SMB_USB_CPU0_HUB1_SCL   I137 @T6G_MB_LIB.T6G(SCH_1):PAGE155
     2 USB_HUB2_TI_OVERCUR2_MRP_PROG_FUNC5 @T6G_MB_LIB.T6G(SCH_1):USB_HUB2_TI_OVERCUR2_MRP_PROG_FUNC5   I137 @T6G_MB_LIB.T6G(SCH_1):PAGE155

R6315 Q_RES_0402LF-10K,1%,1/16W,CHIP,CS31002FB08
     1 P3V3_AUX @T6G_MB_LIB.T6G(SCH_1):P3V3_AUX   I140 @T6G_MB_LIB.T6G(SCH_1):PAGE155
     2 USB_HUB2_TI_OVERCUR2 @T6G_MB_LIB.T6G(SCH_1):USB_HUB2_TI_OVERCUR2   I140 @T6G_MB_LIB.T6G(SCH_1):PAGE155

R6316 Q_RES_0402LF-0,5%,1/16W,CHIP,CS00002JB13
     1 USB_HUB2_TI_USB_VBUS @T6G_MB_LIB.T6G(SCH_1):USB_HUB2_TI_USB_VBUS   I119 @T6G_MB_LIB.T6G(SCH_1):PAGE155
     2 USB_HUB2_TI_USB_VBUS_MRP_RESET_N @T6G_MB_LIB.T6G(SCH_1):USB_HUB2_TI_USB_VBUS_MRP_RESET_N   I119 @T6G_MB_LIB.T6G(SCH_1):PAGE155

R6317 Q_RES_0402LF-0,5%,1/16W,CHIP,CS00002JB13
     1 USB_HUB2_MRP_RESET_N @T6G_MB_LIB.T6G(SCH_1):USB_HUB2_MRP_RESET_N   I124 @T6G_MB_LIB.T6G(SCH_1):PAGE155
     2 USB_HUB2_TI_USB_VBUS_MRP_RESET_N @T6G_MB_LIB.T6G(SCH_1):USB_HUB2_TI_USB_VBUS_MRP_RESET_N   I124 @T6G_MB_LIB.T6G(SCH_1):PAGE155

R6318 Q_RES_0402LF-90.9K,1%,1/16W,CHIP,CS39092FB04
     1 P5V_AUX @T6G_MB_LIB.T6G(SCH_1):P5V_AUX   I123 @T6G_MB_LIB.T6G(SCH_1):PAGE155
     2 USB_HUB2_TI_USB_VBUS @T6G_MB_LIB.T6G(SCH_1):USB_HUB2_TI_USB_VBUS   I123 @T6G_MB_LIB.T6G(SCH_1):PAGE155

R6319 Q_RES_0402LF-10K,1%,1/16W,CHIP,CS31002FB08
     1 USB_HUB2_TI_USB_VBUS @T6G_MB_LIB.T6G(SCH_1):USB_HUB2_TI_USB_VBUS   I121 @T6G_MB_LIB.T6G(SCH_1):PAGE155
     2    GND @T6G_MB_LIB.T6G(SCH_1):GND   I121 @T6G_MB_LIB.T6G(SCH_1):PAGE155

R6320 Q_RES_0402LF-10K,1%,1/16W,EMPTY,CS31002FB08
     1 P3V3_AUX @T6G_MB_LIB.T6G(SCH_1):P3V3_AUX   I212 @T6G_MB_LIB.T6G(SCH_1):PAGE155
     2 USB_HUB2_MRP_RESET_N @T6G_MB_LIB.T6G(SCH_1):USB_HUB2_MRP_RESET_N   I212 @T6G_MB_LIB.T6G(SCH_1):PAGE155

R6321 Q_RES_0402LF-47K,0.1%,1/16W,EMPTY,CS34702BB05
     1 USB_HUB2_MRP_RESET_N @T6G_MB_LIB.T6G(SCH_1):USB_HUB2_MRP_RESET_N   I129 @T6G_MB_LIB.T6G(SCH_1):PAGE155
     2    GND @T6G_MB_LIB.T6G(SCH_1):GND   I129 @T6G_MB_LIB.T6G(SCH_1):PAGE155

R6322 Q_RES_0402LF-0,5%,1/16W,CHIP,CS00002JB13
     1 RST_USB_HUB_N @T6G_MB_LIB.T6G(SCH_1):RST_USB_HUB_N   I131 @T6G_MB_LIB.T6G(SCH_1):PAGE155
     2 USB_HUB2_MRP_RESET_N @T6G_MB_LIB.T6G(SCH_1):USB_HUB2_MRP_RESET_N   I131 @T6G_MB_LIB.T6G(SCH_1):PAGE155

R6323 Q_RES_0402LF-0,5%,1/16W,CHIP,CS00002JB13
     1 USB_HUB2_TI_TEST @T6G_MB_LIB.T6G(SCH_1):USB_HUB2_TI_TEST   I115 @T6G_MB_LIB.T6G(SCH_1):PAGE155
     2 USB_HUB2_TI_TEST_MRP_PROG_FUNC6 @T6G_MB_LIB.T6G(SCH_1):USB_HUB2_TI_TEST_MRP_PROG_FUNC6   I115 @T6G_MB_LIB.T6G(SCH_1):PAGE155

R6324 Q_RES_0402LF-0,5%,1/16W,CHIP,CS00002JB13
     1 USB_HUB2_MRP_PROG_FUNC6 @T6G_MB_LIB.T6G(SCH_1):USB_HUB2_MRP_PROG_FUNC6   I118 @T6G_MB_LIB.T6G(SCH_1):PAGE155
     2 USB_HUB2_TI_TEST_MRP_PROG_FUNC6 @T6G_MB_LIB.T6G(SCH_1):USB_HUB2_TI_TEST_MRP_PROG_FUNC6   I118 @T6G_MB_LIB.T6G(SCH_1):PAGE155

R6325 Q_RES_0402LF-10K,1%,1/16W,CHIP,CS31002FB08
     1 USB_HUB2_TI_TEST @T6G_MB_LIB.T6G(SCH_1):USB_HUB2_TI_TEST   I116 @T6G_MB_LIB.T6G(SCH_1):PAGE155
     2    GND @T6G_MB_LIB.T6G(SCH_1):GND   I116 @T6G_MB_LIB.T6G(SCH_1):PAGE155

R6326 Q_RES_0402LF-4.7K,1%,1/16W,CHIP,CS24702FB06
     1 USB_HUB2_MRP_PROG_FUNC6 @T6G_MB_LIB.T6G(SCH_1):USB_HUB2_MRP_PROG_FUNC6    I89 @T6G_MB_LIB.T6G(SCH_1):PAGE155
     2    GND @T6G_MB_LIB.T6G(SCH_1):GND    I89 @T6G_MB_LIB.T6G(SCH_1):PAGE155

R6327 Q_RES_0402LF-4.7K,1%,1/16W,EMPTY,CS24702FB06
     1 P3V3_AUX @T6G_MB_LIB.T6G(SCH_1):P3V3_AUX    I91 @T6G_MB_LIB.T6G(SCH_1):PAGE155
     2 USB_HUB2_MRP_PROG_FUNC6 @T6G_MB_LIB.T6G(SCH_1):USB_HUB2_MRP_PROG_FUNC6    I91 @T6G_MB_LIB.T6G(SCH_1):PAGE155

R6328 Q_RES_0402LF-0,5%,1/16W,CHIP,CS00002JB13
     1 RST_USB_HUB_N @T6G_MB_LIB.T6G(SCH_1):RST_USB_HUB_N   I114 @T6G_MB_LIB.T6G(SCH_1):PAGE155
     2 USB_HUB2_TI_GRSTZ_MRP_PROG_FUNC1 @T6G_MB_LIB.T6G(SCH_1):USB_HUB2_TI_GRSTZ_MRP_PROG_FUNC1   I114 @T6G_MB_LIB.T6G(SCH_1):PAGE155

R6329 Q_RES_0402LF-10K,1%,1/16W,EMPTY,CS31002FB08
     1 P3V3_AUX @T6G_MB_LIB.T6G(SCH_1):P3V3_AUX   I213 @T6G_MB_LIB.T6G(SCH_1):PAGE155
     2 USB_HUB2_TI_GRSTZ_MRP_PROG_FUNC1 @T6G_MB_LIB.T6G(SCH_1):USB_HUB2_TI_GRSTZ_MRP_PROG_FUNC1   I213 @T6G_MB_LIB.T6G(SCH_1):PAGE155

R6330 Q_RES_0402LF-4.7K,1%,1/16W,CHIP,CS24702FB06
     1    GND @T6G_MB_LIB.T6G(SCH_1):GND   I188 @T6G_MB_LIB.T6G(SCH_1):PAGE155
     2 USB_HUB2_TI_NC_MRP_ATEST @T6G_MB_LIB.T6G(SCH_1):USB_HUB2_TI_NC_MRP_ATEST   I188 @T6G_MB_LIB.T6G(SCH_1):PAGE155

R6331 Q_RES_0402LF-9.53K,1%,1/16W,CHIP,CS29532FB06
     1 USB_HUB2_TI_USB_R1_MRP_RBIAS @T6G_MB_LIB.T6G(SCH_1):USB_HUB2_TI_USB_R1_MRP_RBIAS   I207 @T6G_MB_LIB.T6G(SCH_1):PAGE155
     2    GND @T6G_MB_LIB.T6G(SCH_1):GND   I207 @T6G_MB_LIB.T6G(SCH_1):PAGE155

R6332 Q_RES_0402LF-12K,1%,1/16W,CHIP,CS31202FB04
     1 USB_HUB2_TI_USB_R1_MRP_RBIAS @T6G_MB_LIB.T6G(SCH_1):USB_HUB2_TI_USB_R1_MRP_RBIAS   I208 @T6G_MB_LIB.T6G(SCH_1):PAGE155
     2    GND @T6G_MB_LIB.T6G(SCH_1):GND   I208 @T6G_MB_LIB.T6G(SCH_1):PAGE155

R6333 Q_RES_0402LF-47K,0.1%,1/16W,EMPTY,CS34702BB05
     1 USB_HUB2_TI_GRSTZ_MRP_PROG_FUNC1 @T6G_MB_LIB.T6G(SCH_1):USB_HUB2_TI_GRSTZ_MRP_PROG_FUNC1   I111 @T6G_MB_LIB.T6G(SCH_1):PAGE155
     2    GND @T6G_MB_LIB.T6G(SCH_1):GND   I111 @T6G_MB_LIB.T6G(SCH_1):PAGE155

R6500 Q_RES_0402LF-0,5%,1/16W,CHIP,CS00002JB13
     1 PWRGD_P3V3_EN_R @T6G_MB_LIB.T6G(SCH_1):PWRGD_P3V3_EN_R   I136 @T6G_MB_LIB.T6G(SCH_1):PAGE273
     2 PWRGD_P3V3_EN @T6G_MB_LIB.T6G(SCH_1):PWRGD_P3V3_EN   I136 @T6G_MB_LIB.T6G(SCH_1):PAGE273

R6501 Q_RES_0402LF-100K,1%,1/16W,CHIP,CS41002FB09
     1 PWRGD_P3V3_EN_R @T6G_MB_LIB.T6G(SCH_1):PWRGD_P3V3_EN_R   I139 @T6G_MB_LIB.T6G(SCH_1):PAGE273
     2    GND @T6G_MB_LIB.T6G(SCH_1):GND   I139 @T6G_MB_LIB.T6G(SCH_1):PAGE273

R6502 Q_RES_0402LF-2.2K,5%,1/16W,CHIP,CS22202JB07
     1 CPU0_FORCE_SELFREFRESH @T6G_MB_LIB.T6G(SCH_1):CPU0_FORCE_SELFREFRESH   I224 @T6G_MB_LIB.T6G(SCH_1):PAGE28
     2    GND @T6G_MB_LIB.T6G(SCH_1):GND   I224 @T6G_MB_LIB.T6G(SCH_1):PAGE28

R6503 Q_RES_0402LF-2.2K,5%,1/16W,CHIP,CS22202JB07
     1 CPU1_FORCE_SELFREFRESH @T6G_MB_LIB.T6G(SCH_1):CPU1_FORCE_SELFREFRESH   I392 @T6G_MB_LIB.T6G(SCH_1):PAGE55
     2    GND @T6G_MB_LIB.T6G(SCH_1):GND   I392 @T6G_MB_LIB.T6G(SCH_1):PAGE55

R6504 Q_RES_0402LF-10K,1%,1/16W,CHIP,CS31002FB08
     1 P1V8_AUX @T6G_MB_LIB.T6G(SCH_1):P1V8_AUX    I51 @T6G_MB_LIB.T6G(SCH_1):PAGE264
     2 PU_U38_6 @T6G_MB_LIB.T6G(SCH_1):PU_U38_6    I51 @T6G_MB_LIB.T6G(SCH_1):PAGE264

R6505 Q_RES_0402LF-10K,5%,1/16W,CHIP,CS31002JB08
     1 P3V3_AUX @T6G_MB_LIB.T6G(SCH_1):P3V3_AUX    I28 @T6G_MB_LIB.T6G(SCH_1):PAGE469
     2 PWRGD_P1V8_RETIMER_CPU0 @T6G_MB_LIB.T6G(SCH_1):PWRGD_P1V8_RETIMER_CPU0    I28 @T6G_MB_LIB.T6G(SCH_1):PAGE469

R6506 Q_RES_0402LF-33,5%,1/16W,CHIP,CS03302JB10
     1 PWRGD_P1V8_RETIMER_CPU0 @T6G_MB_LIB.T6G(SCH_1):PWRGD_P1V8_RETIMER_CPU0    I37 @T6G_MB_LIB.T6G(SCH_1):PAGE469
     2 FM_PWRGD_P1V8_RETIMER_CPU0 @T6G_MB_LIB.T6G(SCH_1):FM_PWRGD_P1V8_RETIMER_CPU0    I37 @T6G_MB_LIB.T6G(SCH_1):PAGE469

R6701 Q_RES_0402LF-0,5%,1/16W,EMPTY,CS00002JB13
     1 P1V8_CPU1_RT_1D @T6G_MB_LIB.T6G(SCH_1):P1V8_CPU1_RT_1D    I98 @T6G_MB_LIB.T6G(SCH_1):PAGE398
     2 P1V8_CPU1_RT0_1A_1D @T6G_MB_LIB.T6G(SCH_1):P1V8_CPU1_RT0_1A_1D    I98 @T6G_MB_LIB.T6G(SCH_1):PAGE398

R6702 Q_RES_0402LF-0,5%,1/16W,EMPTY,CS00002JB13
     1 P1V8_CPU1_RT0_1A_1D @T6G_MB_LIB.T6G(SCH_1):P1V8_CPU1_RT0_1A_1D    I32 @T6G_MB_LIB.T6G(SCH_1):PAGE398
     2 P1V8_CPU1_RT0_1A @T6G_MB_LIB.T6G(SCH_1):P1V8_CPU1_RT0_1A    I32 @T6G_MB_LIB.T6G(SCH_1):PAGE398

R6703 Q_RES_0402LF-0,5%,1/16W,EMPTY,CS00002JB13
     1 P1V8_CPU1_RT0_1A_1D @T6G_MB_LIB.T6G(SCH_1):P1V8_CPU1_RT0_1A_1D    I33 @T6G_MB_LIB.T6G(SCH_1):PAGE398
     2 P1V8_CPU1_RT0_1A @T6G_MB_LIB.T6G(SCH_1):P1V8_CPU1_RT0_1A    I33 @T6G_MB_LIB.T6G(SCH_1):PAGE398

R6704 Q_RES_0603LF-0,5%,1/4W,EMPTY,CS00006J900
     1 P0V9_CPU1_RT_2D @T6G_MB_LIB.T6G(SCH_1):P0V9_CPU1_RT_2D    I96 @T6G_MB_LIB.T6G(SCH_1):PAGE398
     2 P0V9_CPU1_RT0_2A_2D @T6G_MB_LIB.T6G(SCH_1):P0V9_CPU1_RT0_2A_2D    I96 @T6G_MB_LIB.T6G(SCH_1):PAGE398

R6705 Q_RES_0603LF-0,5%,1/4W,CHIP,CS00006J900
     1 P0V9_CPU1_RT0_2A_2D @T6G_MB_LIB.T6G(SCH_1):P0V9_CPU1_RT0_2A_2D    I95 @T6G_MB_LIB.T6G(SCH_1):PAGE398
     2 P0V9_CPU1_RT0_2A @T6G_MB_LIB.T6G(SCH_1):P0V9_CPU1_RT0_2A    I95 @T6G_MB_LIB.T6G(SCH_1):PAGE398

R6706 Q_RES_0201LF-1K,1%,1/20W,CHIP,CS21001FE07
     1 P1V8_CPU1_RT_1D @T6G_MB_LIB.T6G(SCH_1):P1V8_CPU1_RT_1D    I65 @T6G_MB_LIB.T6G(SCH_1):PAGE377
     2 SMB_RT_CPU1_P0_ROM_R_SCL @T6G_MB_LIB.T6G(SCH_1):SMB_RT_CPU1_P0_ROM_R_SCL    I65 @T6G_MB_LIB.T6G(SCH_1):PAGE377

R6707 Q_RES_0201LF-1K,1%,1/20W,CHIP,CS21001FE07
     1 P1V8_CPU1_RT_1D @T6G_MB_LIB.T6G(SCH_1):P1V8_CPU1_RT_1D    I64 @T6G_MB_LIB.T6G(SCH_1):PAGE377
     2 SMB_RT_CPU1_P0_ROM_R_SDA @T6G_MB_LIB.T6G(SCH_1):SMB_RT_CPU1_P0_ROM_R_SDA    I64 @T6G_MB_LIB.T6G(SCH_1):PAGE377

R6708 Q_RES_0201LF-0,5%,1/20W,CHIP,CS00001JE10
     1 RST_RT_CPU1_P0_PERST_N @T6G_MB_LIB.T6G(SCH_1):RST_RT_CPU1_P0_PERST_N    I62 @T6G_MB_LIB.T6G(SCH_1):PAGE401
     2 RST_RT_CPU1_P0_PERST_R_N @T6G_MB_LIB.T6G(SCH_1):RST_RT_CPU1_P0_PERST_R_N    I62 @T6G_MB_LIB.T6G(SCH_1):PAGE401

R6709 Q_RES_0201LF-0,5%,1/20W,CHIP,CS00001JE10
     1 RST_RT_CPU1_P0_RESET_N @T6G_MB_LIB.T6G(SCH_1):RST_RT_CPU1_P0_RESET_N    I65 @T6G_MB_LIB.T6G(SCH_1):PAGE401
     2 RST_RT_CPU1_P0_RESET_R_N @T6G_MB_LIB.T6G(SCH_1):RST_RT_CPU1_P0_RESET_R_N    I65 @T6G_MB_LIB.T6G(SCH_1):PAGE401

R6710 Q_RES_0402LF-0,5%,1/16W,CHIP,CS00002JB13
     1 RST_RT_CPU1_P0_PERST_R_N @T6G_MB_LIB.T6G(SCH_1):RST_RT_CPU1_P0_PERST_R_N   I322 @T6G_MB_LIB.T6G(SCH_1):PAGE80
     2 RST_RT_CPU1_P0_PERST_R2_N @T6G_MB_LIB.T6G(SCH_1):RST_RT_CPU1_P0_PERST_R2_N   I322 @T6G_MB_LIB.T6G(SCH_1):PAGE80

R6711 Q_RES_0402LF-0,5%,1/16W,CHIP,CS00002JB13
     1 RST_RT_CPU1_P0_RESET_R_N @T6G_MB_LIB.T6G(SCH_1):RST_RT_CPU1_P0_RESET_R_N   I324 @T6G_MB_LIB.T6G(SCH_1):PAGE80
     2 RST_RT_CPU1_P0_RESET_R2_N @T6G_MB_LIB.T6G(SCH_1):RST_RT_CPU1_P0_RESET_R2_N   I324 @T6G_MB_LIB.T6G(SCH_1):PAGE80

R6712 Q_RES_0201LF-1K,1%,1/20W,CHIP,CS21001FE07
     1 P1V8_CPU1_RT_1D @T6G_MB_LIB.T6G(SCH_1):P1V8_CPU1_RT_1D   I102 @T6G_MB_LIB.T6G(SCH_1):PAGE401
     2 RT_CPU1_P0_ADDR3 @T6G_MB_LIB.T6G(SCH_1):RT_CPU1_P0_ADDR3   I102 @T6G_MB_LIB.T6G(SCH_1):PAGE401

R6713 Q_RES_0201LF-1K,1%,1/20W,EMPTY,CS21001FE07
     1 RT_CPU1_P0_ADDR3 @T6G_MB_LIB.T6G(SCH_1):RT_CPU1_P0_ADDR3   I103 @T6G_MB_LIB.T6G(SCH_1):PAGE401
     2    GND @T6G_MB_LIB.T6G(SCH_1):GND   I103 @T6G_MB_LIB.T6G(SCH_1):PAGE401

R6714 Q_RES_0201LF-1K,1%,1/20W,EMPTY,CS21001FE07
     1 P1V8_CPU1_RT_1D @T6G_MB_LIB.T6G(SCH_1):P1V8_CPU1_RT_1D   I104 @T6G_MB_LIB.T6G(SCH_1):PAGE401
     2 RT_CPU1_P0_ADDR2 @T6G_MB_LIB.T6G(SCH_1):RT_CPU1_P0_ADDR2   I104 @T6G_MB_LIB.T6G(SCH_1):PAGE401

R6715 Q_RES_0201LF-20K,1%,1/20W,CHIP,CS32001FE00
     1 RT_CPU1_P0_ADDR2 @T6G_MB_LIB.T6G(SCH_1):RT_CPU1_P0_ADDR2   I105 @T6G_MB_LIB.T6G(SCH_1):PAGE401
     2    GND @T6G_MB_LIB.T6G(SCH_1):GND   I105 @T6G_MB_LIB.T6G(SCH_1):PAGE401

R6716 Q_RES_0201LF-1K,1%,1/20W,EMPTY,CS21001FE07
     1 P1V8_CPU1_RT_1D @T6G_MB_LIB.T6G(SCH_1):P1V8_CPU1_RT_1D   I107 @T6G_MB_LIB.T6G(SCH_1):PAGE401
     2 RT_CPU1_P0_ADDR1 @T6G_MB_LIB.T6G(SCH_1):RT_CPU1_P0_ADDR1   I107 @T6G_MB_LIB.T6G(SCH_1):PAGE401

R6717 Q_RES_0201LF-1K,1%,1/20W,CHIP,CS21001FE07
     1 RT_CPU1_P0_ADDR1 @T6G_MB_LIB.T6G(SCH_1):RT_CPU1_P0_ADDR1   I106 @T6G_MB_LIB.T6G(SCH_1):PAGE401
     2    GND @T6G_MB_LIB.T6G(SCH_1):GND   I106 @T6G_MB_LIB.T6G(SCH_1):PAGE401

R6718 Q_RES_0201LF-1K,1%,1/20W,CHIP,CS21001FE07
     1 P1V8_CPU1_RT_1D @T6G_MB_LIB.T6G(SCH_1):P1V8_CPU1_RT_1D     I9 @T6G_MB_LIB.T6G(SCH_1):PAGE378
     2 SMB_RT_CPU1_P0_R_SDA @T6G_MB_LIB.T6G(SCH_1):SMB_RT_CPU1_P0_R_SDA     I9 @T6G_MB_LIB.T6G(SCH_1):PAGE378

R6719 Q_RES_0201LF-1K,1%,1/20W,CHIP,CS21001FE07
     1 P1V8_CPU1_RT_1D @T6G_MB_LIB.T6G(SCH_1):P1V8_CPU1_RT_1D    I11 @T6G_MB_LIB.T6G(SCH_1):PAGE378
     2 SMB_RT_CPU1_P0_R_SCL @T6G_MB_LIB.T6G(SCH_1):SMB_RT_CPU1_P0_R_SCL    I11 @T6G_MB_LIB.T6G(SCH_1):PAGE378

R6720 Q_RES_0201LF-10K,1%,1/20W,CHIP,CS31001FE17
     1 RST_RT_CPU1_P0_PERST_R_N @T6G_MB_LIB.T6G(SCH_1):RST_RT_CPU1_P0_PERST_R_N    I97 @T6G_MB_LIB.T6G(SCH_1):PAGE401
     2    GND @T6G_MB_LIB.T6G(SCH_1):GND    I97 @T6G_MB_LIB.T6G(SCH_1):PAGE401

R6721 Q_RES_0201LF-10K,1%,1/20W,CHIP,CS31001FE17
     1 RST_RT_CPU1_P0_RESET_R_N @T6G_MB_LIB.T6G(SCH_1):RST_RT_CPU1_P0_RESET_R_N    I96 @T6G_MB_LIB.T6G(SCH_1):PAGE401
     2    GND @T6G_MB_LIB.T6G(SCH_1):GND    I96 @T6G_MB_LIB.T6G(SCH_1):PAGE401

R6722 Q_RES_0201LF-4.7K,5%,1/20W,EMPTY,CS24701JE04
     1 P1V8_CPU1_RT_1D @T6G_MB_LIB.T6G(SCH_1):P1V8_CPU1_RT_1D    I85 @T6G_MB_LIB.T6G(SCH_1):PAGE401
     2 RT_CPU1_P0_SCAN_MODE @T6G_MB_LIB.T6G(SCH_1):RT_CPU1_P0_SCAN_MODE    I85 @T6G_MB_LIB.T6G(SCH_1):PAGE401

R6723 Q_RES_0201LF-200,1%,1/20W,CHIP,CS12001FE12
     1 RT_CPU1_P0_SCAN_MODE @T6G_MB_LIB.T6G(SCH_1):RT_CPU1_P0_SCAN_MODE   I128 @T6G_MB_LIB.T6G(SCH_1):PAGE401
     2    GND @T6G_MB_LIB.T6G(SCH_1):GND   I128 @T6G_MB_LIB.T6G(SCH_1):PAGE401

R6724 Q_RES_0201LF-4.7K,5%,1/20W,EMPTY,CS24701JE04
     1 P1V8_CPU1_RT_1D @T6G_MB_LIB.T6G(SCH_1):P1V8_CPU1_RT_1D   I101 @T6G_MB_LIB.T6G(SCH_1):PAGE401
     2 RST_RT_CPU1_P0_RESET_R_N @T6G_MB_LIB.T6G(SCH_1):RST_RT_CPU1_P0_RESET_R_N   I101 @T6G_MB_LIB.T6G(SCH_1):PAGE401

R6725 Q_RES_0201LF-4.7K,5%,1/20W,EMPTY,CS24701JE04
     1 P1V8_CPU1_RT_1D @T6G_MB_LIB.T6G(SCH_1):P1V8_CPU1_RT_1D    I91 @T6G_MB_LIB.T6G(SCH_1):PAGE401
     2 JTAG_TEST_MODE_RT_CPU1_P0 @T6G_MB_LIB.T6G(SCH_1):JTAG_TEST_MODE_RT_CPU1_P0    I91 @T6G_MB_LIB.T6G(SCH_1):PAGE401

R6730 Q_RES_0201LF-1K,1%,1/20W,EMPTY,CS21001FE07
     1 P1V8_CPU1_RT_1D @T6G_MB_LIB.T6G(SCH_1):P1V8_CPU1_RT_1D    I21 @T6G_MB_LIB.T6G(SCH_1):PAGE391
     2 RT_CPU1_P1_VQPS @T6G_MB_LIB.T6G(SCH_1):RT_CPU1_P1_VQPS    I21 @T6G_MB_LIB.T6G(SCH_1):PAGE391

R6731 Q_RES_0201LF-200,1%,1/20W,CHIP,CS12001FE12
     1 RT_CPU1_P1_VQPS @T6G_MB_LIB.T6G(SCH_1):RT_CPU1_P1_VQPS    I20 @T6G_MB_LIB.T6G(SCH_1):PAGE391
     2    GND @T6G_MB_LIB.T6G(SCH_1):GND    I20 @T6G_MB_LIB.T6G(SCH_1):PAGE391

R6732 Q_RES_0201LF-0,5%,1/20W,CHIP,CS00001JE10
     1 NCF_A1_CPU1_P1_GND @T6G_MB_LIB.T6G(SCH_1):NCF_A1_CPU1_P1_GND    I16 @T6G_MB_LIB.T6G(SCH_1):PAGE391
     2    GND @T6G_MB_LIB.T6G(SCH_1):GND    I16 @T6G_MB_LIB.T6G(SCH_1):PAGE391

R6733 Q_RES_0201LF-0,5%,1/20W,CHIP,CS00001JE10
     1 NCF_CPU1_P1_GND @T6G_MB_LIB.T6G(SCH_1):NCF_CPU1_P1_GND    I15 @T6G_MB_LIB.T6G(SCH_1):PAGE391
     2    GND @T6G_MB_LIB.T6G(SCH_1):GND    I15 @T6G_MB_LIB.T6G(SCH_1):PAGE391

R6734 Q_RES_0201LF-1K,1%,1/20W,CHIP,CS21001FE07
     1 P1V8_CPU1_RT_1D @T6G_MB_LIB.T6G(SCH_1):P1V8_CPU1_RT_1D    I62 @T6G_MB_LIB.T6G(SCH_1):PAGE377
     2 SMB_RT_CPU1_P1_ROM_R_SCL @T6G_MB_LIB.T6G(SCH_1):SMB_RT_CPU1_P1_ROM_R_SCL    I62 @T6G_MB_LIB.T6G(SCH_1):PAGE377

R6735 Q_RES_0201LF-1K,1%,1/20W,CHIP,CS21001FE07
     1 P1V8_CPU1_RT_1D @T6G_MB_LIB.T6G(SCH_1):P1V8_CPU1_RT_1D    I63 @T6G_MB_LIB.T6G(SCH_1):PAGE377
     2 SMB_RT_CPU1_P1_ROM_R_SDA @T6G_MB_LIB.T6G(SCH_1):SMB_RT_CPU1_P1_ROM_R_SDA    I63 @T6G_MB_LIB.T6G(SCH_1):PAGE377

R6736 Q_RES_0201LF-0,5%,1/20W,CHIP,CS00001JE10
     1 SMB_RT_CPU1_P1_R_SDA @T6G_MB_LIB.T6G(SCH_1):SMB_RT_CPU1_P1_R_SDA    I13 @T6G_MB_LIB.T6G(SCH_1):PAGE378
     2 SMB_RT_CPU1_P1_SDA @T6G_MB_LIB.T6G(SCH_1):SMB_RT_CPU1_P1_SDA    I13 @T6G_MB_LIB.T6G(SCH_1):PAGE378

R6737 Q_RES_0201LF-0,5%,1/20W,CHIP,CS00001JE10
     1 SMB_RT_CPU1_P1_R_SCL @T6G_MB_LIB.T6G(SCH_1):SMB_RT_CPU1_P1_R_SCL    I14 @T6G_MB_LIB.T6G(SCH_1):PAGE378
     2 SMB_RT_CPU1_P1_SCL @T6G_MB_LIB.T6G(SCH_1):SMB_RT_CPU1_P1_SCL    I14 @T6G_MB_LIB.T6G(SCH_1):PAGE378

R6738 Q_RES_0201LF-1K,1%,1/20W,CHIP,CS21001FE07
     1 P1V8_CPU1_RT_1D @T6G_MB_LIB.T6G(SCH_1):P1V8_CPU1_RT_1D    I17 @T6G_MB_LIB.T6G(SCH_1):PAGE378
     2 SMB_RT_CPU1_P1_R_SDA @T6G_MB_LIB.T6G(SCH_1):SMB_RT_CPU1_P1_R_SDA    I17 @T6G_MB_LIB.T6G(SCH_1):PAGE378

R6739 Q_RES_0201LF-1K,1%,1/20W,CHIP,CS21001FE07
     1 P1V8_CPU1_RT_1D @T6G_MB_LIB.T6G(SCH_1):P1V8_CPU1_RT_1D    I18 @T6G_MB_LIB.T6G(SCH_1):PAGE378
     2 SMB_RT_CPU1_P1_R_SCL @T6G_MB_LIB.T6G(SCH_1):SMB_RT_CPU1_P1_R_SCL    I18 @T6G_MB_LIB.T6G(SCH_1):PAGE378

R6740 Q_RES_0402LF-0,5%,1/16W,CHIP,CS00002JB13
     1 RST_RT_CPU1_P1_PERST_R_N @T6G_MB_LIB.T6G(SCH_1):RST_RT_CPU1_P1_PERST_R_N   I326 @T6G_MB_LIB.T6G(SCH_1):PAGE80
     2 RST_RT_CPU1_P1_PERST_R2_N @T6G_MB_LIB.T6G(SCH_1):RST_RT_CPU1_P1_PERST_R2_N   I326 @T6G_MB_LIB.T6G(SCH_1):PAGE80

R6741 Q_RES_0402LF-0,5%,1/16W,CHIP,CS00002JB13
     1 RST_RT_CPU1_P1_RESET_R_N @T6G_MB_LIB.T6G(SCH_1):RST_RT_CPU1_P1_RESET_R_N   I327 @T6G_MB_LIB.T6G(SCH_1):PAGE80
     2 RST_RT_CPU1_P1_RESET_R2_N @T6G_MB_LIB.T6G(SCH_1):RST_RT_CPU1_P1_RESET_R2_N   I327 @T6G_MB_LIB.T6G(SCH_1):PAGE80

R6742 Q_RES_0402LF-1K,1%,1/16W,EMPTY,CS21002FB06
     1 P1V8_AUX @T6G_MB_LIB.T6G(SCH_1):P1V8_AUX     I5 @T6G_MB_LIB.T6G(SCH_1):PAGE467
     2 RT_BOARD_ID_ID1 @T6G_MB_LIB.T6G(SCH_1):RT_BOARD_ID_ID1     I5 @T6G_MB_LIB.T6G(SCH_1):PAGE467

R6743 Q_RES_0402LF-1K,1%,1/16W,EMPTY,CS21002FB06
     1 P1V8_AUX @T6G_MB_LIB.T6G(SCH_1):P1V8_AUX     I6 @T6G_MB_LIB.T6G(SCH_1):PAGE467
     2 RT_BOARD_ID_ID0 @T6G_MB_LIB.T6G(SCH_1):RT_BOARD_ID_ID0     I6 @T6G_MB_LIB.T6G(SCH_1):PAGE467

R6744 Q_RES_0402LF-1K,1%,1/16W,CHIP,CS21002FB06
     1 RT_BOARD_ID_ID1 @T6G_MB_LIB.T6G(SCH_1):RT_BOARD_ID_ID1     I2 @T6G_MB_LIB.T6G(SCH_1):PAGE467
     2    GND @T6G_MB_LIB.T6G(SCH_1):GND     I2 @T6G_MB_LIB.T6G(SCH_1):PAGE467

R6745 Q_RES_0402LF-1K,1%,1/16W,CHIP,CS21002FB06
     1 RT_BOARD_ID_ID0 @T6G_MB_LIB.T6G(SCH_1):RT_BOARD_ID_ID0     I4 @T6G_MB_LIB.T6G(SCH_1):PAGE467
     2    GND @T6G_MB_LIB.T6G(SCH_1):GND     I4 @T6G_MB_LIB.T6G(SCH_1):PAGE467

R6746 Q_RES_0201LF-0,5%,1/20W,CHIP,CS00001JE10
     1 SMB_RT_CPU1_P3_R_SDA @T6G_MB_LIB.T6G(SCH_1):SMB_RT_CPU1_P3_R_SDA    I22 @T6G_MB_LIB.T6G(SCH_1):PAGE378
     2 SMB_RT_CPU1_P3_SDA @T6G_MB_LIB.T6G(SCH_1):SMB_RT_CPU1_P3_SDA    I22 @T6G_MB_LIB.T6G(SCH_1):PAGE378

R6747 Q_RES_0201LF-0,5%,1/20W,CHIP,CS00001JE10
     1 SMB_RT_CPU1_P3_R_SCL @T6G_MB_LIB.T6G(SCH_1):SMB_RT_CPU1_P3_R_SCL    I21 @T6G_MB_LIB.T6G(SCH_1):PAGE378
     2 SMB_RT_CPU1_P3_SCL @T6G_MB_LIB.T6G(SCH_1):SMB_RT_CPU1_P3_SCL    I21 @T6G_MB_LIB.T6G(SCH_1):PAGE378

R6748 Q_RES_0201LF-0,5%,1/20W,CHIP,CS00001JE10
     1 SMB_RT_CPU1_P2_R_SDA @T6G_MB_LIB.T6G(SCH_1):SMB_RT_CPU1_P2_R_SDA    I26 @T6G_MB_LIB.T6G(SCH_1):PAGE378
     2 SMB_RT_CPU1_P2_SDA @T6G_MB_LIB.T6G(SCH_1):SMB_RT_CPU1_P2_SDA    I26 @T6G_MB_LIB.T6G(SCH_1):PAGE378

R6749 Q_RES_0201LF-0,5%,1/20W,CHIP,CS00001JE10
     1 SMB_RT_CPU1_P2_R_SCL @T6G_MB_LIB.T6G(SCH_1):SMB_RT_CPU1_P2_R_SCL    I25 @T6G_MB_LIB.T6G(SCH_1):PAGE378
     2 SMB_RT_CPU1_P2_SCL @T6G_MB_LIB.T6G(SCH_1):SMB_RT_CPU1_P2_SCL    I25 @T6G_MB_LIB.T6G(SCH_1):PAGE378

R6750 Q_RES_0201LF-1K,1%,1/20W,CHIP,CS21001FE07
     1 P1V8_CPU1_RT_1D @T6G_MB_LIB.T6G(SCH_1):P1V8_CPU1_RT_1D    I31 @T6G_MB_LIB.T6G(SCH_1):PAGE378
     2 SMB_RT_CPU1_P3_R_SDA @T6G_MB_LIB.T6G(SCH_1):SMB_RT_CPU1_P3_R_SDA    I31 @T6G_MB_LIB.T6G(SCH_1):PAGE378

R6751 Q_RES_0201LF-1K,1%,1/20W,CHIP,CS21001FE07
     1 P1V8_CPU1_RT_1D @T6G_MB_LIB.T6G(SCH_1):P1V8_CPU1_RT_1D    I32 @T6G_MB_LIB.T6G(SCH_1):PAGE378
     2 SMB_RT_CPU1_P3_R_SCL @T6G_MB_LIB.T6G(SCH_1):SMB_RT_CPU1_P3_R_SCL    I32 @T6G_MB_LIB.T6G(SCH_1):PAGE378

R6752 Q_RES_0201LF-1K,1%,1/20W,CHIP,CS21001FE07
     1 P1V8_CPU1_RT_1D @T6G_MB_LIB.T6G(SCH_1):P1V8_CPU1_RT_1D    I35 @T6G_MB_LIB.T6G(SCH_1):PAGE378
     2 SMB_RT_CPU1_P2_R_SDA @T6G_MB_LIB.T6G(SCH_1):SMB_RT_CPU1_P2_R_SDA    I35 @T6G_MB_LIB.T6G(SCH_1):PAGE378

R6753 Q_RES_0201LF-1K,1%,1/20W,CHIP,CS21001FE07
     1 P1V8_CPU1_RT_1D @T6G_MB_LIB.T6G(SCH_1):P1V8_CPU1_RT_1D    I36 @T6G_MB_LIB.T6G(SCH_1):PAGE378
     2 SMB_RT_CPU1_P2_R_SCL @T6G_MB_LIB.T6G(SCH_1):SMB_RT_CPU1_P2_R_SCL    I36 @T6G_MB_LIB.T6G(SCH_1):PAGE378

R6754 Q_RES_0201LF-0,5%,1/20W,CHIP,CS00001JE10
     1 SMB_RT_CPU0_P0_SDA @T6G_MB_LIB.T6G(SCH_1):SMB_RT_CPU0_P0_SDA    I53 @T6G_MB_LIB.T6G(SCH_1):PAGE378
     2 SMB_RT_CPU0_P0_R_SDA @T6G_MB_LIB.T6G(SCH_1):SMB_RT_CPU0_P0_R_SDA    I53 @T6G_MB_LIB.T6G(SCH_1):PAGE378

R6755 Q_RES_0201LF-0,5%,1/20W,CHIP,CS00001JE10
     1 SMB_RT_CPU0_P0_SCL @T6G_MB_LIB.T6G(SCH_1):SMB_RT_CPU0_P0_SCL    I54 @T6G_MB_LIB.T6G(SCH_1):PAGE378
     2 SMB_RT_CPU0_P0_R_SCL @T6G_MB_LIB.T6G(SCH_1):SMB_RT_CPU0_P0_R_SCL    I54 @T6G_MB_LIB.T6G(SCH_1):PAGE378

R6756 Q_RES_0201LF-0,5%,1/20W,CHIP,CS00001JE10
     1 SMB_RT_CPU0_P1_SDA @T6G_MB_LIB.T6G(SCH_1):SMB_RT_CPU0_P1_SDA    I56 @T6G_MB_LIB.T6G(SCH_1):PAGE378
     2 SMB_RT_CPU0_P1_R_SDA @T6G_MB_LIB.T6G(SCH_1):SMB_RT_CPU0_P1_R_SDA    I56 @T6G_MB_LIB.T6G(SCH_1):PAGE378

R6757 Q_RES_0201LF-0,5%,1/20W,CHIP,CS00001JE10
     1 SMB_RT_CPU0_P1_SCL @T6G_MB_LIB.T6G(SCH_1):SMB_RT_CPU0_P1_SCL    I57 @T6G_MB_LIB.T6G(SCH_1):PAGE378
     2 SMB_RT_CPU0_P1_R_SCL @T6G_MB_LIB.T6G(SCH_1):SMB_RT_CPU0_P1_R_SCL    I57 @T6G_MB_LIB.T6G(SCH_1):PAGE378

R6758 Q_RES_0201LF-0,5%,1/20W,CHIP,CS00001JE10
     1 SMB_RT_CPU0_P3_SDA @T6G_MB_LIB.T6G(SCH_1):SMB_RT_CPU0_P3_SDA    I55 @T6G_MB_LIB.T6G(SCH_1):PAGE378
     2 SMB_RT_CPU0_P3_R_SDA @T6G_MB_LIB.T6G(SCH_1):SMB_RT_CPU0_P3_R_SDA    I55 @T6G_MB_LIB.T6G(SCH_1):PAGE378

R6759 Q_RES_0201LF-0,5%,1/20W,CHIP,CS00001JE10
     1 SMB_RT_CPU0_P3_SCL @T6G_MB_LIB.T6G(SCH_1):SMB_RT_CPU0_P3_SCL    I59 @T6G_MB_LIB.T6G(SCH_1):PAGE378
     2 SMB_RT_CPU0_P3_R_SCL @T6G_MB_LIB.T6G(SCH_1):SMB_RT_CPU0_P3_R_SCL    I59 @T6G_MB_LIB.T6G(SCH_1):PAGE378

R6760 Q_RES_0201LF-0,5%,1/20W,CHIP,CS00001JE10
     1 SMB_RT_CPU0_P2_SDA @T6G_MB_LIB.T6G(SCH_1):SMB_RT_CPU0_P2_SDA    I58 @T6G_MB_LIB.T6G(SCH_1):PAGE378
     2 SMB_RT_CPU0_P2_R_SDA @T6G_MB_LIB.T6G(SCH_1):SMB_RT_CPU0_P2_R_SDA    I58 @T6G_MB_LIB.T6G(SCH_1):PAGE378

R6761 Q_RES_0201LF-0,5%,1/20W,CHIP,CS00001JE10
     1 SMB_RT_CPU0_P2_SCL @T6G_MB_LIB.T6G(SCH_1):SMB_RT_CPU0_P2_SCL    I60 @T6G_MB_LIB.T6G(SCH_1):PAGE378
     2 SMB_RT_CPU0_P2_R_SCL @T6G_MB_LIB.T6G(SCH_1):SMB_RT_CPU0_P2_R_SCL    I60 @T6G_MB_LIB.T6G(SCH_1):PAGE378

R6762 Q_RES_0201LF-1K,1%,1/20W,CHIP,CS21001FE07
     1 P1V8_CPU0_RT_1D @T6G_MB_LIB.T6G(SCH_1):P1V8_CPU0_RT_1D    I77 @T6G_MB_LIB.T6G(SCH_1):PAGE378
     2 SMB_RT_CPU0_P0_R_SDA @T6G_MB_LIB.T6G(SCH_1):SMB_RT_CPU0_P0_R_SDA    I77 @T6G_MB_LIB.T6G(SCH_1):PAGE378

R6763 Q_RES_0201LF-1K,1%,1/20W,CHIP,CS21001FE07
     1 P1V8_CPU0_RT_1D @T6G_MB_LIB.T6G(SCH_1):P1V8_CPU0_RT_1D    I78 @T6G_MB_LIB.T6G(SCH_1):PAGE378
     2 SMB_RT_CPU0_P0_R_SCL @T6G_MB_LIB.T6G(SCH_1):SMB_RT_CPU0_P0_R_SCL    I78 @T6G_MB_LIB.T6G(SCH_1):PAGE378

R6764 Q_RES_0201LF-1K,1%,1/20W,CHIP,CS21001FE07
     1 P1V8_CPU0_RT_1D @T6G_MB_LIB.T6G(SCH_1):P1V8_CPU0_RT_1D    I79 @T6G_MB_LIB.T6G(SCH_1):PAGE378
     2 SMB_RT_CPU0_P1_R_SDA @T6G_MB_LIB.T6G(SCH_1):SMB_RT_CPU0_P1_R_SDA    I79 @T6G_MB_LIB.T6G(SCH_1):PAGE378

R6765 Q_RES_0201LF-1K,1%,1/20W,CHIP,CS21001FE07
     1 P1V8_CPU0_RT_1D @T6G_MB_LIB.T6G(SCH_1):P1V8_CPU0_RT_1D    I80 @T6G_MB_LIB.T6G(SCH_1):PAGE378
     2 SMB_RT_CPU0_P1_R_SCL @T6G_MB_LIB.T6G(SCH_1):SMB_RT_CPU0_P1_R_SCL    I80 @T6G_MB_LIB.T6G(SCH_1):PAGE378

R6766 Q_RES_0201LF-1K,1%,1/20W,CHIP,CS21001FE07
     1 P1V8_CPU0_RT_1D @T6G_MB_LIB.T6G(SCH_1):P1V8_CPU0_RT_1D    I83 @T6G_MB_LIB.T6G(SCH_1):PAGE378
     2 SMB_RT_CPU0_P3_R_SDA @T6G_MB_LIB.T6G(SCH_1):SMB_RT_CPU0_P3_R_SDA    I83 @T6G_MB_LIB.T6G(SCH_1):PAGE378

R6767 Q_RES_0201LF-1K,1%,1/20W,CHIP,CS21001FE07
     1 P1V8_CPU0_RT_1D @T6G_MB_LIB.T6G(SCH_1):P1V8_CPU0_RT_1D    I82 @T6G_MB_LIB.T6G(SCH_1):PAGE378
     2 SMB_RT_CPU0_P3_R_SCL @T6G_MB_LIB.T6G(SCH_1):SMB_RT_CPU0_P3_R_SCL    I82 @T6G_MB_LIB.T6G(SCH_1):PAGE378

R6768 Q_RES_0201LF-1K,1%,1/20W,CHIP,CS21001FE07
     1 P1V8_CPU0_RT_1D @T6G_MB_LIB.T6G(SCH_1):P1V8_CPU0_RT_1D    I84 @T6G_MB_LIB.T6G(SCH_1):PAGE378
     2 SMB_RT_CPU0_P2_R_SDA @T6G_MB_LIB.T6G(SCH_1):SMB_RT_CPU0_P2_R_SDA    I84 @T6G_MB_LIB.T6G(SCH_1):PAGE378

R6769 Q_RES_0201LF-1K,1%,1/20W,CHIP,CS21001FE07
     1 P1V8_CPU0_RT_1D @T6G_MB_LIB.T6G(SCH_1):P1V8_CPU0_RT_1D    I85 @T6G_MB_LIB.T6G(SCH_1):PAGE378
     2 SMB_RT_CPU0_P2_R_SCL @T6G_MB_LIB.T6G(SCH_1):SMB_RT_CPU0_P2_R_SCL    I85 @T6G_MB_LIB.T6G(SCH_1):PAGE378

R6770 Q_RES_0201LF-4.7K,5%,1/20W,EMPTY,CS24701JE04
     1 P1V8_AUX @T6G_MB_LIB.T6G(SCH_1):P1V8_AUX    I96 @T6G_MB_LIB.T6G(SCH_1):PAGE378
     2 RT_SMB_MUX_ADDR2 @T6G_MB_LIB.T6G(SCH_1):RT_SMB_MUX_ADDR2    I96 @T6G_MB_LIB.T6G(SCH_1):PAGE378

R6771 Q_RES_0201LF-4.7K,5%,1/20W,EMPTY,CS24701JE04
     1 P1V8_AUX @T6G_MB_LIB.T6G(SCH_1):P1V8_AUX   I100 @T6G_MB_LIB.T6G(SCH_1):PAGE378
     2 RT_SMB_MUX_ADDR1 @T6G_MB_LIB.T6G(SCH_1):RT_SMB_MUX_ADDR1   I100 @T6G_MB_LIB.T6G(SCH_1):PAGE378

R6772 Q_RES_0201LF-4.7K,5%,1/20W,EMPTY,CS24701JE04
     1 P1V8_AUX @T6G_MB_LIB.T6G(SCH_1):P1V8_AUX    I98 @T6G_MB_LIB.T6G(SCH_1):PAGE378
     2 RT_SMB_MUX_ADDR0 @T6G_MB_LIB.T6G(SCH_1):RT_SMB_MUX_ADDR0    I98 @T6G_MB_LIB.T6G(SCH_1):PAGE378

R6773 Q_RES_0201LF-4.7K,5%,1/20W,CHIP,CS24701JE04
     1 RT_SMB_MUX_ADDR2 @T6G_MB_LIB.T6G(SCH_1):RT_SMB_MUX_ADDR2    I94 @T6G_MB_LIB.T6G(SCH_1):PAGE378
     2    GND @T6G_MB_LIB.T6G(SCH_1):GND    I94 @T6G_MB_LIB.T6G(SCH_1):PAGE378

R6774 Q_RES_0201LF-4.7K,5%,1/20W,CHIP,CS24701JE04
     1 RT_SMB_MUX_ADDR1 @T6G_MB_LIB.T6G(SCH_1):RT_SMB_MUX_ADDR1    I95 @T6G_MB_LIB.T6G(SCH_1):PAGE378
     2    GND @T6G_MB_LIB.T6G(SCH_1):GND    I95 @T6G_MB_LIB.T6G(SCH_1):PAGE378

R6775 Q_RES_0201LF-4.7K,5%,1/20W,CHIP,CS24701JE04
     1 RT_SMB_MUX_ADDR0 @T6G_MB_LIB.T6G(SCH_1):RT_SMB_MUX_ADDR0    I97 @T6G_MB_LIB.T6G(SCH_1):PAGE378
     2    GND @T6G_MB_LIB.T6G(SCH_1):GND    I97 @T6G_MB_LIB.T6G(SCH_1):PAGE378

R6776 Q_RES_0201LF-0,5%,1/20W,CHIP,CS00001JE10
     1 RST_SMB_RT_R1_N @T6G_MB_LIB.T6G(SCH_1):RST_SMB_RT_R1_N   I104 @T6G_MB_LIB.T6G(SCH_1):PAGE378
     2 RST_SMB_RT_N @T6G_MB_LIB.T6G(SCH_1):RST_SMB_RT_N   I104 @T6G_MB_LIB.T6G(SCH_1):PAGE378

R6777 Q_RES_0402LF-0,5%,1/16W,CHIP,CS00002JB13
     1 RST_SMB_RT_R2_N @T6G_MB_LIB.T6G(SCH_1):RST_SMB_RT_R2_N   I330 @T6G_MB_LIB.T6G(SCH_1):PAGE80
     2 RST_SMB_RT_R1_N @T6G_MB_LIB.T6G(SCH_1):RST_SMB_RT_R1_N   I330 @T6G_MB_LIB.T6G(SCH_1):PAGE80

R6778 Q_RES_0201LF-10K,1%,1/20W,CHIP,CS31001FE17
     1 RST_SMB_RT_R1_N @T6G_MB_LIB.T6G(SCH_1):RST_SMB_RT_R1_N   I107 @T6G_MB_LIB.T6G(SCH_1):PAGE378
     2    GND @T6G_MB_LIB.T6G(SCH_1):GND   I107 @T6G_MB_LIB.T6G(SCH_1):PAGE378

R6779 Q_RES_0201LF-33.2,1%,1/20W,CHIP,CS03321FE09
     1 SMB_MUX_RT_SDA @T6G_MB_LIB.T6G(SCH_1):SMB_MUX_RT_SDA   I119 @T6G_MB_LIB.T6G(SCH_1):PAGE378
     2 SMB_MUX_RT_R1_SDA @T6G_MB_LIB.T6G(SCH_1):SMB_MUX_RT_R1_SDA   I119 @T6G_MB_LIB.T6G(SCH_1):PAGE378

R6780 Q_RES_0201LF-33.2,1%,1/20W,CHIP,CS03321FE09
     1 SMB_MUX_RT_SCL @T6G_MB_LIB.T6G(SCH_1):SMB_MUX_RT_SCL   I120 @T6G_MB_LIB.T6G(SCH_1):PAGE378
     2 SMB_MUX_RT_R1_SCL @T6G_MB_LIB.T6G(SCH_1):SMB_MUX_RT_R1_SCL   I120 @T6G_MB_LIB.T6G(SCH_1):PAGE378

R6781 Q_RES_0402LF-0,5%,1/16W,CHIP,CS00002JB13
     1 RST_SMB_RT_ROM_R2_N @T6G_MB_LIB.T6G(SCH_1):RST_SMB_RT_ROM_R2_N   I332 @T6G_MB_LIB.T6G(SCH_1):PAGE80
     2 RST_SMB_RT_ROM_R1_N @T6G_MB_LIB.T6G(SCH_1):RST_SMB_RT_ROM_R1_N   I332 @T6G_MB_LIB.T6G(SCH_1):PAGE80

R6782 Q_RES_0402LF-33,5%,1/16W,CHIP,CS03302JB10
     1 SMB_MUX_RT_ROM_R1_SCL @T6G_MB_LIB.T6G(SCH_1):SMB_MUX_RT_ROM_R1_SCL   I228 @T6G_MB_LIB.T6G(SCH_1):PAGE349
     2 SMB_HOST_CLK_3V3AUX_SCL_R1 @T6G_MB_LIB.T6G(SCH_1):SMB_HOST_CLK_3V3AUX_SCL_R1   I228 @T6G_MB_LIB.T6G(SCH_1):PAGE349

R6783 Q_RES_0402LF-33,5%,1/16W,CHIP,CS03302JB10
     1 SMB_MUX_RT_ROM_R1_SDA @T6G_MB_LIB.T6G(SCH_1):SMB_MUX_RT_ROM_R1_SDA   I229 @T6G_MB_LIB.T6G(SCH_1):PAGE349
     2 SMB_HOST_CLK_3V3AUX_SDA_R1 @T6G_MB_LIB.T6G(SCH_1):SMB_HOST_CLK_3V3AUX_SDA_R1   I229 @T6G_MB_LIB.T6G(SCH_1):PAGE349

R6784 Q_RES_0402LF-0,5%,1/16W,CHIP,CS00002JB13
     1 SMB_MUX_RT_R1_SCL @T6G_MB_LIB.T6G(SCH_1):SMB_MUX_RT_R1_SCL   I198 @T6G_MB_LIB.T6G(SCH_1):PAGE349
     2 SMB_SML1_PMBUS_HSC_SCL @T6G_MB_LIB.T6G(SCH_1):SMB_SML1_PMBUS_HSC_SCL   I198 @T6G_MB_LIB.T6G(SCH_1):PAGE349

R6785 Q_RES_0402LF-0,5%,1/16W,CHIP,CS00002JB13
     1 SMB_MUX_RT_R1_SDA @T6G_MB_LIB.T6G(SCH_1):SMB_MUX_RT_R1_SDA   I199 @T6G_MB_LIB.T6G(SCH_1):PAGE349
     2 SMB_SML1_PMBUS_HSC_SDA @T6G_MB_LIB.T6G(SCH_1):SMB_SML1_PMBUS_HSC_SDA   I199 @T6G_MB_LIB.T6G(SCH_1):PAGE349

R6786 Q_RES_0402LF-1K,1%,1/16W,CHIP,CS21002FB06
     1 P0V9_RETIMER_CPU0_EN0_R @T6G_MB_LIB.T6G(SCH_1):P0V9_RETIMER_CPU0_EN0_R   I208 @T6G_MB_LIB.T6G(SCH_1):PAGE475
     2    GND @T6G_MB_LIB.T6G(SCH_1):GND   I208 @T6G_MB_LIB.T6G(SCH_1):PAGE475

R6787 Q_RES_0402LF-1K,1%,1/16W,CHIP,CS21002FB06
     1 P0V9_RETIMER_CPU1_EN0_R @T6G_MB_LIB.T6G(SCH_1):P0V9_RETIMER_CPU1_EN0_R    I90 @T6G_MB_LIB.T6G(SCH_1):PAGE477
     2    GND @T6G_MB_LIB.T6G(SCH_1):GND    I90 @T6G_MB_LIB.T6G(SCH_1):PAGE477

R6788 Q_RES_0201LF-1K,1%,1/20W,CHIP,CS21001FE07
     1 U12_E2 @T6G_MB_LIB.T6G(SCH_1):U12_E2    I13 @T6G_MB_LIB.T6G(SCH_1):PAGE399
     2    GND @T6G_MB_LIB.T6G(SCH_1):GND    I13 @T6G_MB_LIB.T6G(SCH_1):PAGE399

R6789 Q_RES_0201LF-1K,1%,1/20W,CHIP,CS21001FE07
     1 U19_E2 @T6G_MB_LIB.T6G(SCH_1):U19_E2    I19 @T6G_MB_LIB.T6G(SCH_1):PAGE442
     2    GND @T6G_MB_LIB.T6G(SCH_1):GND    I19 @T6G_MB_LIB.T6G(SCH_1):PAGE442

R6790 Q_RES_0201LF-1K,1%,1/20W,CHIP,CS21001FE07
     1 U20_E2 @T6G_MB_LIB.T6G(SCH_1):U20_E2    I19 @T6G_MB_LIB.T6G(SCH_1):PAGE453
     2    GND @T6G_MB_LIB.T6G(SCH_1):GND    I19 @T6G_MB_LIB.T6G(SCH_1):PAGE453

R6791 Q_RES_0201LF-1K,1%,1/20W,CHIP,CS21001FE07
     1 U21_E2 @T6G_MB_LIB.T6G(SCH_1):U21_E2    I22 @T6G_MB_LIB.T6G(SCH_1):PAGE464
     2    GND @T6G_MB_LIB.T6G(SCH_1):GND    I22 @T6G_MB_LIB.T6G(SCH_1):PAGE464

R6792 Q_RES_0402LF-0,5%,1/16W,CHIP,CS00002JB13
     1 RST_RT_CPU1_P2_PERST_R_N @T6G_MB_LIB.T6G(SCH_1):RST_RT_CPU1_P2_PERST_R_N   I334 @T6G_MB_LIB.T6G(SCH_1):PAGE80
     2 RST_RT_CPU1_P2_PERST_R2_N @T6G_MB_LIB.T6G(SCH_1):RST_RT_CPU1_P2_PERST_R2_N   I334 @T6G_MB_LIB.T6G(SCH_1):PAGE80

R6793 Q_RES_0402LF-0,5%,1/16W,CHIP,CS00002JB13
     1 RST_RT_CPU1_P2_RESET_R_N @T6G_MB_LIB.T6G(SCH_1):RST_RT_CPU1_P2_RESET_R_N   I335 @T6G_MB_LIB.T6G(SCH_1):PAGE80
     2 RST_RT_CPU1_P2_RESET_R2_N @T6G_MB_LIB.T6G(SCH_1):RST_RT_CPU1_P2_RESET_R2_N   I335 @T6G_MB_LIB.T6G(SCH_1):PAGE80

R6794 Q_RES_0201LF-1K,1%,1/20W,EMPTY,CS21001FE07
     1 P1V8_CPU1_RT_1D @T6G_MB_LIB.T6G(SCH_1):P1V8_CPU1_RT_1D    I21 @T6G_MB_LIB.T6G(SCH_1):PAGE452
     2 RT_CPU1_P2_VQPS @T6G_MB_LIB.T6G(SCH_1):RT_CPU1_P2_VQPS    I21 @T6G_MB_LIB.T6G(SCH_1):PAGE452

R6795 Q_RES_0201LF-200,1%,1/20W,CHIP,CS12001FE12
     1 RT_CPU1_P2_VQPS @T6G_MB_LIB.T6G(SCH_1):RT_CPU1_P2_VQPS    I20 @T6G_MB_LIB.T6G(SCH_1):PAGE452
     2    GND @T6G_MB_LIB.T6G(SCH_1):GND    I20 @T6G_MB_LIB.T6G(SCH_1):PAGE452

R6796 Q_RES_0201LF-0,5%,1/20W,CHIP,CS00001JE10
     1 NCF_A1_CPU1_P2_GND @T6G_MB_LIB.T6G(SCH_1):NCF_A1_CPU1_P2_GND    I18 @T6G_MB_LIB.T6G(SCH_1):PAGE452
     2    GND @T6G_MB_LIB.T6G(SCH_1):GND    I18 @T6G_MB_LIB.T6G(SCH_1):PAGE452

R6797 Q_RES_0201LF-0,5%,1/20W,CHIP,CS00001JE10
     1 NCF_CPU1_P2_GND @T6G_MB_LIB.T6G(SCH_1):NCF_CPU1_P2_GND    I15 @T6G_MB_LIB.T6G(SCH_1):PAGE452
     2    GND @T6G_MB_LIB.T6G(SCH_1):GND    I15 @T6G_MB_LIB.T6G(SCH_1):PAGE452

R6798 Q_RES_0402LF-0,5%,1/16W,CHIP,CS00002JB13
     1 RST_RT_CPU1_P3_PERST_R_N @T6G_MB_LIB.T6G(SCH_1):RST_RT_CPU1_P3_PERST_R_N   I338 @T6G_MB_LIB.T6G(SCH_1):PAGE80
     2 RST_RT_CPU1_P3_PERST_R2_N @T6G_MB_LIB.T6G(SCH_1):RST_RT_CPU1_P3_PERST_R2_N   I338 @T6G_MB_LIB.T6G(SCH_1):PAGE80

R6799 Q_RES_0402LF-0,5%,1/16W,CHIP,CS00002JB13
     1 RST_RT_CPU1_P3_RESET_R_N @T6G_MB_LIB.T6G(SCH_1):RST_RT_CPU1_P3_RESET_R_N   I339 @T6G_MB_LIB.T6G(SCH_1):PAGE80
     2 RST_RT_CPU1_P3_RESET_R2_N @T6G_MB_LIB.T6G(SCH_1):RST_RT_CPU1_P3_RESET_R2_N   I339 @T6G_MB_LIB.T6G(SCH_1):PAGE80

R6800 Q_RES_0402LF-0,5%,1/16W,CHIP,CS00002JB13
     1    GND @T6G_MB_LIB.T6G(SCH_1):GND     I2 @T6G_MB_LIB.T6G(SCH_1):PAGE477
     2 P0V9_RETIMER_CPU1_EN1_R @T6G_MB_LIB.T6G(SCH_1):P0V9_RETIMER_CPU1_EN1_R     I2 @T6G_MB_LIB.T6G(SCH_1):PAGE477

R6801 Q_RES_0402LF-0,5%,1/16W,CHIP,CS00002JB13
     1    GND @T6G_MB_LIB.T6G(SCH_1):GND   I161 @T6G_MB_LIB.T6G(SCH_1):PAGE475
     2 P0V9_RETIMER_CPU0_EN1_R @T6G_MB_LIB.T6G(SCH_1):P0V9_RETIMER_CPU0_EN1_R   I161 @T6G_MB_LIB.T6G(SCH_1):PAGE475

R6802 Q_RES_0402LF-10K,1%,1/16W,CHIP,CS31002FB08
     1 FM_9ZXL045_P0_3_OE_N @T6G_MB_LIB.T6G(SCH_1):FM_9ZXL045_P0_3_OE_N    I68 @T6G_MB_LIB.T6G(SCH_1):PAGE160
     2    GND @T6G_MB_LIB.T6G(SCH_1):GND    I68 @T6G_MB_LIB.T6G(SCH_1):PAGE160

R6803 Q_RES_0402LF-10K,1%,1/16W,CHIP,CS31002FB08
     1 FM_9ZXL045_P1_3_OE_N @T6G_MB_LIB.T6G(SCH_1):FM_9ZXL045_P1_3_OE_N    I76 @T6G_MB_LIB.T6G(SCH_1):PAGE379
     2    GND @T6G_MB_LIB.T6G(SCH_1):GND    I76 @T6G_MB_LIB.T6G(SCH_1):PAGE379

R6804 Q_RES_0402LF-0,5%,1/16W,CHIP,CS00002JB13
     1 RST_RT_CPU0_P0_PERST_R_N @T6G_MB_LIB.T6G(SCH_1):RST_RT_CPU0_P0_PERST_R_N   I342 @T6G_MB_LIB.T6G(SCH_1):PAGE80
     2 RST_RT_CPU0_P0_PERST_R2_N @T6G_MB_LIB.T6G(SCH_1):RST_RT_CPU0_P0_PERST_R2_N   I342 @T6G_MB_LIB.T6G(SCH_1):PAGE80

R6805 Q_RES_0402LF-0,5%,1/16W,CHIP,CS00002JB13
     1 RST_RT_CPU0_P0_RESET_R_N @T6G_MB_LIB.T6G(SCH_1):RST_RT_CPU0_P0_RESET_R_N   I343 @T6G_MB_LIB.T6G(SCH_1):PAGE80
     2 RST_RT_CPU0_P0_RESET_R2_N @T6G_MB_LIB.T6G(SCH_1):RST_RT_CPU0_P0_RESET_R2_N   I343 @T6G_MB_LIB.T6G(SCH_1):PAGE80

R6806 Q_RES_0402LF-0,5%,1/16W,CHIP,CS00002JB13
     1 RST_RT_CPU0_P1_PERST_R_N @T6G_MB_LIB.T6G(SCH_1):RST_RT_CPU0_P1_PERST_R_N   I344 @T6G_MB_LIB.T6G(SCH_1):PAGE80
     2 RST_RT_CPU0_P1_PERST_R2_N @T6G_MB_LIB.T6G(SCH_1):RST_RT_CPU0_P1_PERST_R2_N   I344 @T6G_MB_LIB.T6G(SCH_1):PAGE80

R6807 Q_RES_0402LF-0,5%,1/16W,CHIP,CS00002JB13
     1 RST_RT_CPU0_P1_RESET_R_N @T6G_MB_LIB.T6G(SCH_1):RST_RT_CPU0_P1_RESET_R_N   I345 @T6G_MB_LIB.T6G(SCH_1):PAGE80
     2 RST_RT_CPU0_P1_RESET_R2_N @T6G_MB_LIB.T6G(SCH_1):RST_RT_CPU0_P1_RESET_R2_N   I345 @T6G_MB_LIB.T6G(SCH_1):PAGE80

R6808 Q_RES_0201LF-1K,1%,1/20W,EMPTY,CS21001FE07
     1 P1V8_CPU0_RT_1D @T6G_MB_LIB.T6G(SCH_1):P1V8_CPU0_RT_1D    I19 @T6G_MB_LIB.T6G(SCH_1):PAGE386
     2 RT_CPU0_P0_VQPS @T6G_MB_LIB.T6G(SCH_1):RT_CPU0_P0_VQPS    I19 @T6G_MB_LIB.T6G(SCH_1):PAGE386

R6809 Q_RES_0201LF-200,1%,1/20W,CHIP,CS12001FE12
     1 RT_CPU0_P0_VQPS @T6G_MB_LIB.T6G(SCH_1):RT_CPU0_P0_VQPS    I18 @T6G_MB_LIB.T6G(SCH_1):PAGE386
     2    GND @T6G_MB_LIB.T6G(SCH_1):GND    I18 @T6G_MB_LIB.T6G(SCH_1):PAGE386

R6810 Q_RES_0201LF-0,5%,1/20W,CHIP,CS00001JE10
     1 SMB_RT_CPU1_P0_R_SDA @T6G_MB_LIB.T6G(SCH_1):SMB_RT_CPU1_P0_R_SDA     I6 @T6G_MB_LIB.T6G(SCH_1):PAGE378
     2 SMB_RT_CPU1_P0_SDA @T6G_MB_LIB.T6G(SCH_1):SMB_RT_CPU1_P0_SDA     I6 @T6G_MB_LIB.T6G(SCH_1):PAGE378

R6811 Q_RES_0201LF-0,5%,1/20W,CHIP,CS00001JE10
     1 SMB_RT_CPU1_P0_R_SCL @T6G_MB_LIB.T6G(SCH_1):SMB_RT_CPU1_P0_R_SCL     I7 @T6G_MB_LIB.T6G(SCH_1):PAGE378
     2 SMB_RT_CPU1_P0_SCL @T6G_MB_LIB.T6G(SCH_1):SMB_RT_CPU1_P0_SCL     I7 @T6G_MB_LIB.T6G(SCH_1):PAGE378

R6812 Q_RES_0201LF-0,5%,1/20W,CHIP,CS00001JE10
     1 SMB_RT_CPU1_P0_R_SCL @T6G_MB_LIB.T6G(SCH_1):SMB_RT_CPU1_P0_R_SCL    I19 @T6G_MB_LIB.T6G(SCH_1):PAGE401
     2 SMB_RT_CPU1_P0_R2_SCL @T6G_MB_LIB.T6G(SCH_1):SMB_RT_CPU1_P0_R2_SCL    I19 @T6G_MB_LIB.T6G(SCH_1):PAGE401

R6813 Q_RES_0201LF-0,5%,1/20W,CHIP,CS00001JE10
     1 SMB_RT_CPU1_P0_R_SDA @T6G_MB_LIB.T6G(SCH_1):SMB_RT_CPU1_P0_R_SDA    I20 @T6G_MB_LIB.T6G(SCH_1):PAGE401
     2 SMB_RT_CPU1_P0_R2_SDA @T6G_MB_LIB.T6G(SCH_1):SMB_RT_CPU1_P0_R2_SDA    I20 @T6G_MB_LIB.T6G(SCH_1):PAGE401

R6820 Q_RES_0201LF-0,5%,1/20W,CHIP,CS00001JE10
     1 NCF_A1_CPU0_P0_GND @T6G_MB_LIB.T6G(SCH_1):NCF_A1_CPU0_P0_GND    I15 @T6G_MB_LIB.T6G(SCH_1):PAGE386
     2    GND @T6G_MB_LIB.T6G(SCH_1):GND    I15 @T6G_MB_LIB.T6G(SCH_1):PAGE386

R6821 Q_RES_0201LF-0,5%,1/20W,CHIP,CS00001JE10
     1 NCF_CPU0_P0_GND @T6G_MB_LIB.T6G(SCH_1):NCF_CPU0_P0_GND    I13 @T6G_MB_LIB.T6G(SCH_1):PAGE386
     2    GND @T6G_MB_LIB.T6G(SCH_1):GND    I13 @T6G_MB_LIB.T6G(SCH_1):PAGE386

R6822 Q_RES_0201LF-1K,1%,1/20W,CHIP,CS21001FE07
     1 U11_E2 @T6G_MB_LIB.T6G(SCH_1):U11_E2    I24 @T6G_MB_LIB.T6G(SCH_1):PAGE387
     2    GND @T6G_MB_LIB.T6G(SCH_1):GND    I24 @T6G_MB_LIB.T6G(SCH_1):PAGE387

R6823 Q_RES_0402LF-0,5%,1/16W,CHIP,CS00002JB13
     1 RST_RT_CPU0_P2_PERST_R2_N @T6G_MB_LIB.T6G(SCH_1):RST_RT_CPU0_P2_PERST_R2_N   I350 @T6G_MB_LIB.T6G(SCH_1):PAGE80
     2 RST_RT_CPU0_P2_PERST_R_N @T6G_MB_LIB.T6G(SCH_1):RST_RT_CPU0_P2_PERST_R_N   I350 @T6G_MB_LIB.T6G(SCH_1):PAGE80

R6824 Q_RES_0402LF-0,5%,1/16W,CHIP,CS00002JB13
     1 RST_RT_CPU0_P2_RESET_R2_N @T6G_MB_LIB.T6G(SCH_1):RST_RT_CPU0_P2_RESET_R2_N   I351 @T6G_MB_LIB.T6G(SCH_1):PAGE80
     2 RST_RT_CPU0_P2_RESET_R_N @T6G_MB_LIB.T6G(SCH_1):RST_RT_CPU0_P2_RESET_R_N   I351 @T6G_MB_LIB.T6G(SCH_1):PAGE80

R6825 Q_RES_0402LF-0,5%,1/16W,CHIP,CS00002JB13
     1 RST_RT_CPU0_P3_PERST_R2_N @T6G_MB_LIB.T6G(SCH_1):RST_RT_CPU0_P3_PERST_R2_N   I352 @T6G_MB_LIB.T6G(SCH_1):PAGE80
     2 RST_RT_CPU0_P3_PERST_R_N @T6G_MB_LIB.T6G(SCH_1):RST_RT_CPU0_P3_PERST_R_N   I352 @T6G_MB_LIB.T6G(SCH_1):PAGE80

R6826 Q_RES_0402LF-0,5%,1/16W,CHIP,CS00002JB13
     1 RST_RT_CPU0_P3_RESET_R2_N @T6G_MB_LIB.T6G(SCH_1):RST_RT_CPU0_P3_RESET_R2_N   I353 @T6G_MB_LIB.T6G(SCH_1):PAGE80
     2 RST_RT_CPU0_P3_RESET_R_N @T6G_MB_LIB.T6G(SCH_1):RST_RT_CPU0_P3_RESET_R_N   I353 @T6G_MB_LIB.T6G(SCH_1):PAGE80

R6850 Q_RES_0402LF-33,5%,1/16W,CHIP,CS03302JB10
     1 P1V8_RETIMER_CPU0_EN @T6G_MB_LIB.T6G(SCH_1):P1V8_RETIMER_CPU0_EN   I146 @T6G_MB_LIB.T6G(SCH_1):PAGE79
     2 P1V8_RETIMER_CPU0_R_EN @T6G_MB_LIB.T6G(SCH_1):P1V8_RETIMER_CPU0_R_EN   I146 @T6G_MB_LIB.T6G(SCH_1):PAGE79

R6851 Q_RES_0402LF-33,5%,1/16W,CHIP,CS03302JB10
     1 P1V8_RETIMER_CPU1_EN @T6G_MB_LIB.T6G(SCH_1):P1V8_RETIMER_CPU1_EN   I147 @T6G_MB_LIB.T6G(SCH_1):PAGE79
     2 P1V8_RETIMER_CPU1_R_EN @T6G_MB_LIB.T6G(SCH_1):P1V8_RETIMER_CPU1_R_EN   I147 @T6G_MB_LIB.T6G(SCH_1):PAGE79

R6852 Q_RES_0402LF-0,5%,1/16W,CHIP,CS00002JB13
     1 PWRGD_P0V9_RETIMER_CPU0 @T6G_MB_LIB.T6G(SCH_1):PWRGD_P0V9_RETIMER_CPU0   I360 @T6G_MB_LIB.T6G(SCH_1):PAGE80
     2 PWRGD_P0V9_RETIMER_CPU0_R2 @T6G_MB_LIB.T6G(SCH_1):PWRGD_P0V9_RETIMER_CPU0_R2   I360 @T6G_MB_LIB.T6G(SCH_1):PAGE80

R6853 Q_RES_0402LF-0,5%,1/16W,CHIP,CS00002JB13
     1 PWRGD_P0V9_RETIMER_CPU1 @T6G_MB_LIB.T6G(SCH_1):PWRGD_P0V9_RETIMER_CPU1   I362 @T6G_MB_LIB.T6G(SCH_1):PAGE80
     2 PWRGD_P0V9_RETIMER_CPU1_R2 @T6G_MB_LIB.T6G(SCH_1):PWRGD_P0V9_RETIMER_CPU1_R2   I362 @T6G_MB_LIB.T6G(SCH_1):PAGE80

R6854 Q_RES_0402LF-33,5%,1/16W,CHIP,CS03302JB10
     1 P0V9_RETIMER_CPU0_EN @T6G_MB_LIB.T6G(SCH_1):P0V9_RETIMER_CPU0_EN   I364 @T6G_MB_LIB.T6G(SCH_1):PAGE80
     2 P0V9_RETIMER_CPU0_EN_R2 @T6G_MB_LIB.T6G(SCH_1):P0V9_RETIMER_CPU0_EN_R2   I364 @T6G_MB_LIB.T6G(SCH_1):PAGE80

R6855 Q_RES_0402LF-33,5%,1/16W,CHIP,CS03302JB10
     1 P0V9_RETIMER_CPU1_EN_R2 @T6G_MB_LIB.T6G(SCH_1):P0V9_RETIMER_CPU1_EN_R2   I366 @T6G_MB_LIB.T6G(SCH_1):PAGE80
     2 P0V9_RETIMER_CPU1_EN @T6G_MB_LIB.T6G(SCH_1):P0V9_RETIMER_CPU1_EN   I366 @T6G_MB_LIB.T6G(SCH_1):PAGE80

R6856 Q_RES_0402LF-33,5%,1/16W,CHIP,CS03302JB10
     1 SMB_SCM_2_R6_SCL @T6G_MB_LIB.T6G(SCH_1):SMB_SCM_2_R6_SCL   I226 @T6G_MB_LIB.T6G(SCH_1):PAGE349
     2 P0V9_RETIMER_CPU0_PMSCL @T6G_MB_LIB.T6G(SCH_1):P0V9_RETIMER_CPU0_PMSCL   I226 @T6G_MB_LIB.T6G(SCH_1):PAGE349

R6857 Q_RES_0402LF-33,5%,1/16W,CHIP,CS03302JB10
     1 SMB_SCM_2_R6_SDA @T6G_MB_LIB.T6G(SCH_1):SMB_SCM_2_R6_SDA   I227 @T6G_MB_LIB.T6G(SCH_1):PAGE349
     2 P0V9_RETIMER_CPU0_PMSDA @T6G_MB_LIB.T6G(SCH_1):P0V9_RETIMER_CPU0_PMSDA   I227 @T6G_MB_LIB.T6G(SCH_1):PAGE349

R6858 Q_RES_0402LF-0,5%,1/16W,CHIP,CS00002JB13
     1 SMB_VR_3V3STBY_SCL @T6G_MB_LIB.T6G(SCH_1):SMB_VR_3V3STBY_SCL   I207 @T6G_MB_LIB.T6G(SCH_1):PAGE349
     2 P0V9_RETIMER_CPU1_PMSCL @T6G_MB_LIB.T6G(SCH_1):P0V9_RETIMER_CPU1_PMSCL   I207 @T6G_MB_LIB.T6G(SCH_1):PAGE349

R6859 Q_RES_0402LF-0,5%,1/16W,CHIP,CS00002JB13
     1 SMB_VR_3V3STBY_SDA @T6G_MB_LIB.T6G(SCH_1):SMB_VR_3V3STBY_SDA   I206 @T6G_MB_LIB.T6G(SCH_1):PAGE349
     2 P0V9_RETIMER_CPU1_PMSDA @T6G_MB_LIB.T6G(SCH_1):P0V9_RETIMER_CPU1_PMSDA   I206 @T6G_MB_LIB.T6G(SCH_1):PAGE349

R6860 Q_RES_0402LF-1K,1%,1/16W,CHIP,CS21002FB06
     1 P1V8_AUX @T6G_MB_LIB.T6G(SCH_1):P1V8_AUX   I213 @T6G_MB_LIB.T6G(SCH_1):PAGE475
     2 PWRGD_P0V9_RETIMER_CPU0_R @T6G_MB_LIB.T6G(SCH_1):PWRGD_P0V9_RETIMER_CPU0_R   I213 @T6G_MB_LIB.T6G(SCH_1):PAGE475

R6861 Q_RES_0402LF-1K,1%,1/16W,CHIP,CS21002FB06
     1 P1V8_AUX @T6G_MB_LIB.T6G(SCH_1):P1V8_AUX    I93 @T6G_MB_LIB.T6G(SCH_1):PAGE477
     2 PWRGD_P0V9_RETIMER_CPU1_R @T6G_MB_LIB.T6G(SCH_1):PWRGD_P0V9_RETIMER_CPU1_R    I93 @T6G_MB_LIB.T6G(SCH_1):PAGE477

R6862 Q_RES_0402LF-33,5%,1/16W,CHIP,CS03302JB10
     1 SMB_HOST_CLK_3V3AUX_SCL_R1 @T6G_MB_LIB.T6G(SCH_1):SMB_HOST_CLK_3V3AUX_SCL_R1   I218 @T6G_MB_LIB.T6G(SCH_1):PAGE349
     2 SMB_9ZXL045_P1_SCL @T6G_MB_LIB.T6G(SCH_1):SMB_9ZXL045_P1_SCL   I218 @T6G_MB_LIB.T6G(SCH_1):PAGE349

R6863 Q_RES_0402LF-33,5%,1/16W,CHIP,CS03302JB10
     1 SMB_HOST_CLK_3V3AUX_SDA_R1 @T6G_MB_LIB.T6G(SCH_1):SMB_HOST_CLK_3V3AUX_SDA_R1   I219 @T6G_MB_LIB.T6G(SCH_1):PAGE349
     2 SMB_9ZXL045_P1_SDA @T6G_MB_LIB.T6G(SCH_1):SMB_9ZXL045_P1_SDA   I219 @T6G_MB_LIB.T6G(SCH_1):PAGE349

R6864 Q_RES_0402LF-33,5%,1/16W,CHIP,CS03302JB10
     1 SMB_HOST_CLK_3V3AUX_SCL_R1 @T6G_MB_LIB.T6G(SCH_1):SMB_HOST_CLK_3V3AUX_SCL_R1   I220 @T6G_MB_LIB.T6G(SCH_1):PAGE349
     2 SMB_9ZXL045_P0_SCL @T6G_MB_LIB.T6G(SCH_1):SMB_9ZXL045_P0_SCL   I220 @T6G_MB_LIB.T6G(SCH_1):PAGE349

R6865 Q_RES_0402LF-33,5%,1/16W,CHIP,CS03302JB10
     1 SMB_HOST_CLK_3V3AUX_SDA_R1 @T6G_MB_LIB.T6G(SCH_1):SMB_HOST_CLK_3V3AUX_SDA_R1   I221 @T6G_MB_LIB.T6G(SCH_1):PAGE349
     2 SMB_9ZXL045_P0_SDA @T6G_MB_LIB.T6G(SCH_1):SMB_9ZXL045_P0_SDA   I221 @T6G_MB_LIB.T6G(SCH_1):PAGE349

R6900 Q_RES_0201LF-1K,1%,1/20W,EMPTY,CS21001FE07
     1 P1V8_CPU1_RT_1D @T6G_MB_LIB.T6G(SCH_1):P1V8_CPU1_RT_1D    I19 @T6G_MB_LIB.T6G(SCH_1):PAGE463
     2 RT_CPU1_P3_VQPS @T6G_MB_LIB.T6G(SCH_1):RT_CPU1_P3_VQPS    I19 @T6G_MB_LIB.T6G(SCH_1):PAGE463

R6901 Q_RES_0201LF-200,1%,1/20W,CHIP,CS12001FE12
     1 RT_CPU1_P3_VQPS @T6G_MB_LIB.T6G(SCH_1):RT_CPU1_P3_VQPS    I18 @T6G_MB_LIB.T6G(SCH_1):PAGE463
     2    GND @T6G_MB_LIB.T6G(SCH_1):GND    I18 @T6G_MB_LIB.T6G(SCH_1):PAGE463

R6902 Q_RES_0201LF-0,5%,1/20W,CHIP,CS00001JE10
     1 NCF_A1_CPU1_P3_GND @T6G_MB_LIB.T6G(SCH_1):NCF_A1_CPU1_P3_GND    I15 @T6G_MB_LIB.T6G(SCH_1):PAGE463
     2    GND @T6G_MB_LIB.T6G(SCH_1):GND    I15 @T6G_MB_LIB.T6G(SCH_1):PAGE463

R6903 Q_RES_0201LF-0,5%,1/20W,CHIP,CS00001JE10
     1 NCF_CPU1_P3_GND @T6G_MB_LIB.T6G(SCH_1):NCF_CPU1_P3_GND    I13 @T6G_MB_LIB.T6G(SCH_1):PAGE463
     2    GND @T6G_MB_LIB.T6G(SCH_1):GND    I13 @T6G_MB_LIB.T6G(SCH_1):PAGE463

R8000 Q_RES_0402LF-33.2,1%,1/16W,CHIP,CS03322FB03
     1 PRSNT_SWB_ISO_N @T6G_MB_LIB.T6G(SCH_1):PRSNT_SWB_ISO_N   I315 @T6G_MB_LIB.T6G(SCH_1):PAGE80
     2 PRSNT_SWB_ISO_R_N @T6G_MB_LIB.T6G(SCH_1):PRSNT_SWB_ISO_R_N   I315 @T6G_MB_LIB.T6G(SCH_1):PAGE80

R8001 Q_RES_0402LF-100K,1%,1/16W,EMPTY,CS41002FB09
     1 PRSNT_SWB_N @T6G_MB_LIB.T6G(SCH_1):PRSNT_SWB_N    I12 @T6G_MB_LIB.T6G(SCH_1):PAGE330
     2    GND @T6G_MB_LIB.T6G(SCH_1):GND    I12 @T6G_MB_LIB.T6G(SCH_1):PAGE330

R8002 Q_RES_0402LF-4.7K,5%,1/16W,CHIP,CS24702JB10
     1 P3V3_AUX @T6G_MB_LIB.T6G(SCH_1):P3V3_AUX    I55 @T6G_MB_LIB.T6G(SCH_1):PAGE330
     2 PRSNT_SWB @T6G_MB_LIB.T6G(SCH_1):PRSNT_SWB    I55 @T6G_MB_LIB.T6G(SCH_1):PAGE330

R8003 Q_RES_0402LF-4.7K,5%,1/16W,CHIP,CS24702JB10
     1 P3V3_AUX @T6G_MB_LIB.T6G(SCH_1):P3V3_AUX    I57 @T6G_MB_LIB.T6G(SCH_1):PAGE330
     2 PRSNT_SWB_ISO_N @T6G_MB_LIB.T6G(SCH_1):PRSNT_SWB_ISO_N    I57 @T6G_MB_LIB.T6G(SCH_1):PAGE330

R8004 Q_RES_0402LF-0,5%,1/16W,CHIP,CS00002JB13
     1 PRSNT_SWB_ISO_N @T6G_MB_LIB.T6G(SCH_1):PRSNT_SWB_ISO_N    I41 @T6G_MB_LIB.T6G(SCH_1):PAGE246
     2 PRSNT_SWB_ISO_R1_N @T6G_MB_LIB.T6G(SCH_1):PRSNT_SWB_ISO_R1_N    I41 @T6G_MB_LIB.T6G(SCH_1):PAGE246

R8005 Q_RES_0402LF-33,5%,1/16W,CHIP,CS03302JB10
     1 SPI_CPU0_D3 @T6G_MB_LIB.T6G(SCH_1):SPI_CPU0_D3   I234 @T6G_MB_LIB.T6G(SCH_1):PAGE76
     2 SPI_CPU0_R1_D3 @T6G_MB_LIB.T6G(SCH_1):SPI_CPU0_R1_D3   I234 @T6G_MB_LIB.T6G(SCH_1):PAGE76

R8006 Q_RES_0402LF-33,5%,1/16W,CHIP,CS03302JB10
     1 SPI_CPU0_D2 @T6G_MB_LIB.T6G(SCH_1):SPI_CPU0_D2   I239 @T6G_MB_LIB.T6G(SCH_1):PAGE76
     2 SPI_CPU0_R1_D2 @T6G_MB_LIB.T6G(SCH_1):SPI_CPU0_R1_D2   I239 @T6G_MB_LIB.T6G(SCH_1):PAGE76

R8007 Q_RES_0402LF-33,5%,1/16W,CHIP,CS03302JB10
     1 SPI_CPU0_D0 @T6G_MB_LIB.T6G(SCH_1):SPI_CPU0_D0   I240 @T6G_MB_LIB.T6G(SCH_1):PAGE76
     2 SPI_CPU0_R1_D0 @T6G_MB_LIB.T6G(SCH_1):SPI_CPU0_R1_D0   I240 @T6G_MB_LIB.T6G(SCH_1):PAGE76

R8008 Q_RES_0402LF-33,5%,1/16W,CHIP,CS03302JB10
     1 SPI_CPU0_D1 @T6G_MB_LIB.T6G(SCH_1):SPI_CPU0_D1   I241 @T6G_MB_LIB.T6G(SCH_1):PAGE76
     2 SPI_CPU0_R1_D1 @T6G_MB_LIB.T6G(SCH_1):SPI_CPU0_R1_D1   I241 @T6G_MB_LIB.T6G(SCH_1):PAGE76

R8009 Q_RES_0402LF-10K,5%,1/16W,CHIP,CS31002JB08
     1 P3V3_AUX @T6G_MB_LIB.T6G(SCH_1):P3V3_AUX    I26 @T6G_MB_LIB.T6G(SCH_1):PAGE201
     2 PWRGD_PVDD18_S5_P1 @T6G_MB_LIB.T6G(SCH_1):PWRGD_PVDD18_S5_P1    I26 @T6G_MB_LIB.T6G(SCH_1):PAGE201

R8010 Q_RES_0402LF-0,5%,1/16W,EMPTY,CS00002JB13
     1 PVDD11_S3_P1_OCP_N @T6G_MB_LIB.T6G(SCH_1):PVDD11_S3_P1_OCP_N    I13 @T6G_MB_LIB.T6G(SCH_1):PAGE199
     2 PVDD11_S3_P1_OCP_N_R @T6G_MB_LIB.T6G(SCH_1):PVDD11_S3_P1_OCP_N_R    I13 @T6G_MB_LIB.T6G(SCH_1):PAGE199

R8011 Q_RES_0402LF-1K,1%,1/16W,EMPTY,CS21002FB06
     1 PVDD18_S5_P1 @T6G_MB_LIB.T6G(SCH_1):PVDD18_S5_P1    I24 @T6G_MB_LIB.T6G(SCH_1):PAGE199
     2 PVDD11_S3_P1_OCP_N_R @T6G_MB_LIB.T6G(SCH_1):PVDD11_S3_P1_OCP_N_R    I24 @T6G_MB_LIB.T6G(SCH_1):PAGE199

R8012 Q_RES_0402LF-0,5%,1/16W,CHIP,CS00002JB13
     1 HP_LVC3_SCM_HSC_PWRGD_R @T6G_MB_LIB.T6G(SCH_1):HP_LVC3_SCM_HSC_PWRGD_R    I89 @T6G_MB_LIB.T6G(SCH_1):PAGE350
     2 HP_LVC3_SCM_HSC_PWRGD @T6G_MB_LIB.T6G(SCH_1):HP_LVC3_SCM_HSC_PWRGD    I89 @T6G_MB_LIB.T6G(SCH_1):PAGE350

R8013 Q_RES_0402LF-0,5%,1/16W,EMPTY,CS00002JB13
     1 OCP_SFF_PRSNT01_R_N @T6G_MB_LIB.T6G(SCH_1):OCP_SFF_PRSNT01_R_N    I64 @T6G_MB_LIB.T6G(SCH_1):PAGE258
     2 OCP_SFF_PRSNT01_R1_N @T6G_MB_LIB.T6G(SCH_1):OCP_SFF_PRSNT01_R1_N    I64 @T6G_MB_LIB.T6G(SCH_1):PAGE258

R8014 Q_RES_0402LF-0,5%,1/16W,EMPTY,CS00002JB13
     1 OCP_SFF_PRSNT23_R_N @T6G_MB_LIB.T6G(SCH_1):OCP_SFF_PRSNT23_R_N    I65 @T6G_MB_LIB.T6G(SCH_1):PAGE258
     2 OCP_SFF_PRSNT23_R1_N @T6G_MB_LIB.T6G(SCH_1):OCP_SFF_PRSNT23_R1_N    I65 @T6G_MB_LIB.T6G(SCH_1):PAGE258

R8015 Q_RES_0402LF-0,5%,1/16W,EMPTY,CS00002JB13
     1 OCP_V3_2_PRSNT01_R_N @T6G_MB_LIB.T6G(SCH_1):OCP_V3_2_PRSNT01_R_N    I66 @T6G_MB_LIB.T6G(SCH_1):PAGE258
     2 OCP_V3_2_PRSNT01_R1_N @T6G_MB_LIB.T6G(SCH_1):OCP_V3_2_PRSNT01_R1_N    I66 @T6G_MB_LIB.T6G(SCH_1):PAGE258

R8016 Q_RES_0402LF-0,5%,1/16W,EMPTY,CS00002JB13
     1 OCP_V3_2_PRSNT23_R_N @T6G_MB_LIB.T6G(SCH_1):OCP_V3_2_PRSNT23_R_N    I67 @T6G_MB_LIB.T6G(SCH_1):PAGE258
     2 OCP_V3_2_PRSNT23_R1_N @T6G_MB_LIB.T6G(SCH_1):OCP_V3_2_PRSNT23_R1_N    I67 @T6G_MB_LIB.T6G(SCH_1):PAGE258

R8017 Q_RES_0402LF-0,5%,1/16W,EMPTY,CS00002JB13
     1 P3V3_AUX @T6G_MB_LIB.T6G(SCH_1):P3V3_AUX    I85 @T6G_MB_LIB.T6G(SCH_1):PAGE144
     2 U124_VCC @T6G_MB_LIB.T6G(SCH_1):U124_VCC    I85 @T6G_MB_LIB.T6G(SCH_1):PAGE144

R8018 Q_RES_0402LF-0,5%,1/16W,CHIP,CS00002JB13
     1 P1V8_AUX @T6G_MB_LIB.T6G(SCH_1):P1V8_AUX    I84 @T6G_MB_LIB.T6G(SCH_1):PAGE144
     2 U124_VCC @T6G_MB_LIB.T6G(SCH_1):U124_VCC    I84 @T6G_MB_LIB.T6G(SCH_1):PAGE144

R8019 Q_RES_0402LF-100,1%,1/16W,EMPTY,CS11002FB07
     1 P3V3_AUX @T6G_MB_LIB.T6G(SCH_1):P3V3_AUX    I89 @T6G_MB_LIB.T6G(SCH_1):PAGE144
     2 FM_JTAG_BMC_R_OE @T6G_MB_LIB.T6G(SCH_1):FM_JTAG_BMC_R_OE    I89 @T6G_MB_LIB.T6G(SCH_1):PAGE144

R8021 Q_RES_0402LF-0,5%,1/16W,CHIP,CS00002JB13
     1 FM_JTAG_BMC_OE @T6G_MB_LIB.T6G(SCH_1):FM_JTAG_BMC_OE   I318 @T6G_MB_LIB.T6G(SCH_1):PAGE80
     2 FM_JTAG_BMC_R_OE @T6G_MB_LIB.T6G(SCH_1):FM_JTAG_BMC_R_OE   I318 @T6G_MB_LIB.T6G(SCH_1):PAGE80

R8022 Q_RES_0402LF-560,1%,1/16W,CHIP,CS15602FB03
     1 LED_P12V_AUX_R1 @T6G_MB_LIB.T6G(SCH_1):LED_P12V_AUX_R1    I44 @T6G_MB_LIB.T6G(SCH_1):PAGE375
     2 LED_P12V_AUX_R2 @T6G_MB_LIB.T6G(SCH_1):LED_P12V_AUX_R2    I44 @T6G_MB_LIB.T6G(SCH_1):PAGE375

R8023 Q_RES_0402LF-560,1%,1/16W,CHIP,CS15602FB03
     1 LED_P12V_AUX_R2 @T6G_MB_LIB.T6G(SCH_1):LED_P12V_AUX_R2    I45 @T6G_MB_LIB.T6G(SCH_1):PAGE375
     2 LED_P12V_AUX_R3 @T6G_MB_LIB.T6G(SCH_1):LED_P12V_AUX_R3    I45 @T6G_MB_LIB.T6G(SCH_1):PAGE375

R8024 Q_RES_0402LF-560,1%,1/16W,CHIP,CS15602FB03
     1 LED_P12V_AUX_R3 @T6G_MB_LIB.T6G(SCH_1):LED_P12V_AUX_R3    I46 @T6G_MB_LIB.T6G(SCH_1):PAGE375
     2 P12V_AUX @T6G_MB_LIB.T6G(SCH_1):P12V_AUX    I46 @T6G_MB_LIB.T6G(SCH_1):PAGE375

R8025 Q_RES_0402LF-560,1%,1/16W,CHIP,CS15602FB03
     1 LED_P12V_PSU_R1 @T6G_MB_LIB.T6G(SCH_1):LED_P12V_PSU_R1    I51 @T6G_MB_LIB.T6G(SCH_1):PAGE375
     2 LED_P12V_PSU_R2 @T6G_MB_LIB.T6G(SCH_1):LED_P12V_PSU_R2    I51 @T6G_MB_LIB.T6G(SCH_1):PAGE375

R8026 Q_RES_0402LF-560,1%,1/16W,CHIP,CS15602FB03
     1 LED_P12V_PSU_R2 @T6G_MB_LIB.T6G(SCH_1):LED_P12V_PSU_R2    I50 @T6G_MB_LIB.T6G(SCH_1):PAGE375
     2 LED_P12V_PSU_R3 @T6G_MB_LIB.T6G(SCH_1):LED_P12V_PSU_R3    I50 @T6G_MB_LIB.T6G(SCH_1):PAGE375

R8027 Q_RES_0402LF-560,1%,1/16W,CHIP,CS15602FB03
     1 LED_P12V_PSU_R3 @T6G_MB_LIB.T6G(SCH_1):LED_P12V_PSU_R3    I49 @T6G_MB_LIB.T6G(SCH_1):PAGE375
     2 P12V_PSU @T6G_MB_LIB.T6G(SCH_1):P12V_PSU    I49 @T6G_MB_LIB.T6G(SCH_1):PAGE375

R8028 Q_RES_0402LF-4.7K,5%,1/16W,CHIP,CS24702JB10
     1 P3V3_AUX @T6G_MB_LIB.T6G(SCH_1):P3V3_AUX    I62 @T6G_MB_LIB.T6G(SCH_1):PAGE375
     2 LED_P12V_SCM_FAULT_D1 @T6G_MB_LIB.T6G(SCH_1):LED_P12V_SCM_FAULT_D1    I62 @T6G_MB_LIB.T6G(SCH_1):PAGE375

R8029 Q_RES_0402LF-249,1%,1/16W,CHIP,CS12492FB02
     1 LED_P12V_SCM_FAULT @T6G_MB_LIB.T6G(SCH_1):LED_P12V_SCM_FAULT    I55 @T6G_MB_LIB.T6G(SCH_1):PAGE375
     2 P3V3_AUX @T6G_MB_LIB.T6G(SCH_1):P3V3_AUX    I55 @T6G_MB_LIB.T6G(SCH_1):PAGE375

R8030 Q_RES_0402LF-0,5%,1/16W,CHIP,CS00002JB13
     1 P12V_SCM_FAULT_N @T6G_MB_LIB.T6G(SCH_1):P12V_SCM_FAULT_N    I91 @T6G_MB_LIB.T6G(SCH_1):PAGE350
     2 P12V_SCM_FAULT_R_N @T6G_MB_LIB.T6G(SCH_1):P12V_SCM_FAULT_R_N    I91 @T6G_MB_LIB.T6G(SCH_1):PAGE350

R8031 Q_RES_0402LF-0,5%,1/16W,CHIP,CS00002JB13
     1 P12V_SCM_FLTB_N @T6G_MB_LIB.T6G(SCH_1):P12V_SCM_FLTB_N    I93 @T6G_MB_LIB.T6G(SCH_1):PAGE350
     2 P12V_SCM_FAULT_R_N @T6G_MB_LIB.T6G(SCH_1):P12V_SCM_FAULT_R_N    I93 @T6G_MB_LIB.T6G(SCH_1):PAGE350

R8032 Q_RES_0402LF-0,5%,1/16W,CHIP,CS00002JB13
     1 FM_ESPI_CPU0_ALERT_SEL @T6G_MB_LIB.T6G(SCH_1):FM_ESPI_CPU0_ALERT_SEL   I319 @T6G_MB_LIB.T6G(SCH_1):PAGE80
     2 FM_ESPI_CPU0_ALERT_R_SEL @T6G_MB_LIB.T6G(SCH_1):FM_ESPI_CPU0_ALERT_R_SEL   I319 @T6G_MB_LIB.T6G(SCH_1):PAGE80

R8033 Q_RES_0402LF-1K,1%,1/16W,CHIP,CS21002FB06
     1 FM_ESPI_CPU0_ALERT_R_SEL @T6G_MB_LIB.T6G(SCH_1):FM_ESPI_CPU0_ALERT_R_SEL   I170 @T6G_MB_LIB.T6G(SCH_1):PAGE82
     2    GND @T6G_MB_LIB.T6G(SCH_1):GND   I170 @T6G_MB_LIB.T6G(SCH_1):PAGE82

R8034 Q_RES_0402LF-0,5%,1/16W,CHIP,CS00002JB13
     1 ESPI_CPU0_ALERT_R1_N @T6G_MB_LIB.T6G(SCH_1):ESPI_CPU0_ALERT_R1_N    I23 @T6G_MB_LIB.T6G(SCH_1):PAGE130
     2 ESPI_CPU0_ALERT_N @T6G_MB_LIB.T6G(SCH_1):ESPI_CPU0_ALERT_N    I23 @T6G_MB_LIB.T6G(SCH_1):PAGE130

R8035 Q_RES_0402LF-4.7K,5%,1/16W,EMPTY,CS24702JB10
     1 P1V8_AUX @T6G_MB_LIB.T6G(SCH_1):P1V8_AUX    I11 @T6G_MB_LIB.T6G(SCH_1):PAGE130
     2 ESPI_CPU0_ALERT_N @T6G_MB_LIB.T6G(SCH_1):ESPI_CPU0_ALERT_N    I11 @T6G_MB_LIB.T6G(SCH_1):PAGE130

R8036 Q_RES_0402LF-4.7K,5%,1/16W,EMPTY,CS24702JB10
     1 PVDD18_S5_P0 @T6G_MB_LIB.T6G(SCH_1):PVDD18_S5_P0    I12 @T6G_MB_LIB.T6G(SCH_1):PAGE130
     2 ESPI_CPU0_ALERT_PLD_N @T6G_MB_LIB.T6G(SCH_1):ESPI_CPU0_ALERT_PLD_N    I12 @T6G_MB_LIB.T6G(SCH_1):PAGE130

R8037 Q_RES_0402LF-10K,1%,1/16W,CHIP,CS31002FB08
     1 P3V3_AUX @T6G_MB_LIB.T6G(SCH_1):P3V3_AUX   I540 @T6G_MB_LIB.T6G(SCH_1):PAGE85
     2 PWRGD_CHAF_CPU0 @T6G_MB_LIB.T6G(SCH_1):PWRGD_CHAF_CPU0   I540 @T6G_MB_LIB.T6G(SCH_1):PAGE85

R8038 Q_RES_0402LF-10K,1%,1/16W,CHIP,CS31002FB08
     1 P3V3_AUX @T6G_MB_LIB.T6G(SCH_1):P3V3_AUX   I243 @T6G_MB_LIB.T6G(SCH_1):PAGE91
     2 PWRGD_CHGL_CPU0 @T6G_MB_LIB.T6G(SCH_1):PWRGD_CHGL_CPU0   I243 @T6G_MB_LIB.T6G(SCH_1):PAGE91

R8039 Q_RES_0402LF-10K,1%,1/16W,CHIP,CS31002FB08
     1 P3V3_AUX @T6G_MB_LIB.T6G(SCH_1):P3V3_AUX   I245 @T6G_MB_LIB.T6G(SCH_1):PAGE97
     2 PWRGD_CHAF_CPU1 @T6G_MB_LIB.T6G(SCH_1):PWRGD_CHAF_CPU1   I245 @T6G_MB_LIB.T6G(SCH_1):PAGE97

R8040 Q_RES_0402LF-10K,1%,1/16W,CHIP,CS31002FB08
     1 P3V3_AUX @T6G_MB_LIB.T6G(SCH_1):P3V3_AUX   I245 @T6G_MB_LIB.T6G(SCH_1):PAGE103
     2 PWRGD_CHGL_CPU1 @T6G_MB_LIB.T6G(SCH_1):PWRGD_CHGL_CPU1   I245 @T6G_MB_LIB.T6G(SCH_1):PAGE103

R8042 Q_RES_0402LF-1K,1%,1/16W,EMPTY,CS21002FB06
     1 SVID_PVDDCR_CPU1_P0_SVTO @T6G_MB_LIB.T6G(SCH_1):SVID_PVDDCR_CPU1_P0_SVTO    I32 @T6G_MB_LIB.T6G(SCH_1):PAGE175
     2    GND @T6G_MB_LIB.T6G(SCH_1):GND    I32 @T6G_MB_LIB.T6G(SCH_1):PAGE175

R8043 Q_RES_0402LF-1K,1%,1/16W,EMPTY,CS21002FB06
     1 PVDD18_S5_P0 @T6G_MB_LIB.T6G(SCH_1):PVDD18_S5_P0    I42 @T6G_MB_LIB.T6G(SCH_1):PAGE175
     2 SVID_PVDDCR_CPU1_P0_SVTO @T6G_MB_LIB.T6G(SCH_1):SVID_PVDDCR_CPU1_P0_SVTO    I42 @T6G_MB_LIB.T6G(SCH_1):PAGE175

R8045 Q_RES_0402LF-1K,1%,1/16W,EMPTY,CS21002FB06
     1 PVDD18_S5_P0 @T6G_MB_LIB.T6G(SCH_1):PVDD18_S5_P0    I43 @T6G_MB_LIB.T6G(SCH_1):PAGE175
     2 SVID_PVDDCR_CPU1_P0_SVD_R @T6G_MB_LIB.T6G(SCH_1):SVID_PVDDCR_CPU1_P0_SVD_R    I43 @T6G_MB_LIB.T6G(SCH_1):PAGE175

R8047 Q_RES_0402LF-0,5%,1/16W,CHIP,CS00002JB13
     1 PVDDIO_P0_EN @T6G_MB_LIB.T6G(SCH_1):PVDDIO_P0_EN     I2 @T6G_MB_LIB.T6G(SCH_1):PAGE175
     2 PVDDIO_P0_EN_R @T6G_MB_LIB.T6G(SCH_1):PVDDIO_P0_EN_R     I2 @T6G_MB_LIB.T6G(SCH_1):PAGE175

R8048 Q_RES_0402LF-1K,1%,1/16W,EMPTY,CS21002FB06
     1 PVDD18_S5_P0 @T6G_MB_LIB.T6G(SCH_1):PVDD18_S5_P0    I44 @T6G_MB_LIB.T6G(SCH_1):PAGE175
     2 SVID_PVDDCR_CPU1_P0_SVC_R @T6G_MB_LIB.T6G(SCH_1):SVID_PVDDCR_CPU1_P0_SVC_R    I44 @T6G_MB_LIB.T6G(SCH_1):PAGE175

R8056 Q_RES_0402LF-1K,1%,1/16W,CHIP,CS21002FB06
     1 P3V3_AUX @T6G_MB_LIB.T6G(SCH_1):P3V3_AUX    I90 @T6G_MB_LIB.T6G(SCH_1):PAGE175
     2 PWRGD_PVDDCR_CPU1_P0_R @T6G_MB_LIB.T6G(SCH_1):PWRGD_PVDDCR_CPU1_P0_R    I90 @T6G_MB_LIB.T6G(SCH_1):PAGE175

R8057 Q_RES_0402LF-33,5%,1/16W,CHIP,CS03302JB10
     1 PWRGD_PVDDCR_CPU1_P0 @T6G_MB_LIB.T6G(SCH_1):PWRGD_PVDDCR_CPU1_P0    I89 @T6G_MB_LIB.T6G(SCH_1):PAGE175
     2 PWRGD_PVDDCR_CPU1_P0_R @T6G_MB_LIB.T6G(SCH_1):PWRGD_PVDDCR_CPU1_P0_R    I89 @T6G_MB_LIB.T6G(SCH_1):PAGE175

R8058 Q_RES_0402LF-0,5%,1/16W,CHIP,CS00002JB13
     1 FM_PVDDCR_CPU1_P0_EN @T6G_MB_LIB.T6G(SCH_1):FM_PVDDCR_CPU1_P0_EN    I88 @T6G_MB_LIB.T6G(SCH_1):PAGE175
     2 PVDDCR_CPU1_P0_EN_R @T6G_MB_LIB.T6G(SCH_1):PVDDCR_CPU1_P0_EN_R    I88 @T6G_MB_LIB.T6G(SCH_1):PAGE175

R8063 Q_RES_0402LF-100,1%,1/16W,CHIP,CS11002FB07
     1 PVDDCR_CPU1_P0_RESET_N @T6G_MB_LIB.T6G(SCH_1):PVDDCR_CPU1_P0_RESET_N    I67 @T6G_MB_LIB.T6G(SCH_1):PAGE175
     2 PVDDCR_CPU1_P0_RESET_N_R @T6G_MB_LIB.T6G(SCH_1):PVDDCR_CPU1_P0_RESET_N_R    I67 @T6G_MB_LIB.T6G(SCH_1):PAGE175

R8064 Q_RES_0402LF-0,5%,1/16W,CHIP,CS00002JB13
     1 PVDDCR_CPU1_P0_OCP_N @T6G_MB_LIB.T6G(SCH_1):PVDDCR_CPU1_P0_OCP_N    I66 @T6G_MB_LIB.T6G(SCH_1):PAGE175
     2 PVDDCR_CPU1_P0_OCP_N_R @T6G_MB_LIB.T6G(SCH_1):PVDDCR_CPU1_P0_OCP_N_R    I66 @T6G_MB_LIB.T6G(SCH_1):PAGE175

R8065 Q_RES_0402LF-1K,1%,1/16W,CHIP,CS21002FB06
     1 P3V3_AUX @T6G_MB_LIB.T6G(SCH_1):P3V3_AUX    I54 @T6G_MB_LIB.T6G(SCH_1):PAGE175
     2 PWRGD_PVDDIO_P0_R @T6G_MB_LIB.T6G(SCH_1):PWRGD_PVDDIO_P0_R    I54 @T6G_MB_LIB.T6G(SCH_1):PAGE175

R8066 Q_RES_0402LF-33,5%,1/16W,CHIP,CS03302JB10
     1 PWRGD_PVDDIO_P0 @T6G_MB_LIB.T6G(SCH_1):PWRGD_PVDDIO_P0    I53 @T6G_MB_LIB.T6G(SCH_1):PAGE175
     2 PWRGD_PVDDIO_P0_R @T6G_MB_LIB.T6G(SCH_1):PWRGD_PVDDIO_P0_R    I53 @T6G_MB_LIB.T6G(SCH_1):PAGE175

R8070 Q_RES_0402LF-1K,1%,1/16W,CHIP,CS21002FB06
     1 PVDD18_S5_P0 @T6G_MB_LIB.T6G(SCH_1):PVDD18_S5_P0    I68 @T6G_MB_LIB.T6G(SCH_1):PAGE175
     2 PVDDCR_CPU1_P0_RESET_N_R @T6G_MB_LIB.T6G(SCH_1):PVDDCR_CPU1_P0_RESET_N_R    I68 @T6G_MB_LIB.T6G(SCH_1):PAGE175

R8071 Q_RES_0402LF-0,5%,1/16W,CHIP,CS00002JB13
     1 SMB_SCM_2_R5_SCL @T6G_MB_LIB.T6G(SCH_1):SMB_SCM_2_R5_SCL    I85 @T6G_MB_LIB.T6G(SCH_1):PAGE175
     2 SMB_CLK_PVDDCR_CPU1_P0_R @T6G_MB_LIB.T6G(SCH_1):SMB_CLK_PVDDCR_CPU1_P0_R    I85 @T6G_MB_LIB.T6G(SCH_1):PAGE175

R8072 Q_RES_0402LF-0,5%,1/16W,CHIP,CS00002JB13
     1 SMB_SCM_2_R5_SDA @T6G_MB_LIB.T6G(SCH_1):SMB_SCM_2_R5_SDA    I82 @T6G_MB_LIB.T6G(SCH_1):PAGE175
     2 SMB_DIO_PVDDCR_CPU1_P0_R @T6G_MB_LIB.T6G(SCH_1):SMB_DIO_PVDDCR_CPU1_P0_R    I82 @T6G_MB_LIB.T6G(SCH_1):PAGE175

R8073 Q_RES_0402LF-33,5%,1/16W,CHIP,CS03302JB10
     1 PVDDCR_CPU1_P0_SMB_ALERT @T6G_MB_LIB.T6G(SCH_1):PVDDCR_CPU1_P0_SMB_ALERT    I81 @T6G_MB_LIB.T6G(SCH_1):PAGE175
     2 PVDDCR_CPU1_P0_SMB_ALERT_R @T6G_MB_LIB.T6G(SCH_1):PVDDCR_CPU1_P0_SMB_ALERT_R    I81 @T6G_MB_LIB.T6G(SCH_1):PAGE175

R8075 Q_RES_0402LF-1K,1%,1/16W,CHIP,CS21002FB06
     1 PVDD18_S5_P0 @T6G_MB_LIB.T6G(SCH_1):PVDD18_S5_P0    I71 @T6G_MB_LIB.T6G(SCH_1):PAGE175
     2 PVDDCR_CPU1_P0_OCP_N_R @T6G_MB_LIB.T6G(SCH_1):PVDDCR_CPU1_P0_OCP_N_R    I71 @T6G_MB_LIB.T6G(SCH_1):PAGE175

R8080 Q_RES_0402LF-0,5%,1/16W,CHIP,CS00002JB13
     1 PWRGD_CHAF_CPU0 @T6G_MB_LIB.T6G(SCH_1):PWRGD_CHAF_CPU0   I544 @T6G_MB_LIB.T6G(SCH_1):PAGE85
     2 PWRGD_CHAF_CPU0_R1 @T6G_MB_LIB.T6G(SCH_1):PWRGD_CHAF_CPU0_R1   I544 @T6G_MB_LIB.T6G(SCH_1):PAGE85

R8081 Q_RES_0402LF-0,5%,1/16W,CHIP,CS00002JB13
     1 PWRGD_CHAF_CPU0_R1 @T6G_MB_LIB.T6G(SCH_1):PWRGD_CHAF_CPU0_R1   I545 @T6G_MB_LIB.T6G(SCH_1):PAGE85
     2 PWRGD_CHAF_CPU0_R2 @T6G_MB_LIB.T6G(SCH_1):PWRGD_CHAF_CPU0_R2   I545 @T6G_MB_LIB.T6G(SCH_1):PAGE85

R8082 Q_RES_0402LF-10K,1%,1/16W,EMPTY,CS31002FB08
     1 P3V3_AUX @T6G_MB_LIB.T6G(SCH_1):P3V3_AUX   I547 @T6G_MB_LIB.T6G(SCH_1):PAGE85
     2 PWRGD_CHAF_CPU0_R1 @T6G_MB_LIB.T6G(SCH_1):PWRGD_CHAF_CPU0_R1   I547 @T6G_MB_LIB.T6G(SCH_1):PAGE85

R8083 Q_RES_0402LF-0,5%,1/16W,CHIP,CS00002JB13
     1 PWRGD_CHGL_CPU0 @T6G_MB_LIB.T6G(SCH_1):PWRGD_CHGL_CPU0   I248 @T6G_MB_LIB.T6G(SCH_1):PAGE91
     2 PWRGD_CHGL_CPU0_R1 @T6G_MB_LIB.T6G(SCH_1):PWRGD_CHGL_CPU0_R1   I248 @T6G_MB_LIB.T6G(SCH_1):PAGE91

R8084 Q_RES_0402LF-0,5%,1/16W,CHIP,CS00002JB13
     1 PWRGD_CHGL_CPU0_R1 @T6G_MB_LIB.T6G(SCH_1):PWRGD_CHGL_CPU0_R1   I250 @T6G_MB_LIB.T6G(SCH_1):PAGE91
     2 PWRGD_CHGL_CPU0_R2 @T6G_MB_LIB.T6G(SCH_1):PWRGD_CHGL_CPU0_R2   I250 @T6G_MB_LIB.T6G(SCH_1):PAGE91

R8085 Q_RES_0402LF-10K,1%,1/16W,EMPTY,CS31002FB08
     1 P3V3_AUX @T6G_MB_LIB.T6G(SCH_1):P3V3_AUX   I249 @T6G_MB_LIB.T6G(SCH_1):PAGE91
     2 PWRGD_CHGL_CPU0_R1 @T6G_MB_LIB.T6G(SCH_1):PWRGD_CHGL_CPU0_R1   I249 @T6G_MB_LIB.T6G(SCH_1):PAGE91

R8086 Q_RES_0402LF-0,5%,1/16W,CHIP,CS00002JB13
     1 PWRGD_CHAF_CPU1 @T6G_MB_LIB.T6G(SCH_1):PWRGD_CHAF_CPU1   I250 @T6G_MB_LIB.T6G(SCH_1):PAGE97
     2 PWRGD_CHAF_CPU1_R1 @T6G_MB_LIB.T6G(SCH_1):PWRGD_CHAF_CPU1_R1   I250 @T6G_MB_LIB.T6G(SCH_1):PAGE97

R8087 Q_RES_0402LF-0,5%,1/16W,CHIP,CS00002JB13
     1 PWRGD_CHAF_CPU1_R1 @T6G_MB_LIB.T6G(SCH_1):PWRGD_CHAF_CPU1_R1   I252 @T6G_MB_LIB.T6G(SCH_1):PAGE97
     2 PWRGD_CHAF_CPU1_R2 @T6G_MB_LIB.T6G(SCH_1):PWRGD_CHAF_CPU1_R2   I252 @T6G_MB_LIB.T6G(SCH_1):PAGE97

R8088 Q_RES_0402LF-10K,1%,1/16W,EMPTY,CS31002FB08
     1 P3V3_AUX @T6G_MB_LIB.T6G(SCH_1):P3V3_AUX   I251 @T6G_MB_LIB.T6G(SCH_1):PAGE97
     2 PWRGD_CHAF_CPU1_R1 @T6G_MB_LIB.T6G(SCH_1):PWRGD_CHAF_CPU1_R1   I251 @T6G_MB_LIB.T6G(SCH_1):PAGE97

R8089 Q_RES_0402LF-0,5%,1/16W,CHIP,CS00002JB13
     1 PWRGD_CHGL_CPU1 @T6G_MB_LIB.T6G(SCH_1):PWRGD_CHGL_CPU1   I249 @T6G_MB_LIB.T6G(SCH_1):PAGE103
     2 PWRGD_CHGL_CPU1_R1 @T6G_MB_LIB.T6G(SCH_1):PWRGD_CHGL_CPU1_R1   I249 @T6G_MB_LIB.T6G(SCH_1):PAGE103

R8090 Q_RES_0402LF-0,5%,1/16W,CHIP,CS00002JB13
     1 PWRGD_CHGL_CPU1_R1 @T6G_MB_LIB.T6G(SCH_1):PWRGD_CHGL_CPU1_R1   I252 @T6G_MB_LIB.T6G(SCH_1):PAGE103
     2 PWRGD_CHGL_CPU1_R2 @T6G_MB_LIB.T6G(SCH_1):PWRGD_CHGL_CPU1_R2   I252 @T6G_MB_LIB.T6G(SCH_1):PAGE103

R8091 Q_RES_0402LF-10K,1%,1/16W,EMPTY,CS31002FB08
     1 P3V3_AUX @T6G_MB_LIB.T6G(SCH_1):P3V3_AUX   I251 @T6G_MB_LIB.T6G(SCH_1):PAGE103
     2 PWRGD_CHGL_CPU1_R1 @T6G_MB_LIB.T6G(SCH_1):PWRGD_CHGL_CPU1_R1   I251 @T6G_MB_LIB.T6G(SCH_1):PAGE103

R8092 Q_RES_0402LF-10K,5%,1/16W,EMPTY,CS31002JB08
     1 P3V3_OCP_SFF_R @T6G_MB_LIB.T6G(SCH_1):P3V3_OCP_SFF_R    I90 @T6G_MB_LIB.T6G(SCH_1):PAGE340
     2 OCP_V3_1_P3V3_R1_PWRGD @T6G_MB_LIB.T6G(SCH_1):OCP_V3_1_P3V3_R1_PWRGD    I90 @T6G_MB_LIB.T6G(SCH_1):PAGE340

R8093 Q_RES_0402LF-100K,1%,1/16W,CHIP,CS41002FB09
     1 OCP_V3_1_P3V3_R1_PWRGD @T6G_MB_LIB.T6G(SCH_1):OCP_V3_1_P3V3_R1_PWRGD    I84 @T6G_MB_LIB.T6G(SCH_1):PAGE340
     2    GND @T6G_MB_LIB.T6G(SCH_1):GND    I84 @T6G_MB_LIB.T6G(SCH_1):PAGE340

R8094 Q_RES_0402LF-0,5%,1/16W,CHIP,CS00002JB13
     1 OCP_V3_1_P3V3_R1_PWRGD @T6G_MB_LIB.T6G(SCH_1):OCP_V3_1_P3V3_R1_PWRGD    I85 @T6G_MB_LIB.T6G(SCH_1):PAGE340
     2 OCP_V3_1_P3V3_PWRGD @T6G_MB_LIB.T6G(SCH_1):OCP_V3_1_P3V3_PWRGD    I85 @T6G_MB_LIB.T6G(SCH_1):PAGE340

R8095 Q_RES_0402LF-10K,5%,1/16W,EMPTY,CS31002JB08
     1 P3V3_OCP_V3_2_R @T6G_MB_LIB.T6G(SCH_1):P3V3_OCP_V3_2_R    I77 @T6G_MB_LIB.T6G(SCH_1):PAGE257
     2 OCP_V3_2_P3V3_R1_PWRGD @T6G_MB_LIB.T6G(SCH_1):OCP_V3_2_P3V3_R1_PWRGD    I77 @T6G_MB_LIB.T6G(SCH_1):PAGE257

R8096 Q_RES_0402LF-100K,1%,1/16W,CHIP,CS41002FB09
     1 OCP_V3_2_P3V3_R1_PWRGD @T6G_MB_LIB.T6G(SCH_1):OCP_V3_2_P3V3_R1_PWRGD    I70 @T6G_MB_LIB.T6G(SCH_1):PAGE257
     2    GND @T6G_MB_LIB.T6G(SCH_1):GND    I70 @T6G_MB_LIB.T6G(SCH_1):PAGE257

R8097 Q_RES_0402LF-0,5%,1/16W,CHIP,CS00002JB13
     1 OCP_V3_2_P3V3_R1_PWRGD @T6G_MB_LIB.T6G(SCH_1):OCP_V3_2_P3V3_R1_PWRGD    I73 @T6G_MB_LIB.T6G(SCH_1):PAGE257
     2 OCP_V3_2_P3V3_PWRGD @T6G_MB_LIB.T6G(SCH_1):OCP_V3_2_P3V3_PWRGD    I73 @T6G_MB_LIB.T6G(SCH_1):PAGE257

R8098 Q_RES_0402LF-10K,5%,1/16W,EMPTY,CS31002JB08
     1 P3V3_E1S_0_R @T6G_MB_LIB.T6G(SCH_1):P3V3_E1S_0_R    I70 @T6G_MB_LIB.T6G(SCH_1):PAGE323
     2 P3V3_E1S_PWRGD_0_R1 @T6G_MB_LIB.T6G(SCH_1):P3V3_E1S_PWRGD_0_R1    I70 @T6G_MB_LIB.T6G(SCH_1):PAGE323

R8099 Q_RES_0402LF-100K,1%,1/16W,CHIP,CS41002FB09
     1 P3V3_E1S_PWRGD_0_R1 @T6G_MB_LIB.T6G(SCH_1):P3V3_E1S_PWRGD_0_R1    I68 @T6G_MB_LIB.T6G(SCH_1):PAGE323
     2    GND @T6G_MB_LIB.T6G(SCH_1):GND    I68 @T6G_MB_LIB.T6G(SCH_1):PAGE323

R8100 Q_RES_0402LF-0,5%,1/16W,CHIP,CS00002JB13
     1 P3V3_E1S_PWRGD_0_R1 @T6G_MB_LIB.T6G(SCH_1):P3V3_E1S_PWRGD_0_R1    I71 @T6G_MB_LIB.T6G(SCH_1):PAGE323
     2 P3V3_E1S_PWRGD_0_R @T6G_MB_LIB.T6G(SCH_1):P3V3_E1S_PWRGD_0_R    I71 @T6G_MB_LIB.T6G(SCH_1):PAGE323

R8101 Q_RES_0402LF-0,5%,1/16W,CHIP,CS00002JB13
     1 FM_AC_PWR_BTN_R_N @T6G_MB_LIB.T6G(SCH_1):FM_AC_PWR_BTN_R_N   I215 @T6G_MB_LIB.T6G(SCH_1):PAGE348
     2 FM_AC_PWR_BTN_N @T6G_MB_LIB.T6G(SCH_1):FM_AC_PWR_BTN_N   I215 @T6G_MB_LIB.T6G(SCH_1):PAGE348

R8102 Q_RES_0402LF-0,5%,1/16W,CHIP,CS00002JB13
     1 FM_AC_PWR_BTN_R_N @T6G_MB_LIB.T6G(SCH_1):FM_AC_PWR_BTN_R_N   I467 @T6G_MB_LIB.T6G(SCH_1):PAGE363
     2 FM_AC_PWR_BTN_PDB_N @T6G_MB_LIB.T6G(SCH_1):FM_AC_PWR_BTN_PDB_N   I467 @T6G_MB_LIB.T6G(SCH_1):PAGE363

R8103 Q_RES_0402LF-8.45K,1%,1/16W,EMPTY,CS28452FB06
     1 P3V3_AUX @T6G_MB_LIB.T6G(SCH_1):P3V3_AUX    I27 @T6G_MB_LIB.T6G(SCH_1):PAGE365
     2 FM_AC_PWR_BTN_R_N @T6G_MB_LIB.T6G(SCH_1):FM_AC_PWR_BTN_R_N    I27 @T6G_MB_LIB.T6G(SCH_1):PAGE365

R8104 Q_RES_0402LF-0,5%,1/16W,EMPTY,CS00002JB13
     1 FM_AC_PWR_BTN_R_N @T6G_MB_LIB.T6G(SCH_1):FM_AC_PWR_BTN_R_N    I18 @T6G_MB_LIB.T6G(SCH_1):PAGE365
     2 FM_AC_PWR_BTN_PLD_N @T6G_MB_LIB.T6G(SCH_1):FM_AC_PWR_BTN_PLD_N    I18 @T6G_MB_LIB.T6G(SCH_1):PAGE365

R8105 Q_RES_0402LF-0,5%,1/16W,EMPTY,CS00002JB13
     1 FM_AC_PWR_BTN_PLD_ISO_R_N @T6G_MB_LIB.T6G(SCH_1):FM_AC_PWR_BTN_PLD_ISO_R_N    I20 @T6G_MB_LIB.T6G(SCH_1):PAGE365
     2 FM_AC_PWR_BTN_PLD_ISO_N @T6G_MB_LIB.T6G(SCH_1):FM_AC_PWR_BTN_PLD_ISO_N    I20 @T6G_MB_LIB.T6G(SCH_1):PAGE365

R8106 Q_RES_0402LF-1K,1%,1/16W,CHIP,CS21002FB06
     1 P3V3_AUX @T6G_MB_LIB.T6G(SCH_1):P3V3_AUX    I31 @T6G_MB_LIB.T6G(SCH_1):PAGE365
     2 FM_AC_PWR_BTN_PLD_ISO_N @T6G_MB_LIB.T6G(SCH_1):FM_AC_PWR_BTN_PLD_ISO_N    I31 @T6G_MB_LIB.T6G(SCH_1):PAGE365

R8107 Q_RES_0402LF-10K,1%,1/16W,EMPTY,CS31002FB08
     1 P3V3_AUX @T6G_MB_LIB.T6G(SCH_1):P3V3_AUX    I81 @T6G_MB_LIB.T6G(SCH_1):PAGE371
     2 OC_P2V5_COMP @T6G_MB_LIB.T6G(SCH_1):OC_P2V5_COMP    I81 @T6G_MB_LIB.T6G(SCH_1):PAGE371

R8108 Q_RES_0402LF-160K,1%,1/16W,EMPTY,CS41602FB05
     1 HSC_CSOUT @T6G_MB_LIB.T6G(SCH_1):HSC_CSOUT    I84 @T6G_MB_LIB.T6G(SCH_1):PAGE371
     2 HSC_OC_VOL @T6G_MB_LIB.T6G(SCH_1):HSC_OC_VOL    I84 @T6G_MB_LIB.T6G(SCH_1):PAGE371

R8109 Q_RES_0402LF-10K,1%,1/16W,EMPTY,CS31002FB08
     1 HSC_OC_VOL @T6G_MB_LIB.T6G(SCH_1):HSC_OC_VOL    I82 @T6G_MB_LIB.T6G(SCH_1):PAGE371
     2    GND @T6G_MB_LIB.T6G(SCH_1):GND    I82 @T6G_MB_LIB.T6G(SCH_1):PAGE371

R8110 Q_RES_0402LF-33.2,1%,1/16W,EMPTY,CS03322FB03
     1 HSC_D_OC_R2 @T6G_MB_LIB.T6G(SCH_1):HSC_D_OC_R2    I96 @T6G_MB_LIB.T6G(SCH_1):PAGE371
     2 A_HSC_LOW_GATE @T6G_MB_LIB.T6G(SCH_1):A_HSC_LOW_GATE    I96 @T6G_MB_LIB.T6G(SCH_1):PAGE371

R8111 Q_RES_0402LF-10K,1%,1/16W,EMPTY,CS31002FB08
     1 P3V3_AUX @T6G_MB_LIB.T6G(SCH_1):P3V3_AUX    I98 @T6G_MB_LIB.T6G(SCH_1):PAGE371
     2 A_HSC_LOW_GATE @T6G_MB_LIB.T6G(SCH_1):A_HSC_LOW_GATE    I98 @T6G_MB_LIB.T6G(SCH_1):PAGE371

R8112 Q_RES_0402LF-1M,1%,1/16W,EMPTY,CS51002FB05
     1 HSC_OC_VOL @T6G_MB_LIB.T6G(SCH_1):HSC_OC_VOL   I103 @T6G_MB_LIB.T6G(SCH_1):PAGE371
     2 HSC_D_OC_R2 @T6G_MB_LIB.T6G(SCH_1):HSC_D_OC_R2   I103 @T6G_MB_LIB.T6G(SCH_1):PAGE371

R8113 Q_RES_0402LF-10K,1%,1/16W,CHIP,CS31002FB08
     1 P3V3_AUX @T6G_MB_LIB.T6G(SCH_1):P3V3_AUX    I52 @T6G_MB_LIB.T6G(SCH_1):PAGE372
     2 UV_ADR_P2V5_COMP @T6G_MB_LIB.T6G(SCH_1):UV_ADR_P2V5_COMP    I52 @T6G_MB_LIB.T6G(SCH_1):PAGE372

R8114 Q_RES_0402LF-17.8K,1%,1/16W,CHIP,CS31782FB04
     1 P12V_AUX @T6G_MB_LIB.T6G(SCH_1):P12V_AUX    I56 @T6G_MB_LIB.T6G(SCH_1):PAGE372
     2 P12V_AUX_UV_ADR_TRIGGER @T6G_MB_LIB.T6G(SCH_1):P12V_AUX_UV_ADR_TRIGGER    I56 @T6G_MB_LIB.T6G(SCH_1):PAGE372

R8115 Q_RES_0402LF-5.11K,1%,1/16W,CHIP,CS25112FB04
     1 P12V_AUX_UV_ADR_TRIGGER @T6G_MB_LIB.T6G(SCH_1):P12V_AUX_UV_ADR_TRIGGER    I55 @T6G_MB_LIB.T6G(SCH_1):PAGE372
     2    GND @T6G_MB_LIB.T6G(SCH_1):GND    I55 @T6G_MB_LIB.T6G(SCH_1):PAGE372

R8116 Q_RES_0402LF-0,5%,1/16W,EMPTY,CS00002JB13
     1 PVDD11_S3_P0_OCP_N @T6G_MB_LIB.T6G(SCH_1):PVDD11_S3_P0_OCP_N    I13 @T6G_MB_LIB.T6G(SCH_1):PAGE182
     2 PVDD11_S3_P0_OCP_N_R @T6G_MB_LIB.T6G(SCH_1):PVDD11_S3_P0_OCP_N_R    I13 @T6G_MB_LIB.T6G(SCH_1):PAGE182

R8117 Q_RES_0402LF-1M,1%,1/16W,CHIP,CS51002FB05
     1 P12V_AUX_UV_ADR_TRIGGER @T6G_MB_LIB.T6G(SCH_1):P12V_AUX_UV_ADR_TRIGGER    I63 @T6G_MB_LIB.T6G(SCH_1):PAGE372
     2 FM_UV_ADR_TRIGGER_N_R2 @T6G_MB_LIB.T6G(SCH_1):FM_UV_ADR_TRIGGER_N_R2    I63 @T6G_MB_LIB.T6G(SCH_1):PAGE372

R8118 Q_RES_0402LF-33.2,1%,1/16W,CHIP,CS03322FB03
     1 FM_UV_ADR_TRIGGER_N_R2 @T6G_MB_LIB.T6G(SCH_1):FM_UV_ADR_TRIGGER_N_R2    I67 @T6G_MB_LIB.T6G(SCH_1):PAGE372
     2 FM_UV_ADR_TRIGGER_N @T6G_MB_LIB.T6G(SCH_1):FM_UV_ADR_TRIGGER_N    I67 @T6G_MB_LIB.T6G(SCH_1):PAGE372

R8119 Q_RES_0402LF-1K,1%,1/16W,CHIP,CS21002FB06
     1 P3V3_AUX @T6G_MB_LIB.T6G(SCH_1):P3V3_AUX    I69 @T6G_MB_LIB.T6G(SCH_1):PAGE372
     2 FM_UV_ADR_TRIGGER_N @T6G_MB_LIB.T6G(SCH_1):FM_UV_ADR_TRIGGER_N    I69 @T6G_MB_LIB.T6G(SCH_1):PAGE372

R8120 Q_RES_0402LF-10K,1%,1/16W,CHIP,CS31002FB08
     1 P3V3_AUX @T6G_MB_LIB.T6G(SCH_1):P3V3_AUX    I72 @T6G_MB_LIB.T6G(SCH_1):PAGE372
     2 UV_P2V5_COMP @T6G_MB_LIB.T6G(SCH_1):UV_P2V5_COMP    I72 @T6G_MB_LIB.T6G(SCH_1):PAGE372

R8121 Q_RES_0402LF-17.8K,1%,1/16W,CHIP,CS31782FB04
     1 P12V_AUX @T6G_MB_LIB.T6G(SCH_1):P12V_AUX    I76 @T6G_MB_LIB.T6G(SCH_1):PAGE372
     2 P12V_AUX_UV_TRIGGER @T6G_MB_LIB.T6G(SCH_1):P12V_AUX_UV_TRIGGER    I76 @T6G_MB_LIB.T6G(SCH_1):PAGE372

R8122 Q_RES_0402LF-5.11K,1%,1/16W,CHIP,CS25112FB04
     1 P12V_AUX_UV_TRIGGER @T6G_MB_LIB.T6G(SCH_1):P12V_AUX_UV_TRIGGER    I75 @T6G_MB_LIB.T6G(SCH_1):PAGE372
     2    GND @T6G_MB_LIB.T6G(SCH_1):GND    I75 @T6G_MB_LIB.T6G(SCH_1):PAGE372

R8123 Q_RES_0402LF-1M,1%,1/16W,CHIP,CS51002FB05
     1 P12V_AUX_UV_TRIGGER @T6G_MB_LIB.T6G(SCH_1):P12V_AUX_UV_TRIGGER    I81 @T6G_MB_LIB.T6G(SCH_1):PAGE372
     2 IRQ_UV_DETECT_R2_N @T6G_MB_LIB.T6G(SCH_1):IRQ_UV_DETECT_R2_N    I81 @T6G_MB_LIB.T6G(SCH_1):PAGE372

R8124 Q_RES_0402LF-33.2,1%,1/16W,CHIP,CS03322FB03
     1 IRQ_UV_DETECT_R2_N @T6G_MB_LIB.T6G(SCH_1):IRQ_UV_DETECT_R2_N    I85 @T6G_MB_LIB.T6G(SCH_1):PAGE372
     2 IRQ_UV_DETECT_N @T6G_MB_LIB.T6G(SCH_1):IRQ_UV_DETECT_N    I85 @T6G_MB_LIB.T6G(SCH_1):PAGE372

R8125 Q_RES_0402LF-1K,1%,1/16W,CHIP,CS21002FB06
     1 P3V3_AUX @T6G_MB_LIB.T6G(SCH_1):P3V3_AUX   I104 @T6G_MB_LIB.T6G(SCH_1):PAGE372
     2 IRQ_UV_DETECT_N @T6G_MB_LIB.T6G(SCH_1):IRQ_UV_DETECT_N   I104 @T6G_MB_LIB.T6G(SCH_1):PAGE372

R8146 Q_RES_0402LF-0,5%,1/16W,EMPTY,CS00002JB13
     1 P3V3_AUX @T6G_MB_LIB.T6G(SCH_1):P3V3_AUX     I9 @T6G_MB_LIB.T6G(SCH_1):PAGE199
     2 PVDD11_S3_P1_VDDIO @T6G_MB_LIB.T6G(SCH_1):PVDD11_S3_P1_VDDIO     I9 @T6G_MB_LIB.T6G(SCH_1):PAGE199

R8153 Q_RES_0402LF-1K,1%,1/16W,EMPTY,CS21002FB06
     1 SVID_PVDDCR_CPU0_P1_SVTO @T6G_MB_LIB.T6G(SCH_1):SVID_PVDDCR_CPU0_P1_SVTO     I6 @T6G_MB_LIB.T6G(SCH_1):PAGE185
     2    GND @T6G_MB_LIB.T6G(SCH_1):GND     I6 @T6G_MB_LIB.T6G(SCH_1):PAGE185

R8156 Q_RES_0402LF-1K,1%,1/16W,EMPTY,CS21002FB06
     1 PVDD18_S5_P1 @T6G_MB_LIB.T6G(SCH_1):PVDD18_S5_P1    I68 @T6G_MB_LIB.T6G(SCH_1):PAGE185
     2 SVID_PVDDCR_CPU0_P1_SVD_R @T6G_MB_LIB.T6G(SCH_1):SVID_PVDDCR_CPU0_P1_SVD_R    I68 @T6G_MB_LIB.T6G(SCH_1):PAGE185

R8160 Q_RES_0402LF-1K,1%,1/16W,EMPTY,CS21002FB06
     1 PVDD18_S5_P1 @T6G_MB_LIB.T6G(SCH_1):PVDD18_S5_P1    I69 @T6G_MB_LIB.T6G(SCH_1):PAGE185
     2 SVID_PVDDCR_CPU0_P1_SVC_R @T6G_MB_LIB.T6G(SCH_1):SVID_PVDDCR_CPU0_P1_SVC_R    I69 @T6G_MB_LIB.T6G(SCH_1):PAGE185

R8165 Q_RES_0402LF-1K,1%,1/16W,CHIP,CS21002FB06
     1 P3V3_AUX @T6G_MB_LIB.T6G(SCH_1):P3V3_AUX    I27 @T6G_MB_LIB.T6G(SCH_1):PAGE185
     2 PWRGD_PVDDCR_SOC_P1_R @T6G_MB_LIB.T6G(SCH_1):PWRGD_PVDDCR_SOC_P1_R    I27 @T6G_MB_LIB.T6G(SCH_1):PAGE185

R8166 Q_RES_0402LF-33,5%,1/16W,CHIP,CS03302JB10
     1 PWRGD_PVDDCR_SOC_P1 @T6G_MB_LIB.T6G(SCH_1):PWRGD_PVDDCR_SOC_P1    I23 @T6G_MB_LIB.T6G(SCH_1):PAGE185
     2 PWRGD_PVDDCR_SOC_P1_R @T6G_MB_LIB.T6G(SCH_1):PWRGD_PVDDCR_SOC_P1_R    I23 @T6G_MB_LIB.T6G(SCH_1):PAGE185

R8167 Q_RES_0402LF-1K,1%,1/16W,CHIP,CS21002FB06
     1 P3V3_AUX @T6G_MB_LIB.T6G(SCH_1):P3V3_AUX    I78 @T6G_MB_LIB.T6G(SCH_1):PAGE185
     2 PWRGD_PVDDCR_CPU0_P1_R @T6G_MB_LIB.T6G(SCH_1):PWRGD_PVDDCR_CPU0_P1_R    I78 @T6G_MB_LIB.T6G(SCH_1):PAGE185

R8168 Q_RES_0402LF-0,5%,1/16W,CHIP,CS00002JB13
     1 PVDDCR_CPU0_P1_OCP_N @T6G_MB_LIB.T6G(SCH_1):PVDDCR_CPU0_P1_OCP_N    I43 @T6G_MB_LIB.T6G(SCH_1):PAGE185
     2 PVDDCR_CPU0_P1_OCP_N_R @T6G_MB_LIB.T6G(SCH_1):PVDDCR_CPU0_P1_OCP_N_R    I43 @T6G_MB_LIB.T6G(SCH_1):PAGE185

R8171 Q_RES_0402LF-49.9,1%,1/16W,CHIP,CS04992FB07
     1 SVID_PVDDCR_CPU0_P1_SVTO @T6G_MB_LIB.T6G(SCH_1):SVID_PVDDCR_CPU0_P1_SVTO    I83 @T6G_MB_LIB.T6G(SCH_1):PAGE185
     2 SVID_PVDDCR_CPU0_P1_SVTO_R @T6G_MB_LIB.T6G(SCH_1):SVID_PVDDCR_CPU0_P1_SVTO_R    I83 @T6G_MB_LIB.T6G(SCH_1):PAGE185

R8176 Q_RES_0402LF-0,5%,1/16W,CHIP,CS00002JB13
     1 SMB_VR_3V3STBY_SDA @T6G_MB_LIB.T6G(SCH_1):SMB_VR_3V3STBY_SDA    I80 @T6G_MB_LIB.T6G(SCH_1):PAGE185
     2 PVDDCR_CPU0_P1_PMSDA_R @T6G_MB_LIB.T6G(SCH_1):PVDDCR_CPU0_P1_PMSDA_R    I80 @T6G_MB_LIB.T6G(SCH_1):PAGE185

R8177 Q_RES_0402LF-33,5%,1/16W,CHIP,CS03302JB10
     1 PVDDCR_CPU0_P1_PMALERT @T6G_MB_LIB.T6G(SCH_1):PVDDCR_CPU0_P1_PMALERT    I79 @T6G_MB_LIB.T6G(SCH_1):PAGE185
     2 PVDDCR_CPU0_P1_PMALERT_R @T6G_MB_LIB.T6G(SCH_1):PVDDCR_CPU0_P1_PMALERT_R    I79 @T6G_MB_LIB.T6G(SCH_1):PAGE185

R8178 Q_RES_0402LF-33,5%,1/16W,CHIP,CS03302JB10
     1 PWRGD_PVDDCR_CPU0_P1 @T6G_MB_LIB.T6G(SCH_1):PWRGD_PVDDCR_CPU0_P1    I85 @T6G_MB_LIB.T6G(SCH_1):PAGE185
     2 PWRGD_PVDDCR_CPU0_P1_R @T6G_MB_LIB.T6G(SCH_1):PWRGD_PVDDCR_CPU0_P1_R    I85 @T6G_MB_LIB.T6G(SCH_1):PAGE185

R8179 Q_RES_0402LF-0,5%,1/16W,CHIP,CS00002JB13
     1 PVDDCR_CPU0_P1_EN @T6G_MB_LIB.T6G(SCH_1):PVDDCR_CPU0_P1_EN    I84 @T6G_MB_LIB.T6G(SCH_1):PAGE185
     2 PVDDCR_CPU0_P1_EN_R @T6G_MB_LIB.T6G(SCH_1):PVDDCR_CPU0_P1_EN_R    I84 @T6G_MB_LIB.T6G(SCH_1):PAGE185

R8180 Q_RES_0402LF-1K,1%,1/16W,CHIP,CS21002FB06
     1 PVDD18_S5_P1 @T6G_MB_LIB.T6G(SCH_1):PVDD18_S5_P1    I54 @T6G_MB_LIB.T6G(SCH_1):PAGE185
     2 PVDDCR_CPU0_P1_OCP_N_R @T6G_MB_LIB.T6G(SCH_1):PVDDCR_CPU0_P1_OCP_N_R    I54 @T6G_MB_LIB.T6G(SCH_1):PAGE185

R8182 Q_RES_0402LF-49.9,1%,1/16W,CHIP,CS04992FB07
     1 PVDDCR_CPU0_P1_RESET_N @T6G_MB_LIB.T6G(SCH_1):PVDDCR_CPU0_P1_RESET_N    I42 @T6G_MB_LIB.T6G(SCH_1):PAGE185
     2 PVDDCR_CPU0_P1_RESET_N_R @T6G_MB_LIB.T6G(SCH_1):PVDDCR_CPU0_P1_RESET_N_R    I42 @T6G_MB_LIB.T6G(SCH_1):PAGE185

R8184 Q_RES_0402LF-1K,1%,1/16W,CHIP,CS21002FB06
     1 PVDD18_S5_P1 @T6G_MB_LIB.T6G(SCH_1):PVDD18_S5_P1    I41 @T6G_MB_LIB.T6G(SCH_1):PAGE185
     2 PVDDCR_CPU0_P1_RESET_N_R @T6G_MB_LIB.T6G(SCH_1):PVDDCR_CPU0_P1_RESET_N_R    I41 @T6G_MB_LIB.T6G(SCH_1):PAGE185

R8219 Q_RES_0402LF-1K,1%,1/16W,EMPTY,CS21002FB06
     1 SVID_PVDDCR_CPU1_P1_SVTO @T6G_MB_LIB.T6G(SCH_1):SVID_PVDDCR_CPU1_P1_SVTO    I30 @T6G_MB_LIB.T6G(SCH_1):PAGE192
     2    GND @T6G_MB_LIB.T6G(SCH_1):GND    I30 @T6G_MB_LIB.T6G(SCH_1):PAGE192

R8220 Q_RES_0402LF-1K,1%,1/16W,EMPTY,CS21002FB06
     1 PVDD18_S5_P1 @T6G_MB_LIB.T6G(SCH_1):PVDD18_S5_P1    I40 @T6G_MB_LIB.T6G(SCH_1):PAGE192
     2 SVID_PVDDCR_CPU1_P1_SVTO @T6G_MB_LIB.T6G(SCH_1):SVID_PVDDCR_CPU1_P1_SVTO    I40 @T6G_MB_LIB.T6G(SCH_1):PAGE192

R8222 Q_RES_0402LF-1K,1%,1/16W,EMPTY,CS21002FB06
     1 PVDD18_S5_P1 @T6G_MB_LIB.T6G(SCH_1):PVDD18_S5_P1    I41 @T6G_MB_LIB.T6G(SCH_1):PAGE192
     2 SVID_PVDDCR_CPU1_P1_SVD_R @T6G_MB_LIB.T6G(SCH_1):SVID_PVDDCR_CPU1_P1_SVD_R    I41 @T6G_MB_LIB.T6G(SCH_1):PAGE192

R8224 Q_RES_0402LF-0,5%,1/16W,CHIP,CS00002JB13
     1 PVDDIO_P1_EN @T6G_MB_LIB.T6G(SCH_1):PVDDIO_P1_EN     I2 @T6G_MB_LIB.T6G(SCH_1):PAGE192
     2 PVDDIO_P1_EN_R @T6G_MB_LIB.T6G(SCH_1):PVDDIO_P1_EN_R     I2 @T6G_MB_LIB.T6G(SCH_1):PAGE192

R8225 Q_RES_0402LF-1K,1%,1/16W,EMPTY,CS21002FB06
     1 PVDD18_S5_P1 @T6G_MB_LIB.T6G(SCH_1):PVDD18_S5_P1    I42 @T6G_MB_LIB.T6G(SCH_1):PAGE192
     2 SVID_PVDDCR_CPU1_P1_SVC_R @T6G_MB_LIB.T6G(SCH_1):SVID_PVDDCR_CPU1_P1_SVC_R    I42 @T6G_MB_LIB.T6G(SCH_1):PAGE192

R8233 Q_RES_0402LF-1K,1%,1/16W,CHIP,CS21002FB06
     1 P3V3_AUX @T6G_MB_LIB.T6G(SCH_1):P3V3_AUX    I89 @T6G_MB_LIB.T6G(SCH_1):PAGE192
     2 PWRGD_PVDDCR_CPU1_P1_R @T6G_MB_LIB.T6G(SCH_1):PWRGD_PVDDCR_CPU1_P1_R    I89 @T6G_MB_LIB.T6G(SCH_1):PAGE192

R8234 Q_RES_0402LF-33,5%,1/16W,CHIP,CS03302JB10
     1 PWRGD_PVDDCR_CPU1_P1 @T6G_MB_LIB.T6G(SCH_1):PWRGD_PVDDCR_CPU1_P1    I88 @T6G_MB_LIB.T6G(SCH_1):PAGE192
     2 PWRGD_PVDDCR_CPU1_P1_R @T6G_MB_LIB.T6G(SCH_1):PWRGD_PVDDCR_CPU1_P1_R    I88 @T6G_MB_LIB.T6G(SCH_1):PAGE192

R8235 Q_RES_0402LF-0,5%,1/16W,CHIP,CS00002JB13
     1 FM_PVDDCR_CPU1_P1_EN @T6G_MB_LIB.T6G(SCH_1):FM_PVDDCR_CPU1_P1_EN    I87 @T6G_MB_LIB.T6G(SCH_1):PAGE192
     2 PVDDCR_CPU1_P1_EN_R @T6G_MB_LIB.T6G(SCH_1):PVDDCR_CPU1_P1_EN_R    I87 @T6G_MB_LIB.T6G(SCH_1):PAGE192

R8238 Q_RES_0402LF-49.9,1%,1/16W,CHIP,CS04992FB07
     1 SVID_PVDDCR_CPU1_P1_SVTO @T6G_MB_LIB.T6G(SCH_1):SVID_PVDDCR_CPU1_P1_SVTO    I82 @T6G_MB_LIB.T6G(SCH_1):PAGE192
     2 SVID_PVDDCR_CPU1_P1_SVTO_R @T6G_MB_LIB.T6G(SCH_1):SVID_PVDDCR_CPU1_P1_SVTO_R    I82 @T6G_MB_LIB.T6G(SCH_1):PAGE192

R8241 Q_RES_0402LF-0,5%,1/16W,CHIP,CS00002JB13
     1 PVDDCR_CPU1_P1_OCP_N @T6G_MB_LIB.T6G(SCH_1):PVDDCR_CPU1_P1_OCP_N    I64 @T6G_MB_LIB.T6G(SCH_1):PAGE192
     2 PVDDCR_CPU1_P1_OCP_N_R @T6G_MB_LIB.T6G(SCH_1):PVDDCR_CPU1_P1_OCP_N_R    I64 @T6G_MB_LIB.T6G(SCH_1):PAGE192

R8242 Q_RES_0402LF-1K,1%,1/16W,CHIP,CS21002FB06
     1 P3V3_AUX @T6G_MB_LIB.T6G(SCH_1):P3V3_AUX    I51 @T6G_MB_LIB.T6G(SCH_1):PAGE192
     2 PWRGD_PVDDIO_P1_R @T6G_MB_LIB.T6G(SCH_1):PWRGD_PVDDIO_P1_R    I51 @T6G_MB_LIB.T6G(SCH_1):PAGE192

R8243 Q_RES_0402LF-33,5%,1/16W,CHIP,CS03302JB10
     1 PWRGD_PVDDIO_P1 @T6G_MB_LIB.T6G(SCH_1):PWRGD_PVDDIO_P1    I50 @T6G_MB_LIB.T6G(SCH_1):PAGE192
     2 PWRGD_PVDDIO_P1_R @T6G_MB_LIB.T6G(SCH_1):PWRGD_PVDDIO_P1_R    I50 @T6G_MB_LIB.T6G(SCH_1):PAGE192

R8247 Q_RES_0402LF-1K,1%,1/16W,CHIP,CS21002FB06
     1 PVDD18_S5_P1 @T6G_MB_LIB.T6G(SCH_1):PVDD18_S5_P1    I66 @T6G_MB_LIB.T6G(SCH_1):PAGE192
     2 PVDDCR_CPU1_P1_RESET_N_R @T6G_MB_LIB.T6G(SCH_1):PVDDCR_CPU1_P1_RESET_N_R    I66 @T6G_MB_LIB.T6G(SCH_1):PAGE192

R8248 Q_RES_0402LF-0,5%,1/16W,CHIP,CS00002JB13
     1 SMB_SCM_2_R1_SCL @T6G_MB_LIB.T6G(SCH_1):SMB_SCM_2_R1_SCL    I84 @T6G_MB_LIB.T6G(SCH_1):PAGE192
     2 SMB_CLK_PVDDCR_CPU1_P1_R @T6G_MB_LIB.T6G(SCH_1):SMB_CLK_PVDDCR_CPU1_P1_R    I84 @T6G_MB_LIB.T6G(SCH_1):PAGE192

R8249 Q_RES_0402LF-0,5%,1/16W,CHIP,CS00002JB13
     1 SMB_SCM_2_R1_SDA @T6G_MB_LIB.T6G(SCH_1):SMB_SCM_2_R1_SDA    I81 @T6G_MB_LIB.T6G(SCH_1):PAGE192
     2 SMB_DIO_PVDDCR_CPU1_P1_R @T6G_MB_LIB.T6G(SCH_1):SMB_DIO_PVDDCR_CPU1_P1_R    I81 @T6G_MB_LIB.T6G(SCH_1):PAGE192

R8250 Q_RES_0402LF-33,5%,1/16W,CHIP,CS03302JB10
     1 PVDDCR_CPU1_P1_SMB_ALERT @T6G_MB_LIB.T6G(SCH_1):PVDDCR_CPU1_P1_SMB_ALERT    I80 @T6G_MB_LIB.T6G(SCH_1):PAGE192
     2 PVDDCR_CPU1_P1_SMB_ALERT_R @T6G_MB_LIB.T6G(SCH_1):PVDDCR_CPU1_P1_SMB_ALERT_R    I80 @T6G_MB_LIB.T6G(SCH_1):PAGE192

R8252 Q_RES_0402LF-1K,1%,1/16W,CHIP,CS21002FB06
     1 PVDD18_S5_P1 @T6G_MB_LIB.T6G(SCH_1):PVDD18_S5_P1    I71 @T6G_MB_LIB.T6G(SCH_1):PAGE192
     2 PVDDCR_CPU1_P1_OCP_N_R @T6G_MB_LIB.T6G(SCH_1):PVDDCR_CPU1_P1_OCP_N_R    I71 @T6G_MB_LIB.T6G(SCH_1):PAGE192

R8282 Q_RES_0402LF-0,5%,1/16W,CHIP,CS00002JB13
     1 PVDDCR_SOC_P0_EN @T6G_MB_LIB.T6G(SCH_1):PVDDCR_SOC_P0_EN     I2 @T6G_MB_LIB.T6G(SCH_1):PAGE168
     2 PVDDCR_SOC_P0_EN_RC @T6G_MB_LIB.T6G(SCH_1):PVDDCR_SOC_P0_EN_RC     I2 @T6G_MB_LIB.T6G(SCH_1):PAGE168

R8286 Q_RES_0402LF-1K,1%,1/16W,EMPTY,CS21002FB06
     1 SVID_PVDDCR_CPU0_P0_SVTO @T6G_MB_LIB.T6G(SCH_1):SVID_PVDDCR_CPU0_P0_SVTO     I6 @T6G_MB_LIB.T6G(SCH_1):PAGE168
     2    GND @T6G_MB_LIB.T6G(SCH_1):GND     I6 @T6G_MB_LIB.T6G(SCH_1):PAGE168

R8287 Q_RES_0402LF-1K,1%,1/16W,EMPTY,CS21002FB06
     1 PVDD18_S5_P0 @T6G_MB_LIB.T6G(SCH_1):PVDD18_S5_P0    I69 @T6G_MB_LIB.T6G(SCH_1):PAGE168
     2 SVID_PVDDCR_CPU0_P0_SVTO @T6G_MB_LIB.T6G(SCH_1):SVID_PVDDCR_CPU0_P0_SVTO    I69 @T6G_MB_LIB.T6G(SCH_1):PAGE168

R8289 Q_RES_0402LF-1K,1%,1/16W,EMPTY,CS21002FB06
     1 PVDD18_S5_P0 @T6G_MB_LIB.T6G(SCH_1):PVDD18_S5_P0    I70 @T6G_MB_LIB.T6G(SCH_1):PAGE168
     2 SVID_PVDDCR_CPU0_P0_SVD_R @T6G_MB_LIB.T6G(SCH_1):SVID_PVDDCR_CPU0_P0_SVD_R    I70 @T6G_MB_LIB.T6G(SCH_1):PAGE168

R8293 Q_RES_0402LF-1K,1%,1/16W,EMPTY,CS21002FB06
     1 PVDD18_S5_P0 @T6G_MB_LIB.T6G(SCH_1):PVDD18_S5_P0    I71 @T6G_MB_LIB.T6G(SCH_1):PAGE168
     2 SVID_PVDDCR_CPU0_P0_SVC_R @T6G_MB_LIB.T6G(SCH_1):SVID_PVDDCR_CPU0_P0_SVC_R    I71 @T6G_MB_LIB.T6G(SCH_1):PAGE168

R8298 Q_RES_0402LF-1K,1%,1/16W,CHIP,CS21002FB06
     1 P3V3_AUX @T6G_MB_LIB.T6G(SCH_1):P3V3_AUX    I28 @T6G_MB_LIB.T6G(SCH_1):PAGE168
     2 PWRGD_PVDDCR_SOC_P0_R @T6G_MB_LIB.T6G(SCH_1):PWRGD_PVDDCR_SOC_P0_R    I28 @T6G_MB_LIB.T6G(SCH_1):PAGE168

R8299 Q_RES_0402LF-33,5%,1/16W,CHIP,CS03302JB10
     1 PWRGD_PVDDCR_SOC_P0 @T6G_MB_LIB.T6G(SCH_1):PWRGD_PVDDCR_SOC_P0    I24 @T6G_MB_LIB.T6G(SCH_1):PAGE168
     2 PWRGD_PVDDCR_SOC_P0_R @T6G_MB_LIB.T6G(SCH_1):PWRGD_PVDDCR_SOC_P0_R    I24 @T6G_MB_LIB.T6G(SCH_1):PAGE168

R8300 Q_RES_0402LF-1K,1%,1/16W,CHIP,CS21002FB06
     1 P3V3_AUX @T6G_MB_LIB.T6G(SCH_1):P3V3_AUX    I82 @T6G_MB_LIB.T6G(SCH_1):PAGE168
     2 PWRGD_PVDDCR_CPU0_P0_R @T6G_MB_LIB.T6G(SCH_1):PWRGD_PVDDCR_CPU0_P0_R    I82 @T6G_MB_LIB.T6G(SCH_1):PAGE168

R8301 Q_RES_0402LF-0,5%,1/16W,CHIP,CS00002JB13
     1 PVDDCR_CPU0_P0_OCP_N @T6G_MB_LIB.T6G(SCH_1):PVDDCR_CPU0_P0_OCP_N    I58 @T6G_MB_LIB.T6G(SCH_1):PAGE168
     2 PVDDCR_CPU0_P0_OCP_N_R @T6G_MB_LIB.T6G(SCH_1):PVDDCR_CPU0_P0_OCP_N_R    I58 @T6G_MB_LIB.T6G(SCH_1):PAGE168

R8304 Q_RES_0402LF-49.9,1%,1/16W,CHIP,CS04992FB07
     1 SVID_PVDDCR_CPU0_P0_SVTO @T6G_MB_LIB.T6G(SCH_1):SVID_PVDDCR_CPU0_P0_SVTO    I87 @T6G_MB_LIB.T6G(SCH_1):PAGE168
     2 SVID_PVDDCR_CPU0_P0_SVTO_R @T6G_MB_LIB.T6G(SCH_1):SVID_PVDDCR_CPU0_P0_SVTO_R    I87 @T6G_MB_LIB.T6G(SCH_1):PAGE168

R8305 Q_RES_0402LF-0,5%,1/16W,CHIP,CS00002JB13
     1 CLK_100M_CPU0_CLK13_R_DP @T6G_MB_LIB.T6G(SCH_1):CLK_100M_CPU0_CLK13_R_DP   I229 @T6G_MB_LIB.T6G(SCH_1):PAGE28
     2 CLK_100M_CPU0_CLK13_DP @T6G_MB_LIB.T6G(SCH_1):CLK_100M_CPU0_CLK13_DP   I229 @T6G_MB_LIB.T6G(SCH_1):PAGE28

R8306 Q_RES_0402LF-0,5%,1/16W,CHIP,CS00002JB13
     1 CLK_100M_CPU0_CLK13_R_DN @T6G_MB_LIB.T6G(SCH_1):CLK_100M_CPU0_CLK13_R_DN   I228 @T6G_MB_LIB.T6G(SCH_1):PAGE28
     2 CLK_100M_CPU0_CLK13_DN @T6G_MB_LIB.T6G(SCH_1):CLK_100M_CPU0_CLK13_DN   I228 @T6G_MB_LIB.T6G(SCH_1):PAGE28

R8308 Q_RES_0402LF-0,5%,1/16W,CHIP,CS00002JB13
     1 SMB_SCM_2_R3_SCL @T6G_MB_LIB.T6G(SCH_1):SMB_SCM_2_R3_SCL    I85 @T6G_MB_LIB.T6G(SCH_1):PAGE168
     2 PVDDCR_CPU0_P0_PMSCL_R @T6G_MB_LIB.T6G(SCH_1):PVDDCR_CPU0_P0_PMSCL_R    I85 @T6G_MB_LIB.T6G(SCH_1):PAGE168

R8309 Q_RES_0402LF-0,5%,1/16W,CHIP,CS00002JB13
     1 SMB_SCM_2_R3_SDA @T6G_MB_LIB.T6G(SCH_1):SMB_SCM_2_R3_SDA    I84 @T6G_MB_LIB.T6G(SCH_1):PAGE168
     2 PVDDCR_CPU0_P0_PMSDA_R @T6G_MB_LIB.T6G(SCH_1):PVDDCR_CPU0_P0_PMSDA_R    I84 @T6G_MB_LIB.T6G(SCH_1):PAGE168

R8310 Q_RES_0402LF-33,5%,1/16W,CHIP,CS03302JB10
     1 PVDDCR_CPU0_P0_PMALERT @T6G_MB_LIB.T6G(SCH_1):PVDDCR_CPU0_P0_PMALERT    I83 @T6G_MB_LIB.T6G(SCH_1):PAGE168
     2 PVDDCR_CPU0_P0_PMALERT_R @T6G_MB_LIB.T6G(SCH_1):PVDDCR_CPU0_P0_PMALERT_R    I83 @T6G_MB_LIB.T6G(SCH_1):PAGE168

R8311 Q_RES_0402LF-33,5%,1/16W,CHIP,CS03302JB10
     1 PWRGD_PVDDCR_CPU0_P0 @T6G_MB_LIB.T6G(SCH_1):PWRGD_PVDDCR_CPU0_P0    I89 @T6G_MB_LIB.T6G(SCH_1):PAGE168
     2 PWRGD_PVDDCR_CPU0_P0_R @T6G_MB_LIB.T6G(SCH_1):PWRGD_PVDDCR_CPU0_P0_R    I89 @T6G_MB_LIB.T6G(SCH_1):PAGE168

R8312 Q_RES_0402LF-0,5%,1/16W,CHIP,CS00002JB13
     1 PVDDCR_CPU0_P0_EN @T6G_MB_LIB.T6G(SCH_1):PVDDCR_CPU0_P0_EN    I88 @T6G_MB_LIB.T6G(SCH_1):PAGE168
     2 PVDDCR_CPU0_P0_EN_R @T6G_MB_LIB.T6G(SCH_1):PVDDCR_CPU0_P0_EN_R    I88 @T6G_MB_LIB.T6G(SCH_1):PAGE168

R8313 Q_RES_0402LF-1K,1%,1/16W,CHIP,CS21002FB06
     1 PVDD18_S5_P0 @T6G_MB_LIB.T6G(SCH_1):PVDD18_S5_P0    I54 @T6G_MB_LIB.T6G(SCH_1):PAGE168
     2 PVDDCR_CPU0_P0_OCP_N_R @T6G_MB_LIB.T6G(SCH_1):PVDDCR_CPU0_P0_OCP_N_R    I54 @T6G_MB_LIB.T6G(SCH_1):PAGE168

R8317 Q_RES_0402LF-1K,1%,1/16W,CHIP,CS21002FB06
     1 PVDD18_S5_P0 @T6G_MB_LIB.T6G(SCH_1):PVDD18_S5_P0    I42 @T6G_MB_LIB.T6G(SCH_1):PAGE168
     2 PVDDCR_CPU0_P0_RESET_N_R @T6G_MB_LIB.T6G(SCH_1):PVDDCR_CPU0_P0_RESET_N_R    I42 @T6G_MB_LIB.T6G(SCH_1):PAGE168

R8350 Q_RES_0402LF-0,5%,1/16W,CHIP,CS00002JB13
     1 CLK_100M_CPU1_CLK13_R_DP @T6G_MB_LIB.T6G(SCH_1):CLK_100M_CPU1_CLK13_R_DP   I397 @T6G_MB_LIB.T6G(SCH_1):PAGE55
     2 CLK_100M_CPU1_CLK13_DP @T6G_MB_LIB.T6G(SCH_1):CLK_100M_CPU1_CLK13_DP   I397 @T6G_MB_LIB.T6G(SCH_1):PAGE55

R8351 Q_RES_0402LF-0,5%,1/16W,CHIP,CS00002JB13
     1 CLK_100M_CPU1_CLK13_R_DN @T6G_MB_LIB.T6G(SCH_1):CLK_100M_CPU1_CLK13_R_DN   I394 @T6G_MB_LIB.T6G(SCH_1):PAGE55
     2 CLK_100M_CPU1_CLK13_DN @T6G_MB_LIB.T6G(SCH_1):CLK_100M_CPU1_CLK13_DN   I394 @T6G_MB_LIB.T6G(SCH_1):PAGE55

R8380 Q_RES_0402LF-1K,1%,1/16W,CHIP,CS21002FB06
     1 P3V3_AUX @T6G_MB_LIB.T6G(SCH_1):P3V3_AUX    I37 @T6G_MB_LIB.T6G(SCH_1):PAGE199
     2 PWRGD_PVDD11_S3_P1_R @T6G_MB_LIB.T6G(SCH_1):PWRGD_PVDD11_S3_P1_R    I37 @T6G_MB_LIB.T6G(SCH_1):PAGE199

R8381 Q_RES_0402LF-0,5%,1/16W,CHIP,CS00002JB13
     1 SMB_SCM_2_R2_SCL @T6G_MB_LIB.T6G(SCH_1):SMB_SCM_2_R2_SCL    I40 @T6G_MB_LIB.T6G(SCH_1):PAGE199
     2 PVDD11_S3_P1_PMSCL_R @T6G_MB_LIB.T6G(SCH_1):PVDD11_S3_P1_PMSCL_R    I40 @T6G_MB_LIB.T6G(SCH_1):PAGE199

R8382 Q_RES_0402LF-0,5%,1/16W,CHIP,CS00002JB13
     1 SMB_SCM_2_R2_SDA @T6G_MB_LIB.T6G(SCH_1):SMB_SCM_2_R2_SDA    I39 @T6G_MB_LIB.T6G(SCH_1):PAGE199
     2 PVDD11_S3_P1_PMSDA_R @T6G_MB_LIB.T6G(SCH_1):PVDD11_S3_P1_PMSDA_R    I39 @T6G_MB_LIB.T6G(SCH_1):PAGE199

R8383 Q_RES_0402LF-33,5%,1/16W,CHIP,CS03302JB10
     1 PVDD11_S3_P1_PMALERT @T6G_MB_LIB.T6G(SCH_1):PVDD11_S3_P1_PMALERT    I38 @T6G_MB_LIB.T6G(SCH_1):PAGE199
     2 PVDD11_S3_P1_PMALERT_R @T6G_MB_LIB.T6G(SCH_1):PVDD11_S3_P1_PMALERT_R    I38 @T6G_MB_LIB.T6G(SCH_1):PAGE199

R8385 Q_RES_0402LF-0,5%,1/16W,CHIP,CS00002JB13
     1 PWRGD_PVDD11_S3_P1 @T6G_MB_LIB.T6G(SCH_1):PWRGD_PVDD11_S3_P1    I43 @T6G_MB_LIB.T6G(SCH_1):PAGE199
     2 PWRGD_PVDD11_S3_P1_R @T6G_MB_LIB.T6G(SCH_1):PWRGD_PVDD11_S3_P1_R    I43 @T6G_MB_LIB.T6G(SCH_1):PAGE199

R8386 Q_RES_0402LF-0,5%,1/16W,CHIP,CS00002JB13
     1 PVDD11_S3_P1_EN @T6G_MB_LIB.T6G(SCH_1):PVDD11_S3_P1_EN    I42 @T6G_MB_LIB.T6G(SCH_1):PAGE199
     2 PVDD11_S3_P1_EN_R @T6G_MB_LIB.T6G(SCH_1):PVDD11_S3_P1_EN_R    I42 @T6G_MB_LIB.T6G(SCH_1):PAGE199

R8413 Q_RES_0402LF-100K,1%,1/16W,CHIP,CS41002FB09
     1    GND @T6G_MB_LIB.T6G(SCH_1):GND    I33 @T6G_MB_LIB.T6G(SCH_1):PAGE341
     2 FM_OCP_V3_2_PWR_GOOD @T6G_MB_LIB.T6G(SCH_1):FM_OCP_V3_2_PWR_GOOD    I33 @T6G_MB_LIB.T6G(SCH_1):PAGE341

R8420 Q_RES_0402LF-1K,1%,1/16W,CHIP,CS21002FB06
     1 SGPIO_OCP_SFF_LD_N @T6G_MB_LIB.T6G(SCH_1):SGPIO_OCP_SFF_LD_N    I22 @T6G_MB_LIB.T6G(SCH_1):PAGE335
     2 P3V3_OCP_SFF @T6G_MB_LIB.T6G(SCH_1):P3V3_OCP_SFF    I22 @T6G_MB_LIB.T6G(SCH_1):PAGE335

R8421 Q_RES_0402LF-10K,1%,1/16W,CHIP,CS31002FB08
     1 SGPIO_OCP_SFF_DATAIN @T6G_MB_LIB.T6G(SCH_1):SGPIO_OCP_SFF_DATAIN    I21 @T6G_MB_LIB.T6G(SCH_1):PAGE335
     2 P3V3_OCP_SFF @T6G_MB_LIB.T6G(SCH_1):P3V3_OCP_SFF    I21 @T6G_MB_LIB.T6G(SCH_1):PAGE335

R8422 Q_RES_0402LF-10K,1%,1/16W,CHIP,CS31002FB08
     1 SGPIO_OCP_SFF_DATAOUT @T6G_MB_LIB.T6G(SCH_1):SGPIO_OCP_SFF_DATAOUT    I19 @T6G_MB_LIB.T6G(SCH_1):PAGE335
     2    GND @T6G_MB_LIB.T6G(SCH_1):GND    I19 @T6G_MB_LIB.T6G(SCH_1):PAGE335

R8423 Q_RES_0402LF-1K,1%,1/16W,CHIP,CS21002FB06
     1 SGPIO_OCP_SFF_CLK @T6G_MB_LIB.T6G(SCH_1):SGPIO_OCP_SFF_CLK    I20 @T6G_MB_LIB.T6G(SCH_1):PAGE335
     2 P3V3_OCP_SFF @T6G_MB_LIB.T6G(SCH_1):P3V3_OCP_SFF    I20 @T6G_MB_LIB.T6G(SCH_1):PAGE335

R8458 Q_RES_0402LF-0,5%,1/16W,EMPTY,CS00002JB13
     1 P3V3_AUX @T6G_MB_LIB.T6G(SCH_1):P3V3_AUX     I9 @T6G_MB_LIB.T6G(SCH_1):PAGE182
     2 PVDD11_S3_P0_VDDIO @T6G_MB_LIB.T6G(SCH_1):PVDD11_S3_P0_VDDIO     I9 @T6G_MB_LIB.T6G(SCH_1):PAGE182

R8465 Q_RES_0402LF-10K,5%,1/16W,CHIP,CS31002JB08
     1 P3V3_AUX @T6G_MB_LIB.T6G(SCH_1):P3V3_AUX    I29 @T6G_MB_LIB.T6G(SCH_1):PAGE184
     2 PWRGD_PVDD18_S5_P0 @T6G_MB_LIB.T6G(SCH_1):PWRGD_PVDD18_S5_P0    I29 @T6G_MB_LIB.T6G(SCH_1):PAGE184

R8563 Q_RES_0402LF-0,5%,1/16W,CHIP,CS00002JB13
     1 CLK_100M_CPU0_CLK02_R_DP @T6G_MB_LIB.T6G(SCH_1):CLK_100M_CPU0_CLK02_R_DP   I157 @T6G_MB_LIB.T6G(SCH_1):PAGE28
     2 CLK_100M_CPU0_CLK02_DP @T6G_MB_LIB.T6G(SCH_1):CLK_100M_CPU0_CLK02_DP   I157 @T6G_MB_LIB.T6G(SCH_1):PAGE28

R8564 Q_RES_0402LF-0,5%,1/16W,CHIP,CS00002JB13
     1 CLK_100M_CPU0_CLK02_R_DN @T6G_MB_LIB.T6G(SCH_1):CLK_100M_CPU0_CLK02_R_DN   I156 @T6G_MB_LIB.T6G(SCH_1):PAGE28
     2 CLK_100M_CPU0_CLK02_DN @T6G_MB_LIB.T6G(SCH_1):CLK_100M_CPU0_CLK02_DN   I156 @T6G_MB_LIB.T6G(SCH_1):PAGE28

R8565 Q_RES_0402LF-0,5%,1/16W,CHIP,CS00002JB13
     1 CLK_100M_CPU0_CLK03_R_DP @T6G_MB_LIB.T6G(SCH_1):CLK_100M_CPU0_CLK03_R_DP   I158 @T6G_MB_LIB.T6G(SCH_1):PAGE28
     2 CLK_100M_CPU0_CLK03_DP @T6G_MB_LIB.T6G(SCH_1):CLK_100M_CPU0_CLK03_DP   I158 @T6G_MB_LIB.T6G(SCH_1):PAGE28

R8566 Q_RES_0402LF-0,5%,1/16W,CHIP,CS00002JB13
     1 CLK_100M_CPU0_CLK03_R_DN @T6G_MB_LIB.T6G(SCH_1):CLK_100M_CPU0_CLK03_R_DN   I155 @T6G_MB_LIB.T6G(SCH_1):PAGE28
     2 CLK_100M_CPU0_CLK03_DN @T6G_MB_LIB.T6G(SCH_1):CLK_100M_CPU0_CLK03_DN   I155 @T6G_MB_LIB.T6G(SCH_1):PAGE28

R9000 Q_RES_0402LF-1K,1%,1/16W,CHIP,CS21002FB06
     1 P3V3_AUX @T6G_MB_LIB.T6G(SCH_1):P3V3_AUX   I472 @T6G_MB_LIB.T6G(SCH_1):PAGE363
     2 FM_FAN_PWR_EN @T6G_MB_LIB.T6G(SCH_1):FM_FAN_PWR_EN   I472 @T6G_MB_LIB.T6G(SCH_1):PAGE363

R9001 Q_RES_0402LF-0,5%,1/16W,CHIP,CS00002JB13
     1 GPU_PRSNT_N_ISO @T6G_MB_LIB.T6G(SCH_1):GPU_PRSNT_N_ISO    I46 @T6G_MB_LIB.T6G(SCH_1):PAGE246
     2 GPU_PRSNT_N_ISO_R1 @T6G_MB_LIB.T6G(SCH_1):GPU_PRSNT_N_ISO_R1    I46 @T6G_MB_LIB.T6G(SCH_1):PAGE246

R9002 Q_RES_0402LF-10K,1%,1/16W,CHIP,CS31002FB08
     1 P3V3_AUX @T6G_MB_LIB.T6G(SCH_1):P3V3_AUX     I8 @T6G_MB_LIB.T6G(SCH_1):PAGE330
     2 PRSNT_CABLE_SWB_B1_N @T6G_MB_LIB.T6G(SCH_1):PRSNT_CABLE_SWB_B1_N     I8 @T6G_MB_LIB.T6G(SCH_1):PAGE330

R9003 Q_RES_0402LF-100K,1%,1/16W,EMPTY,CS41002FB09
     1 PRSNT_CABLE_SWB_B1_N @T6G_MB_LIB.T6G(SCH_1):PRSNT_CABLE_SWB_B1_N    I20 @T6G_MB_LIB.T6G(SCH_1):PAGE330
     2    GND @T6G_MB_LIB.T6G(SCH_1):GND    I20 @T6G_MB_LIB.T6G(SCH_1):PAGE330

R9004 Q_RES_0402LF-4.7K,5%,1/16W,CHIP,CS24702JB10
     1 P3V3_AUX @T6G_MB_LIB.T6G(SCH_1):P3V3_AUX    I26 @T6G_MB_LIB.T6G(SCH_1):PAGE330
     2 PRSNT_CABLE_SWB_B1 @T6G_MB_LIB.T6G(SCH_1):PRSNT_CABLE_SWB_B1    I26 @T6G_MB_LIB.T6G(SCH_1):PAGE330

R9005 Q_RES_0402LF-4.7K,5%,1/16W,CHIP,CS24702JB10
     1 P3V3_AUX @T6G_MB_LIB.T6G(SCH_1):P3V3_AUX    I32 @T6G_MB_LIB.T6G(SCH_1):PAGE330
     2 PRSNT_CABLE_SWB_B1_ISO_N @T6G_MB_LIB.T6G(SCH_1):PRSNT_CABLE_SWB_B1_ISO_N    I32 @T6G_MB_LIB.T6G(SCH_1):PAGE330

R9006 Q_RES_0402LF-10K,1%,1/16W,CHIP,CS31002FB08
     1 P3V3_AUX @T6G_MB_LIB.T6G(SCH_1):P3V3_AUX    I15 @T6G_MB_LIB.T6G(SCH_1):PAGE330
     2 PRSNT_CABLE_SWB_B2_N @T6G_MB_LIB.T6G(SCH_1):PRSNT_CABLE_SWB_B2_N    I15 @T6G_MB_LIB.T6G(SCH_1):PAGE330

R9007 Q_RES_0402LF-100K,1%,1/16W,EMPTY,CS41002FB09
     1 PRSNT_CABLE_SWB_B2_N @T6G_MB_LIB.T6G(SCH_1):PRSNT_CABLE_SWB_B2_N     I2 @T6G_MB_LIB.T6G(SCH_1):PAGE330
     2    GND @T6G_MB_LIB.T6G(SCH_1):GND     I2 @T6G_MB_LIB.T6G(SCH_1):PAGE330

R9008 Q_RES_0402LF-4.7K,5%,1/16W,CHIP,CS24702JB10
     1 P3V3_AUX @T6G_MB_LIB.T6G(SCH_1):P3V3_AUX    I17 @T6G_MB_LIB.T6G(SCH_1):PAGE330
     2 PRSNT_CABLE_SWB_B2 @T6G_MB_LIB.T6G(SCH_1):PRSNT_CABLE_SWB_B2    I17 @T6G_MB_LIB.T6G(SCH_1):PAGE330

R9009 Q_RES_0402LF-4.7K,5%,1/16W,CHIP,CS24702JB10
     1 P3V3_AUX @T6G_MB_LIB.T6G(SCH_1):P3V3_AUX    I23 @T6G_MB_LIB.T6G(SCH_1):PAGE330
     2 PRSNT_CABLE_SWB_B2_ISO_N @T6G_MB_LIB.T6G(SCH_1):PRSNT_CABLE_SWB_B2_ISO_N    I23 @T6G_MB_LIB.T6G(SCH_1):PAGE330

R9010 Q_RES_0402LF-0,5%,1/16W,CHIP,CS00002JB13
     1 PRSNT_CABLE_SWB_B1_ISO_N @T6G_MB_LIB.T6G(SCH_1):PRSNT_CABLE_SWB_B1_ISO_N    I40 @T6G_MB_LIB.T6G(SCH_1):PAGE246
     2 PRSNT_CABLE_SWB_B1_ISO_R_N @T6G_MB_LIB.T6G(SCH_1):PRSNT_CABLE_SWB_B1_ISO_R_N    I40 @T6G_MB_LIB.T6G(SCH_1):PAGE246

R9011 Q_RES_0402LF-0,5%,1/16W,CHIP,CS00002JB13
     1 PRSNT_CABLE_GPU_B3_ISO_N @T6G_MB_LIB.T6G(SCH_1):PRSNT_CABLE_GPU_B3_ISO_N    I45 @T6G_MB_LIB.T6G(SCH_1):PAGE246
     2 PRSNT_CABLE_GPU_B3_ISO_R1_N @T6G_MB_LIB.T6G(SCH_1):PRSNT_CABLE_GPU_B3_ISO_R1_N    I45 @T6G_MB_LIB.T6G(SCH_1):PAGE246

R9012 Q_RES_0402LF-0,5%,1/16W,CHIP,CS00002JB13
     1 PRSNT_CABLE_SWB_B2_ISO_N @T6G_MB_LIB.T6G(SCH_1):PRSNT_CABLE_SWB_B2_ISO_N    I39 @T6G_MB_LIB.T6G(SCH_1):PAGE246
     2 PRSNT_CABLE_SWB_B2_ISO_R_N @T6G_MB_LIB.T6G(SCH_1):PRSNT_CABLE_SWB_B2_ISO_R_N    I39 @T6G_MB_LIB.T6G(SCH_1):PAGE246

R9013 Q_RES_0402LF-0,5%,1/16W,CHIP,CS00002JB13
     1 PRSNT_CABLE_GPU_A2_ISO_N @T6G_MB_LIB.T6G(SCH_1):PRSNT_CABLE_GPU_A2_ISO_N    I43 @T6G_MB_LIB.T6G(SCH_1):PAGE246
     2 PRSNT_CABLE_GPU_A2_ISO_R1_N @T6G_MB_LIB.T6G(SCH_1):PRSNT_CABLE_GPU_A2_ISO_R1_N    I43 @T6G_MB_LIB.T6G(SCH_1):PAGE246

R9014 Q_RES_0402LF-10K,1%,1/16W,CHIP,CS31002FB08
     1 P3V3_AUX @T6G_MB_LIB.T6G(SCH_1):P3V3_AUX    I51 @T6G_MB_LIB.T6G(SCH_1):PAGE330
     2 PRSNT_CABLE_GPU_A3_N @T6G_MB_LIB.T6G(SCH_1):PRSNT_CABLE_GPU_A3_N    I51 @T6G_MB_LIB.T6G(SCH_1):PAGE330

R9015 Q_RES_0402LF-100K,1%,1/16W,EMPTY,CS41002FB09
     1 PRSNT_CABLE_GPU_A3_N @T6G_MB_LIB.T6G(SCH_1):PRSNT_CABLE_GPU_A3_N    I50 @T6G_MB_LIB.T6G(SCH_1):PAGE330
     2    GND @T6G_MB_LIB.T6G(SCH_1):GND    I50 @T6G_MB_LIB.T6G(SCH_1):PAGE330

R9016 Q_RES_0402LF-4.7K,5%,1/16W,CHIP,CS24702JB10
     1 P3V3_AUX @T6G_MB_LIB.T6G(SCH_1):P3V3_AUX    I61 @T6G_MB_LIB.T6G(SCH_1):PAGE330
     2 PRSNT_CABLE_GPU_A3 @T6G_MB_LIB.T6G(SCH_1):PRSNT_CABLE_GPU_A3    I61 @T6G_MB_LIB.T6G(SCH_1):PAGE330

R9017 Q_RES_0402LF-4.7K,5%,1/16W,CHIP,CS24702JB10
     1 P3V3_AUX @T6G_MB_LIB.T6G(SCH_1):P3V3_AUX    I72 @T6G_MB_LIB.T6G(SCH_1):PAGE330
     2 PRSNT_CABLE_GPU_A3_ISO_N @T6G_MB_LIB.T6G(SCH_1):PRSNT_CABLE_GPU_A3_ISO_N    I72 @T6G_MB_LIB.T6G(SCH_1):PAGE330

R9018 Q_RES_0402LF-0,5%,1/16W,CHIP,CS00002JB13
     1 PRSNT_CABLE_GPU_A3_ISO_N @T6G_MB_LIB.T6G(SCH_1):PRSNT_CABLE_GPU_A3_ISO_N    I44 @T6G_MB_LIB.T6G(SCH_1):PAGE246
     2 PRSNT_CABLE_GPU_A3_ISO_R_N @T6G_MB_LIB.T6G(SCH_1):PRSNT_CABLE_GPU_A3_ISO_R_N    I44 @T6G_MB_LIB.T6G(SCH_1):PAGE246

R9019 Q_RES_0402LF-0,5%,1/16W,CHIP,CS00002JB13
     1 PRSNT_CABLE_GPU_A1_ISO_N @T6G_MB_LIB.T6G(SCH_1):PRSNT_CABLE_GPU_A1_ISO_N    I42 @T6G_MB_LIB.T6G(SCH_1):PAGE246
     2 PRSNT_CABLE_GPU_A1_ISO_R1_N @T6G_MB_LIB.T6G(SCH_1):PRSNT_CABLE_GPU_A1_ISO_R1_N    I42 @T6G_MB_LIB.T6G(SCH_1):PAGE246

R9020 Q_RES_0402LF-1K,1%,1/16W,EMPTY,CS21002FB06
     1 P3V3_AUX @T6G_MB_LIB.T6G(SCH_1):P3V3_AUX   I108 @T6G_MB_LIB.T6G(SCH_1):PAGE371
     2 U142_VS @T6G_MB_LIB.T6G(SCH_1):U142_VS   I108 @T6G_MB_LIB.T6G(SCH_1):PAGE371

R9021 Q_RES_0402LF-1K,1%,1/16W,EMPTY,CS21002FB06
     1 P12V_AUX @T6G_MB_LIB.T6G(SCH_1):P12V_AUX    I97 @T6G_MB_LIB.T6G(SCH_1):PAGE372
     2 U206_VS @T6G_MB_LIB.T6G(SCH_1):U206_VS    I97 @T6G_MB_LIB.T6G(SCH_1):PAGE372

R9022 Q_RES_0402LF-33.2,1%,1/16W,CHIP,CS03322FB03
     1 OCP_V3_1_P3V3_R3_PWRGD @T6G_MB_LIB.T6G(SCH_1):OCP_V3_1_P3V3_R3_PWRGD    I13 @T6G_MB_LIB.T6G(SCH_1):PAGE340
     2 HP_LVC3_OCP_V3_1_PWRGD @T6G_MB_LIB.T6G(SCH_1):HP_LVC3_OCP_V3_1_PWRGD    I13 @T6G_MB_LIB.T6G(SCH_1):PAGE340

R9023 Q_RES_0402LF-33.2,1%,1/16W,CHIP,CS03322FB03
     1 RST_PERST_OCP_SFF_N @T6G_MB_LIB.T6G(SCH_1):RST_PERST_OCP_SFF_N    I14 @T6G_MB_LIB.T6G(SCH_1):PAGE340
     2 RST_PERST_OCP_SFF_R_N @T6G_MB_LIB.T6G(SCH_1):RST_PERST_OCP_SFF_R_N    I14 @T6G_MB_LIB.T6G(SCH_1):PAGE340

R9024 Q_RES_0402LF-54.9K,1%,1/16W,CHIP,CS35492FB03
     1 P3V3_AUX @T6G_MB_LIB.T6G(SCH_1):P3V3_AUX   I113 @T6G_MB_LIB.T6G(SCH_1):PAGE371
     2 IRQ_HSC_FAULT_N @T6G_MB_LIB.T6G(SCH_1):IRQ_HSC_FAULT_N   I113 @T6G_MB_LIB.T6G(SCH_1):PAGE371

R9025 Q_RES_0402LF-100K,1%,1/16W,EMPTY,CS41002FB09
     1 IRQ_HSC_FAULT_N @T6G_MB_LIB.T6G(SCH_1):IRQ_HSC_FAULT_N   I106 @T6G_MB_LIB.T6G(SCH_1):PAGE84
     2    GND @T6G_MB_LIB.T6G(SCH_1):GND   I106 @T6G_MB_LIB.T6G(SCH_1):PAGE84

R9026 Q_RES_0402LF-4.7K,5%,1/16W,CHIP,CS24702JB10
     1 P3V3_AUX @T6G_MB_LIB.T6G(SCH_1):P3V3_AUX   I112 @T6G_MB_LIB.T6G(SCH_1):PAGE84
     2 IRQ_HSC_FAULT @T6G_MB_LIB.T6G(SCH_1):IRQ_HSC_FAULT   I112 @T6G_MB_LIB.T6G(SCH_1):PAGE84

R9027 Q_RES_0402LF-100K,1%,1/16W,CHIP,CS41002FB09
     1 P3V3_AUX @T6G_MB_LIB.T6G(SCH_1):P3V3_AUX   I114 @T6G_MB_LIB.T6G(SCH_1):PAGE84
     2 IRQ_HSC_FAULT_BUF_N @T6G_MB_LIB.T6G(SCH_1):IRQ_HSC_FAULT_BUF_N   I114 @T6G_MB_LIB.T6G(SCH_1):PAGE84

R9028 Q_RES_0402LF-0,5%,1/16W,EMPTY,CS00002JB13
     1 IRQ_HSC_FAULT_N @T6G_MB_LIB.T6G(SCH_1):IRQ_HSC_FAULT_N   I118 @T6G_MB_LIB.T6G(SCH_1):PAGE84
     2 IRQ_HSC_FAULT_BUF_N @T6G_MB_LIB.T6G(SCH_1):IRQ_HSC_FAULT_BUF_N   I118 @T6G_MB_LIB.T6G(SCH_1):PAGE84

R9029 Q_RES_0402LF-0,5%,1/16W,EMPTY,CS00002JB13
     1 OCP_SFF_AUX_PWR_EN_R3 @T6G_MB_LIB.T6G(SCH_1):OCP_SFF_AUX_PWR_EN_R3    I18 @T6G_MB_LIB.T6G(SCH_1):PAGE340
     2 HP_LVC3_OCP_V3_1_PWRGD_R1 @T6G_MB_LIB.T6G(SCH_1):HP_LVC3_OCP_V3_1_PWRGD_R1    I18 @T6G_MB_LIB.T6G(SCH_1):PAGE340

R9030 Q_RES_0402LF-0,5%,1/16W,EMPTY,CS00002JB13
     1 OCP_SFF_AUX_PWR_EN_R3 @T6G_MB_LIB.T6G(SCH_1):OCP_SFF_AUX_PWR_EN_R3    I15 @T6G_MB_LIB.T6G(SCH_1):PAGE340
     2 FM_PLD_OCP_SFF_AUX_PWR_EN @T6G_MB_LIB.T6G(SCH_1):FM_PLD_OCP_SFF_AUX_PWR_EN    I15 @T6G_MB_LIB.T6G(SCH_1):PAGE340

R9031 Q_RES_0402LF-33.2,1%,1/16W,CHIP,CS03322FB03
     1 OCP_SFF_AUX_PWR_EN_R3 @T6G_MB_LIB.T6G(SCH_1):OCP_SFF_AUX_PWR_EN_R3    I22 @T6G_MB_LIB.T6G(SCH_1):PAGE340
     2 OCP_SFF_AUX_PWR_EN @T6G_MB_LIB.T6G(SCH_1):OCP_SFF_AUX_PWR_EN    I22 @T6G_MB_LIB.T6G(SCH_1):PAGE340

R9032 Q_RES_0402LF-10K,1%,1/16W,CHIP,CS31002FB08
     1 P3V3_AUX @T6G_MB_LIB.T6G(SCH_1):P3V3_AUX     I2 @T6G_MB_LIB.T6G(SCH_1):PAGE340
     2 FM_PLD_OCP_SFF_AUX_PWR_EN @T6G_MB_LIB.T6G(SCH_1):FM_PLD_OCP_SFF_AUX_PWR_EN     I2 @T6G_MB_LIB.T6G(SCH_1):PAGE340

R9033 Q_RES_0402LF-33.2,1%,1/16W,CHIP,CS03322FB03
     1 RST_PERST_OCP_SFF_BUF_R_N @T6G_MB_LIB.T6G(SCH_1):RST_PERST_OCP_SFF_BUF_R_N    I29 @T6G_MB_LIB.T6G(SCH_1):PAGE340
     2 RST_PERST_OCP_SFF_BUF_N @T6G_MB_LIB.T6G(SCH_1):RST_PERST_OCP_SFF_BUF_N    I29 @T6G_MB_LIB.T6G(SCH_1):PAGE340

R9034 Q_RES_0402LF-33.2,1%,1/16W,CHIP,CS03322FB03
     1 OCP_V3_1_P3V3_R3_PWRGD @T6G_MB_LIB.T6G(SCH_1):OCP_V3_1_P3V3_R3_PWRGD     I3 @T6G_MB_LIB.T6G(SCH_1):PAGE340
     2 HP_LVC3_OCP_V3_1_PWRGD_R1 @T6G_MB_LIB.T6G(SCH_1):HP_LVC3_OCP_V3_1_PWRGD_R1     I3 @T6G_MB_LIB.T6G(SCH_1):PAGE340

R9043 Q_RES_0402LF-4.7K,5%,1/16W,CHIP,CS24702JB10
     1 P3V3_AUX @T6G_MB_LIB.T6G(SCH_1):P3V3_AUX   I192 @T6G_MB_LIB.T6G(SCH_1):PAGE299
     2 GPU_WP_HW_CTRL_ISO @T6G_MB_LIB.T6G(SCH_1):GPU_WP_HW_CTRL_ISO   I192 @T6G_MB_LIB.T6G(SCH_1):PAGE299

R9044 Q_RES_0402LF-4.7K,1%,1/16W,EMPTY,CS24702FB06
     1 P3V3_AUX @T6G_MB_LIB.T6G(SCH_1):P3V3_AUX   I195 @T6G_MB_LIB.T6G(SCH_1):PAGE299
     2 GPU_WP_HW_CTRL_ISO_N @T6G_MB_LIB.T6G(SCH_1):GPU_WP_HW_CTRL_ISO_N   I195 @T6G_MB_LIB.T6G(SCH_1):PAGE299

R9273 Q_RES_0402LF-0,5%,1/16W,CHIP,CS00002JB13
     1 CLK_100M_CPU0_CLK04_R_DP @T6G_MB_LIB.T6G(SCH_1):CLK_100M_CPU0_CLK04_R_DP   I153 @T6G_MB_LIB.T6G(SCH_1):PAGE28
     2 CLK_100M_CPU0_CLK04_DP @T6G_MB_LIB.T6G(SCH_1):CLK_100M_CPU0_CLK04_DP   I153 @T6G_MB_LIB.T6G(SCH_1):PAGE28

R9274 Q_RES_0402LF-0,5%,1/16W,CHIP,CS00002JB13
     1 CLK_100M_CPU0_CLK04_R_DN @T6G_MB_LIB.T6G(SCH_1):CLK_100M_CPU0_CLK04_R_DN   I154 @T6G_MB_LIB.T6G(SCH_1):PAGE28
     2 CLK_100M_CPU0_CLK04_DN @T6G_MB_LIB.T6G(SCH_1):CLK_100M_CPU0_CLK04_DN   I154 @T6G_MB_LIB.T6G(SCH_1):PAGE28

R9275 Q_RES_0402LF-0,5%,1/16W,CHIP,CS00002JB13
     1 CLK_100M_CPU0_CLK05_R_DP @T6G_MB_LIB.T6G(SCH_1):CLK_100M_CPU0_CLK05_R_DP   I167 @T6G_MB_LIB.T6G(SCH_1):PAGE28
     2 CLK_100M_CPU0_CLK05_DP @T6G_MB_LIB.T6G(SCH_1):CLK_100M_CPU0_CLK05_DP   I167 @T6G_MB_LIB.T6G(SCH_1):PAGE28

R9276 Q_RES_0402LF-0,5%,1/16W,CHIP,CS00002JB13
     1 CLK_100M_CPU0_CLK05_R_DN @T6G_MB_LIB.T6G(SCH_1):CLK_100M_CPU0_CLK05_R_DN   I168 @T6G_MB_LIB.T6G(SCH_1):PAGE28
     2 CLK_100M_CPU0_CLK05_DN @T6G_MB_LIB.T6G(SCH_1):CLK_100M_CPU0_CLK05_DN   I168 @T6G_MB_LIB.T6G(SCH_1):PAGE28

R9446 Q_RES_0402LF-33.2,1%,1/16W,CHIP,CS03322FB03
     1 PWRGD_PS_PWROK_PLD_ISO @T6G_MB_LIB.T6G(SCH_1):PWRGD_PS_PWROK_PLD_ISO    I13 @T6G_MB_LIB.T6G(SCH_1):PAGE368
     2 PWRGD_PS_PWROK_PLD_ISO_R @T6G_MB_LIB.T6G(SCH_1):PWRGD_PS_PWROK_PLD_ISO_R    I13 @T6G_MB_LIB.T6G(SCH_1):PAGE368

R10287 Q_RES_0402LF-10K,1%,1/16W,CHIP,CS31002FB08
     1 P3V3_E1S_0 @T6G_MB_LIB.T6G(SCH_1):P3V3_E1S_0    I79 @T6G_MB_LIB.T6G(SCH_1):PAGE297
     2 E1S_0_PERST1_CLKREQ_N @T6G_MB_LIB.T6G(SCH_1):E1S_0_PERST1_CLKREQ_N    I79 @T6G_MB_LIB.T6G(SCH_1):PAGE297

R10296 Q_RES_0402LF-1K,1%,1/16W,CHIP,CS21002FB06
     1 E1S_0_PWRDIS @T6G_MB_LIB.T6G(SCH_1):E1S_0_PWRDIS     I6 @T6G_MB_LIB.T6G(SCH_1):PAGE297
     2    GND @T6G_MB_LIB.T6G(SCH_1):GND     I6 @T6G_MB_LIB.T6G(SCH_1):PAGE297

R11667 Q_RES_0402LF-33.2,1%,1/16W,CHIP,CS03322FB03
     1 FM_SMB_2_ALERT_GPU_ISO_R_N @T6G_MB_LIB.T6G(SCH_1):FM_SMB_2_ALERT_GPU_ISO_R_N   I274 @T6G_MB_LIB.T6G(SCH_1):PAGE80
     2 FM_SMB_2_ALERT_GPU_ISO_N @T6G_MB_LIB.T6G(SCH_1):FM_SMB_2_ALERT_GPU_ISO_N   I274 @T6G_MB_LIB.T6G(SCH_1):PAGE80

 SW1 SW20S_DHNF10FQTR-SW20S_DHNF-10F-Q-T/R,SMLF,MECH,DHA
     1    GND @T6G_MB_LIB.T6G(SCH_1):GND    I90 @T6G_MB_LIB.T6G(SCH_1):PAGE144
     2 FM_FORCE_ALL_PWRON_ON @T6G_MB_LIB.T6G(SCH_1):FM_FORCE_ALL_PWRON_ON    I90 @T6G_MB_LIB.T6G(SCH_1):PAGE144
     3    GND @T6G_MB_LIB.T6G(SCH_1):GND    I90 @T6G_MB_LIB.T6G(SCH_1):PAGE144
     4 PU_BIOS_USB_RECOVERY @T6G_MB_LIB.T6G(SCH_1):PU_BIOS_USB_RECOVERY    I90 @T6G_MB_LIB.T6G(SCH_1):PAGE144
    11 FM_SPD_CPU0_SWITCH_CTRL_N @T6G_MB_LIB.T6G(SCH_1):FM_SPD_CPU0_SWITCH_CTRL_N    I90 @T6G_MB_LIB.T6G(SCH_1):PAGE144
    12 FM_FORCE_ALL_PWRON @T6G_MB_LIB.T6G(SCH_1):FM_FORCE_ALL_PWRON    I90 @T6G_MB_LIB.T6G(SCH_1):PAGE144
    13 BMC_JTAG_SEL @T6G_MB_LIB.T6G(SCH_1):BMC_JTAG_SEL    I90 @T6G_MB_LIB.T6G(SCH_1):PAGE144
    14 FM_BIOS_USB_RECOVERY @T6G_MB_LIB.T6G(SCH_1):FM_BIOS_USB_RECOVERY    I90 @T6G_MB_LIB.T6G(SCH_1):PAGE144
     5 PU_FPGA_DEBUG_SW_SPARE @T6G_MB_LIB.T6G(SCH_1):PU_FPGA_DEBUG_SW_SPARE    I90 @T6G_MB_LIB.T6G(SCH_1):PAGE144
     6 PD_BIOS_DEBUG_MODE @T6G_MB_LIB.T6G(SCH_1):PD_BIOS_DEBUG_MODE    I90 @T6G_MB_LIB.T6G(SCH_1):PAGE144
     7 PRSNT_CPU0_N @T6G_MB_LIB.T6G(SCH_1):PRSNT_CPU0_N    I90 @T6G_MB_LIB.T6G(SCH_1):PAGE144
     8 PRSNT_CPU1_N @T6G_MB_LIB.T6G(SCH_1):PRSNT_CPU1_N    I90 @T6G_MB_LIB.T6G(SCH_1):PAGE144
    15 FPGA_DEBUG_SW_SPARE @T6G_MB_LIB.T6G(SCH_1):FPGA_DEBUG_SW_SPARE    I90 @T6G_MB_LIB.T6G(SCH_1):PAGE144
    16 BIOS_DEBUG_MODE @T6G_MB_LIB.T6G(SCH_1):BIOS_DEBUG_MODE    I90 @T6G_MB_LIB.T6G(SCH_1):PAGE144
    17 FM_PRSNT_CPU0_N @T6G_MB_LIB.T6G(SCH_1):FM_PRSNT_CPU0_N    I90 @T6G_MB_LIB.T6G(SCH_1):PAGE144
    18 FM_PRSNT_CPU1_N @T6G_MB_LIB.T6G(SCH_1):FM_PRSNT_CPU1_N    I90 @T6G_MB_LIB.T6G(SCH_1):PAGE144
    19 FM_PASSWORD_CLEAR_N @T6G_MB_LIB.T6G(SCH_1):FM_PASSWORD_CLEAR_N    I90 @T6G_MB_LIB.T6G(SCH_1):PAGE144
    20 FPGA_DEBUG_LED_CTRL @T6G_MB_LIB.T6G(SCH_1):FPGA_DEBUG_LED_CTRL    I90 @T6G_MB_LIB.T6G(SCH_1):PAGE144
     9    GND @T6G_MB_LIB.T6G(SCH_1):GND    I90 @T6G_MB_LIB.T6G(SCH_1):PAGE144
    10 PU_FPGA_DEBUG_LED_CTRL @T6G_MB_LIB.T6G(SCH_1):PU_FPGA_DEBUG_LED_CTRL    I90 @T6G_MB_LIB.T6G(SCH_1):PAGE144

 TP1 TP_TP-NA,TP26
     1 VSENSE_VSS_SENSE_A_P0 @T6G_MB_LIB.T6G(SCH_1):VSENSE_VSS_SENSE_A_P0   I404 @T6G_MB_LIB.T6G(SCH_1):PAGE27

 TP2 TP_TP-NA,TP30
     1 VSENSE_VSS_SENSE_B_P0 @T6G_MB_LIB.T6G(SCH_1):VSENSE_VSS_SENSE_B_P0   I362 @T6G_MB_LIB.T6G(SCH_1):PAGE27

 TP3 TP_TP-NA,TP30
     1 VSENSE_VSS_SENSE_C_P0 @T6G_MB_LIB.T6G(SCH_1):VSENSE_VSS_SENSE_C_P0   I361 @T6G_MB_LIB.T6G(SCH_1):PAGE27

 TP4 TP_TP-NA,TP30
     1 VSENSE_PVDD18_S5_P0_DN @T6G_MB_LIB.T6G(SCH_1):VSENSE_PVDD18_S5_P0_DN   I360 @T6G_MB_LIB.T6G(SCH_1):PAGE27

 TP5 TP_TP-NA,TP30
     1 VSENSE_PVDDIO_P0_DP @T6G_MB_LIB.T6G(SCH_1):VSENSE_PVDDIO_P0_DP   I359 @T6G_MB_LIB.T6G(SCH_1):PAGE27

 TP6 TP_TP-NA,TP30
     1 VSENSE_PVDDCR_CPU1_P0_DP @T6G_MB_LIB.T6G(SCH_1):VSENSE_PVDDCR_CPU1_P0_DP   I358 @T6G_MB_LIB.T6G(SCH_1):PAGE27

 TP7 TP_TP-NA,TP30
     1 VSENSE_PVDDCR_CPU0_P0_DP @T6G_MB_LIB.T6G(SCH_1):VSENSE_PVDDCR_CPU0_P0_DP   I357 @T6G_MB_LIB.T6G(SCH_1):PAGE27

 TP8 TP_TP-NA,TP30
     1 VSENSE_PVDD11_S3_P0_DP @T6G_MB_LIB.T6G(SCH_1):VSENSE_PVDD11_S3_P0_DP   I356 @T6G_MB_LIB.T6G(SCH_1):PAGE27

 TP9 TP_TP-NA,TP30
     1 VSENSE_PVDD18_S5_P0_DP @T6G_MB_LIB.T6G(SCH_1):VSENSE_PVDD18_S5_P0_DP   I355 @T6G_MB_LIB.T6G(SCH_1):PAGE27

TP10 TP_TP-NA,TP26
     1 VSENSE_PVDDCR_SOC_P0_DP @T6G_MB_LIB.T6G(SCH_1):VSENSE_PVDDCR_SOC_P0_DP   I403 @T6G_MB_LIB.T6G(SCH_1):PAGE27

TP11 TP_TP-NA,TP30
     1 VSENSE_VSS_SENSE_A_P1 @T6G_MB_LIB.T6G(SCH_1):VSENSE_VSS_SENSE_A_P1   I273 @T6G_MB_LIB.T6G(SCH_1):PAGE54

TP12 TP_TP-NA,TP30
     1 VSENSE_VSS_SENSE_B_P1 @T6G_MB_LIB.T6G(SCH_1):VSENSE_VSS_SENSE_B_P1   I272 @T6G_MB_LIB.T6G(SCH_1):PAGE54

TP13 TP_TP-NA,TP30
     1 VSENSE_VSS_SENSE_C_P1 @T6G_MB_LIB.T6G(SCH_1):VSENSE_VSS_SENSE_C_P1   I245 @T6G_MB_LIB.T6G(SCH_1):PAGE54

TP14 TP_TP-NA,TP30
     1 VSENSE_PVDD18_S5_P1_DN @T6G_MB_LIB.T6G(SCH_1):VSENSE_PVDD18_S5_P1_DN   I244 @T6G_MB_LIB.T6G(SCH_1):PAGE54

TP15 TP_TP-NA,TP30
     1 VSENSE_PVDDIO_P1_DP @T6G_MB_LIB.T6G(SCH_1):VSENSE_PVDDIO_P1_DP   I243 @T6G_MB_LIB.T6G(SCH_1):PAGE54

TP16 TP_TP-NA,TP30
     1 VSENSE_PVDDCR_CPU1_P1_DP @T6G_MB_LIB.T6G(SCH_1):VSENSE_PVDDCR_CPU1_P1_DP   I242 @T6G_MB_LIB.T6G(SCH_1):PAGE54

TP17 TP_TP-NA,TP30
     1 VSENSE_PVDDCR_CPU0_P1_DP @T6G_MB_LIB.T6G(SCH_1):VSENSE_PVDDCR_CPU0_P1_DP   I241 @T6G_MB_LIB.T6G(SCH_1):PAGE54

TP18 TP_TP-NA,TP30
     1 VSENSE_PVDD11_S3_P1_DP @T6G_MB_LIB.T6G(SCH_1):VSENSE_PVDD11_S3_P1_DP   I240 @T6G_MB_LIB.T6G(SCH_1):PAGE54

TP19 TP_TP-NA,TP30
     1 VSENSE_PVDD18_S5_P1_DP @T6G_MB_LIB.T6G(SCH_1):VSENSE_PVDD18_S5_P1_DP   I238 @T6G_MB_LIB.T6G(SCH_1):PAGE54

TP20 TP_TP-NA,TP30
     1 VSENSE_PVDDCR_SOC_P1_DP @T6G_MB_LIB.T6G(SCH_1):VSENSE_PVDDCR_SOC_P1_DP   I237 @T6G_MB_LIB.T6G(SCH_1):PAGE54

  U1 M24128BWMN6TP-M24128-BWMN6TP,SMLF,IC,AKE30Z00613
     8 P3V3_AUX @T6G_MB_LIB.T6G(SCH_1):P3V3_AUX    I97 @T6G_MB_LIB.T6G(SCH_1):PAGE361
     7 PD_CPU_FRU_WP @T6G_MB_LIB.T6G(SCH_1):PD_CPU_FRU_WP    I97 @T6G_MB_LIB.T6G(SCH_1):PAGE361
     6 SMB_CPU_FRU_3V3AUX_SCL @T6G_MB_LIB.T6G(SCH_1):SMB_CPU_FRU_3V3AUX_SCL    I97 @T6G_MB_LIB.T6G(SCH_1):PAGE361
     5 SMB_CPU_FRU_3V3AUX_SDA @T6G_MB_LIB.T6G(SCH_1):SMB_CPU_FRU_3V3AUX_SDA    I97 @T6G_MB_LIB.T6G(SCH_1):PAGE361
     4    GND @T6G_MB_LIB.T6G(SCH_1):GND    I97 @T6G_MB_LIB.T6G(SCH_1):PAGE361
     3 CPU_FRU_ADDR2 @T6G_MB_LIB.T6G(SCH_1):CPU_FRU_ADDR2    I97 @T6G_MB_LIB.T6G(SCH_1):PAGE361
     2 CPU_FRU_ADDR1 @T6G_MB_LIB.T6G(SCH_1):CPU_FRU_ADDR1    I97 @T6G_MB_LIB.T6G(SCH_1):PAGE361
     1 CPU_FRU_ADDR0 @T6G_MB_LIB.T6G(SCH_1):CPU_FRU_ADDR0    I97 @T6G_MB_LIB.T6G(SCH_1):PAGE361

  U2 PCA9617ADP-PCA9617ADP,SMLF,IC,AL009617K02
     5 PU_U2_EN @T6G_MB_LIB.T6G(SCH_1):PU_U2_EN    I99 @T6G_MB_LIB.T6G(SCH_1):PAGE137
     1 PVDD11_S3_P0 @T6G_MB_LIB.T6G(SCH_1):PVDD11_S3_P0    I99 @T6G_MB_LIB.T6G(SCH_1):PAGE137
     8 P3V3_AUX @T6G_MB_LIB.T6G(SCH_1):P3V3_AUX    I99 @T6G_MB_LIB.T6G(SCH_1):PAGE137
     2 SMB_CPU0_CPU1_APML_BUF2_SCL_R1 @T6G_MB_LIB.T6G(SCH_1):SMB_CPU0_CPU1_APML_BUF2_SCL_R1    I99 @T6G_MB_LIB.T6G(SCH_1):PAGE137
     3 SMB_CPU0_CPU1_APML_BUF2_SDA_R1 @T6G_MB_LIB.T6G(SCH_1):SMB_CPU0_CPU1_APML_BUF2_SDA_R1    I99 @T6G_MB_LIB.T6G(SCH_1):PAGE137
     6 SMB_CPU0_CPU1_APML_BUF2_SDA @T6G_MB_LIB.T6G(SCH_1):SMB_CPU0_CPU1_APML_BUF2_SDA    I99 @T6G_MB_LIB.T6G(SCH_1):PAGE137
     7 SMB_CPU0_CPU1_APML_BUF2_SCL @T6G_MB_LIB.T6G(SCH_1):SMB_CPU0_CPU1_APML_BUF2_SCL    I99 @T6G_MB_LIB.T6G(SCH_1):PAGE137
     4    GND @T6G_MB_LIB.T6G(SCH_1):GND    I99 @T6G_MB_LIB.T6G(SCH_1):PAGE137

  U3 SN74LVC1G07DBVR_SMLF-SN74LVC1G07DBVR,IC,AL1G0007024
     2 SCM_USB_OC_N @T6G_MB_LIB.T6G(SCH_1):SCM_USB_OC_N   I373 @T6G_MB_LIB.T6G(SCH_1):PAGE29
     4 SCM_USB_OC_BU_R_N @T6G_MB_LIB.T6G(SCH_1):SCM_USB_OC_BU_R_N   I373 @T6G_MB_LIB.T6G(SCH_1):PAGE29
     1     NC     NC   I373 @T6G_MB_LIB.T6G(SCH_1):PAGE29
     5 P1V8_AUX @T6G_MB_LIB.T6G(SCH_1):P1V8_AUX   I373 @T6G_MB_LIB.T6G(SCH_1):PAGE29
     3    GND @T6G_MB_LIB.T6G(SCH_1):GND   I373 @T6G_MB_LIB.T6G(SCH_1):PAGE29

  U4 PI3CSW12ZUAEX-PI3CSW12ZUAEX,SMLF,IC,AL3CSW12000
     1 SMB_APML_CPU0_MUX2_SCL @T6G_MB_LIB.T6G(SCH_1):SMB_APML_CPU0_MUX2_SCL   I114 @T6G_MB_LIB.T6G(SCH_1):PAGE138
     3 SMB_APML_CPU1_MUX2_SCL @T6G_MB_LIB.T6G(SCH_1):SMB_APML_CPU1_MUX2_SCL   I114 @T6G_MB_LIB.T6G(SCH_1):PAGE138
     4 SMB_APML_CPU1_MUX2_SDA @T6G_MB_LIB.T6G(SCH_1):SMB_APML_CPU1_MUX2_SDA   I114 @T6G_MB_LIB.T6G(SCH_1):PAGE138
     7 SMB_CPU0_CPU1_APML_MUX2_SDA @T6G_MB_LIB.T6G(SCH_1):SMB_CPU0_CPU1_APML_MUX2_SDA   I114 @T6G_MB_LIB.T6G(SCH_1):PAGE138
     6 FM_APML_MUX2_OE_N @T6G_MB_LIB.T6G(SCH_1):FM_APML_MUX2_OE_N   I114 @T6G_MB_LIB.T6G(SCH_1):PAGE138
     9 FM_APML_MUX2_SEL @T6G_MB_LIB.T6G(SCH_1):FM_APML_MUX2_SEL   I114 @T6G_MB_LIB.T6G(SCH_1):PAGE138
    10 P3V3_AUX @T6G_MB_LIB.T6G(SCH_1):P3V3_AUX   I114 @T6G_MB_LIB.T6G(SCH_1):PAGE138
     2 SMB_APML_CPU0_MUX2_SDA @T6G_MB_LIB.T6G(SCH_1):SMB_APML_CPU0_MUX2_SDA   I114 @T6G_MB_LIB.T6G(SCH_1):PAGE138
     5    GND @T6G_MB_LIB.T6G(SCH_1):GND   I114 @T6G_MB_LIB.T6G(SCH_1):PAGE138
     8 SMB_CPU0_CPU1_APML_MUX2_SCL @T6G_MB_LIB.T6G(SCH_1):SMB_CPU0_CPU1_APML_MUX2_SCL   I114 @T6G_MB_LIB.T6G(SCH_1):PAGE138

  U5 PCA9617ADP-PCA9617ADP,SMLF,EMPTY,AL009617K02
     5 PU_U5_EN @T6G_MB_LIB.T6G(SCH_1):PU_U5_EN    I48 @T6G_MB_LIB.T6G(SCH_1):PAGE137
     1 P3V3_AUX @T6G_MB_LIB.T6G(SCH_1):P3V3_AUX    I48 @T6G_MB_LIB.T6G(SCH_1):PAGE137
     8   P3V3 @T6G_MB_LIB.T6G(SCH_1):P3V3    I48 @T6G_MB_LIB.T6G(SCH_1):PAGE137
     2 SMB_CPU0_CPU1_APML_BUF1_SCL @T6G_MB_LIB.T6G(SCH_1):SMB_CPU0_CPU1_APML_BUF1_SCL    I48 @T6G_MB_LIB.T6G(SCH_1):PAGE137
     3 SMB_CPU0_CPU1_APML_BUF1_SDA @T6G_MB_LIB.T6G(SCH_1):SMB_CPU0_CPU1_APML_BUF1_SDA    I48 @T6G_MB_LIB.T6G(SCH_1):PAGE137
     6 SMB_CPU0_CPU1_APML_BUF1_SDA_R1 @T6G_MB_LIB.T6G(SCH_1):SMB_CPU0_CPU1_APML_BUF1_SDA_R1    I48 @T6G_MB_LIB.T6G(SCH_1):PAGE137
     7 SMB_CPU0_CPU1_APML_BUF1_SCL_R1 @T6G_MB_LIB.T6G(SCH_1):SMB_CPU0_CPU1_APML_BUF1_SCL_R1    I48 @T6G_MB_LIB.T6G(SCH_1):PAGE137
     4    GND @T6G_MB_LIB.T6G(SCH_1):GND    I48 @T6G_MB_LIB.T6G(SCH_1):PAGE137

  U6 PI3CSW12ZUAEX-PI3CSW12ZUAEX,SMLF,IC,AL3CSW12000
     1 SMB_CPU0_SEC_R_SCL @T6G_MB_LIB.T6G(SCH_1):SMB_CPU0_SEC_R_SCL    I67 @T6G_MB_LIB.T6G(SCH_1):PAGE138
     3 SMB_CPU1_SEC_R_SCL @T6G_MB_LIB.T6G(SCH_1):SMB_CPU1_SEC_R_SCL    I67 @T6G_MB_LIB.T6G(SCH_1):PAGE138
     4 SMB_CPU1_SEC_R_SDA @T6G_MB_LIB.T6G(SCH_1):SMB_CPU1_SEC_R_SDA    I67 @T6G_MB_LIB.T6G(SCH_1):PAGE138
     7 SMB_CPU0_CPU1_SEC_SDA_R2 @T6G_MB_LIB.T6G(SCH_1):SMB_CPU0_CPU1_SEC_SDA_R2    I67 @T6G_MB_LIB.T6G(SCH_1):PAGE138
     6 FM_SEC_MUX_OE_N @T6G_MB_LIB.T6G(SCH_1):FM_SEC_MUX_OE_N    I67 @T6G_MB_LIB.T6G(SCH_1):PAGE138
     9 FM_SEC_MUX_SEL @T6G_MB_LIB.T6G(SCH_1):FM_SEC_MUX_SEL    I67 @T6G_MB_LIB.T6G(SCH_1):PAGE138
    10 P3V3_AUX @T6G_MB_LIB.T6G(SCH_1):P3V3_AUX    I67 @T6G_MB_LIB.T6G(SCH_1):PAGE138
     2 SMB_CPU0_SEC_R_SDA @T6G_MB_LIB.T6G(SCH_1):SMB_CPU0_SEC_R_SDA    I67 @T6G_MB_LIB.T6G(SCH_1):PAGE138
     5    GND @T6G_MB_LIB.T6G(SCH_1):GND    I67 @T6G_MB_LIB.T6G(SCH_1):PAGE138
     8 SMB_CPU0_CPU1_SEC_SCL_R2 @T6G_MB_LIB.T6G(SCH_1):SMB_CPU0_CPU1_SEC_SCL_R2    I67 @T6G_MB_LIB.T6G(SCH_1):PAGE138

  U7 74CBTLV3126PW-74CBTLV3126PW,SMLF,IC,AL003126K08
     5 NCSI_BMC_TXD0_R @T6G_MB_LIB.T6G(SCH_1):NCSI_BMC_TXD0_R     I2 @T6G_MB_LIB.T6G(SCH_1):PAGE336
     8 NCSI_OCP_SFF_TX_EN @T6G_MB_LIB.T6G(SCH_1):NCSI_OCP_SFF_TX_EN     I2 @T6G_MB_LIB.T6G(SCH_1):PAGE336
     1 FB_BMC_ISOLATE @T6G_MB_LIB.T6G(SCH_1):FB_BMC_ISOLATE     I2 @T6G_MB_LIB.T6G(SCH_1):PAGE336
     4 FB_BMC_ISOLATE @T6G_MB_LIB.T6G(SCH_1):FB_BMC_ISOLATE     I2 @T6G_MB_LIB.T6G(SCH_1):PAGE336
     3 NCSI_OCP_SFF_TXD1 @T6G_MB_LIB.T6G(SCH_1):NCSI_OCP_SFF_TXD1     I2 @T6G_MB_LIB.T6G(SCH_1):PAGE336
     6 NCSI_OCP_SFF_TXD0 @T6G_MB_LIB.T6G(SCH_1):NCSI_OCP_SFF_TXD0     I2 @T6G_MB_LIB.T6G(SCH_1):PAGE336
     2 NCSI_BMC_TXD1_R @T6G_MB_LIB.T6G(SCH_1):NCSI_BMC_TXD1_R     I2 @T6G_MB_LIB.T6G(SCH_1):PAGE336
     7    GND @T6G_MB_LIB.T6G(SCH_1):GND     I2 @T6G_MB_LIB.T6G(SCH_1):PAGE336
     9 NCSI_BMC_TX_EN_R @T6G_MB_LIB.T6G(SCH_1):NCSI_BMC_TX_EN_R     I2 @T6G_MB_LIB.T6G(SCH_1):PAGE336
    10 FB_BMC_ISOLATE @T6G_MB_LIB.T6G(SCH_1):FB_BMC_ISOLATE     I2 @T6G_MB_LIB.T6G(SCH_1):PAGE336
    11 OCP_SFF_ISO2_RBT_ARB_OUT @T6G_MB_LIB.T6G(SCH_1):OCP_SFF_ISO2_RBT_ARB_OUT     I2 @T6G_MB_LIB.T6G(SCH_1):PAGE336
    12 OCP_SFF_RBT_ARB_OUT @T6G_MB_LIB.T6G(SCH_1):OCP_SFF_RBT_ARB_OUT     I2 @T6G_MB_LIB.T6G(SCH_1):PAGE336
    13 FB_BMC_ISOLATE @T6G_MB_LIB.T6G(SCH_1):FB_BMC_ISOLATE     I2 @T6G_MB_LIB.T6G(SCH_1):PAGE336
    14 P3V3_AUX @T6G_MB_LIB.T6G(SCH_1):P3V3_AUX     I2 @T6G_MB_LIB.T6G(SCH_1):PAGE336

  U8 74LVC2G07DW7-74LVC2G07DW-7,SMLF,IC,AL002G07003
     1 OCP_SFF_PRSNT2_R_N @T6G_MB_LIB.T6G(SCH_1):OCP_SFF_PRSNT2_R_N    I26 @T6G_MB_LIB.T6G(SCH_1):PAGE338
     3 OCP_SFF_PRSNT3_R_N @T6G_MB_LIB.T6G(SCH_1):OCP_SFF_PRSNT3_R_N    I26 @T6G_MB_LIB.T6G(SCH_1):PAGE338
     6 HP_LVC3_OCP_V3_1_PRSNT2_N_R @T6G_MB_LIB.T6G(SCH_1):HP_LVC3_OCP_V3_1_PRSNT2_N_R    I26 @T6G_MB_LIB.T6G(SCH_1):PAGE338
     4 HP_LVC3_OCP_V3_1_PRSNT2_N_R @T6G_MB_LIB.T6G(SCH_1):HP_LVC3_OCP_V3_1_PRSNT2_N_R    I26 @T6G_MB_LIB.T6G(SCH_1):PAGE338
     2    GND @T6G_MB_LIB.T6G(SCH_1):GND    I26 @T6G_MB_LIB.T6G(SCH_1):PAGE338
     5 P3V3_AUX @T6G_MB_LIB.T6G(SCH_1):P3V3_AUX    I26 @T6G_MB_LIB.T6G(SCH_1):PAGE338

  U9 TPS71715DCKR-TPS71715DCKR,SMLF,EMPTY,AL071715001
     2    GND @T6G_MB_LIB.T6G(SCH_1):GND    I91 @T6G_MB_LIB.T6G(SCH_1):PAGE156
     3 BAT_LDO_EN @T6G_MB_LIB.T6G(SCH_1):BAT_LDO_EN    I91 @T6G_MB_LIB.T6G(SCH_1):PAGE156
     1 P1V5_BAT_IN @T6G_MB_LIB.T6G(SCH_1):P1V5_BAT_IN    I91 @T6G_MB_LIB.T6G(SCH_1):PAGE156
     4  U9_NR @T6G_MB_LIB.T6G(SCH_1):U9_NR    I91 @T6G_MB_LIB.T6G(SCH_1):PAGE156
     5 P1V5_BAT_OUT @T6G_MB_LIB.T6G(SCH_1):P1V5_BAT_OUT    I91 @T6G_MB_LIB.T6G(SCH_1):PAGE156

 U10 9ZXL0451EKILFT-9ZXL0451EKILFT,SMLF,IC,AL000451003
     3 CLK_100M_CPU1_CLK13_DP @T6G_MB_LIB.T6G(SCH_1):CLK_100M_CPU1_CLK13_DP    I63 @T6G_MB_LIB.T6G(SCH_1):PAGE379
     4 CLK_100M_CPU1_CLK13_DN @T6G_MB_LIB.T6G(SCH_1):CLK_100M_CPU1_CLK13_DN    I63 @T6G_MB_LIB.T6G(SCH_1):PAGE379
     2 P3V3_9ZXL045_P1_VDDR @T6G_MB_LIB.T6G(SCH_1):P3V3_9ZXL045_P1_VDDR    I63 @T6G_MB_LIB.T6G(SCH_1):PAGE379
    25 P3V3_9ZXL045_P1_VDD @T6G_MB_LIB.T6G(SCH_1):P3V3_9ZXL045_P1_VDD    I63 @T6G_MB_LIB.T6G(SCH_1):PAGE379
    29 P3V3_9ZXL045_P1_VDD @T6G_MB_LIB.T6G(SCH_1):P3V3_9ZXL045_P1_VDD    I63 @T6G_MB_LIB.T6G(SCH_1):PAGE379
     9 NC_U10_FBOUT @T6G_MB_LIB.T6G(SCH_1):NC_U10_FBOUT    I63 @T6G_MB_LIB.T6G(SCH_1):PAGE379
    15 FM_9ZXL045_P1_0_OE_N @T6G_MB_LIB.T6G(SCH_1):FM_9ZXL045_P1_0_OE_N    I63 @T6G_MB_LIB.T6G(SCH_1):PAGE379
    26 FM_9ZXL045_P1_3_OE_N @T6G_MB_LIB.T6G(SCH_1):FM_9ZXL045_P1_3_OE_N    I63 @T6G_MB_LIB.T6G(SCH_1):PAGE379
     6 SMB_9ZXL045_P1_SDA @T6G_MB_LIB.T6G(SCH_1):SMB_9ZXL045_P1_SDA    I63 @T6G_MB_LIB.T6G(SCH_1):PAGE379
    11 NC_U10_NC1 @T6G_MB_LIB.T6G(SCH_1):NC_U10_NC1    I63 @T6G_MB_LIB.T6G(SCH_1):PAGE379
     8 NC_U10_FBOUT_N @T6G_MB_LIB.T6G(SCH_1):NC_U10_FBOUT_N    I63 @T6G_MB_LIB.T6G(SCH_1):PAGE379
     7 SMB_9ZXL045_P1_SCL @T6G_MB_LIB.T6G(SCH_1):SMB_9ZXL045_P1_SCL    I63 @T6G_MB_LIB.T6G(SCH_1):PAGE379
    21 P3V3_9ZXL045_P1_VDD @T6G_MB_LIB.T6G(SCH_1):P3V3_9ZXL045_P1_VDD    I63 @T6G_MB_LIB.T6G(SCH_1):PAGE379
     1 FM_9ZXL045_P1_DEV_EN @T6G_MB_LIB.T6G(SCH_1):FM_9ZXL045_P1_DEV_EN    I63 @T6G_MB_LIB.T6G(SCH_1):PAGE379
    14 CLK_100M_RETIMER_CPU1_P0_R_DN @T6G_MB_LIB.T6G(SCH_1):CLK_100M_RETIMER_CPU1_P0_R_DN    I63 @T6G_MB_LIB.T6G(SCH_1):PAGE379
    13 CLK_100M_RETIMER_CPU1_P0_R_DP @T6G_MB_LIB.T6G(SCH_1):CLK_100M_RETIMER_CPU1_P0_R_DP    I63 @T6G_MB_LIB.T6G(SCH_1):PAGE379
    18 FM_9ZXL045_P1_1_OE_N @T6G_MB_LIB.T6G(SCH_1):FM_9ZXL045_P1_1_OE_N    I63 @T6G_MB_LIB.T6G(SCH_1):PAGE379
    20 CLK_100M_RETIMER_CPU1_P1_R_DN @T6G_MB_LIB.T6G(SCH_1):CLK_100M_RETIMER_CPU1_P1_R_DN    I63 @T6G_MB_LIB.T6G(SCH_1):PAGE379
    22 CLK_100M_RETIMER_CPU1_P2_R_DP @T6G_MB_LIB.T6G(SCH_1):CLK_100M_RETIMER_CPU1_P2_R_DP    I63 @T6G_MB_LIB.T6G(SCH_1):PAGE379
    24 FM_9ZXL045_P1_2_OE_N @T6G_MB_LIB.T6G(SCH_1):FM_9ZXL045_P1_2_OE_N    I63 @T6G_MB_LIB.T6G(SCH_1):PAGE379
    23 CLK_100M_RETIMER_CPU1_P2_R_DN @T6G_MB_LIB.T6G(SCH_1):CLK_100M_RETIMER_CPU1_P2_R_DN    I63 @T6G_MB_LIB.T6G(SCH_1):PAGE379
    28 CLK_100M_RETIMER_CPU1_P3_R_DN @T6G_MB_LIB.T6G(SCH_1):CLK_100M_RETIMER_CPU1_P3_R_DN    I63 @T6G_MB_LIB.T6G(SCH_1):PAGE379
    10 NC_U10_NC0 @T6G_MB_LIB.T6G(SCH_1):NC_U10_NC0    I63 @T6G_MB_LIB.T6G(SCH_1):PAGE379
    31 P3V3_9ZXL045_P1_VDDA @T6G_MB_LIB.T6G(SCH_1):P3V3_9ZXL045_P1_VDDA    I63 @T6G_MB_LIB.T6G(SCH_1):PAGE379
    16 P3V3_9ZXL045_P1_VDD @T6G_MB_LIB.T6G(SCH_1):P3V3_9ZXL045_P1_VDD    I63 @T6G_MB_LIB.T6G(SCH_1):PAGE379
    32 CLK_9ZXL045_P1_HIBW @T6G_MB_LIB.T6G(SCH_1):CLK_9ZXL045_P1_HIBW    I63 @T6G_MB_LIB.T6G(SCH_1):PAGE379
    33    GND @T6G_MB_LIB.T6G(SCH_1):GND    I63 @T6G_MB_LIB.T6G(SCH_1):PAGE379
    19 CLK_100M_RETIMER_CPU1_P1_R_DP @T6G_MB_LIB.T6G(SCH_1):CLK_100M_RETIMER_CPU1_P1_R_DP    I63 @T6G_MB_LIB.T6G(SCH_1):PAGE379
    27 CLK_100M_RETIMER_CPU1_P3_R_DP @T6G_MB_LIB.T6G(SCH_1):CLK_100M_RETIMER_CPU1_P3_R_DP    I63 @T6G_MB_LIB.T6G(SCH_1):PAGE379
    12 P3V3_9ZXL045_P1_VDD @T6G_MB_LIB.T6G(SCH_1):P3V3_9ZXL045_P1_VDD    I63 @T6G_MB_LIB.T6G(SCH_1):PAGE379
    30 NC_U10_NC3 @T6G_MB_LIB.T6G(SCH_1):NC_U10_NC3    I63 @T6G_MB_LIB.T6G(SCH_1):PAGE379
    17 NC_U10_NC2 @T6G_MB_LIB.T6G(SCH_1):NC_U10_NC2    I63 @T6G_MB_LIB.T6G(SCH_1):PAGE379
     5 CLK_9ZXL045_P1_SADR0 @T6G_MB_LIB.T6G(SCH_1):CLK_9ZXL045_P1_SADR0    I63 @T6G_MB_LIB.T6G(SCH_1):PAGE379

 U11 M24M02DRMN6TP-M24M02-DRMN6TP,SMLF,IC,AKE33Z00600
     8 P1V8_CPU0_RT_1D @T6G_MB_LIB.T6G(SCH_1):P1V8_CPU0_RT_1D     I3 @T6G_MB_LIB.T6G(SCH_1):PAGE387
     7    GND @T6G_MB_LIB.T6G(SCH_1):GND     I3 @T6G_MB_LIB.T6G(SCH_1):PAGE387
     6 SMB_RT_CPU0_P0_ROM_SCL @T6G_MB_LIB.T6G(SCH_1):SMB_RT_CPU0_P0_ROM_SCL     I3 @T6G_MB_LIB.T6G(SCH_1):PAGE387
     5 SMB_RT_CPU0_P0_ROM_SDA @T6G_MB_LIB.T6G(SCH_1):SMB_RT_CPU0_P0_ROM_SDA     I3 @T6G_MB_LIB.T6G(SCH_1):PAGE387
     4    GND @T6G_MB_LIB.T6G(SCH_1):GND     I3 @T6G_MB_LIB.T6G(SCH_1):PAGE387
     3 U11_E2 @T6G_MB_LIB.T6G(SCH_1):U11_E2     I3 @T6G_MB_LIB.T6G(SCH_1):PAGE387
     2     NC     NC     I3 @T6G_MB_LIB.T6G(SCH_1):PAGE387
     1     NC     NC     I3 @T6G_MB_LIB.T6G(SCH_1):PAGE387

 U12 M24M02DRMN6TP-M24M02-DRMN6TP,SMLF,IC,AKE33Z00600
     8 P1V8_CPU1_RT_1D @T6G_MB_LIB.T6G(SCH_1):P1V8_CPU1_RT_1D     I5 @T6G_MB_LIB.T6G(SCH_1):PAGE399
     7    GND @T6G_MB_LIB.T6G(SCH_1):GND     I5 @T6G_MB_LIB.T6G(SCH_1):PAGE399
     6 SMB_RT_CPU1_P0_ROM_SCL @T6G_MB_LIB.T6G(SCH_1):SMB_RT_CPU1_P0_ROM_SCL     I5 @T6G_MB_LIB.T6G(SCH_1):PAGE399
     5 SMB_RT_CPU1_P0_ROM_SDA @T6G_MB_LIB.T6G(SCH_1):SMB_RT_CPU1_P0_ROM_SDA     I5 @T6G_MB_LIB.T6G(SCH_1):PAGE399
     4    GND @T6G_MB_LIB.T6G(SCH_1):GND     I5 @T6G_MB_LIB.T6G(SCH_1):PAGE399
     3 U12_E2 @T6G_MB_LIB.T6G(SCH_1):U12_E2     I5 @T6G_MB_LIB.T6G(SCH_1):PAGE399
     2     NC     NC     I5 @T6G_MB_LIB.T6G(SCH_1):PAGE399
     1     NC     NC     I5 @T6G_MB_LIB.T6G(SCH_1):PAGE399

 U13 SN74AUC2G66DCTR-SN74AUC2G66DCTR,SMLF,IC,AL2G0066C00
     1 JTAG_CPU0_TDO @T6G_MB_LIB.T6G(SCH_1):JTAG_CPU0_TDO    I17 @T6G_MB_LIB.T6G(SCH_1):PAGE151
     7 CPU0_HDT_BYPASS_SEL @T6G_MB_LIB.T6G(SCH_1):CPU0_HDT_BYPASS_SEL    I17 @T6G_MB_LIB.T6G(SCH_1):PAGE151
     5 JTAG_CPU0_BYPASS_R1 @T6G_MB_LIB.T6G(SCH_1):JTAG_CPU0_BYPASS_R1    I17 @T6G_MB_LIB.T6G(SCH_1):PAGE151
     3 FM_PLD_CPU0_PRSNT_HDT_N @T6G_MB_LIB.T6G(SCH_1):FM_PLD_CPU0_PRSNT_HDT_N    I17 @T6G_MB_LIB.T6G(SCH_1):PAGE151
     8 PVDD18_S5_P0 @T6G_MB_LIB.T6G(SCH_1):PVDD18_S5_P0    I17 @T6G_MB_LIB.T6G(SCH_1):PAGE151
     4    GND @T6G_MB_LIB.T6G(SCH_1):GND    I17 @T6G_MB_LIB.T6G(SCH_1):PAGE151
     2 JTAG_CPU0_TDO_CPU1_TDI @T6G_MB_LIB.T6G(SCH_1):JTAG_CPU0_TDO_CPU1_TDI    I17 @T6G_MB_LIB.T6G(SCH_1):PAGE151
     6 JTAG_CPU0_TDO_CPU1_TDI_R1 @T6G_MB_LIB.T6G(SCH_1):JTAG_CPU0_TDO_CPU1_TDI_R1    I17 @T6G_MB_LIB.T6G(SCH_1):PAGE151

 U14 SN74AUC2G66DCTR-SN74AUC2G66DCTR,SMLF,IC,AL2G0066C00
     1 JTAG_CPU0_TDO_CPU1_TDI @T6G_MB_LIB.T6G(SCH_1):JTAG_CPU0_TDO_CPU1_TDI    I23 @T6G_MB_LIB.T6G(SCH_1):PAGE151
     7 CPU1_HDT_BYPASS_SEL @T6G_MB_LIB.T6G(SCH_1):CPU1_HDT_BYPASS_SEL    I23 @T6G_MB_LIB.T6G(SCH_1):PAGE151
     5 JTAG_CPU0_TDO_CPU1_TDI @T6G_MB_LIB.T6G(SCH_1):JTAG_CPU0_TDO_CPU1_TDI    I23 @T6G_MB_LIB.T6G(SCH_1):PAGE151
     3 FM_PLD_CPU1_PRSNT_HDT_N @T6G_MB_LIB.T6G(SCH_1):FM_PLD_CPU1_PRSNT_HDT_N    I23 @T6G_MB_LIB.T6G(SCH_1):PAGE151
     8 PVDD18_S5_P0 @T6G_MB_LIB.T6G(SCH_1):PVDD18_S5_P0    I23 @T6G_MB_LIB.T6G(SCH_1):PAGE151
     4    GND @T6G_MB_LIB.T6G(SCH_1):GND    I23 @T6G_MB_LIB.T6G(SCH_1):PAGE151
     2 JTAG_CPU1_R_TDI @T6G_MB_LIB.T6G(SCH_1):JTAG_CPU1_R_TDI    I23 @T6G_MB_LIB.T6G(SCH_1):PAGE151
     6 JTAG_CPU1_BYPASS @T6G_MB_LIB.T6G(SCH_1):JTAG_CPU1_BYPASS    I23 @T6G_MB_LIB.T6G(SCH_1):PAGE151

 U15 M24M02DRMN6TP-M24M02-DRMN6TP,SMLF,IC,AKE33Z00600
     8 P1V8_CPU0_RT_1D @T6G_MB_LIB.T6G(SCH_1):P1V8_CPU0_RT_1D     I5 @T6G_MB_LIB.T6G(SCH_1):PAGE410
     7    GND @T6G_MB_LIB.T6G(SCH_1):GND     I5 @T6G_MB_LIB.T6G(SCH_1):PAGE410
     6 SMB_RT_CPU0_P1_ROM_SCL @T6G_MB_LIB.T6G(SCH_1):SMB_RT_CPU0_P1_ROM_SCL     I5 @T6G_MB_LIB.T6G(SCH_1):PAGE410
     5 SMB_RT_CPU0_P1_ROM_SDA @T6G_MB_LIB.T6G(SCH_1):SMB_RT_CPU0_P1_ROM_SDA     I5 @T6G_MB_LIB.T6G(SCH_1):PAGE410
     4    GND @T6G_MB_LIB.T6G(SCH_1):GND     I5 @T6G_MB_LIB.T6G(SCH_1):PAGE410
     3 U15_E2 @T6G_MB_LIB.T6G(SCH_1):U15_E2     I5 @T6G_MB_LIB.T6G(SCH_1):PAGE410
     2     NC     NC     I5 @T6G_MB_LIB.T6G(SCH_1):PAGE410
     1     NC     NC     I5 @T6G_MB_LIB.T6G(SCH_1):PAGE410

 U16 M24M02DRMN6TP-M24M02-DRMN6TP,SMLF,IC,AKE33Z00600
     8 P1V8_CPU0_RT_1D @T6G_MB_LIB.T6G(SCH_1):P1V8_CPU0_RT_1D     I5 @T6G_MB_LIB.T6G(SCH_1):PAGE421
     7    GND @T6G_MB_LIB.T6G(SCH_1):GND     I5 @T6G_MB_LIB.T6G(SCH_1):PAGE421
     6 SMB_RT_CPU0_P2_ROM_SCL @T6G_MB_LIB.T6G(SCH_1):SMB_RT_CPU0_P2_ROM_SCL     I5 @T6G_MB_LIB.T6G(SCH_1):PAGE421
     5 SMB_RT_CPU0_P2_ROM_SDA @T6G_MB_LIB.T6G(SCH_1):SMB_RT_CPU0_P2_ROM_SDA     I5 @T6G_MB_LIB.T6G(SCH_1):PAGE421
     4    GND @T6G_MB_LIB.T6G(SCH_1):GND     I5 @T6G_MB_LIB.T6G(SCH_1):PAGE421
     3 U16_E2 @T6G_MB_LIB.T6G(SCH_1):U16_E2     I5 @T6G_MB_LIB.T6G(SCH_1):PAGE421
     2     NC     NC     I5 @T6G_MB_LIB.T6G(SCH_1):PAGE421
     1     NC     NC     I5 @T6G_MB_LIB.T6G(SCH_1):PAGE421

 U17 M24M02DRMN6TP-M24M02-DRMN6TP,SMLF,IC,AKE33Z00600
     8 P1V8_CPU0_RT_1D @T6G_MB_LIB.T6G(SCH_1):P1V8_CPU0_RT_1D     I5 @T6G_MB_LIB.T6G(SCH_1):PAGE432
     7    GND @T6G_MB_LIB.T6G(SCH_1):GND     I5 @T6G_MB_LIB.T6G(SCH_1):PAGE432
     6 SMB_RT_CPU0_P3_ROM_SCL @T6G_MB_LIB.T6G(SCH_1):SMB_RT_CPU0_P3_ROM_SCL     I5 @T6G_MB_LIB.T6G(SCH_1):PAGE432
     5 SMB_RT_CPU0_P3_ROM_SDA @T6G_MB_LIB.T6G(SCH_1):SMB_RT_CPU0_P3_ROM_SDA     I5 @T6G_MB_LIB.T6G(SCH_1):PAGE432
     4    GND @T6G_MB_LIB.T6G(SCH_1):GND     I5 @T6G_MB_LIB.T6G(SCH_1):PAGE432
     3 U17_E2 @T6G_MB_LIB.T6G(SCH_1):U17_E2     I5 @T6G_MB_LIB.T6G(SCH_1):PAGE432
     2     NC     NC     I5 @T6G_MB_LIB.T6G(SCH_1):PAGE432
     1     NC     NC     I5 @T6G_MB_LIB.T6G(SCH_1):PAGE432

 U18 LCMXO3LF9400C5BG484C-LCMXO3LF-9400C-5BG484C,SMLF,IA
    D3 FM_CPU1_XTRIG_L4 @T6G_MB_LIB.T6G(SCH_1):FM_CPU1_XTRIG_L4   I143 @T6G_MB_LIB.T6G(SCH_1):PAGE81
    D4 FM_CPU1_XTRIG_L5 @T6G_MB_LIB.T6G(SCH_1):FM_CPU1_XTRIG_L5   I143 @T6G_MB_LIB.T6G(SCH_1):PAGE81
    F6 FM_CPU1_XTRIG_L6 @T6G_MB_LIB.T6G(SCH_1):FM_CPU1_XTRIG_L6   I143 @T6G_MB_LIB.T6G(SCH_1):PAGE81
    G7 FM_CPU1_SA1 @T6G_MB_LIB.T6G(SCH_1):FM_CPU1_SA1   I143 @T6G_MB_LIB.T6G(SCH_1):PAGE81
    E4 FM_CPU0_XTRIG_L6 @T6G_MB_LIB.T6G(SCH_1):FM_CPU0_XTRIG_L6   I143 @T6G_MB_LIB.T6G(SCH_1):PAGE81
    F5 IRQ_BMC_SMI_R_N @T6G_MB_LIB.T6G(SCH_1):IRQ_BMC_SMI_R_N   I143 @T6G_MB_LIB.T6G(SCH_1):PAGE81
    G6 FM_CPU1_XTRIG_L7 @T6G_MB_LIB.T6G(SCH_1):FM_CPU1_XTRIG_L7   I143 @T6G_MB_LIB.T6G(SCH_1):PAGE81
    H7 IRQ_CPU_BMC_NMI_R_N @T6G_MB_LIB.T6G(SCH_1):IRQ_CPU_BMC_NMI_R_N   I143 @T6G_MB_LIB.T6G(SCH_1):PAGE81
    C1 FM_CPU0_XTRIG_L5 @T6G_MB_LIB.T6G(SCH_1):FM_CPU0_XTRIG_L5   I143 @T6G_MB_LIB.T6G(SCH_1):PAGE81
    D2 FM_CPU0_XTRIG_L4 @T6G_MB_LIB.T6G(SCH_1):FM_CPU0_XTRIG_L4   I143 @T6G_MB_LIB.T6G(SCH_1):PAGE81
    G5 IRQ_SMI_ACTIVE_N_R @T6G_MB_LIB.T6G(SCH_1):IRQ_SMI_ACTIVE_N_R   I143 @T6G_MB_LIB.T6G(SCH_1):PAGE81
    H6 IRQ_TPM_SPI_R1_N @T6G_MB_LIB.T6G(SCH_1):IRQ_TPM_SPI_R1_N   I143 @T6G_MB_LIB.T6G(SCH_1):PAGE81
    D1 FM_SMM_CRASHDUMP_R @T6G_MB_LIB.T6G(SCH_1):FM_SMM_CRASHDUMP_R   I143 @T6G_MB_LIB.T6G(SCH_1):PAGE81
    E2 FM_CPU1_BMC_RST_R_N @T6G_MB_LIB.T6G(SCH_1):FM_CPU1_BMC_RST_R_N   I143 @T6G_MB_LIB.T6G(SCH_1):PAGE81
    E3 FM_CPU0_XTRIG_L7 @T6G_MB_LIB.T6G(SCH_1):FM_CPU0_XTRIG_L7   I143 @T6G_MB_LIB.T6G(SCH_1):PAGE81
    F4 FM_BMC_READY_R_N @T6G_MB_LIB.T6G(SCH_1):FM_BMC_READY_R_N   I143 @T6G_MB_LIB.T6G(SCH_1):PAGE81
    L7 PVDD11_S3_P0_PMALERT @T6G_MB_LIB.T6G(SCH_1):PVDD11_S3_P0_PMALERT   I143 @T6G_MB_LIB.T6G(SCH_1):PAGE81
    K5 P12V_SCM_ADC_ALERT @T6G_MB_LIB.T6G(SCH_1):P12V_SCM_ADC_ALERT   I143 @T6G_MB_LIB.T6G(SCH_1):PAGE81
    K4 P12V_HSC_T_CRIT_R_N @T6G_MB_LIB.T6G(SCH_1):P12V_HSC_T_CRIT_R_N   I143 @T6G_MB_LIB.T6G(SCH_1):PAGE81
    K3 E1S_0_P3V3_P12V_ADC_ALERT @T6G_MB_LIB.T6G(SCH_1):E1S_0_P3V3_P12V_ADC_ALERT   I143 @T6G_MB_LIB.T6G(SCH_1):PAGE81
    K2 FM_SEC_MUX_OE_R_N @T6G_MB_LIB.T6G(SCH_1):FM_SEC_MUX_OE_R_N   I143 @T6G_MB_LIB.T6G(SCH_1):PAGE81
    K1 FM_SEC_MUX_R_SEL @T6G_MB_LIB.T6G(SCH_1):FM_SEC_MUX_R_SEL   I143 @T6G_MB_LIB.T6G(SCH_1):PAGE81
    L1 LED_HDD_ACTIVITY_B_PLD_N @T6G_MB_LIB.T6G(SCH_1):LED_HDD_ACTIVITY_B_PLD_N   I143 @T6G_MB_LIB.T6G(SCH_1):PAGE81
    M2 FM_SCM_PRSNT1_N @T6G_MB_LIB.T6G(SCH_1):FM_SCM_PRSNT1_N   I143 @T6G_MB_LIB.T6G(SCH_1):PAGE81
    P4 FM_CPU1_CORETYPE0 @T6G_MB_LIB.T6G(SCH_1):FM_CPU1_CORETYPE0   I143 @T6G_MB_LIB.T6G(SCH_1):PAGE81
    N5 FM_CPU0_SP5R1 @T6G_MB_LIB.T6G(SCH_1):FM_CPU0_SP5R1   I143 @T6G_MB_LIB.T6G(SCH_1):PAGE81
    N6 FM_CPU0_SP5R2 @T6G_MB_LIB.T6G(SCH_1):FM_CPU0_SP5R2   I143 @T6G_MB_LIB.T6G(SCH_1):PAGE81
    N7 P12V_HSC_TEMP_ALERT_R_N @T6G_MB_LIB.T6G(SCH_1):P12V_HSC_TEMP_ALERT_R_N   I143 @T6G_MB_LIB.T6G(SCH_1):PAGE81
    R2 FM_CPU0_CORETYPE1 @T6G_MB_LIB.T6G(SCH_1):FM_CPU0_CORETYPE1   I143 @T6G_MB_LIB.T6G(SCH_1):PAGE81
    T1 FM_CPU1_CORETYPE1 @T6G_MB_LIB.T6G(SCH_1):FM_CPU1_CORETYPE1   I143 @T6G_MB_LIB.T6G(SCH_1):PAGE81
    P5 FM_APML_MUX2_SEL_R @T6G_MB_LIB.T6G(SCH_1):FM_APML_MUX2_SEL_R   I143 @T6G_MB_LIB.T6G(SCH_1):PAGE81
    P6 FM_APML_MUX2_OE_R_N @T6G_MB_LIB.T6G(SCH_1):FM_APML_MUX2_OE_R_N   I143 @T6G_MB_LIB.T6G(SCH_1):PAGE81
    T5 FM_PDB_BUF_EN_N @T6G_MB_LIB.T6G(SCH_1):FM_PDB_BUF_EN_N   I143 @T6G_MB_LIB.T6G(SCH_1):PAGE81
    T6 PWRGD_CHGL_CPU1_R2 @T6G_MB_LIB.T6G(SCH_1):PWRGD_CHGL_CPU1_R2   I143 @T6G_MB_LIB.T6G(SCH_1):PAGE81
    L6 PVDDCR_CPU1_P1_SMB_ALERT @T6G_MB_LIB.T6G(SCH_1):PVDDCR_CPU1_P1_SMB_ALERT   I143 @T6G_MB_LIB.T6G(SCH_1):PAGE81
    L5 PVDDCR_CPU1_P0_SMB_ALERT @T6G_MB_LIB.T6G(SCH_1):PVDDCR_CPU1_P0_SMB_ALERT   I143 @T6G_MB_LIB.T6G(SCH_1):PAGE81
    L3 FM_THERMAL_ALERT_R_N @T6G_MB_LIB.T6G(SCH_1):FM_THERMAL_ALERT_R_N   I143 @T6G_MB_LIB.T6G(SCH_1):PAGE81
    L4 SMB_BMC_GPU_EN @T6G_MB_LIB.T6G(SCH_1):SMB_BMC_GPU_EN   I143 @T6G_MB_LIB.T6G(SCH_1):PAGE81
    G3 FM_PVDDCR_CPU1_P0_OCP_N @T6G_MB_LIB.T6G(SCH_1):FM_PVDDCR_CPU1_P0_OCP_N   I143 @T6G_MB_LIB.T6G(SCH_1):PAGE81
    G4 FM_PVDDCR_CPU1_P1_OCP_N @T6G_MB_LIB.T6G(SCH_1):FM_PVDDCR_CPU1_P1_OCP_N   I143 @T6G_MB_LIB.T6G(SCH_1):PAGE81
    E1 FM_BMC_TPM_PRES_N_R @T6G_MB_LIB.T6G(SCH_1):FM_BMC_TPM_PRES_N_R   I143 @T6G_MB_LIB.T6G(SCH_1):PAGE81
    F1 FM_PVDDCR_CPU0_P0_OCP_N @T6G_MB_LIB.T6G(SCH_1):FM_PVDDCR_CPU0_P0_OCP_N   I143 @T6G_MB_LIB.T6G(SCH_1):PAGE81
    T2 FM_CPU1_CORETYPE2 @T6G_MB_LIB.T6G(SCH_1):FM_CPU1_CORETYPE2   I143 @T6G_MB_LIB.T6G(SCH_1):PAGE81
    U1 FM_CPU0_SP5R3 @T6G_MB_LIB.T6G(SCH_1):FM_CPU0_SP5R3   I143 @T6G_MB_LIB.T6G(SCH_1):PAGE81
    R3 FM_CPU1_SP5R1 @T6G_MB_LIB.T6G(SCH_1):FM_CPU1_SP5R1   I143 @T6G_MB_LIB.T6G(SCH_1):PAGE81
    R4 FM_CPU1_SP5R2 @T6G_MB_LIB.T6G(SCH_1):FM_CPU1_SP5R2   I143 @T6G_MB_LIB.T6G(SCH_1):PAGE81
    R5 FM_LED_PWRGD_PVDDCR_CPU1_P0 @T6G_MB_LIB.T6G(SCH_1):FM_LED_PWRGD_PVDDCR_CPU1_P0   I143 @T6G_MB_LIB.T6G(SCH_1):PAGE81
    P7 FM_PVDDCR_CPU1_P0_R_EN @T6G_MB_LIB.T6G(SCH_1):FM_PVDDCR_CPU1_P0_R_EN   I143 @T6G_MB_LIB.T6G(SCH_1):PAGE81
    R6 PWRGD_CHAF_CPU1_R2 @T6G_MB_LIB.T6G(SCH_1):PWRGD_CHAF_CPU1_R2   I143 @T6G_MB_LIB.T6G(SCH_1):PAGE81
    R7 FM_PWRGD_PVDDCR_CPU1_P0 @T6G_MB_LIB.T6G(SCH_1):FM_PWRGD_PVDDCR_CPU1_P0   I143 @T6G_MB_LIB.T6G(SCH_1):PAGE81
    T3 FM_CPU1_SP5R3 @T6G_MB_LIB.T6G(SCH_1):FM_CPU1_SP5R3   I143 @T6G_MB_LIB.T6G(SCH_1):PAGE81
    T4 FM_CPU1_SP5R4 @T6G_MB_LIB.T6G(SCH_1):FM_CPU1_SP5R4   I143 @T6G_MB_LIB.T6G(SCH_1):PAGE81
    M1 M2_0_P3V3_ADC_ALERT @T6G_MB_LIB.T6G(SCH_1):M2_0_P3V3_ADC_ALERT   I143 @T6G_MB_LIB.T6G(SCH_1):PAGE81
    N1 PVDD11_S3_P1_PMALERT @T6G_MB_LIB.T6G(SCH_1):PVDD11_S3_P1_PMALERT   I143 @T6G_MB_LIB.T6G(SCH_1):PAGE81
    M6 FM_PLD_OCP_SFF_AUX_PWR_R_EN @T6G_MB_LIB.T6G(SCH_1):FM_PLD_OCP_SFF_AUX_PWR_R_EN   I143 @T6G_MB_LIB.T6G(SCH_1):PAGE81
    M5 PVDDCR_CPU0_P1_PMALERT @T6G_MB_LIB.T6G(SCH_1):PVDDCR_CPU0_P1_PMALERT   I143 @T6G_MB_LIB.T6G(SCH_1):PAGE81
    N2 FM_CLKREQ_M2_1_N @T6G_MB_LIB.T6G(SCH_1):FM_CLKREQ_M2_1_N   I143 @T6G_MB_LIB.T6G(SCH_1):PAGE81
    P1 OCP_V3_2_P3V3_P12V_ADC_ALERT @T6G_MB_LIB.T6G(SCH_1):OCP_V3_2_P3V3_P12V_ADC_ALERT   I143 @T6G_MB_LIB.T6G(SCH_1):PAGE81
    N3 FM_CLR_CMOS @T6G_MB_LIB.T6G(SCH_1):FM_CLR_CMOS   I143 @T6G_MB_LIB.T6G(SCH_1):PAGE81
    N4 PWRGD_OCP_SFF_PWR_GOOD @T6G_MB_LIB.T6G(SCH_1):PWRGD_OCP_SFF_PWR_GOOD   I143 @T6G_MB_LIB.T6G(SCH_1):PAGE81
    P2 FM_SMB_RST_E1S_0_N @T6G_MB_LIB.T6G(SCH_1):FM_SMB_RST_E1S_0_N   I143 @T6G_MB_LIB.T6G(SCH_1):PAGE81
    R1 FM_CPU0_CORETYPE0 @T6G_MB_LIB.T6G(SCH_1):FM_CPU0_CORETYPE0   I143 @T6G_MB_LIB.T6G(SCH_1):PAGE81
    P3 FM_CPU0_CORETYPE2 @T6G_MB_LIB.T6G(SCH_1):FM_CPU0_CORETYPE2   I143 @T6G_MB_LIB.T6G(SCH_1):PAGE81
    M7 FM_PLD_OCP_SFF_MAIN_PWR_EN_R @T6G_MB_LIB.T6G(SCH_1):FM_PLD_OCP_SFF_MAIN_PWR_EN_R   I143 @T6G_MB_LIB.T6G(SCH_1):PAGE81
    U2 FM_CPU0_SP5R4 @T6G_MB_LIB.T6G(SCH_1):FM_CPU0_SP5R4   I143 @T6G_MB_LIB.T6G(SCH_1):PAGE81
    V1 FM_PRSNT_CPU0_R_N @T6G_MB_LIB.T6G(SCH_1):FM_PRSNT_CPU0_R_N   I143 @T6G_MB_LIB.T6G(SCH_1):PAGE81
    U3 E1S_0_PRSNT_R_N @T6G_MB_LIB.T6G(SCH_1):E1S_0_PRSNT_R_N   I143 @T6G_MB_LIB.T6G(SCH_1):PAGE81
    U4 PWRGD_P5V_AUX_R3 @T6G_MB_LIB.T6G(SCH_1):PWRGD_P5V_AUX_R3   I143 @T6G_MB_LIB.T6G(SCH_1):PAGE81
    W1 PWRGD_CHAF_CPU0_R2 @T6G_MB_LIB.T6G(SCH_1):PWRGD_CHAF_CPU0_R2   I143 @T6G_MB_LIB.T6G(SCH_1):PAGE81
    W2 P12V_OCP_V3_1_PWRGD @T6G_MB_LIB.T6G(SCH_1):P12V_OCP_V3_1_PWRGD   I143 @T6G_MB_LIB.T6G(SCH_1):PAGE81
    V4 FM_LED_PWRGD_PVDDCR_SOC_P0 @T6G_MB_LIB.T6G(SCH_1):FM_LED_PWRGD_PVDDCR_SOC_P0   I143 @T6G_MB_LIB.T6G(SCH_1):PAGE81
    U5 FM_LED_PWRGD_PVDDCR_CPU0_P0 @T6G_MB_LIB.T6G(SCH_1):FM_LED_PWRGD_PVDDCR_CPU0_P0   I143 @T6G_MB_LIB.T6G(SCH_1):PAGE81
    Y1 PWRGD_CHGL_CPU0_R2 @T6G_MB_LIB.T6G(SCH_1):PWRGD_CHGL_CPU0_R2   I143 @T6G_MB_LIB.T6G(SCH_1):PAGE81
   AA1 OCP_SFF_P3V3_P12V_ADC_ALERT @T6G_MB_LIB.T6G(SCH_1):OCP_SFF_P3V3_P12V_ADC_ALERT   I143 @T6G_MB_LIB.T6G(SCH_1):PAGE81
    W3 PVDDCR_SOC_P0_EN @T6G_MB_LIB.T6G(SCH_1):PVDDCR_SOC_P0_EN   I143 @T6G_MB_LIB.T6G(SCH_1):PAGE81
    Y2 PWRGD_PVDDCR_SOC_P0 @T6G_MB_LIB.T6G(SCH_1):PWRGD_PVDDCR_SOC_P0   I143 @T6G_MB_LIB.T6G(SCH_1):PAGE81
    Y3 PWRGD_PVDDCR_CPU0_P0 @T6G_MB_LIB.T6G(SCH_1):PWRGD_PVDDCR_CPU0_P0   I143 @T6G_MB_LIB.T6G(SCH_1):PAGE81
    W4 FM_PVDD11_S3_P0_EN @T6G_MB_LIB.T6G(SCH_1):FM_PVDD11_S3_P0_EN   I143 @T6G_MB_LIB.T6G(SCH_1):PAGE81
    V5 FM_PRSNT_CPU1_R_N @T6G_MB_LIB.T6G(SCH_1):FM_PRSNT_CPU1_R_N   I143 @T6G_MB_LIB.T6G(SCH_1):PAGE81
    T7 FM_PVDDCR_CPU1_P1_R_EN @T6G_MB_LIB.T6G(SCH_1):FM_PVDDCR_CPU1_P1_R_EN   I143 @T6G_MB_LIB.T6G(SCH_1):PAGE81
    G2 FM_PVDDCR_CPU0_P1_OCP_N @T6G_MB_LIB.T6G(SCH_1):FM_PVDDCR_CPU0_P1_OCP_N   I143 @T6G_MB_LIB.T6G(SCH_1):PAGE81
    G1 FM_CPU1_PROCHOT_R_N @T6G_MB_LIB.T6G(SCH_1):FM_CPU1_PROCHOT_R_N   I143 @T6G_MB_LIB.T6G(SCH_1):PAGE81
    H4 FM_PVDD11_S3_P1_OCP_N @T6G_MB_LIB.T6G(SCH_1):FM_PVDD11_S3_P1_OCP_N   I143 @T6G_MB_LIB.T6G(SCH_1):PAGE81
    H3 FM_PVDD11_S3_P0_OCP_N @T6G_MB_LIB.T6G(SCH_1):FM_PVDD11_S3_P0_OCP_N   I143 @T6G_MB_LIB.T6G(SCH_1):PAGE81
    H2 CPU0_THERMTRIP_R_N @T6G_MB_LIB.T6G(SCH_1):CPU0_THERMTRIP_R_N   I143 @T6G_MB_LIB.T6G(SCH_1):PAGE81
    H1 RT_BOARD_ID_ID1 @T6G_MB_LIB.T6G(SCH_1):RT_BOARD_ID_ID1   I143 @T6G_MB_LIB.T6G(SCH_1):PAGE81
    J7 FM_CPU1_SA0 @T6G_MB_LIB.T6G(SCH_1):FM_CPU1_SA0   I143 @T6G_MB_LIB.T6G(SCH_1):PAGE81
    J6 FM_CPU0_PROCHOT_R_N @T6G_MB_LIB.T6G(SCH_1):FM_CPU0_PROCHOT_R_N   I143 @T6G_MB_LIB.T6G(SCH_1):PAGE81
    H5 FM_CPU0_SA0 @T6G_MB_LIB.T6G(SCH_1):FM_CPU0_SA0   I143 @T6G_MB_LIB.T6G(SCH_1):PAGE81
    J5 CPU1_THERMTRIP_R_N @T6G_MB_LIB.T6G(SCH_1):CPU1_THERMTRIP_R_N   I143 @T6G_MB_LIB.T6G(SCH_1):PAGE81
    J4 RT_BOARD_ID_ID0 @T6G_MB_LIB.T6G(SCH_1):RT_BOARD_ID_ID0   I143 @T6G_MB_LIB.T6G(SCH_1):PAGE81
    J3 FM_INT_CPU0_HP_UBM_R_N @T6G_MB_LIB.T6G(SCH_1):FM_INT_CPU0_HP_UBM_R_N   I143 @T6G_MB_LIB.T6G(SCH_1):PAGE81
    J2 FM_CPU0_SA1 @T6G_MB_LIB.T6G(SCH_1):FM_CPU0_SA1   I143 @T6G_MB_LIB.T6G(SCH_1):PAGE81
    J1 FAB_BMC_REV_ID0 @T6G_MB_LIB.T6G(SCH_1):FAB_BMC_REV_ID0   I143 @T6G_MB_LIB.T6G(SCH_1):PAGE81
    K7 FAB_BMC_REV_ID1 @T6G_MB_LIB.T6G(SCH_1):FAB_BMC_REV_ID1   I143 @T6G_MB_LIB.T6G(SCH_1):PAGE81
    K6 FAB_BMC_REV_ID2 @T6G_MB_LIB.T6G(SCH_1):FAB_BMC_REV_ID2   I143 @T6G_MB_LIB.T6G(SCH_1):PAGE81
   AA2 FM_SWB_PWR_EN @T6G_MB_LIB.T6G(SCH_1):FM_SWB_PWR_EN   I216 @T6G_MB_LIB.T6G(SCH_1):PAGE80
   AB2 GPU_NVS_PWR_BRAKE_R_N @T6G_MB_LIB.T6G(SCH_1):GPU_NVS_PWR_BRAKE_R_N   I216 @T6G_MB_LIB.T6G(SCH_1):PAGE80
    V6 FM_PVDDIO_P0_EN @T6G_MB_LIB.T6G(SCH_1):FM_PVDDIO_P0_EN   I216 @T6G_MB_LIB.T6G(SCH_1):PAGE80
    U6 FM_PWRGD_PVDDIO_P0 @T6G_MB_LIB.T6G(SCH_1):FM_PWRGD_PVDDIO_P0   I216 @T6G_MB_LIB.T6G(SCH_1):PAGE80
   AA3 PRSNT_OCP_SFF_N @T6G_MB_LIB.T6G(SCH_1):PRSNT_OCP_SFF_N   I216 @T6G_MB_LIB.T6G(SCH_1):PAGE80
   AB3 PVDDCR_CPU0_P0_PMALERT @T6G_MB_LIB.T6G(SCH_1):PVDDCR_CPU0_P0_PMALERT   I216 @T6G_MB_LIB.T6G(SCH_1):PAGE80
    Y4 FM_PWRGD_PVDD11_S3_P0 @T6G_MB_LIB.T6G(SCH_1):FM_PWRGD_PVDD11_S3_P0   I216 @T6G_MB_LIB.T6G(SCH_1):PAGE80
    W5 FM_PVDDCR_CPU0_P1_R_EN @T6G_MB_LIB.T6G(SCH_1):FM_PVDDCR_CPU0_P1_R_EN   I216 @T6G_MB_LIB.T6G(SCH_1):PAGE80
    U7 FM_UART_LS_EN @T6G_MB_LIB.T6G(SCH_1):FM_UART_LS_EN   I216 @T6G_MB_LIB.T6G(SCH_1):PAGE80
    T8 FM_PWRGD_PVDDCR_CPU1_P1 @T6G_MB_LIB.T6G(SCH_1):FM_PWRGD_PVDDCR_CPU1_P1   I216 @T6G_MB_LIB.T6G(SCH_1):PAGE80
   AA4 GPU_FPGA_EROT_RST_R_N @T6G_MB_LIB.T6G(SCH_1):GPU_FPGA_EROT_RST_R_N   I216 @T6G_MB_LIB.T6G(SCH_1):PAGE80
   AB4 PRSNT_SWB_ISO_R_N @T6G_MB_LIB.T6G(SCH_1):PRSNT_SWB_ISO_R_N   I216 @T6G_MB_LIB.T6G(SCH_1):PAGE80
   AA5 GPU_FPGA_EROT_RECOV_R_N @T6G_MB_LIB.T6G(SCH_1):GPU_FPGA_EROT_RECOV_R_N   I216 @T6G_MB_LIB.T6G(SCH_1):PAGE80
   AB5 BMC_MONITER @T6G_MB_LIB.T6G(SCH_1):BMC_MONITER   I216 @T6G_MB_LIB.T6G(SCH_1):PAGE80
    Y5 FM_PWRGD_PVDDCR_CPU0_P1 @T6G_MB_LIB.T6G(SCH_1):FM_PWRGD_PVDDCR_CPU0_P1   I216 @T6G_MB_LIB.T6G(SCH_1):PAGE80
    Y6 P12V_SCM_PWRGD_R @T6G_MB_LIB.T6G(SCH_1):P12V_SCM_PWRGD_R   I216 @T6G_MB_LIB.T6G(SCH_1):PAGE80
    V8 PVDD18_S5_P1_R_EN @T6G_MB_LIB.T6G(SCH_1):PVDD18_S5_P1_R_EN   I216 @T6G_MB_LIB.T6G(SCH_1):PAGE80
    U8 FM_FPGA_DEBUG_SW_SPARE @T6G_MB_LIB.T6G(SCH_1):FM_FPGA_DEBUG_SW_SPARE   I216 @T6G_MB_LIB.T6G(SCH_1):PAGE80
    T9 FM_PWRGD_P1V8_RETIMER_CPU0 @T6G_MB_LIB.T6G(SCH_1):FM_PWRGD_P1V8_RETIMER_CPU0   I216 @T6G_MB_LIB.T6G(SCH_1):PAGE80
    U9 FM_PWRGD_P1V8_RETIMER_CPU1 @T6G_MB_LIB.T6G(SCH_1):FM_PWRGD_P1V8_RETIMER_CPU1   I216 @T6G_MB_LIB.T6G(SCH_1):PAGE80
   AA8 FM_PVDD18_S5_P0_EN @T6G_MB_LIB.T6G(SCH_1):FM_PVDD18_S5_P0_EN   I216 @T6G_MB_LIB.T6G(SCH_1):PAGE80
   AB8 FM_PWRGD_PVDD18_S5_P0 @T6G_MB_LIB.T6G(SCH_1):FM_PWRGD_PVDD18_S5_P0   I216 @T6G_MB_LIB.T6G(SCH_1):PAGE80
   V10 FM_LED_PWRGD_PVDDCR_CPU0_P1 @T6G_MB_LIB.T6G(SCH_1):FM_LED_PWRGD_PVDDCR_CPU0_P1   I216 @T6G_MB_LIB.T6G(SCH_1):PAGE80
   W10 FM_PLD_OCP_SFF_PWR_GOOD_R @T6G_MB_LIB.T6G(SCH_1):FM_PLD_OCP_SFF_PWR_GOOD_R   I216 @T6G_MB_LIB.T6G(SCH_1):PAGE80
  AA10 P0V9_RETIMER_CPU0_EN_R2 @T6G_MB_LIB.T6G(SCH_1):P0V9_RETIMER_CPU0_EN_R2   I216 @T6G_MB_LIB.T6G(SCH_1):PAGE80
  AB10 BMC_FPGA_LED1 @T6G_MB_LIB.T6G(SCH_1):BMC_FPGA_LED1   I216 @T6G_MB_LIB.T6G(SCH_1):PAGE80
  AA11 P12V_E1S_0_EN @T6G_MB_LIB.T6G(SCH_1):P12V_E1S_0_EN   I216 @T6G_MB_LIB.T6G(SCH_1):PAGE80
  AB11 FM_LED_PWRGD_PVDD18_S5_P0 @T6G_MB_LIB.T6G(SCH_1):FM_LED_PWRGD_PVDD18_S5_P0   I216 @T6G_MB_LIB.T6G(SCH_1):PAGE80
   V11 RST_PERST_CPU1_SWB_1_N @T6G_MB_LIB.T6G(SCH_1):RST_PERST_CPU1_SWB_1_N   I216 @T6G_MB_LIB.T6G(SCH_1):PAGE80
   Y11 FM_LED_PWRGD_PVDDIO_P0 @T6G_MB_LIB.T6G(SCH_1):FM_LED_PWRGD_PVDDIO_P0   I216 @T6G_MB_LIB.T6G(SCH_1):PAGE80
  AB12 GPU_3V3IO_RSVD1_ISO_R @T6G_MB_LIB.T6G(SCH_1):GPU_3V3IO_RSVD1_ISO_R   I216 @T6G_MB_LIB.T6G(SCH_1):PAGE80
  AA12 GPU_3V3IO_RSVD3_ISO_R @T6G_MB_LIB.T6G(SCH_1):GPU_3V3IO_RSVD3_ISO_R   I216 @T6G_MB_LIB.T6G(SCH_1):PAGE80
  AB13 FM_RST_PERST_SCM_R_N @T6G_MB_LIB.T6G(SCH_1):FM_RST_PERST_SCM_R_N   I216 @T6G_MB_LIB.T6G(SCH_1):PAGE80
  AA13 RST_PERST_E1S_0_R_N @T6G_MB_LIB.T6G(SCH_1):RST_PERST_E1S_0_R_N   I216 @T6G_MB_LIB.T6G(SCH_1):PAGE80
  AB14 GPU_3V3IO_RSVD5_FFU_ISO_R @T6G_MB_LIB.T6G(SCH_1):GPU_3V3IO_RSVD5_FFU_ISO_R   I216 @T6G_MB_LIB.T6G(SCH_1):PAGE80
  AA14 PRSNT_CABLE_GPU_A1_ISO_R_N @T6G_MB_LIB.T6G(SCH_1):PRSNT_CABLE_GPU_A1_ISO_R_N   I216 @T6G_MB_LIB.T6G(SCH_1):PAGE80
  AB19 GPU_FPGA_READY_ISO_R @T6G_MB_LIB.T6G(SCH_1):GPU_FPGA_READY_ISO_R   I216 @T6G_MB_LIB.T6G(SCH_1):PAGE80
  AA19 RST_PERST_OCP_V3_2_N @T6G_MB_LIB.T6G(SCH_1):RST_PERST_OCP_V3_2_N   I216 @T6G_MB_LIB.T6G(SCH_1):PAGE80
  AB20 PRSNT_HDT_N @T6G_MB_LIB.T6G(SCH_1):PRSNT_HDT_N   I216 @T6G_MB_LIB.T6G(SCH_1):PAGE80
  AA20 P12V_OCP_V3_2_EN_R @T6G_MB_LIB.T6G(SCH_1):P12V_OCP_V3_2_EN_R   I216 @T6G_MB_LIB.T6G(SCH_1):PAGE80
  AB21 PU_SPI_PLD_CS_N @T6G_MB_LIB.T6G(SCH_1):PU_SPI_PLD_CS_N   I216 @T6G_MB_LIB.T6G(SCH_1):PAGE80
  AA21 P0V9_RETIMER_CPU1_EN_R2 @T6G_MB_LIB.T6G(SCH_1):P0V9_RETIMER_CPU1_EN_R2   I216 @T6G_MB_LIB.T6G(SCH_1):PAGE80
  AB15 GPU_BASE_HMC_READY_ISO_R @T6G_MB_LIB.T6G(SCH_1):GPU_BASE_HMC_READY_ISO_R   I216 @T6G_MB_LIB.T6G(SCH_1):PAGE80
  AA15 GPU_HMC_PRSNT_ISO_R_N @T6G_MB_LIB.T6G(SCH_1):GPU_HMC_PRSNT_ISO_R_N   I216 @T6G_MB_LIB.T6G(SCH_1):PAGE80
   AA6 PWRGD_PVDD18_S5_R_P1 @T6G_MB_LIB.T6G(SCH_1):PWRGD_PVDD18_S5_R_P1   I216 @T6G_MB_LIB.T6G(SCH_1):PAGE80
   AB6 FM_PWRGD_PVDD33_S5 @T6G_MB_LIB.T6G(SCH_1):FM_PWRGD_PVDD33_S5   I216 @T6G_MB_LIB.T6G(SCH_1):PAGE80
    W6 FM_GPU_PWR_EN @T6G_MB_LIB.T6G(SCH_1):FM_GPU_PWR_EN   I216 @T6G_MB_LIB.T6G(SCH_1):PAGE80
    V7 GPU_FPGA_RST_N @T6G_MB_LIB.T6G(SCH_1):GPU_FPGA_RST_N   I216 @T6G_MB_LIB.T6G(SCH_1):PAGE80
   AA7 FM_PVDD11_S3_P1_EN @T6G_MB_LIB.T6G(SCH_1):FM_PVDD11_S3_P1_EN   I216 @T6G_MB_LIB.T6G(SCH_1):PAGE80
   AB7 FM_PWRGD_PVDD11_S3_P1 @T6G_MB_LIB.T6G(SCH_1):FM_PWRGD_PVDD11_S3_P1   I216 @T6G_MB_LIB.T6G(SCH_1):PAGE80
    V9 FM_PVDD33_S5_EN @T6G_MB_LIB.T6G(SCH_1):FM_PVDD33_S5_EN   I216 @T6G_MB_LIB.T6G(SCH_1):PAGE80
    W8 PWRGD_P3V3_AUX_R @T6G_MB_LIB.T6G(SCH_1):PWRGD_P3V3_AUX_R   I216 @T6G_MB_LIB.T6G(SCH_1):PAGE80
    Y8 PWRGD_P1V8_AUX_R @T6G_MB_LIB.T6G(SCH_1):PWRGD_P1V8_AUX_R   I216 @T6G_MB_LIB.T6G(SCH_1):PAGE80
    W9 FM_CPU0_PWR_GOOD @T6G_MB_LIB.T6G(SCH_1):FM_CPU0_PWR_GOOD   I216 @T6G_MB_LIB.T6G(SCH_1):PAGE80
   AA9 FM_PVDDIO_P1_EN @T6G_MB_LIB.T6G(SCH_1):FM_PVDDIO_P1_EN   I216 @T6G_MB_LIB.T6G(SCH_1):PAGE80
   AB9 FM_PWRGD_PVDDIO_P1 @T6G_MB_LIB.T6G(SCH_1):FM_PWRGD_PVDDIO_P1   I216 @T6G_MB_LIB.T6G(SCH_1):PAGE80
   T10 FM_GPU_HSC_EN_R @T6G_MB_LIB.T6G(SCH_1):FM_GPU_HSC_EN_R   I216 @T6G_MB_LIB.T6G(SCH_1):PAGE80
   U10 P12V_E1S_0_PWRGD @T6G_MB_LIB.T6G(SCH_1):P12V_E1S_0_PWRGD   I216 @T6G_MB_LIB.T6G(SCH_1):PAGE80
   T11 FM_LED_PWRGD_PVDD33_S5 @T6G_MB_LIB.T6G(SCH_1):FM_LED_PWRGD_PVDD33_S5   I216 @T6G_MB_LIB.T6G(SCH_1):PAGE80
   U11 P3V3_E1S_PWRGD_0_R @T6G_MB_LIB.T6G(SCH_1):P3V3_E1S_PWRGD_0_R   I216 @T6G_MB_LIB.T6G(SCH_1):PAGE80
   Y12 FM_LED_PWRGD_PVDD11_S3_P0 @T6G_MB_LIB.T6G(SCH_1):FM_LED_PWRGD_PVDD11_S3_P0   I216 @T6G_MB_LIB.T6G(SCH_1):PAGE80
   T12 HPDB_HSC_PWRGD_ISO_R @T6G_MB_LIB.T6G(SCH_1):HPDB_HSC_PWRGD_ISO_R   I216 @T6G_MB_LIB.T6G(SCH_1):PAGE80
   U12     NC     NC   I216 @T6G_MB_LIB.T6G(SCH_1):PAGE80
   V12 P3V3_E1S_0_EN_R @T6G_MB_LIB.T6G(SCH_1):P3V3_E1S_0_EN_R   I216 @T6G_MB_LIB.T6G(SCH_1):PAGE80
   V13 GPU_3V3IO_RSVD4_ISO_R @T6G_MB_LIB.T6G(SCH_1):GPU_3V3IO_RSVD4_ISO_R   I216 @T6G_MB_LIB.T6G(SCH_1):PAGE80
   U13 HGX_DETECT_N_R @T6G_MB_LIB.T6G(SCH_1):HGX_DETECT_N_R   I216 @T6G_MB_LIB.T6G(SCH_1):PAGE80
   Y13 SWB_HSC_EN_R @T6G_MB_LIB.T6G(SCH_1):SWB_HSC_EN_R   I216 @T6G_MB_LIB.T6G(SCH_1):PAGE80
   W13 GPU_3V3IO_RSVD0_FFU_ISO_R @T6G_MB_LIB.T6G(SCH_1):GPU_3V3IO_RSVD0_FFU_ISO_R   I216 @T6G_MB_LIB.T6G(SCH_1):PAGE80
   Y14 SWB_HSC_PWRGD_ISO_R @T6G_MB_LIB.T6G(SCH_1):SWB_HSC_PWRGD_ISO_R   I216 @T6G_MB_LIB.T6G(SCH_1):PAGE80
   W14 GPU_FPGA_THERM_OVERT_ISO_R_N @T6G_MB_LIB.T6G(SCH_1):GPU_FPGA_THERM_OVERT_ISO_R_N   I216 @T6G_MB_LIB.T6G(SCH_1):PAGE80
   T13 GPU_3V3IO_RSVD1_FFU_ISO_R @T6G_MB_LIB.T6G(SCH_1):GPU_3V3IO_RSVD1_FFU_ISO_R   I216 @T6G_MB_LIB.T6G(SCH_1):PAGE80
   T14 RST_PERST_CPU0_SWB_N @T6G_MB_LIB.T6G(SCH_1):RST_PERST_CPU0_SWB_N   I216 @T6G_MB_LIB.T6G(SCH_1):PAGE80
   U14 RST_PERST_CPU1_SWB_N @T6G_MB_LIB.T6G(SCH_1):RST_PERST_CPU1_SWB_N   I216 @T6G_MB_LIB.T6G(SCH_1):PAGE80
   V14 PRSNT_CABLE_GPU_A2_ISO_R_N @T6G_MB_LIB.T6G(SCH_1):PRSNT_CABLE_GPU_A2_ISO_R_N   I216 @T6G_MB_LIB.T6G(SCH_1):PAGE80
   Y15 GPU_FPGA_OVERT_ISO_R_N @T6G_MB_LIB.T6G(SCH_1):GPU_FPGA_OVERT_ISO_R_N   I216 @T6G_MB_LIB.T6G(SCH_1):PAGE80
   W15 GPU_WP_HW_CTRL_R_N @T6G_MB_LIB.T6G(SCH_1):GPU_WP_HW_CTRL_R_N   I216 @T6G_MB_LIB.T6G(SCH_1):PAGE80
  AB16 GPU_PRSNT_N_ISO_R @T6G_MB_LIB.T6G(SCH_1):GPU_PRSNT_N_ISO_R   I216 @T6G_MB_LIB.T6G(SCH_1):PAGE80
  AA16 GPU_FPGA_EROT_FATALERR_ISO_R_N @T6G_MB_LIB.T6G(SCH_1):GPU_FPGA_EROT_FATALERR_ISO_R_N   I216 @T6G_MB_LIB.T6G(SCH_1):PAGE80
   V15 BIC_MONITER_ISO_R @T6G_MB_LIB.T6G(SCH_1):BIC_MONITER_ISO_R   I216 @T6G_MB_LIB.T6G(SCH_1):PAGE80
   U15 RST_BMC_FROM_SWB_ISO_R_N @T6G_MB_LIB.T6G(SCH_1):RST_BMC_FROM_SWB_ISO_R_N   I216 @T6G_MB_LIB.T6G(SCH_1):PAGE80
  AB17 FM_SWB_BIC_READY_ISO_R_N @T6G_MB_LIB.T6G(SCH_1):FM_SWB_BIC_READY_ISO_R_N   I216 @T6G_MB_LIB.T6G(SCH_1):PAGE80
  AA17 FM_SMB_1_ALERT_GPU_ISO_R_N @T6G_MB_LIB.T6G(SCH_1):FM_SMB_1_ALERT_GPU_ISO_R_N   I216 @T6G_MB_LIB.T6G(SCH_1):PAGE80
   Y17 SW_P3V3_EN @T6G_MB_LIB.T6G(SCH_1):SW_P3V3_EN   I216 @T6G_MB_LIB.T6G(SCH_1):PAGE80
   V16 RST_PERST_M2_0_R_N @T6G_MB_LIB.T6G(SCH_1):RST_PERST_M2_0_R_N   I216 @T6G_MB_LIB.T6G(SCH_1):PAGE80
  AB18 FM_SWB_PWRGD_ISO_R @T6G_MB_LIB.T6G(SCH_1):FM_SWB_PWRGD_ISO_R   I216 @T6G_MB_LIB.T6G(SCH_1):PAGE80
  AA18 FM_GPU_PWRGD_ISO_R @T6G_MB_LIB.T6G(SCH_1):FM_GPU_PWRGD_ISO_R   I216 @T6G_MB_LIB.T6G(SCH_1):PAGE80
   Y18 FM_SMB_2_ALERT_GPU_ISO_R_N @T6G_MB_LIB.T6G(SCH_1):FM_SMB_2_ALERT_GPU_ISO_R_N   I216 @T6G_MB_LIB.T6G(SCH_1):PAGE80
   W17 RST_PERST_OCP_SFF_N @T6G_MB_LIB.T6G(SCH_1):RST_PERST_OCP_SFF_N   I216 @T6G_MB_LIB.T6G(SCH_1):PAGE80
   T15 GPU_FPGA_BOOT_EN_R @T6G_MB_LIB.T6G(SCH_1):GPU_FPGA_BOOT_EN_R   I216 @T6G_MB_LIB.T6G(SCH_1):PAGE80
   U16 FM_NCSI_OCP_V3_2_R_OE @T6G_MB_LIB.T6G(SCH_1):FM_NCSI_OCP_V3_2_R_OE   I216 @T6G_MB_LIB.T6G(SCH_1):PAGE80
   Y19 GPU_BASE_STBY_EN_R @T6G_MB_LIB.T6G(SCH_1):GPU_BASE_STBY_EN_R   I216 @T6G_MB_LIB.T6G(SCH_1):PAGE80
   W18 FM_AC_PWR_BTN_PLD_ISO_N @T6G_MB_LIB.T6G(SCH_1):FM_AC_PWR_BTN_PLD_ISO_N   I216 @T6G_MB_LIB.T6G(SCH_1):PAGE80
   V17 P3V3_OCP_V3_2_EN_R @T6G_MB_LIB.T6G(SCH_1):P3V3_OCP_V3_2_EN_R   I216 @T6G_MB_LIB.T6G(SCH_1):PAGE80
   T16 FM_P5V_EN @T6G_MB_LIB.T6G(SCH_1):FM_P5V_EN   I216 @T6G_MB_LIB.T6G(SCH_1):PAGE80
    Y9 PWRGD_P1V2_AUX_R @T6G_MB_LIB.T6G(SCH_1):PWRGD_P1V2_AUX_R   I216 @T6G_MB_LIB.T6G(SCH_1):PAGE80
   Y10 BMC_FPGA_LED2 @T6G_MB_LIB.T6G(SCH_1):BMC_FPGA_LED2   I216 @T6G_MB_LIB.T6G(SCH_1):PAGE80
   B21 IRQ_SML1_PMBUS_ALERT_N @T6G_MB_LIB.T6G(SCH_1):IRQ_SML1_PMBUS_ALERT_N    I94 @T6G_MB_LIB.T6G(SCH_1):PAGE79
   A20 P1V8_RETIMER_CPU1_R_EN @T6G_MB_LIB.T6G(SCH_1):P1V8_RETIMER_CPU1_R_EN    I94 @T6G_MB_LIB.T6G(SCH_1):PAGE79
   B19 FM_LED_PWRGD_PVDD11_S3_P1 @T6G_MB_LIB.T6G(SCH_1):FM_LED_PWRGD_PVDD11_S3_P1    I94 @T6G_MB_LIB.T6G(SCH_1):PAGE79
   A18 FM_LED_PWRGD_PVDDIO_P1 @T6G_MB_LIB.T6G(SCH_1):FM_LED_PWRGD_PVDDIO_P1    I94 @T6G_MB_LIB.T6G(SCH_1):PAGE79
   F14 SCM_SPARE_1 @T6G_MB_LIB.T6G(SCH_1):SCM_SPARE_1    I94 @T6G_MB_LIB.T6G(SCH_1):PAGE79
   G14 SCM_SPARE_0 @T6G_MB_LIB.T6G(SCH_1):SCM_SPARE_0    I94 @T6G_MB_LIB.T6G(SCH_1):PAGE79
   F12 GPU_3V3IO_RSVD3_FFU_ISO_R @T6G_MB_LIB.T6G(SCH_1):GPU_3V3IO_RSVD3_FFU_ISO_R    I94 @T6G_MB_LIB.T6G(SCH_1):PAGE79
   G12 PRSNT_CABLE_GPU_B3_ISO_R_N @T6G_MB_LIB.T6G(SCH_1):PRSNT_CABLE_GPU_B3_ISO_R_N    I94 @T6G_MB_LIB.T6G(SCH_1):PAGE79
   A12 SMB_1_PLD_3V3AUX_SDA_R2 @T6G_MB_LIB.T6G(SCH_1):SMB_1_PLD_3V3AUX_SDA_R2    I94 @T6G_MB_LIB.T6G(SCH_1):PAGE79
   B12 SMB_1_PLD_3V3AUX_SCL_R2 @T6G_MB_LIB.T6G(SCH_1):SMB_1_PLD_3V3AUX_SCL_R2    I94 @T6G_MB_LIB.T6G(SCH_1):PAGE79
   B22 FM_OCP_V3_2_PWR_GOOD @T6G_MB_LIB.T6G(SCH_1):FM_OCP_V3_2_PWR_GOOD    I94 @T6G_MB_LIB.T6G(SCH_1):PAGE79
   A21 SMB_BMC_SWB_EN @T6G_MB_LIB.T6G(SCH_1):SMB_BMC_SWB_EN    I94 @T6G_MB_LIB.T6G(SCH_1):PAGE79
   A10 OC_ALERT_N @T6G_MB_LIB.T6G(SCH_1):OC_ALERT_N    I94 @T6G_MB_LIB.T6G(SCH_1):PAGE79
   B10 UV_ALERT_N @T6G_MB_LIB.T6G(SCH_1):UV_ALERT_N    I94 @T6G_MB_LIB.T6G(SCH_1):PAGE79
    D8 SGPIO_OCP_SFF_LD_N @T6G_MB_LIB.T6G(SCH_1):SGPIO_OCP_SFF_LD_N    I94 @T6G_MB_LIB.T6G(SCH_1):PAGE79
    F7 FM_I3C_CPU0_MUX1_R_SEL @T6G_MB_LIB.T6G(SCH_1):FM_I3C_CPU0_MUX1_R_SEL    I94 @T6G_MB_LIB.T6G(SCH_1):PAGE79
    A2 FM_I3C_CPU1_MUX0_R_SEL @T6G_MB_LIB.T6G(SCH_1):FM_I3C_CPU1_MUX0_R_SEL    I94 @T6G_MB_LIB.T6G(SCH_1):PAGE79
    E6 FM_I3C_CPU1_MUX1_OE_R_N @T6G_MB_LIB.T6G(SCH_1):FM_I3C_CPU1_MUX1_OE_R_N    I94 @T6G_MB_LIB.T6G(SCH_1):PAGE79
    B1 FM_I3C_CPU0_MUX0_OE_R_N @T6G_MB_LIB.T6G(SCH_1):FM_I3C_CPU0_MUX0_OE_R_N    I94 @T6G_MB_LIB.T6G(SCH_1):PAGE79
    C8 PCIE_M2_SSD0_PRSNT_N @T6G_MB_LIB.T6G(SCH_1):PCIE_M2_SSD0_PRSNT_N    I94 @T6G_MB_LIB.T6G(SCH_1):PAGE79
    B3 SCM_JTAG_MUX_R_S0 @T6G_MB_LIB.T6G(SCH_1):SCM_JTAG_MUX_R_S0    I94 @T6G_MB_LIB.T6G(SCH_1):PAGE79
    A4 SGPIO_SCM_DI_R<0> @T6G_MB_LIB.T6G(SCH_1):SGPIO_SCM_DI_R(0)    I94 @T6G_MB_LIB.T6G(SCH_1):PAGE79
   F10 FM_BOARD_BMC_SKU_ID2 @T6G_MB_LIB.T6G(SCH_1):FM_BOARD_BMC_SKU_ID2    I94 @T6G_MB_LIB.T6G(SCH_1):PAGE79
   E10 FM_LED_ACTIVE_E1S_0 @T6G_MB_LIB.T6G(SCH_1):FM_LED_ACTIVE_E1S_0    I94 @T6G_MB_LIB.T6G(SCH_1):PAGE79
    F8 PWRGD_PS_PWROK_PLD_ISO_R @T6G_MB_LIB.T6G(SCH_1):PWRGD_PS_PWROK_PLD_ISO_R    I94 @T6G_MB_LIB.T6G(SCH_1):PAGE79
    G8 SGPIO_SCM_INTR_R_N @T6G_MB_LIB.T6G(SCH_1):SGPIO_SCM_INTR_R_N    I94 @T6G_MB_LIB.T6G(SCH_1):PAGE79
    B2 FM_I3C_CPU1_MUX0_OE_R_N @T6G_MB_LIB.T6G(SCH_1):FM_I3C_CPU1_MUX0_OE_R_N    I94 @T6G_MB_LIB.T6G(SCH_1):PAGE79
    A3 SCM_JTAG_MUX_R_S1 @T6G_MB_LIB.T6G(SCH_1):SCM_JTAG_MUX_R_S1    I94 @T6G_MB_LIB.T6G(SCH_1):PAGE79
    C3 FM_I3C_CPU0_MUX0_R_SEL @T6G_MB_LIB.T6G(SCH_1):FM_I3C_CPU0_MUX0_R_SEL    I94 @T6G_MB_LIB.T6G(SCH_1):PAGE79
    C4 FM_I3C_CPU0_MUX1_OE_R_N @T6G_MB_LIB.T6G(SCH_1):FM_I3C_CPU0_MUX1_OE_R_N    I94 @T6G_MB_LIB.T6G(SCH_1):PAGE79
    B4 SGPIO_SCM_DO_<1> @T6G_MB_LIB.T6G(SCH_1):SGPIO_SCM_DO_(1)    I94 @T6G_MB_LIB.T6G(SCH_1):PAGE79
    A5 SGPIO_SCM_RESET_N @T6G_MB_LIB.T6G(SCH_1):SGPIO_SCM_RESET_N    I94 @T6G_MB_LIB.T6G(SCH_1):PAGE79
    D5 FM_I3C_CPU1_MUX1_R_SEL @T6G_MB_LIB.T6G(SCH_1):FM_I3C_CPU1_MUX1_R_SEL    I94 @T6G_MB_LIB.T6G(SCH_1):PAGE79
    C5 FM_BOARD_BMC_SKU_ID0 @T6G_MB_LIB.T6G(SCH_1):FM_BOARD_BMC_SKU_ID0    I94 @T6G_MB_LIB.T6G(SCH_1):PAGE79
    B5 SGPIO_SCM_LD_<1> @T6G_MB_LIB.T6G(SCH_1):SGPIO_SCM_LD_(1)    I94 @T6G_MB_LIB.T6G(SCH_1):PAGE79
    A6 E1S_0_PERST1_CLKREQ_R_N @T6G_MB_LIB.T6G(SCH_1):E1S_0_PERST1_CLKREQ_R_N    I94 @T6G_MB_LIB.T6G(SCH_1):PAGE79
    D6 SGPIO_SCM_CLK_<0> @T6G_MB_LIB.T6G(SCH_1):SGPIO_SCM_CLK_(0)    I94 @T6G_MB_LIB.T6G(SCH_1):PAGE79
    E7 SGPIO_SCM_DO_<0> @T6G_MB_LIB.T6G(SCH_1):SGPIO_SCM_DO_(0)    I94 @T6G_MB_LIB.T6G(SCH_1):PAGE79
    B6 IRQ_HSC_FAULT_BUF_R_N @T6G_MB_LIB.T6G(SCH_1):IRQ_HSC_FAULT_BUF_R_N    I94 @T6G_MB_LIB.T6G(SCH_1):PAGE79
    A7 FM_UV_ADR_TRIGGER_R_N @T6G_MB_LIB.T6G(SCH_1):FM_UV_ADR_TRIGGER_R_N    I94 @T6G_MB_LIB.T6G(SCH_1):PAGE79
    C6 SGPIO_SCM_DI_R<1> @T6G_MB_LIB.T6G(SCH_1):SGPIO_SCM_DI_R(1)    I94 @T6G_MB_LIB.T6G(SCH_1):PAGE79
    D7 SGPIO_SCM_LD_<0> @T6G_MB_LIB.T6G(SCH_1):SGPIO_SCM_LD_(0)    I94 @T6G_MB_LIB.T6G(SCH_1):PAGE79
    B8 SGPIO_OCP_SFF_DATAIN @T6G_MB_LIB.T6G(SCH_1):SGPIO_OCP_SFF_DATAIN    I94 @T6G_MB_LIB.T6G(SCH_1):PAGE79
    A8 SGPIO_OCP_SFF_DATAOUT @T6G_MB_LIB.T6G(SCH_1):SGPIO_OCP_SFF_DATAOUT    I94 @T6G_MB_LIB.T6G(SCH_1):PAGE79
    C9 SGPIO_OCP_SFF_CLK @T6G_MB_LIB.T6G(SCH_1):SGPIO_OCP_SFF_CLK    I94 @T6G_MB_LIB.T6G(SCH_1):PAGE79
    D9 OCP_V3_2_MAIN_PWR_EN @T6G_MB_LIB.T6G(SCH_1):OCP_V3_2_MAIN_PWR_EN    I94 @T6G_MB_LIB.T6G(SCH_1):PAGE79
    B9 P3V3_OCP_SFF_EN @T6G_MB_LIB.T6G(SCH_1):P3V3_OCP_SFF_EN    I94 @T6G_MB_LIB.T6G(SCH_1):PAGE79
    A9 OCP_V3_1_P3V3_PLD_R_PWRGD @T6G_MB_LIB.T6G(SCH_1):OCP_V3_1_P3V3_PLD_R_PWRGD    I94 @T6G_MB_LIB.T6G(SCH_1):PAGE79
    F9 P12V_OCP_SFF_EN @T6G_MB_LIB.T6G(SCH_1):P12V_OCP_SFF_EN    I94 @T6G_MB_LIB.T6G(SCH_1):PAGE79
    G9 FM_BOARD_BMC_SKU_ID1 @T6G_MB_LIB.T6G(SCH_1):FM_BOARD_BMC_SKU_ID1    I94 @T6G_MB_LIB.T6G(SCH_1):PAGE79
   G11 SMB_CPU0_4_XLTR_R_SCL @T6G_MB_LIB.T6G(SCH_1):SMB_CPU0_4_XLTR_R_SCL    I94 @T6G_MB_LIB.T6G(SCH_1):PAGE79
   F11 SMB_CPU0_4_XLTR_R_SDA @T6G_MB_LIB.T6G(SCH_1):SMB_CPU0_4_XLTR_R_SDA    I94 @T6G_MB_LIB.T6G(SCH_1):PAGE79
   B11 FM_BOARD_BMC_SKU_ID3 @T6G_MB_LIB.T6G(SCH_1):FM_BOARD_BMC_SKU_ID3    I94 @T6G_MB_LIB.T6G(SCH_1):PAGE79
   A11 FM_BOARD_BMC_SKU_ID4 @T6G_MB_LIB.T6G(SCH_1):FM_BOARD_BMC_SKU_ID4    I94 @T6G_MB_LIB.T6G(SCH_1):PAGE79
   E11 FM_SYS_THROTTLE_R_N @T6G_MB_LIB.T6G(SCH_1):FM_SYS_THROTTLE_R_N    I94 @T6G_MB_LIB.T6G(SCH_1):PAGE79
   D11 JTAG_SCM_TRST_R_N @T6G_MB_LIB.T6G(SCH_1):JTAG_SCM_TRST_R_N    I94 @T6G_MB_LIB.T6G(SCH_1):PAGE79
   D12 FM_FAN_PWR_EN @T6G_MB_LIB.T6G(SCH_1):FM_FAN_PWR_EN    I94 @T6G_MB_LIB.T6G(SCH_1):PAGE79
   E12 SCM_SYS_PWRBTN_N @T6G_MB_LIB.T6G(SCH_1):SCM_SYS_PWRBTN_N    I94 @T6G_MB_LIB.T6G(SCH_1):PAGE79
   E13 HP_LVC3_OCP_V3_2_P12V_PWRGD_R @T6G_MB_LIB.T6G(SCH_1):HP_LVC3_OCP_V3_2_P12V_PWRGD_R    I94 @T6G_MB_LIB.T6G(SCH_1):PAGE79
   F13 FM_UARTSW_MSB_N @T6G_MB_LIB.T6G(SCH_1):FM_UARTSW_MSB_N    I94 @T6G_MB_LIB.T6G(SCH_1):PAGE79
   A13 SMB_2_PLD_3V3AUX_SCL_R2 @T6G_MB_LIB.T6G(SCH_1):SMB_2_PLD_3V3AUX_SCL_R2    I94 @T6G_MB_LIB.T6G(SCH_1):PAGE79
   B13 SMB_2_PLD_3V3AUX_SDA_R2 @T6G_MB_LIB.T6G(SCH_1):SMB_2_PLD_3V3AUX_SDA_R2    I94 @T6G_MB_LIB.T6G(SCH_1):PAGE79
   C13 SCM_ROT_CPU_RST_R_N @T6G_MB_LIB.T6G(SCH_1):SCM_ROT_CPU_RST_R_N    I94 @T6G_MB_LIB.T6G(SCH_1):PAGE79
   D13 RST_MB_STBY_N @T6G_MB_LIB.T6G(SCH_1):RST_MB_STBY_N    I94 @T6G_MB_LIB.T6G(SCH_1):PAGE79
   A14 SGPIO_OCP_V3_2_LD_N @T6G_MB_LIB.T6G(SCH_1):SGPIO_OCP_V3_2_LD_N    I94 @T6G_MB_LIB.T6G(SCH_1):PAGE79
   B14 SGPIO_OCP_V3_2_DATAIN @T6G_MB_LIB.T6G(SCH_1):SGPIO_OCP_V3_2_DATAIN    I94 @T6G_MB_LIB.T6G(SCH_1):PAGE79
   C14 SGPIO_OCP_V3_2_DATAOUT @T6G_MB_LIB.T6G(SCH_1):SGPIO_OCP_V3_2_DATAOUT    I94 @T6G_MB_LIB.T6G(SCH_1):PAGE79
   D14 SGPIO_OCP_V3_2_CLK @T6G_MB_LIB.T6G(SCH_1):SGPIO_OCP_V3_2_CLK    I94 @T6G_MB_LIB.T6G(SCH_1):PAGE79
   A15 SCM_SYS_PWROK @T6G_MB_LIB.T6G(SCH_1):SCM_SYS_PWROK    I94 @T6G_MB_LIB.T6G(SCH_1):PAGE79
   B15 P1V8_RETIMER_CPU0_R_EN @T6G_MB_LIB.T6G(SCH_1):P1V8_RETIMER_CPU0_R_EN    I94 @T6G_MB_LIB.T6G(SCH_1):PAGE79
   C15 PVDDCR_SOC_P1_EN @T6G_MB_LIB.T6G(SCH_1):PVDDCR_SOC_P1_EN    I94 @T6G_MB_LIB.T6G(SCH_1):PAGE79
   D15 PRSNT_OCP_V3_2_N @T6G_MB_LIB.T6G(SCH_1):PRSNT_OCP_V3_2_N    I94 @T6G_MB_LIB.T6G(SCH_1):PAGE79
   A16 PWRGD_P5V @T6G_MB_LIB.T6G(SCH_1):PWRGD_P5V    I94 @T6G_MB_LIB.T6G(SCH_1):PAGE79
   B17 PVDDCR_CPU0_P0_EN @T6G_MB_LIB.T6G(SCH_1):PVDDCR_CPU0_P0_EN    I94 @T6G_MB_LIB.T6G(SCH_1):PAGE79
   C17 RST_SRST_PLD_BMC_R_N @T6G_MB_LIB.T6G(SCH_1):RST_SRST_PLD_BMC_R_N    I94 @T6G_MB_LIB.T6G(SCH_1):PAGE79
   D16 FPGA_IO3V3_RSVD_1 @T6G_MB_LIB.T6G(SCH_1):FPGA_IO3V3_RSVD_1    I94 @T6G_MB_LIB.T6G(SCH_1):PAGE79
   A17 PWRGD_PVDDCR_SOC_P1 @T6G_MB_LIB.T6G(SCH_1):PWRGD_PVDDCR_SOC_P1    I94 @T6G_MB_LIB.T6G(SCH_1):PAGE79
   B18 FM_LED_PWRGD_PVDDCR_SOC_P1 @T6G_MB_LIB.T6G(SCH_1):FM_LED_PWRGD_PVDDCR_SOC_P1    I94 @T6G_MB_LIB.T6G(SCH_1):PAGE79
   E16 FM_LED_PWRGD_PVDDCR_CPU1_P1 @T6G_MB_LIB.T6G(SCH_1):FM_LED_PWRGD_PVDDCR_CPU1_P1    I94 @T6G_MB_LIB.T6G(SCH_1):PAGE79
   D17 RST_SMB_SWITCH_N @T6G_MB_LIB.T6G(SCH_1):RST_SMB_SWITCH_N    I94 @T6G_MB_LIB.T6G(SCH_1):PAGE79
   C18 FM_OCP_V3_2_AUX_PWR_EN @T6G_MB_LIB.T6G(SCH_1):FM_OCP_V3_2_AUX_PWR_EN    I94 @T6G_MB_LIB.T6G(SCH_1):PAGE79
   D18 SGPIO_SCM_CLK_<1> @T6G_MB_LIB.T6G(SCH_1):SGPIO_SCM_CLK_(1)    I94 @T6G_MB_LIB.T6G(SCH_1):PAGE79
   A19 FM_LED_PWRGD_PVDD18_S5_P1 @T6G_MB_LIB.T6G(SCH_1):FM_LED_PWRGD_PVDD18_S5_P1    I94 @T6G_MB_LIB.T6G(SCH_1):PAGE79
   B20 FM_SOL_UART_CH_SEL @T6G_MB_LIB.T6G(SCH_1):FM_SOL_UART_CH_SEL    I94 @T6G_MB_LIB.T6G(SCH_1):PAGE79
   F15 OCP_V3_2_P3V3_PLD_R_PWRGD @T6G_MB_LIB.T6G(SCH_1):OCP_V3_2_P3V3_PLD_R_PWRGD    I94 @T6G_MB_LIB.T6G(SCH_1):PAGE79
   G15 FM_UARTSW_LSB_N @T6G_MB_LIB.T6G(SCH_1):FM_UARTSW_LSB_N    I94 @T6G_MB_LIB.T6G(SCH_1):PAGE79
   C19 CLK_GEN2_BMC_RC_OE_R_N @T6G_MB_LIB.T6G(SCH_1):CLK_GEN2_BMC_RC_OE_R_N    I94 @T6G_MB_LIB.T6G(SCH_1):PAGE79
   C20 CLK_GEN2_GPU_FPGA_OE_R_N @T6G_MB_LIB.T6G(SCH_1):CLK_GEN2_GPU_FPGA_OE_R_N    I94 @T6G_MB_LIB.T6G(SCH_1):PAGE79
    E8 JTAG_SCM_PLD_TDI @T6G_MB_LIB.T6G(SCH_1):JTAG_SCM_PLD_TDI    I25 @T6G_MB_LIB.T6G(SCH_1):PAGE79
    E9 JTAG_SCM_PLD_TDO @T6G_MB_LIB.T6G(SCH_1):JTAG_SCM_PLD_TDO    I25 @T6G_MB_LIB.T6G(SCH_1):PAGE79
   D10 JTAG_SCM_PLD_TCK @T6G_MB_LIB.T6G(SCH_1):JTAG_SCM_PLD_TCK    I25 @T6G_MB_LIB.T6G(SCH_1):PAGE79
   C10 JTAG_SCM_PLD_TMS @T6G_MB_LIB.T6G(SCH_1):JTAG_SCM_PLD_TMS    I25 @T6G_MB_LIB.T6G(SCH_1):PAGE79
   E15 CPLD_PROGRAMN @T6G_MB_LIB.T6G(SCH_1):CPLD_PROGRAMN    I25 @T6G_MB_LIB.T6G(SCH_1):PAGE79
   F16 VIRTUAL_RESEAT @T6G_MB_LIB.T6G(SCH_1):VIRTUAL_RESEAT    I25 @T6G_MB_LIB.T6G(SCH_1):PAGE79
   E17 VIRTUAL_RESEAT_FPGA_R_N @T6G_MB_LIB.T6G(SCH_1):VIRTUAL_RESEAT_FPGA_R_N    I25 @T6G_MB_LIB.T6G(SCH_1):PAGE79
   E14 CPLD_JTAG_EN @T6G_MB_LIB.T6G(SCH_1):CPLD_JTAG_EN    I25 @T6G_MB_LIB.T6G(SCH_1):PAGE79
   K10 P3V3_AUX @T6G_MB_LIB.T6G(SCH_1):P3V3_AUX   I141 @T6G_MB_LIB.T6G(SCH_1):PAGE81
   K11 P3V3_AUX @T6G_MB_LIB.T6G(SCH_1):P3V3_AUX   I141 @T6G_MB_LIB.T6G(SCH_1):PAGE81
   K12 P3V3_AUX @T6G_MB_LIB.T6G(SCH_1):P3V3_AUX   I141 @T6G_MB_LIB.T6G(SCH_1):PAGE81
   K13 P3V3_AUX @T6G_MB_LIB.T6G(SCH_1):P3V3_AUX   I141 @T6G_MB_LIB.T6G(SCH_1):PAGE81
   L11 P3V3_AUX @T6G_MB_LIB.T6G(SCH_1):P3V3_AUX   I141 @T6G_MB_LIB.T6G(SCH_1):PAGE81
   L12 P3V3_AUX @T6G_MB_LIB.T6G(SCH_1):P3V3_AUX   I141 @T6G_MB_LIB.T6G(SCH_1):PAGE81
   M11 P3V3_AUX @T6G_MB_LIB.T6G(SCH_1):P3V3_AUX   I141 @T6G_MB_LIB.T6G(SCH_1):PAGE81
   M12 P3V3_AUX @T6G_MB_LIB.T6G(SCH_1):P3V3_AUX   I141 @T6G_MB_LIB.T6G(SCH_1):PAGE81
   N10 P3V3_AUX @T6G_MB_LIB.T6G(SCH_1):P3V3_AUX   I141 @T6G_MB_LIB.T6G(SCH_1):PAGE81
   N11 P3V3_AUX @T6G_MB_LIB.T6G(SCH_1):P3V3_AUX   I141 @T6G_MB_LIB.T6G(SCH_1):PAGE81
   N12 P3V3_AUX @T6G_MB_LIB.T6G(SCH_1):P3V3_AUX   I141 @T6G_MB_LIB.T6G(SCH_1):PAGE81
   N13 P3V3_AUX @T6G_MB_LIB.T6G(SCH_1):P3V3_AUX   I141 @T6G_MB_LIB.T6G(SCH_1):PAGE81
    F3 P1V8_AUX @T6G_MB_LIB.T6G(SCH_1):P1V8_AUX   I141 @T6G_MB_LIB.T6G(SCH_1):PAGE81
    J8 P1V8_AUX @T6G_MB_LIB.T6G(SCH_1):P1V8_AUX   I141 @T6G_MB_LIB.T6G(SCH_1):PAGE81
    K8 P1V8_AUX @T6G_MB_LIB.T6G(SCH_1):P1V8_AUX   I141 @T6G_MB_LIB.T6G(SCH_1):PAGE81
    L8 P3V3_AUX @T6G_MB_LIB.T6G(SCH_1):P3V3_AUX   I141 @T6G_MB_LIB.T6G(SCH_1):PAGE81
    M8 P3V3_AUX @T6G_MB_LIB.T6G(SCH_1):P3V3_AUX   I141 @T6G_MB_LIB.T6G(SCH_1):PAGE81
    M3 P3V3_AUX @T6G_MB_LIB.T6G(SCH_1):P3V3_AUX   I141 @T6G_MB_LIB.T6G(SCH_1):PAGE81
    N8 P3V3_AUX @T6G_MB_LIB.T6G(SCH_1):P3V3_AUX   I141 @T6G_MB_LIB.T6G(SCH_1):PAGE81
    P8 P3V3_AUX @T6G_MB_LIB.T6G(SCH_1):P3V3_AUX   I141 @T6G_MB_LIB.T6G(SCH_1):PAGE81
    V3 P3V3_AUX @T6G_MB_LIB.T6G(SCH_1):P3V3_AUX   I141 @T6G_MB_LIB.T6G(SCH_1):PAGE81
    R9 P3V3_AUX @T6G_MB_LIB.T6G(SCH_1):P3V3_AUX   I141 @T6G_MB_LIB.T6G(SCH_1):PAGE81
   R10 P3V3_AUX @T6G_MB_LIB.T6G(SCH_1):P3V3_AUX   I141 @T6G_MB_LIB.T6G(SCH_1):PAGE81
   R11 P3V3_AUX @T6G_MB_LIB.T6G(SCH_1):P3V3_AUX   I141 @T6G_MB_LIB.T6G(SCH_1):PAGE81
   R12 P3V3_AUX @T6G_MB_LIB.T6G(SCH_1):P3V3_AUX   I141 @T6G_MB_LIB.T6G(SCH_1):PAGE81
   R13 P3V3_AUX @T6G_MB_LIB.T6G(SCH_1):P3V3_AUX   I141 @T6G_MB_LIB.T6G(SCH_1):PAGE81
   R14 P3V3_AUX @T6G_MB_LIB.T6G(SCH_1):P3V3_AUX   I141 @T6G_MB_LIB.T6G(SCH_1):PAGE81
    W7 P3V3_AUX @T6G_MB_LIB.T6G(SCH_1):P3V3_AUX   I141 @T6G_MB_LIB.T6G(SCH_1):PAGE81
   W11 P3V3_AUX @T6G_MB_LIB.T6G(SCH_1):P3V3_AUX   I141 @T6G_MB_LIB.T6G(SCH_1):PAGE81
   W16 P3V3_AUX @T6G_MB_LIB.T6G(SCH_1):P3V3_AUX   I141 @T6G_MB_LIB.T6G(SCH_1):PAGE81
   F20 P1V8_AUX @T6G_MB_LIB.T6G(SCH_1):P1V8_AUX   I141 @T6G_MB_LIB.T6G(SCH_1):PAGE81
   J15 P1V8_AUX @T6G_MB_LIB.T6G(SCH_1):P1V8_AUX   I141 @T6G_MB_LIB.T6G(SCH_1):PAGE81
   K15 P1V8_AUX @T6G_MB_LIB.T6G(SCH_1):P1V8_AUX   I141 @T6G_MB_LIB.T6G(SCH_1):PAGE81
   L15 P1V8_AUX @T6G_MB_LIB.T6G(SCH_1):P1V8_AUX   I141 @T6G_MB_LIB.T6G(SCH_1):PAGE81
   M15 P1V8_AUX @T6G_MB_LIB.T6G(SCH_1):P1V8_AUX   I141 @T6G_MB_LIB.T6G(SCH_1):PAGE81
   M18 P1V8_AUX @T6G_MB_LIB.T6G(SCH_1):P1V8_AUX   I141 @T6G_MB_LIB.T6G(SCH_1):PAGE81
   N15 P1V8_AUX @T6G_MB_LIB.T6G(SCH_1):P1V8_AUX   I141 @T6G_MB_LIB.T6G(SCH_1):PAGE81
   P15 P1V8_AUX @T6G_MB_LIB.T6G(SCH_1):P1V8_AUX   I141 @T6G_MB_LIB.T6G(SCH_1):PAGE81
   V20 P1V8_AUX @T6G_MB_LIB.T6G(SCH_1):P1V8_AUX   I141 @T6G_MB_LIB.T6G(SCH_1):PAGE81
    C7 P3V3_AUX @T6G_MB_LIB.T6G(SCH_1):P3V3_AUX   I141 @T6G_MB_LIB.T6G(SCH_1):PAGE81
   C12 P3V3_AUX @T6G_MB_LIB.T6G(SCH_1):P3V3_AUX   I141 @T6G_MB_LIB.T6G(SCH_1):PAGE81
   C16 P3V3_AUX @T6G_MB_LIB.T6G(SCH_1):P3V3_AUX   I141 @T6G_MB_LIB.T6G(SCH_1):PAGE81
   G10 P3V3_AUX @T6G_MB_LIB.T6G(SCH_1):P3V3_AUX   I141 @T6G_MB_LIB.T6G(SCH_1):PAGE81
   H11 P3V3_AUX @T6G_MB_LIB.T6G(SCH_1):P3V3_AUX   I141 @T6G_MB_LIB.T6G(SCH_1):PAGE81
   H12 P3V3_AUX @T6G_MB_LIB.T6G(SCH_1):P3V3_AUX   I141 @T6G_MB_LIB.T6G(SCH_1):PAGE81
   H14 P3V3_AUX @T6G_MB_LIB.T6G(SCH_1):P3V3_AUX   I141 @T6G_MB_LIB.T6G(SCH_1):PAGE81
    H9 P3V3_AUX @T6G_MB_LIB.T6G(SCH_1):P3V3_AUX   I141 @T6G_MB_LIB.T6G(SCH_1):PAGE81
   G13 P3V3_AUX @T6G_MB_LIB.T6G(SCH_1):P3V3_AUX   I141 @T6G_MB_LIB.T6G(SCH_1):PAGE81
    A1    GND @T6G_MB_LIB.T6G(SCH_1):GND     I1 @T6G_MB_LIB.T6G(SCH_1):PAGE81
   A22    GND @T6G_MB_LIB.T6G(SCH_1):GND     I1 @T6G_MB_LIB.T6G(SCH_1):PAGE81
    B7    GND @T6G_MB_LIB.T6G(SCH_1):GND     I1 @T6G_MB_LIB.T6G(SCH_1):PAGE81
   B16    GND @T6G_MB_LIB.T6G(SCH_1):GND     I1 @T6G_MB_LIB.T6G(SCH_1):PAGE81
    C2    GND @T6G_MB_LIB.T6G(SCH_1):GND     I1 @T6G_MB_LIB.T6G(SCH_1):PAGE81
   C11    GND @T6G_MB_LIB.T6G(SCH_1):GND     I1 @T6G_MB_LIB.T6G(SCH_1):PAGE81
    E5    GND @T6G_MB_LIB.T6G(SCH_1):GND     I1 @T6G_MB_LIB.T6G(SCH_1):PAGE81
   E18    GND @T6G_MB_LIB.T6G(SCH_1):GND     I1 @T6G_MB_LIB.T6G(SCH_1):PAGE81
    F2    GND @T6G_MB_LIB.T6G(SCH_1):GND     I1 @T6G_MB_LIB.T6G(SCH_1):PAGE81
   F21    GND @T6G_MB_LIB.T6G(SCH_1):GND     I1 @T6G_MB_LIB.T6G(SCH_1):PAGE81
    H8    GND @T6G_MB_LIB.T6G(SCH_1):GND     I1 @T6G_MB_LIB.T6G(SCH_1):PAGE81
   H10    GND @T6G_MB_LIB.T6G(SCH_1):GND     I1 @T6G_MB_LIB.T6G(SCH_1):PAGE81
   H13    GND @T6G_MB_LIB.T6G(SCH_1):GND     I1 @T6G_MB_LIB.T6G(SCH_1):PAGE81
   H15    GND @T6G_MB_LIB.T6G(SCH_1):GND     I1 @T6G_MB_LIB.T6G(SCH_1):PAGE81
    J9    GND @T6G_MB_LIB.T6G(SCH_1):GND     I1 @T6G_MB_LIB.T6G(SCH_1):PAGE81
   J10    GND @T6G_MB_LIB.T6G(SCH_1):GND     I1 @T6G_MB_LIB.T6G(SCH_1):PAGE81
   J11    GND @T6G_MB_LIB.T6G(SCH_1):GND     I1 @T6G_MB_LIB.T6G(SCH_1):PAGE81
   J12    GND @T6G_MB_LIB.T6G(SCH_1):GND     I1 @T6G_MB_LIB.T6G(SCH_1):PAGE81
   J13    GND @T6G_MB_LIB.T6G(SCH_1):GND     I1 @T6G_MB_LIB.T6G(SCH_1):PAGE81
   J14    GND @T6G_MB_LIB.T6G(SCH_1):GND     I1 @T6G_MB_LIB.T6G(SCH_1):PAGE81
    K9    GND @T6G_MB_LIB.T6G(SCH_1):GND     I1 @T6G_MB_LIB.T6G(SCH_1):PAGE81
   K14    GND @T6G_MB_LIB.T6G(SCH_1):GND     I1 @T6G_MB_LIB.T6G(SCH_1):PAGE81
   K21    GND @T6G_MB_LIB.T6G(SCH_1):GND     I1 @T6G_MB_LIB.T6G(SCH_1):PAGE81
    L2    GND @T6G_MB_LIB.T6G(SCH_1):GND     I1 @T6G_MB_LIB.T6G(SCH_1):PAGE81
    L9    GND @T6G_MB_LIB.T6G(SCH_1):GND     I1 @T6G_MB_LIB.T6G(SCH_1):PAGE81
   L10    GND @T6G_MB_LIB.T6G(SCH_1):GND     I1 @T6G_MB_LIB.T6G(SCH_1):PAGE81
   L13    GND @T6G_MB_LIB.T6G(SCH_1):GND     I1 @T6G_MB_LIB.T6G(SCH_1):PAGE81
   L14    GND @T6G_MB_LIB.T6G(SCH_1):GND     I1 @T6G_MB_LIB.T6G(SCH_1):PAGE81
   L18    GND @T6G_MB_LIB.T6G(SCH_1):GND     I1 @T6G_MB_LIB.T6G(SCH_1):PAGE81
    M4    GND @T6G_MB_LIB.T6G(SCH_1):GND     I1 @T6G_MB_LIB.T6G(SCH_1):PAGE81
    M9    GND @T6G_MB_LIB.T6G(SCH_1):GND     I1 @T6G_MB_LIB.T6G(SCH_1):PAGE81
   M10    GND @T6G_MB_LIB.T6G(SCH_1):GND     I1 @T6G_MB_LIB.T6G(SCH_1):PAGE81
   M13    GND @T6G_MB_LIB.T6G(SCH_1):GND     I1 @T6G_MB_LIB.T6G(SCH_1):PAGE81
   M14    GND @T6G_MB_LIB.T6G(SCH_1):GND     I1 @T6G_MB_LIB.T6G(SCH_1):PAGE81
    N9    GND @T6G_MB_LIB.T6G(SCH_1):GND     I1 @T6G_MB_LIB.T6G(SCH_1):PAGE81
   N14    GND @T6G_MB_LIB.T6G(SCH_1):GND     I1 @T6G_MB_LIB.T6G(SCH_1):PAGE81
   N21    GND @T6G_MB_LIB.T6G(SCH_1):GND     I1 @T6G_MB_LIB.T6G(SCH_1):PAGE81
    P9    GND @T6G_MB_LIB.T6G(SCH_1):GND     I1 @T6G_MB_LIB.T6G(SCH_1):PAGE81
   P10    GND @T6G_MB_LIB.T6G(SCH_1):GND     I1 @T6G_MB_LIB.T6G(SCH_1):PAGE81
   P11    GND @T6G_MB_LIB.T6G(SCH_1):GND     I1 @T6G_MB_LIB.T6G(SCH_1):PAGE81
   P12    GND @T6G_MB_LIB.T6G(SCH_1):GND     I1 @T6G_MB_LIB.T6G(SCH_1):PAGE81
   P13    GND @T6G_MB_LIB.T6G(SCH_1):GND     I1 @T6G_MB_LIB.T6G(SCH_1):PAGE81
   P14    GND @T6G_MB_LIB.T6G(SCH_1):GND     I1 @T6G_MB_LIB.T6G(SCH_1):PAGE81
    R8    GND @T6G_MB_LIB.T6G(SCH_1):GND     I1 @T6G_MB_LIB.T6G(SCH_1):PAGE81
   R15    GND @T6G_MB_LIB.T6G(SCH_1):GND     I1 @T6G_MB_LIB.T6G(SCH_1):PAGE81
    V2    GND @T6G_MB_LIB.T6G(SCH_1):GND     I1 @T6G_MB_LIB.T6G(SCH_1):PAGE81
   V21    GND @T6G_MB_LIB.T6G(SCH_1):GND     I1 @T6G_MB_LIB.T6G(SCH_1):PAGE81
   W12    GND @T6G_MB_LIB.T6G(SCH_1):GND     I1 @T6G_MB_LIB.T6G(SCH_1):PAGE81
   Y16    GND @T6G_MB_LIB.T6G(SCH_1):GND     I1 @T6G_MB_LIB.T6G(SCH_1):PAGE81
    Y7    GND @T6G_MB_LIB.T6G(SCH_1):GND     I1 @T6G_MB_LIB.T6G(SCH_1):PAGE81
   AB1    GND @T6G_MB_LIB.T6G(SCH_1):GND     I1 @T6G_MB_LIB.T6G(SCH_1):PAGE81
  AB22    GND @T6G_MB_LIB.T6G(SCH_1):GND     I1 @T6G_MB_LIB.T6G(SCH_1):PAGE81
   W20 FM_FORCE_ALL_PWRON_R @T6G_MB_LIB.T6G(SCH_1):FM_FORCE_ALL_PWRON_R   I217 @T6G_MB_LIB.T6G(SCH_1):PAGE80
   V18 RST_SMB_RT_ROM_R2_N @T6G_MB_LIB.T6G(SCH_1):RST_SMB_RT_ROM_R2_N   I217 @T6G_MB_LIB.T6G(SCH_1):PAGE80
   V19 TP_FM_CLK_BUFFER_EN_R @T6G_MB_LIB.T6G(SCH_1):TP_FM_CLK_BUFFER_EN_R   I217 @T6G_MB_LIB.T6G(SCH_1):PAGE80
   Y21 FM_CPU1_PWR_GD_IN @T6G_MB_LIB.T6G(SCH_1):FM_CPU1_PWR_GD_IN   I217 @T6G_MB_LIB.T6G(SCH_1):PAGE80
   U17 FM_CPU0_FORCE_SELFREFRESH @T6G_MB_LIB.T6G(SCH_1):FM_CPU0_FORCE_SELFREFRESH   I217 @T6G_MB_LIB.T6G(SCH_1):PAGE80
  AA22 FM_CPU1_PWRGD_OUT @T6G_MB_LIB.T6G(SCH_1):FM_CPU1_PWRGD_OUT   I217 @T6G_MB_LIB.T6G(SCH_1):PAGE80
   W22 FM_CPU1_NMI_SYNC_FLOOD_N @T6G_MB_LIB.T6G(SCH_1):FM_CPU1_NMI_SYNC_FLOOD_N   I217 @T6G_MB_LIB.T6G(SCH_1):PAGE80
   V22 FM_BIOS_USB_RECOVERY @T6G_MB_LIB.T6G(SCH_1):FM_BIOS_USB_RECOVERY   I217 @T6G_MB_LIB.T6G(SCH_1):PAGE80
   R21 CLK_ESPI_CPU0_R1_CLK1 @T6G_MB_LIB.T6G(SCH_1):CLK_ESPI_CPU0_R1_CLK1   I217 @T6G_MB_LIB.T6G(SCH_1):PAGE80
   R22 FM_JTAG_BMC_OE @T6G_MB_LIB.T6G(SCH_1):FM_JTAG_BMC_OE   I217 @T6G_MB_LIB.T6G(SCH_1):PAGE80
   P21 FM_CPU0_HDT_CONN_TESTEN @T6G_MB_LIB.T6G(SCH_1):FM_CPU0_HDT_CONN_TESTEN   I217 @T6G_MB_LIB.T6G(SCH_1):PAGE80
   N22 BIOS_DEBUG_MODE_R @T6G_MB_LIB.T6G(SCH_1):BIOS_DEBUG_MODE_R   I217 @T6G_MB_LIB.T6G(SCH_1):PAGE80
   M21 FM_CPU0_SMERR_N @T6G_MB_LIB.T6G(SCH_1):FM_CPU0_SMERR_N   I217 @T6G_MB_LIB.T6G(SCH_1):PAGE80
   M22 FM_SMERR_LED_R_N @T6G_MB_LIB.T6G(SCH_1):FM_SMERR_LED_R_N   I217 @T6G_MB_LIB.T6G(SCH_1):PAGE80
   L21 RST_RT_CPU0_P0_RESET_R2_N @T6G_MB_LIB.T6G(SCH_1):RST_RT_CPU0_P0_RESET_R2_N   I217 @T6G_MB_LIB.T6G(SCH_1):PAGE80
   K22 RST_RT_CPU0_P0_PERST_R2_N @T6G_MB_LIB.T6G(SCH_1):RST_RT_CPU0_P0_PERST_R2_N   I217 @T6G_MB_LIB.T6G(SCH_1):PAGE80
   L16 CPU1_SPD_HOST_CTRL_R1_N @T6G_MB_LIB.T6G(SCH_1):CPU1_SPD_HOST_CTRL_R1_N   I217 @T6G_MB_LIB.T6G(SCH_1):PAGE80
   L17 APML_CPU0_ALERT_R_N @T6G_MB_LIB.T6G(SCH_1):APML_CPU0_ALERT_R_N   I217 @T6G_MB_LIB.T6G(SCH_1):PAGE80
   H21 FM_RST_CPU1_RESETL_N @T6G_MB_LIB.T6G(SCH_1):FM_RST_CPU1_RESETL_N   I217 @T6G_MB_LIB.T6G(SCH_1):PAGE80
   H22 FM_RST_CPU0_RESETL_N @T6G_MB_LIB.T6G(SCH_1):FM_RST_CPU0_RESETL_N   I217 @T6G_MB_LIB.T6G(SCH_1):PAGE80
   D21 FM_CPU1_SLP_S3_N @T6G_MB_LIB.T6G(SCH_1):FM_CPU1_SLP_S3_N   I217 @T6G_MB_LIB.T6G(SCH_1):PAGE80
   D22 FM_CPU1_SLP_S5_N @T6G_MB_LIB.T6G(SCH_1):FM_CPU1_SLP_S5_N   I217 @T6G_MB_LIB.T6G(SCH_1):PAGE80
   C22 FM_CPU0_SLP_S3_N @T6G_MB_LIB.T6G(SCH_1):FM_CPU0_SLP_S3_N   I217 @T6G_MB_LIB.T6G(SCH_1):PAGE80
   C21 FM_CPU0_SLP_S5_N @T6G_MB_LIB.T6G(SCH_1):FM_CPU0_SLP_S5_N   I217 @T6G_MB_LIB.T6G(SCH_1):PAGE80
   F17 RST_CPU0_PERST0_R_N @T6G_MB_LIB.T6G(SCH_1):RST_CPU0_PERST0_R_N   I217 @T6G_MB_LIB.T6G(SCH_1):PAGE80
   G16 RST_CPU1_PERST1_R_N @T6G_MB_LIB.T6G(SCH_1):RST_CPU1_PERST1_R_N   I217 @T6G_MB_LIB.T6G(SCH_1):PAGE80
   D19 PWRGD_P0V9_RETIMER_CPU0_R2 @T6G_MB_LIB.T6G(SCH_1):PWRGD_P0V9_RETIMER_CPU0_R2   I217 @T6G_MB_LIB.T6G(SCH_1):PAGE80
   D20 RST_CPU0_PERST1_R_N @T6G_MB_LIB.T6G(SCH_1):RST_CPU0_PERST1_R_N   I217 @T6G_MB_LIB.T6G(SCH_1):PAGE80
   E19 RST_CPU1_PERST0_R_N @T6G_MB_LIB.T6G(SCH_1):RST_CPU1_PERST0_R_N   I217 @T6G_MB_LIB.T6G(SCH_1):PAGE80
   E20 PWRGD_P0V9_RETIMER_CPU1_R2 @T6G_MB_LIB.T6G(SCH_1):PWRGD_P0V9_RETIMER_CPU1_R2   I217 @T6G_MB_LIB.T6G(SCH_1):PAGE80
   E22 RST_RT_CPU1_P0_PERST_R2_N @T6G_MB_LIB.T6G(SCH_1):RST_RT_CPU1_P0_PERST_R2_N   I217 @T6G_MB_LIB.T6G(SCH_1):PAGE80
   E21 RST_RT_CPU1_P0_RESET_R2_N @T6G_MB_LIB.T6G(SCH_1):RST_RT_CPU1_P0_RESET_R2_N   I217 @T6G_MB_LIB.T6G(SCH_1):PAGE80
   F22 FM_CPU1_RSMRST_N @T6G_MB_LIB.T6G(SCH_1):FM_CPU1_RSMRST_N   I217 @T6G_MB_LIB.T6G(SCH_1):PAGE80
   G22 FM_CPU0_RSMRST_N @T6G_MB_LIB.T6G(SCH_1):FM_CPU0_RSMRST_N   I217 @T6G_MB_LIB.T6G(SCH_1):PAGE80
   F18 TP_SLOT1_CLKREQ_0_R_N @T6G_MB_LIB.T6G(SCH_1):TP_SLOT1_CLKREQ_0_R_N   I217 @T6G_MB_LIB.T6G(SCH_1):PAGE80
   F19 FM_CPU0_SYS_RESET_N @T6G_MB_LIB.T6G(SCH_1):FM_CPU0_SYS_RESET_N   I217 @T6G_MB_LIB.T6G(SCH_1):PAGE80
   G21 FM_CPU1_SYS_RESET_N @T6G_MB_LIB.T6G(SCH_1):FM_CPU1_SYS_RESET_N   I217 @T6G_MB_LIB.T6G(SCH_1):PAGE80
   G20 FM_CPU0_NV_SAVE_N @T6G_MB_LIB.T6G(SCH_1):FM_CPU0_NV_SAVE_N   I217 @T6G_MB_LIB.T6G(SCH_1):PAGE80
   G19 RST_RT_CPU1_P1_PERST_R2_N @T6G_MB_LIB.T6G(SCH_1):RST_RT_CPU1_P1_PERST_R2_N   I217 @T6G_MB_LIB.T6G(SCH_1):PAGE80
   G18 RST_RT_CPU1_P1_RESET_R2_N @T6G_MB_LIB.T6G(SCH_1):RST_RT_CPU1_P1_RESET_R2_N   I217 @T6G_MB_LIB.T6G(SCH_1):PAGE80
   G17 RST_CPU0_KBRST_N @T6G_MB_LIB.T6G(SCH_1):RST_CPU0_KBRST_N   I217 @T6G_MB_LIB.T6G(SCH_1):PAGE80
   H20 CPU0_JTAG_BUF_R_OE @T6G_MB_LIB.T6G(SCH_1):CPU0_JTAG_BUF_R_OE   I217 @T6G_MB_LIB.T6G(SCH_1):PAGE80
   H19 FM_PWRGD_CPU0_PWROK @T6G_MB_LIB.T6G(SCH_1):FM_PWRGD_CPU0_PWROK   I217 @T6G_MB_LIB.T6G(SCH_1):PAGE80
   H18 FM_CPU1_NV_SAVE_N @T6G_MB_LIB.T6G(SCH_1):FM_CPU1_NV_SAVE_N   I217 @T6G_MB_LIB.T6G(SCH_1):PAGE80
   H17 PVDD11_S3_P0_RESET_N @T6G_MB_LIB.T6G(SCH_1):PVDD11_S3_P0_RESET_N   I217 @T6G_MB_LIB.T6G(SCH_1):PAGE80
   H16 PVDD11_S3_P1_RESET_N @T6G_MB_LIB.T6G(SCH_1):PVDD11_S3_P1_RESET_N   I217 @T6G_MB_LIB.T6G(SCH_1):PAGE80
   J16 FM_CPU0_NMI_SYNC_FLOOD_N @T6G_MB_LIB.T6G(SCH_1):FM_CPU0_NMI_SYNC_FLOOD_N   I217 @T6G_MB_LIB.T6G(SCH_1):PAGE80
   J17 FM_FPGA_DEBUG_LED_CTRL @T6G_MB_LIB.T6G(SCH_1):FM_FPGA_DEBUG_LED_CTRL   I217 @T6G_MB_LIB.T6G(SCH_1):PAGE80
   J18 FM_PWRGD_CPU1_PWROK @T6G_MB_LIB.T6G(SCH_1):FM_PWRGD_CPU1_PWROK   I217 @T6G_MB_LIB.T6G(SCH_1):PAGE80
   J19 FM_P1_PCC0_R_N @T6G_MB_LIB.T6G(SCH_1):FM_P1_PCC0_R_N   I217 @T6G_MB_LIB.T6G(SCH_1):PAGE80
   J21 TP_SLOT2_CLKREQ_0_R_N @T6G_MB_LIB.T6G(SCH_1):TP_SLOT2_CLKREQ_0_R_N   I217 @T6G_MB_LIB.T6G(SCH_1):PAGE80
   J22 FM_CPU0_PWR_BTN_N @T6G_MB_LIB.T6G(SCH_1):FM_CPU0_PWR_BTN_N   I217 @T6G_MB_LIB.T6G(SCH_1):PAGE80
   J20 FM_P1_PCC1_R_N @T6G_MB_LIB.T6G(SCH_1):FM_P1_PCC1_R_N   I217 @T6G_MB_LIB.T6G(SCH_1):PAGE80
   K20 RST_RT_CPU1_P2_PERST_R2_N @T6G_MB_LIB.T6G(SCH_1):RST_RT_CPU1_P2_PERST_R2_N   I217 @T6G_MB_LIB.T6G(SCH_1):PAGE80
   K19 RST_RT_CPU1_P2_RESET_R2_N @T6G_MB_LIB.T6G(SCH_1):RST_RT_CPU1_P2_RESET_R2_N   I217 @T6G_MB_LIB.T6G(SCH_1):PAGE80
   K18 FM_P0_PCC1_R_N @T6G_MB_LIB.T6G(SCH_1):FM_P0_PCC1_R_N   I217 @T6G_MB_LIB.T6G(SCH_1):PAGE80
   K17 FM_P0_PCC0_R_N @T6G_MB_LIB.T6G(SCH_1):FM_P0_PCC0_R_N   I217 @T6G_MB_LIB.T6G(SCH_1):PAGE80
   K16 APML_CPU1_ALERT_R_N @T6G_MB_LIB.T6G(SCH_1):APML_CPU1_ALERT_R_N   I217 @T6G_MB_LIB.T6G(SCH_1):PAGE80
   L19 RST_RT_CPU1_P3_PERST_R2_N @T6G_MB_LIB.T6G(SCH_1):RST_RT_CPU1_P3_PERST_R2_N   I217 @T6G_MB_LIB.T6G(SCH_1):PAGE80
   L20 RST_RT_CPU1_P3_RESET_R2_N @T6G_MB_LIB.T6G(SCH_1):RST_RT_CPU1_P3_RESET_R2_N   I217 @T6G_MB_LIB.T6G(SCH_1):PAGE80
   L22 RST_RT_CPU0_P1_PERST_R2_N @T6G_MB_LIB.T6G(SCH_1):RST_RT_CPU0_P1_PERST_R2_N   I217 @T6G_MB_LIB.T6G(SCH_1):PAGE80
   M17 RST_RT_CPU0_P1_RESET_R2_N @T6G_MB_LIB.T6G(SCH_1):RST_RT_CPU0_P1_RESET_R2_N   I217 @T6G_MB_LIB.T6G(SCH_1):PAGE80
   M20 SMB_CPU_5_R1_SCL @T6G_MB_LIB.T6G(SCH_1):SMB_CPU_5_R1_SCL   I217 @T6G_MB_LIB.T6G(SCH_1):PAGE80
   M19 SMB_CPU_5_R1_SDA @T6G_MB_LIB.T6G(SCH_1):SMB_CPU_5_R1_SDA   I217 @T6G_MB_LIB.T6G(SCH_1):PAGE80
   M16 PWRGD_P3V3_R2 @T6G_MB_LIB.T6G(SCH_1):PWRGD_P3V3_R2   I217 @T6G_MB_LIB.T6G(SCH_1):PAGE80
   N16 FM_CPU1_SMERR_N @T6G_MB_LIB.T6G(SCH_1):FM_CPU1_SMERR_N   I217 @T6G_MB_LIB.T6G(SCH_1):PAGE80
   N17 FM_ESPI_CPU0_ALERT_SEL @T6G_MB_LIB.T6G(SCH_1):FM_ESPI_CPU0_ALERT_SEL   I217 @T6G_MB_LIB.T6G(SCH_1):PAGE80
   N18 RST_RT_CPU0_P2_PERST_R2_N @T6G_MB_LIB.T6G(SCH_1):RST_RT_CPU0_P2_PERST_R2_N   I217 @T6G_MB_LIB.T6G(SCH_1):PAGE80
   N20 TP_PWRGD_P12V_FAN_DR_R @T6G_MB_LIB.T6G(SCH_1):TP_PWRGD_P12V_FAN_DR_R   I217 @T6G_MB_LIB.T6G(SCH_1):PAGE80
   N19 PWRGD_P12V_MEM_R @T6G_MB_LIB.T6G(SCH_1):PWRGD_P12V_MEM_R   I217 @T6G_MB_LIB.T6G(SCH_1):PAGE80
   P22 ESPI_CPU0_CS1_R_N @T6G_MB_LIB.T6G(SCH_1):ESPI_CPU0_CS1_R_N   I217 @T6G_MB_LIB.T6G(SCH_1):PAGE80
   P20 ESPI_CPU0_ALERT_R_N @T6G_MB_LIB.T6G(SCH_1):ESPI_CPU0_ALERT_R_N   I217 @T6G_MB_LIB.T6G(SCH_1):PAGE80
   T22 RST_ESPI_CPU0_RSTOUT_R_N @T6G_MB_LIB.T6G(SCH_1):RST_ESPI_CPU0_RSTOUT_R_N   I217 @T6G_MB_LIB.T6G(SCH_1):PAGE80
   T21 ESPI_CPU0_R1_D0 @T6G_MB_LIB.T6G(SCH_1):ESPI_CPU0_R1_D0   I217 @T6G_MB_LIB.T6G(SCH_1):PAGE80
   P19 ESPI_CPU0_R1_D1 @T6G_MB_LIB.T6G(SCH_1):ESPI_CPU0_R1_D1   I217 @T6G_MB_LIB.T6G(SCH_1):PAGE80
   P18 ESPI_CPU0_R1_D2 @T6G_MB_LIB.T6G(SCH_1):ESPI_CPU0_R1_D2   I217 @T6G_MB_LIB.T6G(SCH_1):PAGE80
   P17 ESPI_CPU0_R1_D3 @T6G_MB_LIB.T6G(SCH_1):ESPI_CPU0_R1_D3   I217 @T6G_MB_LIB.T6G(SCH_1):PAGE80
   P16 FM_HDT_HDR_PWROK @T6G_MB_LIB.T6G(SCH_1):FM_HDT_HDR_PWROK   I217 @T6G_MB_LIB.T6G(SCH_1):PAGE80
   U22 FM_HDT_HDR_RESET_N @T6G_MB_LIB.T6G(SCH_1):FM_HDT_HDR_RESET_N   I217 @T6G_MB_LIB.T6G(SCH_1):PAGE80
   U21 FM_BIOS_POST_CMPLT_BUF_R_N @T6G_MB_LIB.T6G(SCH_1):FM_BIOS_POST_CMPLT_BUF_R_N   I217 @T6G_MB_LIB.T6G(SCH_1):PAGE80
   R20 RST_RT_CPU0_P2_RESET_R2_N @T6G_MB_LIB.T6G(SCH_1):RST_RT_CPU0_P2_RESET_R2_N   I217 @T6G_MB_LIB.T6G(SCH_1):PAGE80
   R19 SCM_USB_OC_R_N @T6G_MB_LIB.T6G(SCH_1):SCM_USB_OC_R_N   I217 @T6G_MB_LIB.T6G(SCH_1):PAGE80
   R18 CPU0_SPD_HOST_CTRL_R1_N @T6G_MB_LIB.T6G(SCH_1):CPU0_SPD_HOST_CTRL_R1_N   I217 @T6G_MB_LIB.T6G(SCH_1):PAGE80
   R17 FM_PLD_CPU1_PRSNT_HDT @T6G_MB_LIB.T6G(SCH_1):FM_PLD_CPU1_PRSNT_HDT   I217 @T6G_MB_LIB.T6G(SCH_1):PAGE80
   R16 CPU1_JTAG_BUF_R_OE @T6G_MB_LIB.T6G(SCH_1):CPU1_JTAG_BUF_R_OE   I217 @T6G_MB_LIB.T6G(SCH_1):PAGE80
   T20 SCM_IRQ_1V8_R_N @T6G_MB_LIB.T6G(SCH_1):SCM_IRQ_1V8_R_N   I217 @T6G_MB_LIB.T6G(SCH_1):PAGE80
   T19 RST_RT_CPU0_P3_PERST_R2_N @T6G_MB_LIB.T6G(SCH_1):RST_RT_CPU0_P3_PERST_R2_N   I217 @T6G_MB_LIB.T6G(SCH_1):PAGE80
   T18 P12V_ALL_PWROK_R @T6G_MB_LIB.T6G(SCH_1):P12V_ALL_PWROK_R   I217 @T6G_MB_LIB.T6G(SCH_1):PAGE80
   T17 RST_RT_CPU0_P3_RESET_R2_N @T6G_MB_LIB.T6G(SCH_1):RST_RT_CPU0_P3_RESET_R2_N   I217 @T6G_MB_LIB.T6G(SCH_1):PAGE80
   U20 BMC_JTAG_SEL_R @T6G_MB_LIB.T6G(SCH_1):BMC_JTAG_SEL_R   I217 @T6G_MB_LIB.T6G(SCH_1):PAGE80
   Y22 FM_ROM_LS_EN @T6G_MB_LIB.T6G(SCH_1):FM_ROM_LS_EN   I217 @T6G_MB_LIB.T6G(SCH_1):PAGE80
   W21 FM_ROM_SD_LS_OE @T6G_MB_LIB.T6G(SCH_1):FM_ROM_SD_LS_OE   I217 @T6G_MB_LIB.T6G(SCH_1):PAGE80
   U19 FM_SPD_CPU0_SWITCH_CTRL_R_N @T6G_MB_LIB.T6G(SCH_1):FM_SPD_CPU0_SWITCH_CTRL_R_N   I217 @T6G_MB_LIB.T6G(SCH_1):PAGE80
   U18 FM_PLD_CPU0_PRSNT_HDT @T6G_MB_LIB.T6G(SCH_1):FM_PLD_CPU0_PRSNT_HDT   I217 @T6G_MB_LIB.T6G(SCH_1):PAGE80
   W19 FM_CPU1_FORCE_SELFREFRESH @T6G_MB_LIB.T6G(SCH_1):FM_CPU1_FORCE_SELFREFRESH   I217 @T6G_MB_LIB.T6G(SCH_1):PAGE80
   Y20 RST_SMB_RT_R2_N @T6G_MB_LIB.T6G(SCH_1):RST_SMB_RT_R2_N   I217 @T6G_MB_LIB.T6G(SCH_1):PAGE80

 U19 M24M02DRMN6TP-M24M02-DRMN6TP,SMLF,IC,AKE33Z00600
     8 P1V8_CPU1_RT_1D @T6G_MB_LIB.T6G(SCH_1):P1V8_CPU1_RT_1D     I5 @T6G_MB_LIB.T6G(SCH_1):PAGE442
     7    GND @T6G_MB_LIB.T6G(SCH_1):GND     I5 @T6G_MB_LIB.T6G(SCH_1):PAGE442
     6 SMB_RT_CPU1_P1_ROM_SCL @T6G_MB_LIB.T6G(SCH_1):SMB_RT_CPU1_P1_ROM_SCL     I5 @T6G_MB_LIB.T6G(SCH_1):PAGE442
     5 SMB_RT_CPU1_P1_ROM_SDA @T6G_MB_LIB.T6G(SCH_1):SMB_RT_CPU1_P1_ROM_SDA     I5 @T6G_MB_LIB.T6G(SCH_1):PAGE442
     4    GND @T6G_MB_LIB.T6G(SCH_1):GND     I5 @T6G_MB_LIB.T6G(SCH_1):PAGE442
     3 U19_E2 @T6G_MB_LIB.T6G(SCH_1):U19_E2     I5 @T6G_MB_LIB.T6G(SCH_1):PAGE442
     2     NC     NC     I5 @T6G_MB_LIB.T6G(SCH_1):PAGE442
     1     NC     NC     I5 @T6G_MB_LIB.T6G(SCH_1):PAGE442

 U20 M24M02DRMN6TP-M24M02-DRMN6TP,SMLF,IC,AKE33Z00600
     8 P1V8_CPU1_RT_1D @T6G_MB_LIB.T6G(SCH_1):P1V8_CPU1_RT_1D     I5 @T6G_MB_LIB.T6G(SCH_1):PAGE453
     7    GND @T6G_MB_LIB.T6G(SCH_1):GND     I5 @T6G_MB_LIB.T6G(SCH_1):PAGE453
     6 SMB_RT_CPU1_P2_ROM_SCL @T6G_MB_LIB.T6G(SCH_1):SMB_RT_CPU1_P2_ROM_SCL     I5 @T6G_MB_LIB.T6G(SCH_1):PAGE453
     5 SMB_RT_CPU1_P2_ROM_SDA @T6G_MB_LIB.T6G(SCH_1):SMB_RT_CPU1_P2_ROM_SDA     I5 @T6G_MB_LIB.T6G(SCH_1):PAGE453
     4    GND @T6G_MB_LIB.T6G(SCH_1):GND     I5 @T6G_MB_LIB.T6G(SCH_1):PAGE453
     3 U20_E2 @T6G_MB_LIB.T6G(SCH_1):U20_E2     I5 @T6G_MB_LIB.T6G(SCH_1):PAGE453
     2     NC     NC     I5 @T6G_MB_LIB.T6G(SCH_1):PAGE453
     1     NC     NC     I5 @T6G_MB_LIB.T6G(SCH_1):PAGE453

 U21 M24M02DRMN6TP-M24M02-DRMN6TP,SMLF,IC,AKE33Z00600
     8 P1V8_CPU1_RT_1D @T6G_MB_LIB.T6G(SCH_1):P1V8_CPU1_RT_1D     I5 @T6G_MB_LIB.T6G(SCH_1):PAGE464
     7    GND @T6G_MB_LIB.T6G(SCH_1):GND     I5 @T6G_MB_LIB.T6G(SCH_1):PAGE464
     6 SMB_RT_CPU1_P3_ROM_SCL @T6G_MB_LIB.T6G(SCH_1):SMB_RT_CPU1_P3_ROM_SCL     I5 @T6G_MB_LIB.T6G(SCH_1):PAGE464
     5 SMB_RT_CPU1_P3_ROM_SDA @T6G_MB_LIB.T6G(SCH_1):SMB_RT_CPU1_P3_ROM_SDA     I5 @T6G_MB_LIB.T6G(SCH_1):PAGE464
     4    GND @T6G_MB_LIB.T6G(SCH_1):GND     I5 @T6G_MB_LIB.T6G(SCH_1):PAGE464
     3 U21_E2 @T6G_MB_LIB.T6G(SCH_1):U21_E2     I5 @T6G_MB_LIB.T6G(SCH_1):PAGE464
     2     NC     NC     I5 @T6G_MB_LIB.T6G(SCH_1):PAGE464
     1     NC     NC     I5 @T6G_MB_LIB.T6G(SCH_1):PAGE464

 U22 TCA9548APWR-TCA9548APWR,SMLF,IC,AL009548K02
     1 RT_ROM_SMB_MUX_ADDR0 @T6G_MB_LIB.T6G(SCH_1):RT_ROM_SMB_MUX_ADDR0    I94 @T6G_MB_LIB.T6G(SCH_1):PAGE377
     2 RT_ROM_SMB_MUX_ADDR1 @T6G_MB_LIB.T6G(SCH_1):RT_ROM_SMB_MUX_ADDR1    I94 @T6G_MB_LIB.T6G(SCH_1):PAGE377
     3 RST_SMB_RT_ROM_N @T6G_MB_LIB.T6G(SCH_1):RST_SMB_RT_ROM_N    I94 @T6G_MB_LIB.T6G(SCH_1):PAGE377
     4 SMB_RT_CPU1_P0_ROM_MUX_2D_R_SDA @T6G_MB_LIB.T6G(SCH_1):SMB_RT_CPU1_P0_ROM_MUX_2D_R_SDA    I94 @T6G_MB_LIB.T6G(SCH_1):PAGE377
     5 SMB_RT_CPU1_P0_ROM_MUX_2D_R_SCL @T6G_MB_LIB.T6G(SCH_1):SMB_RT_CPU1_P0_ROM_MUX_2D_R_SCL    I94 @T6G_MB_LIB.T6G(SCH_1):PAGE377
     6 SMB_RT_CPU1_P1_ROM_MUX_2D_R_SDA @T6G_MB_LIB.T6G(SCH_1):SMB_RT_CPU1_P1_ROM_MUX_2D_R_SDA    I94 @T6G_MB_LIB.T6G(SCH_1):PAGE377
     7 SMB_RT_CPU1_P1_ROM_MUX_2D_R_SCL @T6G_MB_LIB.T6G(SCH_1):SMB_RT_CPU1_P1_ROM_MUX_2D_R_SCL    I94 @T6G_MB_LIB.T6G(SCH_1):PAGE377
     8 SMB_RT_CPU1_P3_ROM_MUX_2D_R_SDA @T6G_MB_LIB.T6G(SCH_1):SMB_RT_CPU1_P3_ROM_MUX_2D_R_SDA    I94 @T6G_MB_LIB.T6G(SCH_1):PAGE377
     9 SMB_RT_CPU1_P3_ROM_MUX_2D_R_SCL @T6G_MB_LIB.T6G(SCH_1):SMB_RT_CPU1_P3_ROM_MUX_2D_R_SCL    I94 @T6G_MB_LIB.T6G(SCH_1):PAGE377
    10 SMB_RT_CPU1_P2_ROM_MUX_2D_R_SDA @T6G_MB_LIB.T6G(SCH_1):SMB_RT_CPU1_P2_ROM_MUX_2D_R_SDA    I94 @T6G_MB_LIB.T6G(SCH_1):PAGE377
    11 SMB_RT_CPU1_P2_ROM_MUX_2D_R_SCL @T6G_MB_LIB.T6G(SCH_1):SMB_RT_CPU1_P2_ROM_MUX_2D_R_SCL    I94 @T6G_MB_LIB.T6G(SCH_1):PAGE377
    12    GND @T6G_MB_LIB.T6G(SCH_1):GND    I94 @T6G_MB_LIB.T6G(SCH_1):PAGE377
    24 P1V8_AUX @T6G_MB_LIB.T6G(SCH_1):P1V8_AUX    I94 @T6G_MB_LIB.T6G(SCH_1):PAGE377
    23 SMB_MUX_RT_ROM_SDA @T6G_MB_LIB.T6G(SCH_1):SMB_MUX_RT_ROM_SDA    I94 @T6G_MB_LIB.T6G(SCH_1):PAGE377
    22 SMB_MUX_RT_ROM_SCL @T6G_MB_LIB.T6G(SCH_1):SMB_MUX_RT_ROM_SCL    I94 @T6G_MB_LIB.T6G(SCH_1):PAGE377
    21 RT_ROM_SMB_MUX_ADDR2 @T6G_MB_LIB.T6G(SCH_1):RT_ROM_SMB_MUX_ADDR2    I94 @T6G_MB_LIB.T6G(SCH_1):PAGE377
    20 SMB_RT_CPU0_P2_ROM_MUX_2D_R_SCL @T6G_MB_LIB.T6G(SCH_1):SMB_RT_CPU0_P2_ROM_MUX_2D_R_SCL    I94 @T6G_MB_LIB.T6G(SCH_1):PAGE377
    19 SMB_RT_CPU0_P2_ROM_MUX_2D_R_SDA @T6G_MB_LIB.T6G(SCH_1):SMB_RT_CPU0_P2_ROM_MUX_2D_R_SDA    I94 @T6G_MB_LIB.T6G(SCH_1):PAGE377
    18 SMB_RT_CPU0_P3_ROM_MUX_2D_R_SCL @T6G_MB_LIB.T6G(SCH_1):SMB_RT_CPU0_P3_ROM_MUX_2D_R_SCL    I94 @T6G_MB_LIB.T6G(SCH_1):PAGE377
    17 SMB_RT_CPU0_P3_ROM_MUX_2D_R_SDA @T6G_MB_LIB.T6G(SCH_1):SMB_RT_CPU0_P3_ROM_MUX_2D_R_SDA    I94 @T6G_MB_LIB.T6G(SCH_1):PAGE377
    16 SMB_RT_CPU0_P1_ROM_MUX_2D_R_SCL @T6G_MB_LIB.T6G(SCH_1):SMB_RT_CPU0_P1_ROM_MUX_2D_R_SCL    I94 @T6G_MB_LIB.T6G(SCH_1):PAGE377
    15 SMB_RT_CPU0_P1_ROM_MUX_2D_R_SDA @T6G_MB_LIB.T6G(SCH_1):SMB_RT_CPU0_P1_ROM_MUX_2D_R_SDA    I94 @T6G_MB_LIB.T6G(SCH_1):PAGE377
    14 SMB_RT_CPU0_P0_ROM_MUX_2D_R_SCL @T6G_MB_LIB.T6G(SCH_1):SMB_RT_CPU0_P0_ROM_MUX_2D_R_SCL    I94 @T6G_MB_LIB.T6G(SCH_1):PAGE377
    13 SMB_RT_CPU0_P0_ROM_MUX_2D_R_SDA @T6G_MB_LIB.T6G(SCH_1):SMB_RT_CPU0_P0_ROM_MUX_2D_R_SDA    I94 @T6G_MB_LIB.T6G(SCH_1):PAGE377

 U23 74LVC1G08W57-74LVC1G08W5-7,SMLF,IC,AL1G0008020
     1 P12V_OCP_SFF_EN_R3 @T6G_MB_LIB.T6G(SCH_1):P12V_OCP_SFF_EN_R3    I36 @T6G_MB_LIB.T6G(SCH_1):PAGE340
     2 HP_LVC3_OCP_SFF_PRSNT2 @T6G_MB_LIB.T6G(SCH_1):HP_LVC3_OCP_SFF_PRSNT2    I36 @T6G_MB_LIB.T6G(SCH_1):PAGE340
     3    GND @T6G_MB_LIB.T6G(SCH_1):GND    I36 @T6G_MB_LIB.T6G(SCH_1):PAGE340
     4 P12V_OCP_SFF_BUF_EN @T6G_MB_LIB.T6G(SCH_1):P12V_OCP_SFF_BUF_EN    I36 @T6G_MB_LIB.T6G(SCH_1):PAGE340
     5 P3V3_AUX @T6G_MB_LIB.T6G(SCH_1):P3V3_AUX    I36 @T6G_MB_LIB.T6G(SCH_1):PAGE340

 U24 MOSFET_N_SMLF-BSS138K,BSS138K,IC,BAM138K0000
     G HP_LVC3_OCP_SFF_PRSNT2_N @T6G_MB_LIB.T6G(SCH_1):HP_LVC3_OCP_SFF_PRSNT2_N    I31 @T6G_MB_LIB.T6G(SCH_1):PAGE340
     D HP_LVC3_OCP_SFF_PRSNT2 @T6G_MB_LIB.T6G(SCH_1):HP_LVC3_OCP_SFF_PRSNT2    I31 @T6G_MB_LIB.T6G(SCH_1):PAGE340
     S    GND @T6G_MB_LIB.T6G(SCH_1):GND    I31 @T6G_MB_LIB.T6G(SCH_1):PAGE340

 U25 GENOA_SP5-SOCKET6096_13568-001,SMLF,IO,DGA^6000030
  AR74 M_A_CPU0_ALERT_R_N @T6G_MB_LIB.T6G(SCH_1):M_A_CPU0_ALERT_R_N   I200 @T6G_MB_LIB.T6G(SCH_1):PAGE10
  AT74 M_A_CPU0_RESET_N @T6G_MB_LIB.T6G(SCH_1):M_A_CPU0_RESET_N   I200 @T6G_MB_LIB.T6G(SCH_1):PAGE10
  CE73 M_A_CPU0_SB_DQS_DN<5> @T6G_MB_LIB.T6G(SCH_1):M_A_CPU0_SB_DQS_DN(5)   I200 @T6G_MB_LIB.T6G(SCH_1):PAGE10
  CK74 M_A_CPU0_SB_DQS_DP<1> @T6G_MB_LIB.T6G(SCH_1):M_A_CPU0_SB_DQS_DP(1)   I200 @T6G_MB_LIB.T6G(SCH_1):PAGE10
  DE73 M_A_CPU0_SB_DQ<29> @T6G_MB_LIB.T6G(SCH_1):M_A_CPU0_SB_DQ(29)   I200 @T6G_MB_LIB.T6G(SCH_1):PAGE10
  CR74 M_A_CPU0_SB_DQ<18> @T6G_MB_LIB.T6G(SCH_1):M_A_CPU0_SB_DQ(18)   I200 @T6G_MB_LIB.T6G(SCH_1):PAGE10
  CD72 M_A_CPU0_SB_DQ<3> @T6G_MB_LIB.T6G(SCH_1):M_A_CPU0_SB_DQ(3)   I200 @T6G_MB_LIB.T6G(SCH_1):PAGE10
  AA73 M_A_CPU0_SA_DQS_DP<7> @T6G_MB_LIB.T6G(SCH_1):M_A_CPU0_SA_DQS_DP(7)   I200 @T6G_MB_LIB.T6G(SCH_1):PAGE10
   J74 M_A_CPU0_SA_DQ<4> @T6G_MB_LIB.T6G(SCH_1):M_A_CPU0_SA_DQ(4)   I200 @T6G_MB_LIB.T6G(SCH_1):PAGE10
  AU74     NC     NC   I200 @T6G_MB_LIB.T6G(SCH_1):PAGE10
  AW73 M_A_CPU0_SA_CS_N<1> @T6G_MB_LIB.T6G(SCH_1):M_A_CPU0_SA_CS_N(1)   I200 @T6G_MB_LIB.T6G(SCH_1):PAGE10
  CL73 M_A_CPU0_SB_DQS_DN<6> @T6G_MB_LIB.T6G(SCH_1):M_A_CPU0_SB_DQS_DN(6)   I200 @T6G_MB_LIB.T6G(SCH_1):PAGE10
  CT74 M_A_CPU0_SB_DQS_DP<2> @T6G_MB_LIB.T6G(SCH_1):M_A_CPU0_SB_DQS_DP(2)   I200 @T6G_MB_LIB.T6G(SCH_1):PAGE10
  CT72 M_A_CPU0_SB_DQ<19> @T6G_MB_LIB.T6G(SCH_1):M_A_CPU0_SB_DQ(19)   I200 @T6G_MB_LIB.T6G(SCH_1):PAGE10
  CF74 M_A_CPU0_SB_DQ<4> @T6G_MB_LIB.T6G(SCH_1):M_A_CPU0_SB_DQ(4)   I200 @T6G_MB_LIB.T6G(SCH_1):PAGE10
  AG73 M_A_CPU0_SA_DQS_DP<8> @T6G_MB_LIB.T6G(SCH_1):M_A_CPU0_SA_DQS_DP(8)   I200 @T6G_MB_LIB.T6G(SCH_1):PAGE10
  AH74 M_A_CPU0_SA_DQ<30> @T6G_MB_LIB.T6G(SCH_1):M_A_CPU0_SA_DQ(30)   I200 @T6G_MB_LIB.T6G(SCH_1):PAGE10
   K72 M_A_CPU0_SA_DQ<5> @T6G_MB_LIB.T6G(SCH_1):M_A_CPU0_SA_DQ(5)   I200 @T6G_MB_LIB.T6G(SCH_1):PAGE10
  AV72     NC     NC   I200 @T6G_MB_LIB.T6G(SCH_1):PAGE10
  CU73 M_A_CPU0_SB_DQS_DN<7> @T6G_MB_LIB.T6G(SCH_1):M_A_CPU0_SB_DQS_DN(7)   I200 @T6G_MB_LIB.T6G(SCH_1):PAGE10
  DB74 M_A_CPU0_SB_DQS_DP<3> @T6G_MB_LIB.T6G(SCH_1):M_A_CPU0_SB_DQS_DP(3)   I200 @T6G_MB_LIB.T6G(SCH_1):PAGE10
  CG73 M_A_CPU0_SB_DQ<5> @T6G_MB_LIB.T6G(SCH_1):M_A_CPU0_SB_DQ(5)   I200 @T6G_MB_LIB.T6G(SCH_1):PAGE10
  AN73 M_A_CPU0_SA_DQS_DP<9> @T6G_MB_LIB.T6G(SCH_1):M_A_CPU0_SA_DQS_DP(9)   I200 @T6G_MB_LIB.T6G(SCH_1):PAGE10
  AJ73 M_A_CPU0_SA_DQ<31> @T6G_MB_LIB.T6G(SCH_1):M_A_CPU0_SA_DQ(31)   I200 @T6G_MB_LIB.T6G(SCH_1):PAGE10
  AA74 M_A_CPU0_SA_DQ<20> @T6G_MB_LIB.T6G(SCH_1):M_A_CPU0_SA_DQ(20)   I200 @T6G_MB_LIB.T6G(SCH_1):PAGE10
   K74 M_A_CPU0_SA_DQ<6> @T6G_MB_LIB.T6G(SCH_1):M_A_CPU0_SA_DQ(6)   I200 @T6G_MB_LIB.T6G(SCH_1):PAGE10
  AJ74 M_A_CPU0_SA_CB<0> @T6G_MB_LIB.T6G(SCH_1):M_A_CPU0_SA_CB(0)   I200 @T6G_MB_LIB.T6G(SCH_1):PAGE10
  DC73 M_A_CPU0_SB_DQS_DN<8> @T6G_MB_LIB.T6G(SCH_1):M_A_CPU0_SB_DQS_DN(8)   I200 @T6G_MB_LIB.T6G(SCH_1):PAGE10
  BY72 M_A_CPU0_SB_DQS_DP<4> @T6G_MB_LIB.T6G(SCH_1):M_A_CPU0_SB_DQS_DP(4)   I200 @T6G_MB_LIB.T6G(SCH_1):PAGE10
  CG74 M_A_CPU0_SB_DQ<6> @T6G_MB_LIB.T6G(SCH_1):M_A_CPU0_SB_DQ(6)   I200 @T6G_MB_LIB.T6G(SCH_1):PAGE10
  AB72 M_A_CPU0_SA_DQ<21> @T6G_MB_LIB.T6G(SCH_1):M_A_CPU0_SA_DQ(21)   I200 @T6G_MB_LIB.T6G(SCH_1):PAGE10
   M74 M_A_CPU0_SA_DQ<10> @T6G_MB_LIB.T6G(SCH_1):M_A_CPU0_SA_DQ(10)   I200 @T6G_MB_LIB.T6G(SCH_1):PAGE10
   L73 M_A_CPU0_SA_DQ<7> @T6G_MB_LIB.T6G(SCH_1):M_A_CPU0_SA_DQ(7)   I200 @T6G_MB_LIB.T6G(SCH_1):PAGE10
  AK72 M_A_CPU0_SA_CB<1> @T6G_MB_LIB.T6G(SCH_1):M_A_CPU0_SA_CB(1)   I200 @T6G_MB_LIB.T6G(SCH_1):PAGE10
  BW74 M_A_CPU0_SB_DQS_DN<9> @T6G_MB_LIB.T6G(SCH_1):M_A_CPU0_SB_DQS_DN(9)   I200 @T6G_MB_LIB.T6G(SCH_1):PAGE10
  CF72 M_A_CPU0_SB_DQS_DP<5> @T6G_MB_LIB.T6G(SCH_1):M_A_CPU0_SB_DQS_DP(5)   I200 @T6G_MB_LIB.T6G(SCH_1):PAGE10
  CH72 M_A_CPU0_SB_DQ<7> @T6G_MB_LIB.T6G(SCH_1):M_A_CPU0_SB_DQ(7)   I200 @T6G_MB_LIB.T6G(SCH_1):PAGE10
  AB74 M_A_CPU0_SA_DQ<22> @T6G_MB_LIB.T6G(SCH_1):M_A_CPU0_SA_DQ(22)   I200 @T6G_MB_LIB.T6G(SCH_1):PAGE10
   N73 M_A_CPU0_SA_DQ<11> @T6G_MB_LIB.T6G(SCH_1):M_A_CPU0_SA_DQ(11)   I200 @T6G_MB_LIB.T6G(SCH_1):PAGE10
   L74 M_A_CPU0_SA_DQ<8> @T6G_MB_LIB.T6G(SCH_1):M_A_CPU0_SA_DQ(8)   I200 @T6G_MB_LIB.T6G(SCH_1):PAGE10
  AK74 M_A_CPU0_SA_CB<2> @T6G_MB_LIB.T6G(SCH_1):M_A_CPU0_SA_CB(2)   I200 @T6G_MB_LIB.T6G(SCH_1):PAGE10
  CM72 M_A_CPU0_SB_DQS_DP<6> @T6G_MB_LIB.T6G(SCH_1):M_A_CPU0_SB_DQS_DP(6)   I200 @T6G_MB_LIB.T6G(SCH_1):PAGE10
  CH74 M_A_CPU0_SB_DQ<8> @T6G_MB_LIB.T6G(SCH_1):M_A_CPU0_SB_DQ(8)   I200 @T6G_MB_LIB.T6G(SCH_1):PAGE10
  BM72 M_A_CPU0_SB_CS_N<0> @T6G_MB_LIB.T6G(SCH_1):M_A_CPU0_SB_CS_N(0)   I200 @T6G_MB_LIB.T6G(SCH_1):PAGE10
  AC73 M_A_CPU0_SA_DQ<23> @T6G_MB_LIB.T6G(SCH_1):M_A_CPU0_SA_DQ(23)   I200 @T6G_MB_LIB.T6G(SCH_1):PAGE10
   R74 M_A_CPU0_SA_DQ<12> @T6G_MB_LIB.T6G(SCH_1):M_A_CPU0_SA_DQ(12)   I200 @T6G_MB_LIB.T6G(SCH_1):PAGE10
   M72 M_A_CPU0_SA_DQ<9> @T6G_MB_LIB.T6G(SCH_1):M_A_CPU0_SA_DQ(9)   I200 @T6G_MB_LIB.T6G(SCH_1):PAGE10
  AL73 M_A_CPU0_SA_CB<3> @T6G_MB_LIB.T6G(SCH_1):M_A_CPU0_SA_CB(3)   I200 @T6G_MB_LIB.T6G(SCH_1):PAGE10
  CV72 M_A_CPU0_SB_DQS_DP<7> @T6G_MB_LIB.T6G(SCH_1):M_A_CPU0_SB_DQS_DP(7)   I200 @T6G_MB_LIB.T6G(SCH_1):PAGE10
  CJ73 M_A_CPU0_SB_DQ<9> @T6G_MB_LIB.T6G(SCH_1):M_A_CPU0_SB_DQ(9)   I200 @T6G_MB_LIB.T6G(SCH_1):PAGE10
  BL73     NC     NC   I200 @T6G_MB_LIB.T6G(SCH_1):PAGE10
  BN74 M_A_CPU0_SB_CS_N<1> @T6G_MB_LIB.T6G(SCH_1):M_A_CPU0_SB_CS_N(1)   I200 @T6G_MB_LIB.T6G(SCH_1):PAGE10
   H74 M_A_CPU0_SA_DQS_DN<0> @T6G_MB_LIB.T6G(SCH_1):M_A_CPU0_SA_DQS_DN(0)   I200 @T6G_MB_LIB.T6G(SCH_1):PAGE10
  AC74 M_A_CPU0_SA_DQ<24> @T6G_MB_LIB.T6G(SCH_1):M_A_CPU0_SA_DQ(24)   I200 @T6G_MB_LIB.T6G(SCH_1):PAGE10
   T72 M_A_CPU0_SA_DQ<13> @T6G_MB_LIB.T6G(SCH_1):M_A_CPU0_SA_DQ(13)   I200 @T6G_MB_LIB.T6G(SCH_1):PAGE10
  AN74 M_A_CPU0_SA_CB<4> @T6G_MB_LIB.T6G(SCH_1):M_A_CPU0_SA_CB(4)   I200 @T6G_MB_LIB.T6G(SCH_1):PAGE10
  DD72 M_A_CPU0_SB_DQS_DP<8> @T6G_MB_LIB.T6G(SCH_1):M_A_CPU0_SB_DQS_DP(8)   I200 @T6G_MB_LIB.T6G(SCH_1):PAGE10
  DE74 M_A_CPU0_SB_DQ<30> @T6G_MB_LIB.T6G(SCH_1):M_A_CPU0_SB_DQ(30)   I200 @T6G_MB_LIB.T6G(SCH_1):PAGE10
  BM74     NC     NC   I200 @T6G_MB_LIB.T6G(SCH_1):PAGE10
   P74 M_A_CPU0_SA_DQS_DN<1> @T6G_MB_LIB.T6G(SCH_1):M_A_CPU0_SA_DQS_DN(1)   I200 @T6G_MB_LIB.T6G(SCH_1):PAGE10
  AD72 M_A_CPU0_SA_DQ<25> @T6G_MB_LIB.T6G(SCH_1):M_A_CPU0_SA_DQ(25)   I200 @T6G_MB_LIB.T6G(SCH_1):PAGE10
   T74 M_A_CPU0_SA_DQ<14> @T6G_MB_LIB.T6G(SCH_1):M_A_CPU0_SA_DQ(14)   I200 @T6G_MB_LIB.T6G(SCH_1):PAGE10
  AP72 M_A_CPU0_SA_CB<5> @T6G_MB_LIB.T6G(SCH_1):M_A_CPU0_SA_CB(5)   I200 @T6G_MB_LIB.T6G(SCH_1):PAGE10
  DF74 M_A_CPU0_SB_DQ<31> @T6G_MB_LIB.T6G(SCH_1):M_A_CPU0_SB_DQ(31)   I200 @T6G_MB_LIB.T6G(SCH_1):PAGE10
  CV74 M_A_CPU0_SB_DQ<20> @T6G_MB_LIB.T6G(SCH_1):M_A_CPU0_SB_DQ(20)   I200 @T6G_MB_LIB.T6G(SCH_1):PAGE10
  BY74 M_A_CPU0_SB_CB<0> @T6G_MB_LIB.T6G(SCH_1):M_A_CPU0_SB_CB(0)   I200 @T6G_MB_LIB.T6G(SCH_1):PAGE10
   Y74 M_A_CPU0_SA_DQS_DN<2> @T6G_MB_LIB.T6G(SCH_1):M_A_CPU0_SA_DQS_DN(2)   I200 @T6G_MB_LIB.T6G(SCH_1):PAGE10
  AD74 M_A_CPU0_SA_DQ<26> @T6G_MB_LIB.T6G(SCH_1):M_A_CPU0_SA_DQ(26)   I200 @T6G_MB_LIB.T6G(SCH_1):PAGE10
   U73 M_A_CPU0_SA_DQ<15> @T6G_MB_LIB.T6G(SCH_1):M_A_CPU0_SA_DQ(15)   I200 @T6G_MB_LIB.T6G(SCH_1):PAGE10
  AP74 M_A_CPU0_SA_CB<6> @T6G_MB_LIB.T6G(SCH_1):M_A_CPU0_SA_CB(6)   I200 @T6G_MB_LIB.T6G(SCH_1):PAGE10
  BN73 M_A_CPU0_SA_RSP<0> @T6G_MB_LIB.T6G(SCH_1):M_A_CPU0_SA_RSP(0)   I200 @T6G_MB_LIB.T6G(SCH_1):PAGE10
  CW73 M_A_CPU0_SB_DQ<21> @T6G_MB_LIB.T6G(SCH_1):M_A_CPU0_SB_DQ(21)   I200 @T6G_MB_LIB.T6G(SCH_1):PAGE10
  CJ74 M_A_CPU0_SB_DQ<10> @T6G_MB_LIB.T6G(SCH_1):M_A_CPU0_SB_DQ(10)   I200 @T6G_MB_LIB.T6G(SCH_1):PAGE10
  CA73 M_A_CPU0_SB_CB<1> @T6G_MB_LIB.T6G(SCH_1):M_A_CPU0_SB_CB(1)   I200 @T6G_MB_LIB.T6G(SCH_1):PAGE10
  AF74 M_A_CPU0_SA_DQS_DN<3> @T6G_MB_LIB.T6G(SCH_1):M_A_CPU0_SA_DQS_DN(3)   I200 @T6G_MB_LIB.T6G(SCH_1):PAGE10
  AE73 M_A_CPU0_SA_DQ<27> @T6G_MB_LIB.T6G(SCH_1):M_A_CPU0_SA_DQ(27)   I200 @T6G_MB_LIB.T6G(SCH_1):PAGE10
   U74 M_A_CPU0_SA_DQ<16> @T6G_MB_LIB.T6G(SCH_1):M_A_CPU0_SA_DQ(16)   I200 @T6G_MB_LIB.T6G(SCH_1):PAGE10
  AR73 M_A_CPU0_SA_CB<7> @T6G_MB_LIB.T6G(SCH_1):M_A_CPU0_SA_CB(7)   I200 @T6G_MB_LIB.T6G(SCH_1):PAGE10
  AW74 M_A_CPU0_SA_CA<0> @T6G_MB_LIB.T6G(SCH_1):M_A_CPU0_SA_CA(0)   I200 @T6G_MB_LIB.T6G(SCH_1):PAGE10
  BP72     NC     NC   I200 @T6G_MB_LIB.T6G(SCH_1):PAGE10
  CW74 M_A_CPU0_SB_DQ<22> @T6G_MB_LIB.T6G(SCH_1):M_A_CPU0_SB_DQ(22)   I200 @T6G_MB_LIB.T6G(SCH_1):PAGE10
  CK72 M_A_CPU0_SB_DQ<11> @T6G_MB_LIB.T6G(SCH_1):M_A_CPU0_SB_DQ(11)   I200 @T6G_MB_LIB.T6G(SCH_1):PAGE10
  CA74 M_A_CPU0_SB_CB<2> @T6G_MB_LIB.T6G(SCH_1):M_A_CPU0_SB_CB(2)   I200 @T6G_MB_LIB.T6G(SCH_1):PAGE10
  BG73 M_A_CPU0_SB_CA<0> @T6G_MB_LIB.T6G(SCH_1):M_A_CPU0_SB_CA(0)   I200 @T6G_MB_LIB.T6G(SCH_1):PAGE10
  AM74 M_A_CPU0_SA_DQS_DN<4> @T6G_MB_LIB.T6G(SCH_1):M_A_CPU0_SA_DQS_DN(4)   I200 @T6G_MB_LIB.T6G(SCH_1):PAGE10
   G74 M_A_CPU0_SA_DQS_DP<0> @T6G_MB_LIB.T6G(SCH_1):M_A_CPU0_SA_DQS_DP(0)   I200 @T6G_MB_LIB.T6G(SCH_1):PAGE10
  AG74 M_A_CPU0_SA_DQ<28> @T6G_MB_LIB.T6G(SCH_1):M_A_CPU0_SA_DQ(28)   I200 @T6G_MB_LIB.T6G(SCH_1):PAGE10
   V72 M_A_CPU0_SA_DQ<17> @T6G_MB_LIB.T6G(SCH_1):M_A_CPU0_SA_DQ(17)   I200 @T6G_MB_LIB.T6G(SCH_1):PAGE10
  AY74 M_A_CPU0_SA_CA<1> @T6G_MB_LIB.T6G(SCH_1):M_A_CPU0_SA_CA(1)   I200 @T6G_MB_LIB.T6G(SCH_1):PAGE10
  CY72 M_A_CPU0_SB_DQ<23> @T6G_MB_LIB.T6G(SCH_1):M_A_CPU0_SB_DQ(23)   I200 @T6G_MB_LIB.T6G(SCH_1):PAGE10
  CM74 M_A_CPU0_SB_DQ<12> @T6G_MB_LIB.T6G(SCH_1):M_A_CPU0_SB_DQ(12)   I200 @T6G_MB_LIB.T6G(SCH_1):PAGE10
  CB72 M_A_CPU0_SB_CB<3> @T6G_MB_LIB.T6G(SCH_1):M_A_CPU0_SB_CB(3)   I200 @T6G_MB_LIB.T6G(SCH_1):PAGE10
  BH72 M_A_CPU0_SB_CA<1> @T6G_MB_LIB.T6G(SCH_1):M_A_CPU0_SB_CA(1)   I200 @T6G_MB_LIB.T6G(SCH_1):PAGE10
   H72 M_A_CPU0_SA_DQS_DN<5> @T6G_MB_LIB.T6G(SCH_1):M_A_CPU0_SA_DQS_DN(5)   I200 @T6G_MB_LIB.T6G(SCH_1):PAGE10
   N74 M_A_CPU0_SA_DQS_DP<1> @T6G_MB_LIB.T6G(SCH_1):M_A_CPU0_SA_DQS_DP(1)   I200 @T6G_MB_LIB.T6G(SCH_1):PAGE10
  AH72 M_A_CPU0_SA_DQ<29> @T6G_MB_LIB.T6G(SCH_1):M_A_CPU0_SA_DQ(29)   I200 @T6G_MB_LIB.T6G(SCH_1):PAGE10
   V74 M_A_CPU0_SA_DQ<18> @T6G_MB_LIB.T6G(SCH_1):M_A_CPU0_SA_DQ(18)   I200 @T6G_MB_LIB.T6G(SCH_1):PAGE10
  AY72 M_A_CPU0_SA_CA<2> @T6G_MB_LIB.T6G(SCH_1):M_A_CPU0_SA_CA(2)   I200 @T6G_MB_LIB.T6G(SCH_1):PAGE10
  CE74 M_A_CPU0_SB_DQS_DN<0> @T6G_MB_LIB.T6G(SCH_1):M_A_CPU0_SB_DQS_DN(0)   I200 @T6G_MB_LIB.T6G(SCH_1):PAGE10
  CY74 M_A_CPU0_SB_DQ<24> @T6G_MB_LIB.T6G(SCH_1):M_A_CPU0_SB_DQ(24)   I200 @T6G_MB_LIB.T6G(SCH_1):PAGE10
  CN73 M_A_CPU0_SB_DQ<13> @T6G_MB_LIB.T6G(SCH_1):M_A_CPU0_SB_DQ(13)   I200 @T6G_MB_LIB.T6G(SCH_1):PAGE10
  BT74 M_A_CPU0_SB_CB<4> @T6G_MB_LIB.T6G(SCH_1):M_A_CPU0_SB_CB(4)   I200 @T6G_MB_LIB.T6G(SCH_1):PAGE10
  BH74 M_A_CPU0_SB_CA<2> @T6G_MB_LIB.T6G(SCH_1):M_A_CPU0_SB_CA(2)   I200 @T6G_MB_LIB.T6G(SCH_1):PAGE10
   P72 M_A_CPU0_SA_DQS_DN<6> @T6G_MB_LIB.T6G(SCH_1):M_A_CPU0_SA_DQS_DN(6)   I200 @T6G_MB_LIB.T6G(SCH_1):PAGE10
   W74 M_A_CPU0_SA_DQS_DP<2> @T6G_MB_LIB.T6G(SCH_1):M_A_CPU0_SA_DQS_DP(2)   I200 @T6G_MB_LIB.T6G(SCH_1):PAGE10
   W73 M_A_CPU0_SA_DQ<19> @T6G_MB_LIB.T6G(SCH_1):M_A_CPU0_SA_DQ(19)   I200 @T6G_MB_LIB.T6G(SCH_1):PAGE10
  BA73 M_A_CPU0_SA_CA<3> @T6G_MB_LIB.T6G(SCH_1):M_A_CPU0_SA_CA(3)   I200 @T6G_MB_LIB.T6G(SCH_1):PAGE10
  CL74 M_A_CPU0_SB_DQS_DN<1> @T6G_MB_LIB.T6G(SCH_1):M_A_CPU0_SB_DQS_DN(1)   I200 @T6G_MB_LIB.T6G(SCH_1):PAGE10
  DA73 M_A_CPU0_SB_DQ<25> @T6G_MB_LIB.T6G(SCH_1):M_A_CPU0_SB_DQ(25)   I200 @T6G_MB_LIB.T6G(SCH_1):PAGE10
  CN74 M_A_CPU0_SB_DQ<14> @T6G_MB_LIB.T6G(SCH_1):M_A_CPU0_SB_DQ(14)   I200 @T6G_MB_LIB.T6G(SCH_1):PAGE10
  BU73 M_A_CPU0_SB_CB<5> @T6G_MB_LIB.T6G(SCH_1):M_A_CPU0_SB_CB(5)   I200 @T6G_MB_LIB.T6G(SCH_1):PAGE10
  BJ74 M_A_CPU0_SB_CA<3> @T6G_MB_LIB.T6G(SCH_1):M_A_CPU0_SB_CA(3)   I200 @T6G_MB_LIB.T6G(SCH_1):PAGE10
   Y72 M_A_CPU0_SA_DQS_DN<7> @T6G_MB_LIB.T6G(SCH_1):M_A_CPU0_SA_DQS_DN(7)   I200 @T6G_MB_LIB.T6G(SCH_1):PAGE10
  AE74 M_A_CPU0_SA_DQS_DP<3> @T6G_MB_LIB.T6G(SCH_1):M_A_CPU0_SA_DQS_DP(3)   I200 @T6G_MB_LIB.T6G(SCH_1):PAGE10
   E74 M_A_CPU0_SA_DQ<0> @T6G_MB_LIB.T6G(SCH_1):M_A_CPU0_SA_DQ(0)   I200 @T6G_MB_LIB.T6G(SCH_1):PAGE10
  BA74 M_A_CPU0_SA_CA<4> @T6G_MB_LIB.T6G(SCH_1):M_A_CPU0_SA_CA(4)   I200 @T6G_MB_LIB.T6G(SCH_1):PAGE10
  CU74 M_A_CPU0_SB_DQS_DN<2> @T6G_MB_LIB.T6G(SCH_1):M_A_CPU0_SB_DQS_DN(2)   I200 @T6G_MB_LIB.T6G(SCH_1):PAGE10
  DA74 M_A_CPU0_SB_DQ<26> @T6G_MB_LIB.T6G(SCH_1):M_A_CPU0_SB_DQ(26)   I200 @T6G_MB_LIB.T6G(SCH_1):PAGE10
  CP72 M_A_CPU0_SB_DQ<15> @T6G_MB_LIB.T6G(SCH_1):M_A_CPU0_SB_DQ(15)   I200 @T6G_MB_LIB.T6G(SCH_1):PAGE10
  CB74 M_A_CPU0_SB_DQ<0> @T6G_MB_LIB.T6G(SCH_1):M_A_CPU0_SB_DQ(0)   I200 @T6G_MB_LIB.T6G(SCH_1):PAGE10
  BU74 M_A_CPU0_SB_CB<6> @T6G_MB_LIB.T6G(SCH_1):M_A_CPU0_SB_CB(6)   I200 @T6G_MB_LIB.T6G(SCH_1):PAGE10
  BJ73 M_A_CPU0_SB_CA<4> @T6G_MB_LIB.T6G(SCH_1):M_A_CPU0_SB_CA(4)   I200 @T6G_MB_LIB.T6G(SCH_1):PAGE10
  BP74 M_A_CPU0_SB_RSP<0> @T6G_MB_LIB.T6G(SCH_1):M_A_CPU0_SB_RSP(0)   I200 @T6G_MB_LIB.T6G(SCH_1):PAGE10
  AF72 M_A_CPU0_SA_DQS_DN<8> @T6G_MB_LIB.T6G(SCH_1):M_A_CPU0_SA_DQS_DN(8)   I200 @T6G_MB_LIB.T6G(SCH_1):PAGE10
  AL74 M_A_CPU0_SA_DQS_DP<4> @T6G_MB_LIB.T6G(SCH_1):M_A_CPU0_SA_DQS_DP(4)   I200 @T6G_MB_LIB.T6G(SCH_1):PAGE10
   F72 M_A_CPU0_SA_DQ<1> @T6G_MB_LIB.T6G(SCH_1):M_A_CPU0_SA_DQ(1)   I200 @T6G_MB_LIB.T6G(SCH_1):PAGE10
  BB74 M_A_CPU0_SA_CA<5> @T6G_MB_LIB.T6G(SCH_1):M_A_CPU0_SA_CA(5)   I200 @T6G_MB_LIB.T6G(SCH_1):PAGE10
  DC74 M_A_CPU0_SB_DQS_DN<3> @T6G_MB_LIB.T6G(SCH_1):M_A_CPU0_SB_DQS_DN(3)   I200 @T6G_MB_LIB.T6G(SCH_1):PAGE10
  DB72 M_A_CPU0_SB_DQ<27> @T6G_MB_LIB.T6G(SCH_1):M_A_CPU0_SB_DQ(27)   I200 @T6G_MB_LIB.T6G(SCH_1):PAGE10
  CP74 M_A_CPU0_SB_DQ<16> @T6G_MB_LIB.T6G(SCH_1):M_A_CPU0_SB_DQ(16)   I200 @T6G_MB_LIB.T6G(SCH_1):PAGE10
  CC73 M_A_CPU0_SB_DQ<1> @T6G_MB_LIB.T6G(SCH_1):M_A_CPU0_SB_DQ(1)   I200 @T6G_MB_LIB.T6G(SCH_1):PAGE10
  BV72 M_A_CPU0_SB_CB<7> @T6G_MB_LIB.T6G(SCH_1):M_A_CPU0_SB_CB(7)   I200 @T6G_MB_LIB.T6G(SCH_1):PAGE10
  BK72 M_A_CPU0_SB_CA<5> @T6G_MB_LIB.T6G(SCH_1):M_A_CPU0_SB_CA(5)   I200 @T6G_MB_LIB.T6G(SCH_1):PAGE10
  BR74     NC     NC   I200 @T6G_MB_LIB.T6G(SCH_1):PAGE10
  AM72 M_A_CPU0_SA_DQS_DN<9> @T6G_MB_LIB.T6G(SCH_1):M_A_CPU0_SA_DQS_DN(9)   I200 @T6G_MB_LIB.T6G(SCH_1):PAGE10
   J73 M_A_CPU0_SA_DQS_DP<5> @T6G_MB_LIB.T6G(SCH_1):M_A_CPU0_SA_DQS_DP(5)   I200 @T6G_MB_LIB.T6G(SCH_1):PAGE10
   F74 M_A_CPU0_SA_DQ<2> @T6G_MB_LIB.T6G(SCH_1):M_A_CPU0_SA_DQ(2)   I200 @T6G_MB_LIB.T6G(SCH_1):PAGE10
  BB72 M_A_CPU0_SA_CA<6> @T6G_MB_LIB.T6G(SCH_1):M_A_CPU0_SA_CA(6)   I200 @T6G_MB_LIB.T6G(SCH_1):PAGE10
  BW73 M_A_CPU0_SB_DQS_DN<4> @T6G_MB_LIB.T6G(SCH_1):M_A_CPU0_SB_DQS_DN(4)   I200 @T6G_MB_LIB.T6G(SCH_1):PAGE10
  CD74 M_A_CPU0_SB_DQS_DP<0> @T6G_MB_LIB.T6G(SCH_1):M_A_CPU0_SB_DQS_DP(0)   I200 @T6G_MB_LIB.T6G(SCH_1):PAGE10
  DD74 M_A_CPU0_SB_DQ<28> @T6G_MB_LIB.T6G(SCH_1):M_A_CPU0_SB_DQ(28)   I200 @T6G_MB_LIB.T6G(SCH_1):PAGE10
  CR73 M_A_CPU0_SB_DQ<17> @T6G_MB_LIB.T6G(SCH_1):M_A_CPU0_SB_DQ(17)   I200 @T6G_MB_LIB.T6G(SCH_1):PAGE10
  CC74 M_A_CPU0_SB_DQ<2> @T6G_MB_LIB.T6G(SCH_1):M_A_CPU0_SB_DQ(2)   I200 @T6G_MB_LIB.T6G(SCH_1):PAGE10
  BK74 M_A_CPU0_SB_CA<6> @T6G_MB_LIB.T6G(SCH_1):M_A_CPU0_SB_CA(6)   I200 @T6G_MB_LIB.T6G(SCH_1):PAGE10
   R73 M_A_CPU0_SA_DQS_DP<6> @T6G_MB_LIB.T6G(SCH_1):M_A_CPU0_SA_DQS_DP(6)   I200 @T6G_MB_LIB.T6G(SCH_1):PAGE10
   G73 M_A_CPU0_SA_DQ<3> @T6G_MB_LIB.T6G(SCH_1):M_A_CPU0_SA_DQ(3)   I200 @T6G_MB_LIB.T6G(SCH_1):PAGE10
  AV74 M_A_CPU0_SA_CS_N<0> @T6G_MB_LIB.T6G(SCH_1):M_A_CPU0_SA_CS_N(0)   I200 @T6G_MB_LIB.T6G(SCH_1):PAGE10
  BC73 M_A_CPU0_SA_PAR @T6G_MB_LIB.T6G(SCH_1):M_A_CPU0_SA_PAR   I200 @T6G_MB_LIB.T6G(SCH_1):PAGE10
  BL74 M_A_CPU0_SB_PAR @T6G_MB_LIB.T6G(SCH_1):M_A_CPU0_SB_PAR   I200 @T6G_MB_LIB.T6G(SCH_1):PAGE10
  BC74 M_A_CPU0_CLK_DP<0> @T6G_MB_LIB.T6G(SCH_1):M_A_CPU0_CLK_DP(0)   I200 @T6G_MB_LIB.T6G(SCH_1):PAGE10
  BV74 M_A_CPU0_SB_DQS_DP<9> @T6G_MB_LIB.T6G(SCH_1):M_A_CPU0_SB_DQS_DP(9)   I200 @T6G_MB_LIB.T6G(SCH_1):PAGE10
  BF74     NC     NC   I200 @T6G_MB_LIB.T6G(SCH_1):PAGE10
  BD74 M_A_CPU0_CLK_DN<0> @T6G_MB_LIB.T6G(SCH_1):M_A_CPU0_CLK_DN(0)   I200 @T6G_MB_LIB.T6G(SCH_1):PAGE10
  BG74     NC     NC   I200 @T6G_MB_LIB.T6G(SCH_1):PAGE10
  BF72 TP_M_A_CPU0_SA_TEST39A @T6G_MB_LIB.T6G(SCH_1):TP_M_A_CPU0_SA_TEST39A   I200 @T6G_MB_LIB.T6G(SCH_1):PAGE10
   C60 TP_M_A_CPU0_SA_TEST40 @T6G_MB_LIB.T6G(SCH_1):TP_M_A_CPU0_SA_TEST40   I200 @T6G_MB_LIB.T6G(SCH_1):PAGE10
  AT62 M_B_CPU0_ALERT_R_N @T6G_MB_LIB.T6G(SCH_1):M_B_CPU0_ALERT_R_N   I171 @T6G_MB_LIB.T6G(SCH_1):PAGE11
  AU62 M_B_CPU0_RESET_N @T6G_MB_LIB.T6G(SCH_1):M_B_CPU0_RESET_N   I171 @T6G_MB_LIB.T6G(SCH_1):PAGE11
  BW64 M_B_CPU0_SB_DQS_DN<9> @T6G_MB_LIB.T6G(SCH_1):M_B_CPU0_SB_DQS_DN(9)   I171 @T6G_MB_LIB.T6G(SCH_1):PAGE11
  CF62 M_B_CPU0_SB_DQS_DP<5> @T6G_MB_LIB.T6G(SCH_1):M_B_CPU0_SB_DQS_DP(5)   I171 @T6G_MB_LIB.T6G(SCH_1):PAGE11
  AB63 M_B_CPU0_SA_DQ<22> @T6G_MB_LIB.T6G(SCH_1):M_B_CPU0_SA_DQ(22)   I171 @T6G_MB_LIB.T6G(SCH_1):PAGE11
   N62 M_B_CPU0_SA_DQ<11> @T6G_MB_LIB.T6G(SCH_1):M_B_CPU0_SA_DQ(11)   I171 @T6G_MB_LIB.T6G(SCH_1):PAGE11
  AK63 M_B_CPU0_SA_CB<2> @T6G_MB_LIB.T6G(SCH_1):M_B_CPU0_SA_CB(2)   I171 @T6G_MB_LIB.T6G(SCH_1):PAGE11
  CM62 M_B_CPU0_SB_DQS_DP<6> @T6G_MB_LIB.T6G(SCH_1):M_B_CPU0_SB_DQS_DP(6)   I171 @T6G_MB_LIB.T6G(SCH_1):PAGE11
  AC62 M_B_CPU0_SA_DQ<23> @T6G_MB_LIB.T6G(SCH_1):M_B_CPU0_SA_DQ(23)   I171 @T6G_MB_LIB.T6G(SCH_1):PAGE11
   R64 M_B_CPU0_SA_DQ<12> @T6G_MB_LIB.T6G(SCH_1):M_B_CPU0_SA_DQ(12)   I171 @T6G_MB_LIB.T6G(SCH_1):PAGE11
  AL62 M_B_CPU0_SA_CB<3> @T6G_MB_LIB.T6G(SCH_1):M_B_CPU0_SA_CB(3)   I171 @T6G_MB_LIB.T6G(SCH_1):PAGE11
  CV62 M_B_CPU0_SB_DQS_DP<7> @T6G_MB_LIB.T6G(SCH_1):M_B_CPU0_SB_DQS_DP(7)   I171 @T6G_MB_LIB.T6G(SCH_1):PAGE11
  BM62 M_B_CPU0_SB_CS_N<0> @T6G_MB_LIB.T6G(SCH_1):M_B_CPU0_SB_CS_N(0)   I171 @T6G_MB_LIB.T6G(SCH_1):PAGE11
   H63 M_B_CPU0_SA_DQS_DN<0> @T6G_MB_LIB.T6G(SCH_1):M_B_CPU0_SA_DQS_DN(0)   I171 @T6G_MB_LIB.T6G(SCH_1):PAGE11
   T62 M_B_CPU0_SA_DQ<13> @T6G_MB_LIB.T6G(SCH_1):M_B_CPU0_SA_DQ(13)   I171 @T6G_MB_LIB.T6G(SCH_1):PAGE11
   E64 M_B_CPU0_SA_DQ<0> @T6G_MB_LIB.T6G(SCH_1):M_B_CPU0_SA_DQ(0)   I171 @T6G_MB_LIB.T6G(SCH_1):PAGE11
  AN64 M_B_CPU0_SA_CB<4> @T6G_MB_LIB.T6G(SCH_1):M_B_CPU0_SA_CB(4)   I171 @T6G_MB_LIB.T6G(SCH_1):PAGE11
  DD62 M_B_CPU0_SB_DQS_DP<8> @T6G_MB_LIB.T6G(SCH_1):M_B_CPU0_SB_DQS_DP(8)   I171 @T6G_MB_LIB.T6G(SCH_1):PAGE11
  DE64 M_B_CPU0_SB_DQ<30> @T6G_MB_LIB.T6G(SCH_1):M_B_CPU0_SB_DQ(30)   I171 @T6G_MB_LIB.T6G(SCH_1):PAGE11
  CB63 M_B_CPU0_SB_DQ<0> @T6G_MB_LIB.T6G(SCH_1):M_B_CPU0_SB_DQ(0)   I171 @T6G_MB_LIB.T6G(SCH_1):PAGE11
  BL62     NC     NC   I171 @T6G_MB_LIB.T6G(SCH_1):PAGE11
  BN64 M_B_CPU0_SB_CS_N<1> @T6G_MB_LIB.T6G(SCH_1):M_B_CPU0_SB_CS_N(1)   I171 @T6G_MB_LIB.T6G(SCH_1):PAGE11
   P63 M_B_CPU0_SA_DQS_DN<1> @T6G_MB_LIB.T6G(SCH_1):M_B_CPU0_SA_DQS_DN(1)   I171 @T6G_MB_LIB.T6G(SCH_1):PAGE11
  AD62 M_B_CPU0_SA_DQ<25> @T6G_MB_LIB.T6G(SCH_1):M_B_CPU0_SA_DQ(25)   I171 @T6G_MB_LIB.T6G(SCH_1):PAGE11
   T63 M_B_CPU0_SA_DQ<14> @T6G_MB_LIB.T6G(SCH_1):M_B_CPU0_SA_DQ(14)   I171 @T6G_MB_LIB.T6G(SCH_1):PAGE11
   F62 M_B_CPU0_SA_DQ<1> @T6G_MB_LIB.T6G(SCH_1):M_B_CPU0_SA_DQ(1)   I171 @T6G_MB_LIB.T6G(SCH_1):PAGE11
  AP62 M_B_CPU0_SA_CB<5> @T6G_MB_LIB.T6G(SCH_1):M_B_CPU0_SA_CB(5)   I171 @T6G_MB_LIB.T6G(SCH_1):PAGE11
  DF62 M_B_CPU0_SB_DQ<31> @T6G_MB_LIB.T6G(SCH_1):M_B_CPU0_SB_DQ(31)   I171 @T6G_MB_LIB.T6G(SCH_1):PAGE11
  CC62 M_B_CPU0_SB_DQ<1> @T6G_MB_LIB.T6G(SCH_1):M_B_CPU0_SB_DQ(1)   I171 @T6G_MB_LIB.T6G(SCH_1):PAGE11
  BY63 M_B_CPU0_SB_CB<0> @T6G_MB_LIB.T6G(SCH_1):M_B_CPU0_SB_CB(0)   I171 @T6G_MB_LIB.T6G(SCH_1):PAGE11
  BM63     NC     NC   I171 @T6G_MB_LIB.T6G(SCH_1):PAGE11
   Y63 M_B_CPU0_SA_DQS_DN<2> @T6G_MB_LIB.T6G(SCH_1):M_B_CPU0_SA_DQS_DN(2)   I171 @T6G_MB_LIB.T6G(SCH_1):PAGE11
  AD63 M_B_CPU0_SA_DQ<26> @T6G_MB_LIB.T6G(SCH_1):M_B_CPU0_SA_DQ(26)   I171 @T6G_MB_LIB.T6G(SCH_1):PAGE11
   U62 M_B_CPU0_SA_DQ<15> @T6G_MB_LIB.T6G(SCH_1):M_B_CPU0_SA_DQ(15)   I171 @T6G_MB_LIB.T6G(SCH_1):PAGE11
   F63 M_B_CPU0_SA_DQ<2> @T6G_MB_LIB.T6G(SCH_1):M_B_CPU0_SA_DQ(2)   I171 @T6G_MB_LIB.T6G(SCH_1):PAGE11
  AP63 M_B_CPU0_SA_CB<6> @T6G_MB_LIB.T6G(SCH_1):M_B_CPU0_SA_CB(6)   I171 @T6G_MB_LIB.T6G(SCH_1):PAGE11
  CW62 M_B_CPU0_SB_DQ<21> @T6G_MB_LIB.T6G(SCH_1):M_B_CPU0_SB_DQ(21)   I171 @T6G_MB_LIB.T6G(SCH_1):PAGE11
  CJ64 M_B_CPU0_SB_DQ<10> @T6G_MB_LIB.T6G(SCH_1):M_B_CPU0_SB_DQ(10)   I171 @T6G_MB_LIB.T6G(SCH_1):PAGE11
  CC64 M_B_CPU0_SB_DQ<2> @T6G_MB_LIB.T6G(SCH_1):M_B_CPU0_SB_DQ(2)   I171 @T6G_MB_LIB.T6G(SCH_1):PAGE11
  CA62 M_B_CPU0_SB_CB<1> @T6G_MB_LIB.T6G(SCH_1):M_B_CPU0_SB_CB(1)   I171 @T6G_MB_LIB.T6G(SCH_1):PAGE11
  AF63 M_B_CPU0_SA_DQS_DN<3> @T6G_MB_LIB.T6G(SCH_1):M_B_CPU0_SA_DQS_DN(3)   I171 @T6G_MB_LIB.T6G(SCH_1):PAGE11
  AE62 M_B_CPU0_SA_DQ<27> @T6G_MB_LIB.T6G(SCH_1):M_B_CPU0_SA_DQ(27)   I171 @T6G_MB_LIB.T6G(SCH_1):PAGE11
   U64 M_B_CPU0_SA_DQ<16> @T6G_MB_LIB.T6G(SCH_1):M_B_CPU0_SA_DQ(16)   I171 @T6G_MB_LIB.T6G(SCH_1):PAGE11
   G62 M_B_CPU0_SA_DQ<3> @T6G_MB_LIB.T6G(SCH_1):M_B_CPU0_SA_DQ(3)   I171 @T6G_MB_LIB.T6G(SCH_1):PAGE11
  AR62 M_B_CPU0_SA_CB<7> @T6G_MB_LIB.T6G(SCH_1):M_B_CPU0_SA_CB(7)   I171 @T6G_MB_LIB.T6G(SCH_1):PAGE11
  BN62 M_B_CPU0_SA_RSP<0> @T6G_MB_LIB.T6G(SCH_1):M_B_CPU0_SA_RSP(0)   I171 @T6G_MB_LIB.T6G(SCH_1):PAGE11
  CW64 M_B_CPU0_SB_DQ<22> @T6G_MB_LIB.T6G(SCH_1):M_B_CPU0_SB_DQ(22)   I171 @T6G_MB_LIB.T6G(SCH_1):PAGE11
  CK62 M_B_CPU0_SB_DQ<11> @T6G_MB_LIB.T6G(SCH_1):M_B_CPU0_SB_DQ(11)   I171 @T6G_MB_LIB.T6G(SCH_1):PAGE11
  CD62 M_B_CPU0_SB_DQ<3> @T6G_MB_LIB.T6G(SCH_1):M_B_CPU0_SB_DQ(3)   I171 @T6G_MB_LIB.T6G(SCH_1):PAGE11
  CA64 M_B_CPU0_SB_CB<2> @T6G_MB_LIB.T6G(SCH_1):M_B_CPU0_SB_CB(2)   I171 @T6G_MB_LIB.T6G(SCH_1):PAGE11
  AM63 M_B_CPU0_SA_DQS_DN<4> @T6G_MB_LIB.T6G(SCH_1):M_B_CPU0_SA_DQS_DN(4)   I171 @T6G_MB_LIB.T6G(SCH_1):PAGE11
   G64 M_B_CPU0_SA_DQS_DP<0> @T6G_MB_LIB.T6G(SCH_1):M_B_CPU0_SA_DQS_DP(0)   I171 @T6G_MB_LIB.T6G(SCH_1):PAGE11
  AG64 M_B_CPU0_SA_DQ<28> @T6G_MB_LIB.T6G(SCH_1):M_B_CPU0_SA_DQ(28)   I171 @T6G_MB_LIB.T6G(SCH_1):PAGE11
   V62 M_B_CPU0_SA_DQ<17> @T6G_MB_LIB.T6G(SCH_1):M_B_CPU0_SA_DQ(17)   I171 @T6G_MB_LIB.T6G(SCH_1):PAGE11
   J64 M_B_CPU0_SA_DQ<4> @T6G_MB_LIB.T6G(SCH_1):M_B_CPU0_SA_DQ(4)   I171 @T6G_MB_LIB.T6G(SCH_1):PAGE11
  BP62     NC     NC   I171 @T6G_MB_LIB.T6G(SCH_1):PAGE11
  CY62 M_B_CPU0_SB_DQ<23> @T6G_MB_LIB.T6G(SCH_1):M_B_CPU0_SB_DQ(23)   I171 @T6G_MB_LIB.T6G(SCH_1):PAGE11
  CM63 M_B_CPU0_SB_DQ<12> @T6G_MB_LIB.T6G(SCH_1):M_B_CPU0_SB_DQ(12)   I171 @T6G_MB_LIB.T6G(SCH_1):PAGE11
  CF63 M_B_CPU0_SB_DQ<4> @T6G_MB_LIB.T6G(SCH_1):M_B_CPU0_SB_DQ(4)   I171 @T6G_MB_LIB.T6G(SCH_1):PAGE11
  CB62 M_B_CPU0_SB_CB<3> @T6G_MB_LIB.T6G(SCH_1):M_B_CPU0_SB_CB(3)   I171 @T6G_MB_LIB.T6G(SCH_1):PAGE11
   H62 M_B_CPU0_SA_DQS_DN<5> @T6G_MB_LIB.T6G(SCH_1):M_B_CPU0_SA_DQS_DN(5)   I171 @T6G_MB_LIB.T6G(SCH_1):PAGE11
   N64 M_B_CPU0_SA_DQS_DP<1> @T6G_MB_LIB.T6G(SCH_1):M_B_CPU0_SA_DQS_DP(1)   I171 @T6G_MB_LIB.T6G(SCH_1):PAGE11
  AH62 M_B_CPU0_SA_DQ<29> @T6G_MB_LIB.T6G(SCH_1):M_B_CPU0_SA_DQ(29)   I171 @T6G_MB_LIB.T6G(SCH_1):PAGE11
   V63 M_B_CPU0_SA_DQ<18> @T6G_MB_LIB.T6G(SCH_1):M_B_CPU0_SA_DQ(18)   I171 @T6G_MB_LIB.T6G(SCH_1):PAGE11
   K62 M_B_CPU0_SA_DQ<5> @T6G_MB_LIB.T6G(SCH_1):M_B_CPU0_SA_DQ(5)   I171 @T6G_MB_LIB.T6G(SCH_1):PAGE11
  CE64 M_B_CPU0_SB_DQS_DN<0> @T6G_MB_LIB.T6G(SCH_1):M_B_CPU0_SB_DQS_DN(0)   I171 @T6G_MB_LIB.T6G(SCH_1):PAGE11
  CY63 M_B_CPU0_SB_DQ<24> @T6G_MB_LIB.T6G(SCH_1):M_B_CPU0_SB_DQ(24)   I171 @T6G_MB_LIB.T6G(SCH_1):PAGE11
  CN62 M_B_CPU0_SB_DQ<13> @T6G_MB_LIB.T6G(SCH_1):M_B_CPU0_SB_DQ(13)   I171 @T6G_MB_LIB.T6G(SCH_1):PAGE11
  CG62 M_B_CPU0_SB_DQ<5> @T6G_MB_LIB.T6G(SCH_1):M_B_CPU0_SB_DQ(5)   I171 @T6G_MB_LIB.T6G(SCH_1):PAGE11
  BT63 M_B_CPU0_SB_CB<4> @T6G_MB_LIB.T6G(SCH_1):M_B_CPU0_SB_CB(4)   I171 @T6G_MB_LIB.T6G(SCH_1):PAGE11
   P62 M_B_CPU0_SA_DQS_DN<6> @T6G_MB_LIB.T6G(SCH_1):M_B_CPU0_SA_DQS_DN(6)   I171 @T6G_MB_LIB.T6G(SCH_1):PAGE11
   W64 M_B_CPU0_SA_DQS_DP<2> @T6G_MB_LIB.T6G(SCH_1):M_B_CPU0_SA_DQS_DP(2)   I171 @T6G_MB_LIB.T6G(SCH_1):PAGE11
   W62 M_B_CPU0_SA_DQ<19> @T6G_MB_LIB.T6G(SCH_1):M_B_CPU0_SA_DQ(19)   I171 @T6G_MB_LIB.T6G(SCH_1):PAGE11
   K63 M_B_CPU0_SA_DQ<6> @T6G_MB_LIB.T6G(SCH_1):M_B_CPU0_SA_DQ(6)   I171 @T6G_MB_LIB.T6G(SCH_1):PAGE11
  AW64 M_B_CPU0_SA_CA<0> @T6G_MB_LIB.T6G(SCH_1):M_B_CPU0_SA_CA(0)   I171 @T6G_MB_LIB.T6G(SCH_1):PAGE11
  CL64 M_B_CPU0_SB_DQS_DN<1> @T6G_MB_LIB.T6G(SCH_1):M_B_CPU0_SB_DQS_DN(1)   I171 @T6G_MB_LIB.T6G(SCH_1):PAGE11
  DA62 M_B_CPU0_SB_DQ<25> @T6G_MB_LIB.T6G(SCH_1):M_B_CPU0_SB_DQ(25)   I171 @T6G_MB_LIB.T6G(SCH_1):PAGE11
  CN64 M_B_CPU0_SB_DQ<14> @T6G_MB_LIB.T6G(SCH_1):M_B_CPU0_SB_DQ(14)   I171 @T6G_MB_LIB.T6G(SCH_1):PAGE11
  CG64 M_B_CPU0_SB_DQ<6> @T6G_MB_LIB.T6G(SCH_1):M_B_CPU0_SB_DQ(6)   I171 @T6G_MB_LIB.T6G(SCH_1):PAGE11
  BU62 M_B_CPU0_SB_CB<5> @T6G_MB_LIB.T6G(SCH_1):M_B_CPU0_SB_CB(5)   I171 @T6G_MB_LIB.T6G(SCH_1):PAGE11
  BG62 M_B_CPU0_SB_CA<0> @T6G_MB_LIB.T6G(SCH_1):M_B_CPU0_SB_CA(0)   I171 @T6G_MB_LIB.T6G(SCH_1):PAGE11
   Y62 M_B_CPU0_SA_DQS_DN<7> @T6G_MB_LIB.T6G(SCH_1):M_B_CPU0_SA_DQS_DN(7)   I171 @T6G_MB_LIB.T6G(SCH_1):PAGE11
  AE64 M_B_CPU0_SA_DQS_DP<3> @T6G_MB_LIB.T6G(SCH_1):M_B_CPU0_SA_DQS_DP(3)   I171 @T6G_MB_LIB.T6G(SCH_1):PAGE11
   L62 M_B_CPU0_SA_DQ<7> @T6G_MB_LIB.T6G(SCH_1):M_B_CPU0_SA_DQ(7)   I171 @T6G_MB_LIB.T6G(SCH_1):PAGE11
  AY63 M_B_CPU0_SA_CA<1> @T6G_MB_LIB.T6G(SCH_1):M_B_CPU0_SA_CA(1)   I171 @T6G_MB_LIB.T6G(SCH_1):PAGE11
  CU64 M_B_CPU0_SB_DQS_DN<2> @T6G_MB_LIB.T6G(SCH_1):M_B_CPU0_SB_DQS_DN(2)   I171 @T6G_MB_LIB.T6G(SCH_1):PAGE11
  DA64 M_B_CPU0_SB_DQ<26> @T6G_MB_LIB.T6G(SCH_1):M_B_CPU0_SB_DQ(26)   I171 @T6G_MB_LIB.T6G(SCH_1):PAGE11
  CP62 M_B_CPU0_SB_DQ<15> @T6G_MB_LIB.T6G(SCH_1):M_B_CPU0_SB_DQ(15)   I171 @T6G_MB_LIB.T6G(SCH_1):PAGE11
  CH62 M_B_CPU0_SB_DQ<7> @T6G_MB_LIB.T6G(SCH_1):M_B_CPU0_SB_DQ(7)   I171 @T6G_MB_LIB.T6G(SCH_1):PAGE11
  BU64 M_B_CPU0_SB_CB<6> @T6G_MB_LIB.T6G(SCH_1):M_B_CPU0_SB_CB(6)   I171 @T6G_MB_LIB.T6G(SCH_1):PAGE11
  BH62 M_B_CPU0_SB_CA<1> @T6G_MB_LIB.T6G(SCH_1):M_B_CPU0_SB_CA(1)   I171 @T6G_MB_LIB.T6G(SCH_1):PAGE11
  AF62 M_B_CPU0_SA_DQS_DN<8> @T6G_MB_LIB.T6G(SCH_1):M_B_CPU0_SA_DQS_DN(8)   I171 @T6G_MB_LIB.T6G(SCH_1):PAGE11
  AL64 M_B_CPU0_SA_DQS_DP<4> @T6G_MB_LIB.T6G(SCH_1):M_B_CPU0_SA_DQS_DP(4)   I171 @T6G_MB_LIB.T6G(SCH_1):PAGE11
   L64 M_B_CPU0_SA_DQ<8> @T6G_MB_LIB.T6G(SCH_1):M_B_CPU0_SA_DQ(8)   I171 @T6G_MB_LIB.T6G(SCH_1):PAGE11
  AY62 M_B_CPU0_SA_CA<2> @T6G_MB_LIB.T6G(SCH_1):M_B_CPU0_SA_CA(2)   I171 @T6G_MB_LIB.T6G(SCH_1):PAGE11
  DC64 M_B_CPU0_SB_DQS_DN<3> @T6G_MB_LIB.T6G(SCH_1):M_B_CPU0_SB_DQS_DN(3)   I171 @T6G_MB_LIB.T6G(SCH_1):PAGE11
  DB62 M_B_CPU0_SB_DQ<27> @T6G_MB_LIB.T6G(SCH_1):M_B_CPU0_SB_DQ(27)   I171 @T6G_MB_LIB.T6G(SCH_1):PAGE11
  CP63 M_B_CPU0_SB_DQ<16> @T6G_MB_LIB.T6G(SCH_1):M_B_CPU0_SB_DQ(16)   I171 @T6G_MB_LIB.T6G(SCH_1):PAGE11
  CH63 M_B_CPU0_SB_DQ<8> @T6G_MB_LIB.T6G(SCH_1):M_B_CPU0_SB_DQ(8)   I171 @T6G_MB_LIB.T6G(SCH_1):PAGE11
  BV62 M_B_CPU0_SB_CB<7> @T6G_MB_LIB.T6G(SCH_1):M_B_CPU0_SB_CB(7)   I171 @T6G_MB_LIB.T6G(SCH_1):PAGE11
  BH63 M_B_CPU0_SB_CA<2> @T6G_MB_LIB.T6G(SCH_1):M_B_CPU0_SB_CA(2)   I171 @T6G_MB_LIB.T6G(SCH_1):PAGE11
  BP63 M_B_CPU0_SB_RSP<0> @T6G_MB_LIB.T6G(SCH_1):M_B_CPU0_SB_RSP(0)   I171 @T6G_MB_LIB.T6G(SCH_1):PAGE11
  AM62 M_B_CPU0_SA_DQS_DN<9> @T6G_MB_LIB.T6G(SCH_1):M_B_CPU0_SA_DQS_DN(9)   I171 @T6G_MB_LIB.T6G(SCH_1):PAGE11
   J62 M_B_CPU0_SA_DQS_DP<5> @T6G_MB_LIB.T6G(SCH_1):M_B_CPU0_SA_DQS_DP(5)   I171 @T6G_MB_LIB.T6G(SCH_1):PAGE11
   M62 M_B_CPU0_SA_DQ<9> @T6G_MB_LIB.T6G(SCH_1):M_B_CPU0_SA_DQ(9)   I171 @T6G_MB_LIB.T6G(SCH_1):PAGE11
  BA62 M_B_CPU0_SA_CA<3> @T6G_MB_LIB.T6G(SCH_1):M_B_CPU0_SA_CA(3)   I171 @T6G_MB_LIB.T6G(SCH_1):PAGE11
  BW62 M_B_CPU0_SB_DQS_DN<4> @T6G_MB_LIB.T6G(SCH_1):M_B_CPU0_SB_DQS_DN(4)   I171 @T6G_MB_LIB.T6G(SCH_1):PAGE11
  CD63 M_B_CPU0_SB_DQS_DP<0> @T6G_MB_LIB.T6G(SCH_1):M_B_CPU0_SB_DQS_DP(0)   I171 @T6G_MB_LIB.T6G(SCH_1):PAGE11
  DD63 M_B_CPU0_SB_DQ<28> @T6G_MB_LIB.T6G(SCH_1):M_B_CPU0_SB_DQ(28)   I171 @T6G_MB_LIB.T6G(SCH_1):PAGE11
  CR62 M_B_CPU0_SB_DQ<17> @T6G_MB_LIB.T6G(SCH_1):M_B_CPU0_SB_DQ(17)   I171 @T6G_MB_LIB.T6G(SCH_1):PAGE11
  CJ62 M_B_CPU0_SB_DQ<9> @T6G_MB_LIB.T6G(SCH_1):M_B_CPU0_SB_DQ(9)   I171 @T6G_MB_LIB.T6G(SCH_1):PAGE11
  BJ64 M_B_CPU0_SB_CA<3> @T6G_MB_LIB.T6G(SCH_1):M_B_CPU0_SB_CA(3)   I171 @T6G_MB_LIB.T6G(SCH_1):PAGE11
  BR64     NC     NC   I171 @T6G_MB_LIB.T6G(SCH_1):PAGE11
   R62 M_B_CPU0_SA_DQS_DP<6> @T6G_MB_LIB.T6G(SCH_1):M_B_CPU0_SA_DQS_DP(6)   I171 @T6G_MB_LIB.T6G(SCH_1):PAGE11
  BA64 M_B_CPU0_SA_CA<4> @T6G_MB_LIB.T6G(SCH_1):M_B_CPU0_SA_CA(4)   I171 @T6G_MB_LIB.T6G(SCH_1):PAGE11
  CE62 M_B_CPU0_SB_DQS_DN<5> @T6G_MB_LIB.T6G(SCH_1):M_B_CPU0_SB_DQS_DN(5)   I171 @T6G_MB_LIB.T6G(SCH_1):PAGE11
  CK63 M_B_CPU0_SB_DQS_DP<1> @T6G_MB_LIB.T6G(SCH_1):M_B_CPU0_SB_DQS_DP(1)   I171 @T6G_MB_LIB.T6G(SCH_1):PAGE11
  DE62 M_B_CPU0_SB_DQ<29> @T6G_MB_LIB.T6G(SCH_1):M_B_CPU0_SB_DQ(29)   I171 @T6G_MB_LIB.T6G(SCH_1):PAGE11
  CR64 M_B_CPU0_SB_DQ<18> @T6G_MB_LIB.T6G(SCH_1):M_B_CPU0_SB_DQ(18)   I171 @T6G_MB_LIB.T6G(SCH_1):PAGE11
  BJ62 M_B_CPU0_SB_CA<4> @T6G_MB_LIB.T6G(SCH_1):M_B_CPU0_SB_CA(4)   I171 @T6G_MB_LIB.T6G(SCH_1):PAGE11
  AA62 M_B_CPU0_SA_DQS_DP<7> @T6G_MB_LIB.T6G(SCH_1):M_B_CPU0_SA_DQS_DP(7)   I171 @T6G_MB_LIB.T6G(SCH_1):PAGE11
  BB63 M_B_CPU0_SA_CA<5> @T6G_MB_LIB.T6G(SCH_1):M_B_CPU0_SA_CA(5)   I171 @T6G_MB_LIB.T6G(SCH_1):PAGE11
  AV63 M_B_CPU0_SA_CS_N<0> @T6G_MB_LIB.T6G(SCH_1):M_B_CPU0_SA_CS_N(0)   I171 @T6G_MB_LIB.T6G(SCH_1):PAGE11
  CL62 M_B_CPU0_SB_DQS_DN<6> @T6G_MB_LIB.T6G(SCH_1):M_B_CPU0_SB_DQS_DN(6)   I171 @T6G_MB_LIB.T6G(SCH_1):PAGE11
  CT63 M_B_CPU0_SB_DQS_DP<2> @T6G_MB_LIB.T6G(SCH_1):M_B_CPU0_SB_DQS_DP(2)   I171 @T6G_MB_LIB.T6G(SCH_1):PAGE11
  BK62 M_B_CPU0_SB_CA<5> @T6G_MB_LIB.T6G(SCH_1):M_B_CPU0_SB_CA(5)   I171 @T6G_MB_LIB.T6G(SCH_1):PAGE11
  AG62 M_B_CPU0_SA_DQS_DP<8> @T6G_MB_LIB.T6G(SCH_1):M_B_CPU0_SA_DQS_DP(8)   I171 @T6G_MB_LIB.T6G(SCH_1):PAGE11
  AH63 M_B_CPU0_SA_DQ<30> @T6G_MB_LIB.T6G(SCH_1):M_B_CPU0_SA_DQ(30)   I171 @T6G_MB_LIB.T6G(SCH_1):PAGE11
  BB62 M_B_CPU0_SA_CA<6> @T6G_MB_LIB.T6G(SCH_1):M_B_CPU0_SA_CA(6)   I171 @T6G_MB_LIB.T6G(SCH_1):PAGE11
  AU64     NC     NC   I171 @T6G_MB_LIB.T6G(SCH_1):PAGE11
  AW62 M_B_CPU0_SA_CS_N<1> @T6G_MB_LIB.T6G(SCH_1):M_B_CPU0_SA_CS_N(1)   I171 @T6G_MB_LIB.T6G(SCH_1):PAGE11
  CU62 M_B_CPU0_SB_DQS_DN<7> @T6G_MB_LIB.T6G(SCH_1):M_B_CPU0_SB_DQS_DN(7)   I171 @T6G_MB_LIB.T6G(SCH_1):PAGE11
  DB63 M_B_CPU0_SB_DQS_DP<3> @T6G_MB_LIB.T6G(SCH_1):M_B_CPU0_SB_DQS_DP(3)   I171 @T6G_MB_LIB.T6G(SCH_1):PAGE11
  BK63 M_B_CPU0_SB_CA<6> @T6G_MB_LIB.T6G(SCH_1):M_B_CPU0_SB_CA(6)   I171 @T6G_MB_LIB.T6G(SCH_1):PAGE11
  AN62 M_B_CPU0_SA_DQS_DP<9> @T6G_MB_LIB.T6G(SCH_1):M_B_CPU0_SA_DQS_DP(9)   I171 @T6G_MB_LIB.T6G(SCH_1):PAGE11
  AJ62 M_B_CPU0_SA_DQ<31> @T6G_MB_LIB.T6G(SCH_1):M_B_CPU0_SA_DQ(31)   I171 @T6G_MB_LIB.T6G(SCH_1):PAGE11
  AA64 M_B_CPU0_SA_DQ<20> @T6G_MB_LIB.T6G(SCH_1):M_B_CPU0_SA_DQ(20)   I171 @T6G_MB_LIB.T6G(SCH_1):PAGE11
  AJ64 M_B_CPU0_SA_CB<0> @T6G_MB_LIB.T6G(SCH_1):M_B_CPU0_SA_CB(0)   I171 @T6G_MB_LIB.T6G(SCH_1):PAGE11
  AV62     NC     NC   I171 @T6G_MB_LIB.T6G(SCH_1):PAGE11
  DC62 M_B_CPU0_SB_DQS_DN<8> @T6G_MB_LIB.T6G(SCH_1):M_B_CPU0_SB_DQS_DN(8)   I171 @T6G_MB_LIB.T6G(SCH_1):PAGE11
  BY62 M_B_CPU0_SB_DQS_DP<4> @T6G_MB_LIB.T6G(SCH_1):M_B_CPU0_SB_DQS_DP(4)   I171 @T6G_MB_LIB.T6G(SCH_1):PAGE11
  AB62 M_B_CPU0_SA_DQ<21> @T6G_MB_LIB.T6G(SCH_1):M_B_CPU0_SA_DQ(21)   I171 @T6G_MB_LIB.T6G(SCH_1):PAGE11
   M63 M_B_CPU0_SA_DQ<10> @T6G_MB_LIB.T6G(SCH_1):M_B_CPU0_SA_DQ(10)   I171 @T6G_MB_LIB.T6G(SCH_1):PAGE11
  AK62 M_B_CPU0_SA_CB<1> @T6G_MB_LIB.T6G(SCH_1):M_B_CPU0_SA_CB(1)   I171 @T6G_MB_LIB.T6G(SCH_1):PAGE11
  BV63 M_B_CPU0_SB_DQS_DP<9> @T6G_MB_LIB.T6G(SCH_1):M_B_CPU0_SB_DQS_DP(9)   I171 @T6G_MB_LIB.T6G(SCH_1):PAGE11
  BC62 M_B_CPU0_SA_PAR @T6G_MB_LIB.T6G(SCH_1):M_B_CPU0_SA_PAR   I171 @T6G_MB_LIB.T6G(SCH_1):PAGE11
  BL64 M_B_CPU0_SB_PAR @T6G_MB_LIB.T6G(SCH_1):M_B_CPU0_SB_PAR   I171 @T6G_MB_LIB.T6G(SCH_1):PAGE11
  BC64 M_B_CPU0_CLK_DP<0> @T6G_MB_LIB.T6G(SCH_1):M_B_CPU0_CLK_DP(0)   I171 @T6G_MB_LIB.T6G(SCH_1):PAGE11
  BD63 M_B_CPU0_CLK_DN<0> @T6G_MB_LIB.T6G(SCH_1):M_B_CPU0_CLK_DN(0)   I171 @T6G_MB_LIB.T6G(SCH_1):PAGE11
  BF63     NC     NC   I171 @T6G_MB_LIB.T6G(SCH_1):PAGE11
  BG64     NC     NC   I171 @T6G_MB_LIB.T6G(SCH_1):PAGE11
  CT62 M_B_CPU0_SB_DQ<19> @T6G_MB_LIB.T6G(SCH_1):M_B_CPU0_SB_DQ(19)   I171 @T6G_MB_LIB.T6G(SCH_1):PAGE11
  AC64 M_B_CPU0_SA_DQ<24> @T6G_MB_LIB.T6G(SCH_1):M_B_CPU0_SA_DQ(24)   I171 @T6G_MB_LIB.T6G(SCH_1):PAGE11
  CV63 M_B_CPU0_SB_DQ<20> @T6G_MB_LIB.T6G(SCH_1):M_B_CPU0_SB_DQ(20)   I171 @T6G_MB_LIB.T6G(SCH_1):PAGE11
  BF62 TP_M_B_CPU0_SA_TEST39B @T6G_MB_LIB.T6G(SCH_1):TP_M_B_CPU0_SA_TEST39B   I171 @T6G_MB_LIB.T6G(SCH_1):PAGE11
  AT55 M_C_CPU0_ALERT_R_N @T6G_MB_LIB.T6G(SCH_1):M_C_CPU0_ALERT_R_N   I159 @T6G_MB_LIB.T6G(SCH_1):PAGE12
  AU55 M_C_CPU0_RESET_N @T6G_MB_LIB.T6G(SCH_1):M_C_CPU0_RESET_N   I159 @T6G_MB_LIB.T6G(SCH_1):PAGE12
  DD55 M_C_CPU0_SB_DQS_DP<8> @T6G_MB_LIB.T6G(SCH_1):M_C_CPU0_SB_DQS_DP(8)   I159 @T6G_MB_LIB.T6G(SCH_1):PAGE12
  DE57 M_C_CPU0_SB_DQ<30> @T6G_MB_LIB.T6G(SCH_1):M_C_CPU0_SB_DQ(30)   I159 @T6G_MB_LIB.T6G(SCH_1):PAGE12
  CH56 M_C_CPU0_SB_DQ<8> @T6G_MB_LIB.T6G(SCH_1):M_C_CPU0_SB_DQ(8)   I159 @T6G_MB_LIB.T6G(SCH_1):PAGE12
  BM56     NC     NC   I159 @T6G_MB_LIB.T6G(SCH_1):PAGE12
  BN57 M_C_CPU0_SB_CS_N<1> @T6G_MB_LIB.T6G(SCH_1):M_C_CPU0_SB_CS_N(1)   I159 @T6G_MB_LIB.T6G(SCH_1):PAGE12
   P56 M_C_CPU0_SA_DQS_DN<1> @T6G_MB_LIB.T6G(SCH_1):M_C_CPU0_SA_DQS_DN(1)   I159 @T6G_MB_LIB.T6G(SCH_1):PAGE12
  AD55 M_C_CPU0_SA_DQ<25> @T6G_MB_LIB.T6G(SCH_1):M_C_CPU0_SA_DQ(25)   I159 @T6G_MB_LIB.T6G(SCH_1):PAGE12
   T56 M_C_CPU0_SA_DQ<14> @T6G_MB_LIB.T6G(SCH_1):M_C_CPU0_SA_DQ(14)   I159 @T6G_MB_LIB.T6G(SCH_1):PAGE12
   M55 M_C_CPU0_SA_DQ<9> @T6G_MB_LIB.T6G(SCH_1):M_C_CPU0_SA_DQ(9)   I159 @T6G_MB_LIB.T6G(SCH_1):PAGE12
  AP55 M_C_CPU0_SA_CB<5> @T6G_MB_LIB.T6G(SCH_1):M_C_CPU0_SA_CB(5)   I159 @T6G_MB_LIB.T6G(SCH_1):PAGE12
  DF55 M_C_CPU0_SB_DQ<31> @T6G_MB_LIB.T6G(SCH_1):M_C_CPU0_SB_DQ(31)   I159 @T6G_MB_LIB.T6G(SCH_1):PAGE12
  CV56 M_C_CPU0_SB_DQ<20> @T6G_MB_LIB.T6G(SCH_1):M_C_CPU0_SB_DQ(20)   I159 @T6G_MB_LIB.T6G(SCH_1):PAGE12
  CJ55 M_C_CPU0_SB_DQ<9> @T6G_MB_LIB.T6G(SCH_1):M_C_CPU0_SB_DQ(9)   I159 @T6G_MB_LIB.T6G(SCH_1):PAGE12
  BY56 M_C_CPU0_SB_CB<0> @T6G_MB_LIB.T6G(SCH_1):M_C_CPU0_SB_CB(0)   I159 @T6G_MB_LIB.T6G(SCH_1):PAGE12
   Y56 M_C_CPU0_SA_DQS_DN<2> @T6G_MB_LIB.T6G(SCH_1):M_C_CPU0_SA_DQS_DN(2)   I159 @T6G_MB_LIB.T6G(SCH_1):PAGE12
  AD56 M_C_CPU0_SA_DQ<26> @T6G_MB_LIB.T6G(SCH_1):M_C_CPU0_SA_DQ(26)   I159 @T6G_MB_LIB.T6G(SCH_1):PAGE12
   U55 M_C_CPU0_SA_DQ<15> @T6G_MB_LIB.T6G(SCH_1):M_C_CPU0_SA_DQ(15)   I159 @T6G_MB_LIB.T6G(SCH_1):PAGE12
  AP56 M_C_CPU0_SA_CB<6> @T6G_MB_LIB.T6G(SCH_1):M_C_CPU0_SA_CB(6)   I159 @T6G_MB_LIB.T6G(SCH_1):PAGE12
  BN55 M_C_CPU0_SA_RSP<0> @T6G_MB_LIB.T6G(SCH_1):M_C_CPU0_SA_RSP(0)   I159 @T6G_MB_LIB.T6G(SCH_1):PAGE12
  CW55 M_C_CPU0_SB_DQ<21> @T6G_MB_LIB.T6G(SCH_1):M_C_CPU0_SB_DQ(21)   I159 @T6G_MB_LIB.T6G(SCH_1):PAGE12
  CJ57 M_C_CPU0_SB_DQ<10> @T6G_MB_LIB.T6G(SCH_1):M_C_CPU0_SB_DQ(10)   I159 @T6G_MB_LIB.T6G(SCH_1):PAGE12
  CA55 M_C_CPU0_SB_CB<1> @T6G_MB_LIB.T6G(SCH_1):M_C_CPU0_SB_CB(1)   I159 @T6G_MB_LIB.T6G(SCH_1):PAGE12
  AF56 M_C_CPU0_SA_DQS_DN<3> @T6G_MB_LIB.T6G(SCH_1):M_C_CPU0_SA_DQS_DN(3)   I159 @T6G_MB_LIB.T6G(SCH_1):PAGE12
  AE55 M_C_CPU0_SA_DQ<27> @T6G_MB_LIB.T6G(SCH_1):M_C_CPU0_SA_DQ(27)   I159 @T6G_MB_LIB.T6G(SCH_1):PAGE12
   U57 M_C_CPU0_SA_DQ<16> @T6G_MB_LIB.T6G(SCH_1):M_C_CPU0_SA_DQ(16)   I159 @T6G_MB_LIB.T6G(SCH_1):PAGE12
  AR55 M_C_CPU0_SA_CB<7> @T6G_MB_LIB.T6G(SCH_1):M_C_CPU0_SA_CB(7)   I159 @T6G_MB_LIB.T6G(SCH_1):PAGE12
  BP55     NC     NC   I159 @T6G_MB_LIB.T6G(SCH_1):PAGE12
  CW57 M_C_CPU0_SB_DQ<22> @T6G_MB_LIB.T6G(SCH_1):M_C_CPU0_SB_DQ(22)   I159 @T6G_MB_LIB.T6G(SCH_1):PAGE12
  CK55 M_C_CPU0_SB_DQ<11> @T6G_MB_LIB.T6G(SCH_1):M_C_CPU0_SB_DQ(11)   I159 @T6G_MB_LIB.T6G(SCH_1):PAGE12
  CA57 M_C_CPU0_SB_CB<2> @T6G_MB_LIB.T6G(SCH_1):M_C_CPU0_SB_CB(2)   I159 @T6G_MB_LIB.T6G(SCH_1):PAGE12
  AM56 M_C_CPU0_SA_DQS_DN<4> @T6G_MB_LIB.T6G(SCH_1):M_C_CPU0_SA_DQS_DN(4)   I159 @T6G_MB_LIB.T6G(SCH_1):PAGE12
   G57 M_C_CPU0_SA_DQS_DP<0> @T6G_MB_LIB.T6G(SCH_1):M_C_CPU0_SA_DQS_DP(0)   I159 @T6G_MB_LIB.T6G(SCH_1):PAGE12
  AG57 M_C_CPU0_SA_DQ<28> @T6G_MB_LIB.T6G(SCH_1):M_C_CPU0_SA_DQ(28)   I159 @T6G_MB_LIB.T6G(SCH_1):PAGE12
   V55 M_C_CPU0_SA_DQ<17> @T6G_MB_LIB.T6G(SCH_1):M_C_CPU0_SA_DQ(17)   I159 @T6G_MB_LIB.T6G(SCH_1):PAGE12
  CY55 M_C_CPU0_SB_DQ<23> @T6G_MB_LIB.T6G(SCH_1):M_C_CPU0_SB_DQ(23)   I159 @T6G_MB_LIB.T6G(SCH_1):PAGE12
  CM56 M_C_CPU0_SB_DQ<12> @T6G_MB_LIB.T6G(SCH_1):M_C_CPU0_SB_DQ(12)   I159 @T6G_MB_LIB.T6G(SCH_1):PAGE12
  CB55 M_C_CPU0_SB_CB<3> @T6G_MB_LIB.T6G(SCH_1):M_C_CPU0_SB_CB(3)   I159 @T6G_MB_LIB.T6G(SCH_1):PAGE12
   H55 M_C_CPU0_SA_DQS_DN<5> @T6G_MB_LIB.T6G(SCH_1):M_C_CPU0_SA_DQS_DN(5)   I159 @T6G_MB_LIB.T6G(SCH_1):PAGE12
   N57 M_C_CPU0_SA_DQS_DP<1> @T6G_MB_LIB.T6G(SCH_1):M_C_CPU0_SA_DQS_DP(1)   I159 @T6G_MB_LIB.T6G(SCH_1):PAGE12
  AH55 M_C_CPU0_SA_DQ<29> @T6G_MB_LIB.T6G(SCH_1):M_C_CPU0_SA_DQ(29)   I159 @T6G_MB_LIB.T6G(SCH_1):PAGE12
   V56 M_C_CPU0_SA_DQ<18> @T6G_MB_LIB.T6G(SCH_1):M_C_CPU0_SA_DQ(18)   I159 @T6G_MB_LIB.T6G(SCH_1):PAGE12
  CE57 M_C_CPU0_SB_DQS_DN<0> @T6G_MB_LIB.T6G(SCH_1):M_C_CPU0_SB_DQS_DN(0)   I159 @T6G_MB_LIB.T6G(SCH_1):PAGE12
  CY56 M_C_CPU0_SB_DQ<24> @T6G_MB_LIB.T6G(SCH_1):M_C_CPU0_SB_DQ(24)   I159 @T6G_MB_LIB.T6G(SCH_1):PAGE12
  CN55 M_C_CPU0_SB_DQ<13> @T6G_MB_LIB.T6G(SCH_1):M_C_CPU0_SB_DQ(13)   I159 @T6G_MB_LIB.T6G(SCH_1):PAGE12
  BT56 M_C_CPU0_SB_CB<4> @T6G_MB_LIB.T6G(SCH_1):M_C_CPU0_SB_CB(4)   I159 @T6G_MB_LIB.T6G(SCH_1):PAGE12
   P55 M_C_CPU0_SA_DQS_DN<6> @T6G_MB_LIB.T6G(SCH_1):M_C_CPU0_SA_DQS_DN(6)   I159 @T6G_MB_LIB.T6G(SCH_1):PAGE12
   W57 M_C_CPU0_SA_DQS_DP<2> @T6G_MB_LIB.T6G(SCH_1):M_C_CPU0_SA_DQS_DP(2)   I159 @T6G_MB_LIB.T6G(SCH_1):PAGE12
   W55 M_C_CPU0_SA_DQ<19> @T6G_MB_LIB.T6G(SCH_1):M_C_CPU0_SA_DQ(19)   I159 @T6G_MB_LIB.T6G(SCH_1):PAGE12
  CL57 M_C_CPU0_SB_DQS_DN<1> @T6G_MB_LIB.T6G(SCH_1):M_C_CPU0_SB_DQS_DN(1)   I159 @T6G_MB_LIB.T6G(SCH_1):PAGE12
  DA55 M_C_CPU0_SB_DQ<25> @T6G_MB_LIB.T6G(SCH_1):M_C_CPU0_SB_DQ(25)   I159 @T6G_MB_LIB.T6G(SCH_1):PAGE12
  CN57 M_C_CPU0_SB_DQ<14> @T6G_MB_LIB.T6G(SCH_1):M_C_CPU0_SB_DQ(14)   I159 @T6G_MB_LIB.T6G(SCH_1):PAGE12
  BU55 M_C_CPU0_SB_CB<5> @T6G_MB_LIB.T6G(SCH_1):M_C_CPU0_SB_CB(5)   I159 @T6G_MB_LIB.T6G(SCH_1):PAGE12
   Y55 M_C_CPU0_SA_DQS_DN<7> @T6G_MB_LIB.T6G(SCH_1):M_C_CPU0_SA_DQS_DN(7)   I159 @T6G_MB_LIB.T6G(SCH_1):PAGE12
  AE57 M_C_CPU0_SA_DQS_DP<3> @T6G_MB_LIB.T6G(SCH_1):M_C_CPU0_SA_DQS_DP(3)   I159 @T6G_MB_LIB.T6G(SCH_1):PAGE12
  CU57 M_C_CPU0_SB_DQS_DN<2> @T6G_MB_LIB.T6G(SCH_1):M_C_CPU0_SB_DQS_DN(2)   I159 @T6G_MB_LIB.T6G(SCH_1):PAGE12
  DA57 M_C_CPU0_SB_DQ<26> @T6G_MB_LIB.T6G(SCH_1):M_C_CPU0_SB_DQ(26)   I159 @T6G_MB_LIB.T6G(SCH_1):PAGE12
  CP55 M_C_CPU0_SB_DQ<15> @T6G_MB_LIB.T6G(SCH_1):M_C_CPU0_SB_DQ(15)   I159 @T6G_MB_LIB.T6G(SCH_1):PAGE12
  BU57 M_C_CPU0_SB_CB<6> @T6G_MB_LIB.T6G(SCH_1):M_C_CPU0_SB_CB(6)   I159 @T6G_MB_LIB.T6G(SCH_1):PAGE12
  AF55 M_C_CPU0_SA_DQS_DN<8> @T6G_MB_LIB.T6G(SCH_1):M_C_CPU0_SA_DQS_DN(8)   I159 @T6G_MB_LIB.T6G(SCH_1):PAGE12
  AL57 M_C_CPU0_SA_DQS_DP<4> @T6G_MB_LIB.T6G(SCH_1):M_C_CPU0_SA_DQS_DP(4)   I159 @T6G_MB_LIB.T6G(SCH_1):PAGE12
  AW57 M_C_CPU0_SA_CA<0> @T6G_MB_LIB.T6G(SCH_1):M_C_CPU0_SA_CA(0)   I159 @T6G_MB_LIB.T6G(SCH_1):PAGE12
  DC57 M_C_CPU0_SB_DQS_DN<3> @T6G_MB_LIB.T6G(SCH_1):M_C_CPU0_SB_DQS_DN(3)   I159 @T6G_MB_LIB.T6G(SCH_1):PAGE12
  DB55 M_C_CPU0_SB_DQ<27> @T6G_MB_LIB.T6G(SCH_1):M_C_CPU0_SB_DQ(27)   I159 @T6G_MB_LIB.T6G(SCH_1):PAGE12
  CP56 M_C_CPU0_SB_DQ<16> @T6G_MB_LIB.T6G(SCH_1):M_C_CPU0_SB_DQ(16)   I159 @T6G_MB_LIB.T6G(SCH_1):PAGE12
  BV55 M_C_CPU0_SB_CB<7> @T6G_MB_LIB.T6G(SCH_1):M_C_CPU0_SB_CB(7)   I159 @T6G_MB_LIB.T6G(SCH_1):PAGE12
  BG55 M_C_CPU0_SB_CA<0> @T6G_MB_LIB.T6G(SCH_1):M_C_CPU0_SB_CA(0)   I159 @T6G_MB_LIB.T6G(SCH_1):PAGE12
  BR57     NC     NC   I159 @T6G_MB_LIB.T6G(SCH_1):PAGE12
  BP56 M_C_CPU0_SB_RSP<0> @T6G_MB_LIB.T6G(SCH_1):M_C_CPU0_SB_RSP(0)   I159 @T6G_MB_LIB.T6G(SCH_1):PAGE12
  AM55 M_C_CPU0_SA_DQS_DN<9> @T6G_MB_LIB.T6G(SCH_1):M_C_CPU0_SA_DQS_DN(9)   I159 @T6G_MB_LIB.T6G(SCH_1):PAGE12
   J55 M_C_CPU0_SA_DQS_DP<5> @T6G_MB_LIB.T6G(SCH_1):M_C_CPU0_SA_DQS_DP(5)   I159 @T6G_MB_LIB.T6G(SCH_1):PAGE12
   E57 M_C_CPU0_SA_DQ<0> @T6G_MB_LIB.T6G(SCH_1):M_C_CPU0_SA_DQ(0)   I159 @T6G_MB_LIB.T6G(SCH_1):PAGE12
  AY56 M_C_CPU0_SA_CA<1> @T6G_MB_LIB.T6G(SCH_1):M_C_CPU0_SA_CA(1)   I159 @T6G_MB_LIB.T6G(SCH_1):PAGE12
  BW55 M_C_CPU0_SB_DQS_DN<4> @T6G_MB_LIB.T6G(SCH_1):M_C_CPU0_SB_DQS_DN(4)   I159 @T6G_MB_LIB.T6G(SCH_1):PAGE12
  CD56 M_C_CPU0_SB_DQS_DP<0> @T6G_MB_LIB.T6G(SCH_1):M_C_CPU0_SB_DQS_DP(0)   I159 @T6G_MB_LIB.T6G(SCH_1):PAGE12
  DD56 M_C_CPU0_SB_DQ<28> @T6G_MB_LIB.T6G(SCH_1):M_C_CPU0_SB_DQ(28)   I159 @T6G_MB_LIB.T6G(SCH_1):PAGE12
  CR55 M_C_CPU0_SB_DQ<17> @T6G_MB_LIB.T6G(SCH_1):M_C_CPU0_SB_DQ(17)   I159 @T6G_MB_LIB.T6G(SCH_1):PAGE12
  CB56 M_C_CPU0_SB_DQ<0> @T6G_MB_LIB.T6G(SCH_1):M_C_CPU0_SB_DQ(0)   I159 @T6G_MB_LIB.T6G(SCH_1):PAGE12
  BH55 M_C_CPU0_SB_CA<1> @T6G_MB_LIB.T6G(SCH_1):M_C_CPU0_SB_CA(1)   I159 @T6G_MB_LIB.T6G(SCH_1):PAGE12
   R55 M_C_CPU0_SA_DQS_DP<6> @T6G_MB_LIB.T6G(SCH_1):M_C_CPU0_SA_DQS_DP(6)   I159 @T6G_MB_LIB.T6G(SCH_1):PAGE12
   F55 M_C_CPU0_SA_DQ<1> @T6G_MB_LIB.T6G(SCH_1):M_C_CPU0_SA_DQ(1)   I159 @T6G_MB_LIB.T6G(SCH_1):PAGE12
  AY55 M_C_CPU0_SA_CA<2> @T6G_MB_LIB.T6G(SCH_1):M_C_CPU0_SA_CA(2)   I159 @T6G_MB_LIB.T6G(SCH_1):PAGE12
  AV56 M_C_CPU0_SA_CS_N<0> @T6G_MB_LIB.T6G(SCH_1):M_C_CPU0_SA_CS_N(0)   I159 @T6G_MB_LIB.T6G(SCH_1):PAGE12
  CE55 M_C_CPU0_SB_DQS_DN<5> @T6G_MB_LIB.T6G(SCH_1):M_C_CPU0_SB_DQS_DN(5)   I159 @T6G_MB_LIB.T6G(SCH_1):PAGE12
  CK56 M_C_CPU0_SB_DQS_DP<1> @T6G_MB_LIB.T6G(SCH_1):M_C_CPU0_SB_DQS_DP(1)   I159 @T6G_MB_LIB.T6G(SCH_1):PAGE12
  DE55 M_C_CPU0_SB_DQ<29> @T6G_MB_LIB.T6G(SCH_1):M_C_CPU0_SB_DQ(29)   I159 @T6G_MB_LIB.T6G(SCH_1):PAGE12
  CR57 M_C_CPU0_SB_DQ<18> @T6G_MB_LIB.T6G(SCH_1):M_C_CPU0_SB_DQ(18)   I159 @T6G_MB_LIB.T6G(SCH_1):PAGE12
  CC55 M_C_CPU0_SB_DQ<1> @T6G_MB_LIB.T6G(SCH_1):M_C_CPU0_SB_DQ(1)   I159 @T6G_MB_LIB.T6G(SCH_1):PAGE12
  BH56 M_C_CPU0_SB_CA<2> @T6G_MB_LIB.T6G(SCH_1):M_C_CPU0_SB_CA(2)   I159 @T6G_MB_LIB.T6G(SCH_1):PAGE12
  AA55 M_C_CPU0_SA_DQS_DP<7> @T6G_MB_LIB.T6G(SCH_1):M_C_CPU0_SA_DQS_DP(7)   I159 @T6G_MB_LIB.T6G(SCH_1):PAGE12
   F56 M_C_CPU0_SA_DQ<2> @T6G_MB_LIB.T6G(SCH_1):M_C_CPU0_SA_DQ(2)   I159 @T6G_MB_LIB.T6G(SCH_1):PAGE12
  BA55 M_C_CPU0_SA_CA<3> @T6G_MB_LIB.T6G(SCH_1):M_C_CPU0_SA_CA(3)   I159 @T6G_MB_LIB.T6G(SCH_1):PAGE12
  AU57     NC     NC   I159 @T6G_MB_LIB.T6G(SCH_1):PAGE12
  AW55 M_C_CPU0_SA_CS_N<1> @T6G_MB_LIB.T6G(SCH_1):M_C_CPU0_SA_CS_N(1)   I159 @T6G_MB_LIB.T6G(SCH_1):PAGE12
  CL55 M_C_CPU0_SB_DQS_DN<6> @T6G_MB_LIB.T6G(SCH_1):M_C_CPU0_SB_DQS_DN(6)   I159 @T6G_MB_LIB.T6G(SCH_1):PAGE12
  CT56 M_C_CPU0_SB_DQS_DP<2> @T6G_MB_LIB.T6G(SCH_1):M_C_CPU0_SB_DQS_DP(2)   I159 @T6G_MB_LIB.T6G(SCH_1):PAGE12
  CT55 M_C_CPU0_SB_DQ<19> @T6G_MB_LIB.T6G(SCH_1):M_C_CPU0_SB_DQ(19)   I159 @T6G_MB_LIB.T6G(SCH_1):PAGE12
  CC57 M_C_CPU0_SB_DQ<2> @T6G_MB_LIB.T6G(SCH_1):M_C_CPU0_SB_DQ(2)   I159 @T6G_MB_LIB.T6G(SCH_1):PAGE12
  BJ57 M_C_CPU0_SB_CA<3> @T6G_MB_LIB.T6G(SCH_1):M_C_CPU0_SB_CA(3)   I159 @T6G_MB_LIB.T6G(SCH_1):PAGE12
  AG55 M_C_CPU0_SA_DQS_DP<8> @T6G_MB_LIB.T6G(SCH_1):M_C_CPU0_SA_DQS_DP(8)   I159 @T6G_MB_LIB.T6G(SCH_1):PAGE12
  AH56 M_C_CPU0_SA_DQ<30> @T6G_MB_LIB.T6G(SCH_1):M_C_CPU0_SA_DQ(30)   I159 @T6G_MB_LIB.T6G(SCH_1):PAGE12
   G55 M_C_CPU0_SA_DQ<3> @T6G_MB_LIB.T6G(SCH_1):M_C_CPU0_SA_DQ(3)   I159 @T6G_MB_LIB.T6G(SCH_1):PAGE12
  BA57 M_C_CPU0_SA_CA<4> @T6G_MB_LIB.T6G(SCH_1):M_C_CPU0_SA_CA(4)   I159 @T6G_MB_LIB.T6G(SCH_1):PAGE12
  AV55     NC     NC   I159 @T6G_MB_LIB.T6G(SCH_1):PAGE12
  CU55 M_C_CPU0_SB_DQS_DN<7> @T6G_MB_LIB.T6G(SCH_1):M_C_CPU0_SB_DQS_DN(7)   I159 @T6G_MB_LIB.T6G(SCH_1):PAGE12
  DB56 M_C_CPU0_SB_DQS_DP<3> @T6G_MB_LIB.T6G(SCH_1):M_C_CPU0_SB_DQS_DP(3)   I159 @T6G_MB_LIB.T6G(SCH_1):PAGE12
  CD55 M_C_CPU0_SB_DQ<3> @T6G_MB_LIB.T6G(SCH_1):M_C_CPU0_SB_DQ(3)   I159 @T6G_MB_LIB.T6G(SCH_1):PAGE12
  BJ55 M_C_CPU0_SB_CA<4> @T6G_MB_LIB.T6G(SCH_1):M_C_CPU0_SB_CA(4)   I159 @T6G_MB_LIB.T6G(SCH_1):PAGE12
  AN55 M_C_CPU0_SA_DQS_DP<9> @T6G_MB_LIB.T6G(SCH_1):M_C_CPU0_SA_DQS_DP(9)   I159 @T6G_MB_LIB.T6G(SCH_1):PAGE12
  AJ55 M_C_CPU0_SA_DQ<31> @T6G_MB_LIB.T6G(SCH_1):M_C_CPU0_SA_DQ(31)   I159 @T6G_MB_LIB.T6G(SCH_1):PAGE12
  AA57 M_C_CPU0_SA_DQ<20> @T6G_MB_LIB.T6G(SCH_1):M_C_CPU0_SA_DQ(20)   I159 @T6G_MB_LIB.T6G(SCH_1):PAGE12
   J57 M_C_CPU0_SA_DQ<4> @T6G_MB_LIB.T6G(SCH_1):M_C_CPU0_SA_DQ(4)   I159 @T6G_MB_LIB.T6G(SCH_1):PAGE12
  AJ57 M_C_CPU0_SA_CB<0> @T6G_MB_LIB.T6G(SCH_1):M_C_CPU0_SA_CB(0)   I159 @T6G_MB_LIB.T6G(SCH_1):PAGE12
  BB56 M_C_CPU0_SA_CA<5> @T6G_MB_LIB.T6G(SCH_1):M_C_CPU0_SA_CA(5)   I159 @T6G_MB_LIB.T6G(SCH_1):PAGE12
  DC55 M_C_CPU0_SB_DQS_DN<8> @T6G_MB_LIB.T6G(SCH_1):M_C_CPU0_SB_DQS_DN(8)   I159 @T6G_MB_LIB.T6G(SCH_1):PAGE12
  BY55 M_C_CPU0_SB_DQS_DP<4> @T6G_MB_LIB.T6G(SCH_1):M_C_CPU0_SB_DQS_DP(4)   I159 @T6G_MB_LIB.T6G(SCH_1):PAGE12
  CF56 M_C_CPU0_SB_DQ<4> @T6G_MB_LIB.T6G(SCH_1):M_C_CPU0_SB_DQ(4)   I159 @T6G_MB_LIB.T6G(SCH_1):PAGE12
  BK55 M_C_CPU0_SB_CA<5> @T6G_MB_LIB.T6G(SCH_1):M_C_CPU0_SB_CA(5)   I159 @T6G_MB_LIB.T6G(SCH_1):PAGE12
  AB55 M_C_CPU0_SA_DQ<21> @T6G_MB_LIB.T6G(SCH_1):M_C_CPU0_SA_DQ(21)   I159 @T6G_MB_LIB.T6G(SCH_1):PAGE12
   M56 M_C_CPU0_SA_DQ<10> @T6G_MB_LIB.T6G(SCH_1):M_C_CPU0_SA_DQ(10)   I159 @T6G_MB_LIB.T6G(SCH_1):PAGE12
   K55 M_C_CPU0_SA_DQ<5> @T6G_MB_LIB.T6G(SCH_1):M_C_CPU0_SA_DQ(5)   I159 @T6G_MB_LIB.T6G(SCH_1):PAGE12
  AK55 M_C_CPU0_SA_CB<1> @T6G_MB_LIB.T6G(SCH_1):M_C_CPU0_SA_CB(1)   I159 @T6G_MB_LIB.T6G(SCH_1):PAGE12
  BB55 M_C_CPU0_SA_CA<6> @T6G_MB_LIB.T6G(SCH_1):M_C_CPU0_SA_CA(6)   I159 @T6G_MB_LIB.T6G(SCH_1):PAGE12
  BW57 M_C_CPU0_SB_DQS_DN<9> @T6G_MB_LIB.T6G(SCH_1):M_C_CPU0_SB_DQS_DN(9)   I159 @T6G_MB_LIB.T6G(SCH_1):PAGE12
  CF55 M_C_CPU0_SB_DQS_DP<5> @T6G_MB_LIB.T6G(SCH_1):M_C_CPU0_SB_DQS_DP(5)   I159 @T6G_MB_LIB.T6G(SCH_1):PAGE12
  CG55 M_C_CPU0_SB_DQ<5> @T6G_MB_LIB.T6G(SCH_1):M_C_CPU0_SB_DQ(5)   I159 @T6G_MB_LIB.T6G(SCH_1):PAGE12
  BK56 M_C_CPU0_SB_CA<6> @T6G_MB_LIB.T6G(SCH_1):M_C_CPU0_SB_CA(6)   I159 @T6G_MB_LIB.T6G(SCH_1):PAGE12
  AB56 M_C_CPU0_SA_DQ<22> @T6G_MB_LIB.T6G(SCH_1):M_C_CPU0_SA_DQ(22)   I159 @T6G_MB_LIB.T6G(SCH_1):PAGE12
   N55 M_C_CPU0_SA_DQ<11> @T6G_MB_LIB.T6G(SCH_1):M_C_CPU0_SA_DQ(11)   I159 @T6G_MB_LIB.T6G(SCH_1):PAGE12
   K56 M_C_CPU0_SA_DQ<6> @T6G_MB_LIB.T6G(SCH_1):M_C_CPU0_SA_DQ(6)   I159 @T6G_MB_LIB.T6G(SCH_1):PAGE12
  AK56 M_C_CPU0_SA_CB<2> @T6G_MB_LIB.T6G(SCH_1):M_C_CPU0_SA_CB(2)   I159 @T6G_MB_LIB.T6G(SCH_1):PAGE12
  CM55 M_C_CPU0_SB_DQS_DP<6> @T6G_MB_LIB.T6G(SCH_1):M_C_CPU0_SB_DQS_DP(6)   I159 @T6G_MB_LIB.T6G(SCH_1):PAGE12
  CG57 M_C_CPU0_SB_DQ<6> @T6G_MB_LIB.T6G(SCH_1):M_C_CPU0_SB_DQ(6)   I159 @T6G_MB_LIB.T6G(SCH_1):PAGE12
  AC55 M_C_CPU0_SA_DQ<23> @T6G_MB_LIB.T6G(SCH_1):M_C_CPU0_SA_DQ(23)   I159 @T6G_MB_LIB.T6G(SCH_1):PAGE12
   R57 M_C_CPU0_SA_DQ<12> @T6G_MB_LIB.T6G(SCH_1):M_C_CPU0_SA_DQ(12)   I159 @T6G_MB_LIB.T6G(SCH_1):PAGE12
   L55 M_C_CPU0_SA_DQ<7> @T6G_MB_LIB.T6G(SCH_1):M_C_CPU0_SA_DQ(7)   I159 @T6G_MB_LIB.T6G(SCH_1):PAGE12
  AL55 M_C_CPU0_SA_CB<3> @T6G_MB_LIB.T6G(SCH_1):M_C_CPU0_SA_CB(3)   I159 @T6G_MB_LIB.T6G(SCH_1):PAGE12
  CV55 M_C_CPU0_SB_DQS_DP<7> @T6G_MB_LIB.T6G(SCH_1):M_C_CPU0_SB_DQS_DP(7)   I159 @T6G_MB_LIB.T6G(SCH_1):PAGE12
  CH55 M_C_CPU0_SB_DQ<7> @T6G_MB_LIB.T6G(SCH_1):M_C_CPU0_SB_DQ(7)   I159 @T6G_MB_LIB.T6G(SCH_1):PAGE12
  BL55     NC     NC   I159 @T6G_MB_LIB.T6G(SCH_1):PAGE12
  BM55 M_C_CPU0_SB_CS_N<0> @T6G_MB_LIB.T6G(SCH_1):M_C_CPU0_SB_CS_N(0)   I159 @T6G_MB_LIB.T6G(SCH_1):PAGE12
   H56 M_C_CPU0_SA_DQS_DN<0> @T6G_MB_LIB.T6G(SCH_1):M_C_CPU0_SA_DQS_DN(0)   I159 @T6G_MB_LIB.T6G(SCH_1):PAGE12
  AC57 M_C_CPU0_SA_DQ<24> @T6G_MB_LIB.T6G(SCH_1):M_C_CPU0_SA_DQ(24)   I159 @T6G_MB_LIB.T6G(SCH_1):PAGE12
   T55 M_C_CPU0_SA_DQ<13> @T6G_MB_LIB.T6G(SCH_1):M_C_CPU0_SA_DQ(13)   I159 @T6G_MB_LIB.T6G(SCH_1):PAGE12
   L57 M_C_CPU0_SA_DQ<8> @T6G_MB_LIB.T6G(SCH_1):M_C_CPU0_SA_DQ(8)   I159 @T6G_MB_LIB.T6G(SCH_1):PAGE12
  AN57 M_C_CPU0_SA_CB<4> @T6G_MB_LIB.T6G(SCH_1):M_C_CPU0_SA_CB(4)   I159 @T6G_MB_LIB.T6G(SCH_1):PAGE12
  BV56 M_C_CPU0_SB_DQS_DP<9> @T6G_MB_LIB.T6G(SCH_1):M_C_CPU0_SB_DQS_DP(9)   I159 @T6G_MB_LIB.T6G(SCH_1):PAGE12
  BC55 M_C_CPU0_SA_PAR @T6G_MB_LIB.T6G(SCH_1):M_C_CPU0_SA_PAR   I159 @T6G_MB_LIB.T6G(SCH_1):PAGE12
  BL57 M_C_CPU0_SB_PAR @T6G_MB_LIB.T6G(SCH_1):M_C_CPU0_SB_PAR   I159 @T6G_MB_LIB.T6G(SCH_1):PAGE12
  BC57 M_C_CPU0_CLK_DP<0> @T6G_MB_LIB.T6G(SCH_1):M_C_CPU0_CLK_DP(0)   I159 @T6G_MB_LIB.T6G(SCH_1):PAGE12
  BD56 M_C_CPU0_CLK_DN<0> @T6G_MB_LIB.T6G(SCH_1):M_C_CPU0_CLK_DN(0)   I159 @T6G_MB_LIB.T6G(SCH_1):PAGE12
  BF56     NC     NC   I159 @T6G_MB_LIB.T6G(SCH_1):PAGE12
  BG57     NC     NC   I159 @T6G_MB_LIB.T6G(SCH_1):PAGE12
  BF55 TP_M_C_CPU0_SA_TEST39C @T6G_MB_LIB.T6G(SCH_1):TP_M_C_CPU0_SA_TEST39C   I159 @T6G_MB_LIB.T6G(SCH_1):PAGE12
  AT58 M_D_CPU0_ALERT_R_N @T6G_MB_LIB.T6G(SCH_1):M_D_CPU0_ALERT_R_N   I159 @T6G_MB_LIB.T6G(SCH_1):PAGE13
  AU59 M_D_CPU0_RESET_N @T6G_MB_LIB.T6G(SCH_1):M_D_CPU0_RESET_N   I159 @T6G_MB_LIB.T6G(SCH_1):PAGE13
  CY58 M_D_CPU0_SB_DQ<23> @T6G_MB_LIB.T6G(SCH_1):M_D_CPU0_SB_DQ(23)   I159 @T6G_MB_LIB.T6G(SCH_1):PAGE13
  CM60 M_D_CPU0_SB_DQ<12> @T6G_MB_LIB.T6G(SCH_1):M_D_CPU0_SB_DQ(12)   I159 @T6G_MB_LIB.T6G(SCH_1):PAGE13
  CC60 M_D_CPU0_SB_DQ<2> @T6G_MB_LIB.T6G(SCH_1):M_D_CPU0_SB_DQ(2)   I159 @T6G_MB_LIB.T6G(SCH_1):PAGE13
  CB58 M_D_CPU0_SB_CB<3> @T6G_MB_LIB.T6G(SCH_1):M_D_CPU0_SB_CB(3)   I159 @T6G_MB_LIB.T6G(SCH_1):PAGE13
   H58 M_D_CPU0_SA_DQS_DN<5> @T6G_MB_LIB.T6G(SCH_1):M_D_CPU0_SA_DQS_DN(5)   I159 @T6G_MB_LIB.T6G(SCH_1):PAGE13
   N60 M_D_CPU0_SA_DQS_DP<1> @T6G_MB_LIB.T6G(SCH_1):M_D_CPU0_SA_DQS_DP(1)   I159 @T6G_MB_LIB.T6G(SCH_1):PAGE13
  AH58 M_D_CPU0_SA_DQ<29> @T6G_MB_LIB.T6G(SCH_1):M_D_CPU0_SA_DQ(29)   I159 @T6G_MB_LIB.T6G(SCH_1):PAGE13
   V60 M_D_CPU0_SA_DQ<18> @T6G_MB_LIB.T6G(SCH_1):M_D_CPU0_SA_DQ(18)   I159 @T6G_MB_LIB.T6G(SCH_1):PAGE13
   G59 M_D_CPU0_SA_DQ<3> @T6G_MB_LIB.T6G(SCH_1):M_D_CPU0_SA_DQ(3)   I159 @T6G_MB_LIB.T6G(SCH_1):PAGE13
  CE60 M_D_CPU0_SB_DQS_DN<0> @T6G_MB_LIB.T6G(SCH_1):M_D_CPU0_SB_DQS_DN(0)   I159 @T6G_MB_LIB.T6G(SCH_1):PAGE13
  CY60 M_D_CPU0_SB_DQ<24> @T6G_MB_LIB.T6G(SCH_1):M_D_CPU0_SB_DQ(24)   I159 @T6G_MB_LIB.T6G(SCH_1):PAGE13
  CN59 M_D_CPU0_SB_DQ<13> @T6G_MB_LIB.T6G(SCH_1):M_D_CPU0_SB_DQ(13)   I159 @T6G_MB_LIB.T6G(SCH_1):PAGE13
  CD58 M_D_CPU0_SB_DQ<3> @T6G_MB_LIB.T6G(SCH_1):M_D_CPU0_SB_DQ(3)   I159 @T6G_MB_LIB.T6G(SCH_1):PAGE13
  BT60 M_D_CPU0_SB_CB<4> @T6G_MB_LIB.T6G(SCH_1):M_D_CPU0_SB_CB(4)   I159 @T6G_MB_LIB.T6G(SCH_1):PAGE13
   P58 M_D_CPU0_SA_DQS_DN<6> @T6G_MB_LIB.T6G(SCH_1):M_D_CPU0_SA_DQS_DN(6)   I159 @T6G_MB_LIB.T6G(SCH_1):PAGE13
   W60 M_D_CPU0_SA_DQS_DP<2> @T6G_MB_LIB.T6G(SCH_1):M_D_CPU0_SA_DQS_DP(2)   I159 @T6G_MB_LIB.T6G(SCH_1):PAGE13
   W59 M_D_CPU0_SA_DQ<19> @T6G_MB_LIB.T6G(SCH_1):M_D_CPU0_SA_DQ(19)   I159 @T6G_MB_LIB.T6G(SCH_1):PAGE13
   J60 M_D_CPU0_SA_DQ<4> @T6G_MB_LIB.T6G(SCH_1):M_D_CPU0_SA_DQ(4)   I159 @T6G_MB_LIB.T6G(SCH_1):PAGE13
  CL60 M_D_CPU0_SB_DQS_DN<1> @T6G_MB_LIB.T6G(SCH_1):M_D_CPU0_SB_DQS_DN(1)   I159 @T6G_MB_LIB.T6G(SCH_1):PAGE13
  DA59 M_D_CPU0_SB_DQ<25> @T6G_MB_LIB.T6G(SCH_1):M_D_CPU0_SB_DQ(25)   I159 @T6G_MB_LIB.T6G(SCH_1):PAGE13
  CN60 M_D_CPU0_SB_DQ<14> @T6G_MB_LIB.T6G(SCH_1):M_D_CPU0_SB_DQ(14)   I159 @T6G_MB_LIB.T6G(SCH_1):PAGE13
  CF60 M_D_CPU0_SB_DQ<4> @T6G_MB_LIB.T6G(SCH_1):M_D_CPU0_SB_DQ(4)   I159 @T6G_MB_LIB.T6G(SCH_1):PAGE13
  BU59 M_D_CPU0_SB_CB<5> @T6G_MB_LIB.T6G(SCH_1):M_D_CPU0_SB_CB(5)   I159 @T6G_MB_LIB.T6G(SCH_1):PAGE13
   Y58 M_D_CPU0_SA_DQS_DN<7> @T6G_MB_LIB.T6G(SCH_1):M_D_CPU0_SA_DQS_DN(7)   I159 @T6G_MB_LIB.T6G(SCH_1):PAGE13
  AE60 M_D_CPU0_SA_DQS_DP<3> @T6G_MB_LIB.T6G(SCH_1):M_D_CPU0_SA_DQS_DP(3)   I159 @T6G_MB_LIB.T6G(SCH_1):PAGE13
   K58 M_D_CPU0_SA_DQ<5> @T6G_MB_LIB.T6G(SCH_1):M_D_CPU0_SA_DQ(5)   I159 @T6G_MB_LIB.T6G(SCH_1):PAGE13
  CU60 M_D_CPU0_SB_DQS_DN<2> @T6G_MB_LIB.T6G(SCH_1):M_D_CPU0_SB_DQS_DN(2)   I159 @T6G_MB_LIB.T6G(SCH_1):PAGE13
  DA60 M_D_CPU0_SB_DQ<26> @T6G_MB_LIB.T6G(SCH_1):M_D_CPU0_SB_DQ(26)   I159 @T6G_MB_LIB.T6G(SCH_1):PAGE13
  CP58 M_D_CPU0_SB_DQ<15> @T6G_MB_LIB.T6G(SCH_1):M_D_CPU0_SB_DQ(15)   I159 @T6G_MB_LIB.T6G(SCH_1):PAGE13
  CG59 M_D_CPU0_SB_DQ<5> @T6G_MB_LIB.T6G(SCH_1):M_D_CPU0_SB_DQ(5)   I159 @T6G_MB_LIB.T6G(SCH_1):PAGE13
  BU60 M_D_CPU0_SB_CB<6> @T6G_MB_LIB.T6G(SCH_1):M_D_CPU0_SB_CB(6)   I159 @T6G_MB_LIB.T6G(SCH_1):PAGE13
  AF58 M_D_CPU0_SA_DQS_DN<8> @T6G_MB_LIB.T6G(SCH_1):M_D_CPU0_SA_DQS_DN(8)   I159 @T6G_MB_LIB.T6G(SCH_1):PAGE13
  AL60 M_D_CPU0_SA_DQS_DP<4> @T6G_MB_LIB.T6G(SCH_1):M_D_CPU0_SA_DQS_DP(4)   I159 @T6G_MB_LIB.T6G(SCH_1):PAGE13
   K60 M_D_CPU0_SA_DQ<6> @T6G_MB_LIB.T6G(SCH_1):M_D_CPU0_SA_DQ(6)   I159 @T6G_MB_LIB.T6G(SCH_1):PAGE13
  DC60 M_D_CPU0_SB_DQS_DN<3> @T6G_MB_LIB.T6G(SCH_1):M_D_CPU0_SB_DQS_DN(3)   I159 @T6G_MB_LIB.T6G(SCH_1):PAGE13
  DB58 M_D_CPU0_SB_DQ<27> @T6G_MB_LIB.T6G(SCH_1):M_D_CPU0_SB_DQ(27)   I159 @T6G_MB_LIB.T6G(SCH_1):PAGE13
  CP60 M_D_CPU0_SB_DQ<16> @T6G_MB_LIB.T6G(SCH_1):M_D_CPU0_SB_DQ(16)   I159 @T6G_MB_LIB.T6G(SCH_1):PAGE13
  CG60 M_D_CPU0_SB_DQ<6> @T6G_MB_LIB.T6G(SCH_1):M_D_CPU0_SB_DQ(6)   I159 @T6G_MB_LIB.T6G(SCH_1):PAGE13
  BV58 M_D_CPU0_SB_CB<7> @T6G_MB_LIB.T6G(SCH_1):M_D_CPU0_SB_CB(7)   I159 @T6G_MB_LIB.T6G(SCH_1):PAGE13
  BP60 M_D_CPU0_SB_RSP<0> @T6G_MB_LIB.T6G(SCH_1):M_D_CPU0_SB_RSP(0)   I159 @T6G_MB_LIB.T6G(SCH_1):PAGE13
  AM58 M_D_CPU0_SA_DQS_DN<9> @T6G_MB_LIB.T6G(SCH_1):M_D_CPU0_SA_DQS_DN(9)   I159 @T6G_MB_LIB.T6G(SCH_1):PAGE13
   J59 M_D_CPU0_SA_DQS_DP<5> @T6G_MB_LIB.T6G(SCH_1):M_D_CPU0_SA_DQS_DP(5)   I159 @T6G_MB_LIB.T6G(SCH_1):PAGE13
   L59 M_D_CPU0_SA_DQ<7> @T6G_MB_LIB.T6G(SCH_1):M_D_CPU0_SA_DQ(7)   I159 @T6G_MB_LIB.T6G(SCH_1):PAGE13
  BW59 M_D_CPU0_SB_DQS_DN<4> @T6G_MB_LIB.T6G(SCH_1):M_D_CPU0_SB_DQS_DN(4)   I159 @T6G_MB_LIB.T6G(SCH_1):PAGE13
  CD60 M_D_CPU0_SB_DQS_DP<0> @T6G_MB_LIB.T6G(SCH_1):M_D_CPU0_SB_DQS_DP(0)   I159 @T6G_MB_LIB.T6G(SCH_1):PAGE13
  DD60 M_D_CPU0_SB_DQ<28> @T6G_MB_LIB.T6G(SCH_1):M_D_CPU0_SB_DQ(28)   I159 @T6G_MB_LIB.T6G(SCH_1):PAGE13
  CR59 M_D_CPU0_SB_DQ<17> @T6G_MB_LIB.T6G(SCH_1):M_D_CPU0_SB_DQ(17)   I159 @T6G_MB_LIB.T6G(SCH_1):PAGE13
  CH58 M_D_CPU0_SB_DQ<7> @T6G_MB_LIB.T6G(SCH_1):M_D_CPU0_SB_DQ(7)   I159 @T6G_MB_LIB.T6G(SCH_1):PAGE13
  BR60     NC     NC   I159 @T6G_MB_LIB.T6G(SCH_1):PAGE13
   R59 M_D_CPU0_SA_DQS_DP<6> @T6G_MB_LIB.T6G(SCH_1):M_D_CPU0_SA_DQS_DP(6)   I159 @T6G_MB_LIB.T6G(SCH_1):PAGE13
   L60 M_D_CPU0_SA_DQ<8> @T6G_MB_LIB.T6G(SCH_1):M_D_CPU0_SA_DQ(8)   I159 @T6G_MB_LIB.T6G(SCH_1):PAGE13
  CE59 M_D_CPU0_SB_DQS_DN<5> @T6G_MB_LIB.T6G(SCH_1):M_D_CPU0_SB_DQS_DN(5)   I159 @T6G_MB_LIB.T6G(SCH_1):PAGE13
  CK60 M_D_CPU0_SB_DQS_DP<1> @T6G_MB_LIB.T6G(SCH_1):M_D_CPU0_SB_DQS_DP(1)   I159 @T6G_MB_LIB.T6G(SCH_1):PAGE13
  DE59 M_D_CPU0_SB_DQ<29> @T6G_MB_LIB.T6G(SCH_1):M_D_CPU0_SB_DQ(29)   I159 @T6G_MB_LIB.T6G(SCH_1):PAGE13
  CR60 M_D_CPU0_SB_DQ<18> @T6G_MB_LIB.T6G(SCH_1):M_D_CPU0_SB_DQ(18)   I159 @T6G_MB_LIB.T6G(SCH_1):PAGE13
  CH60 M_D_CPU0_SB_DQ<8> @T6G_MB_LIB.T6G(SCH_1):M_D_CPU0_SB_DQ(8)   I159 @T6G_MB_LIB.T6G(SCH_1):PAGE13
  AA59 M_D_CPU0_SA_DQS_DP<7> @T6G_MB_LIB.T6G(SCH_1):M_D_CPU0_SA_DQS_DP(7)   I159 @T6G_MB_LIB.T6G(SCH_1):PAGE13
   M58 M_D_CPU0_SA_DQ<9> @T6G_MB_LIB.T6G(SCH_1):M_D_CPU0_SA_DQ(9)   I159 @T6G_MB_LIB.T6G(SCH_1):PAGE13
  AW60 M_D_CPU0_SA_CA<0> @T6G_MB_LIB.T6G(SCH_1):M_D_CPU0_SA_CA(0)   I159 @T6G_MB_LIB.T6G(SCH_1):PAGE13
  AV60 M_D_CPU0_SA_CS_N<0> @T6G_MB_LIB.T6G(SCH_1):M_D_CPU0_SA_CS_N(0)   I159 @T6G_MB_LIB.T6G(SCH_1):PAGE13
  CL59 M_D_CPU0_SB_DQS_DN<6> @T6G_MB_LIB.T6G(SCH_1):M_D_CPU0_SB_DQS_DN(6)   I159 @T6G_MB_LIB.T6G(SCH_1):PAGE13
  CT60 M_D_CPU0_SB_DQS_DP<2> @T6G_MB_LIB.T6G(SCH_1):M_D_CPU0_SB_DQS_DP(2)   I159 @T6G_MB_LIB.T6G(SCH_1):PAGE13
  CT58 M_D_CPU0_SB_DQ<19> @T6G_MB_LIB.T6G(SCH_1):M_D_CPU0_SB_DQ(19)   I159 @T6G_MB_LIB.T6G(SCH_1):PAGE13
  CJ59 M_D_CPU0_SB_DQ<9> @T6G_MB_LIB.T6G(SCH_1):M_D_CPU0_SB_DQ(9)   I159 @T6G_MB_LIB.T6G(SCH_1):PAGE13
  BG59 M_D_CPU0_SB_CA<0> @T6G_MB_LIB.T6G(SCH_1):M_D_CPU0_SB_CA(0)   I159 @T6G_MB_LIB.T6G(SCH_1):PAGE13
  AG59 M_D_CPU0_SA_DQS_DP<8> @T6G_MB_LIB.T6G(SCH_1):M_D_CPU0_SA_DQS_DP(8)   I159 @T6G_MB_LIB.T6G(SCH_1):PAGE13
  AH60 M_D_CPU0_SA_DQ<30> @T6G_MB_LIB.T6G(SCH_1):M_D_CPU0_SA_DQ(30)   I159 @T6G_MB_LIB.T6G(SCH_1):PAGE13
  AY60 M_D_CPU0_SA_CA<1> @T6G_MB_LIB.T6G(SCH_1):M_D_CPU0_SA_CA(1)   I159 @T6G_MB_LIB.T6G(SCH_1):PAGE13
  AU60     NC     NC   I159 @T6G_MB_LIB.T6G(SCH_1):PAGE13
  AW59 M_D_CPU0_SA_CS_N<1> @T6G_MB_LIB.T6G(SCH_1):M_D_CPU0_SA_CS_N(1)   I159 @T6G_MB_LIB.T6G(SCH_1):PAGE13
  CU59 M_D_CPU0_SB_DQS_DN<7> @T6G_MB_LIB.T6G(SCH_1):M_D_CPU0_SB_DQS_DN(7)   I159 @T6G_MB_LIB.T6G(SCH_1):PAGE13
  DB60 M_D_CPU0_SB_DQS_DP<3> @T6G_MB_LIB.T6G(SCH_1):M_D_CPU0_SB_DQS_DP(3)   I159 @T6G_MB_LIB.T6G(SCH_1):PAGE13
  BH58 M_D_CPU0_SB_CA<1> @T6G_MB_LIB.T6G(SCH_1):M_D_CPU0_SB_CA(1)   I159 @T6G_MB_LIB.T6G(SCH_1):PAGE13
  AN59 M_D_CPU0_SA_DQS_DP<9> @T6G_MB_LIB.T6G(SCH_1):M_D_CPU0_SA_DQS_DP(9)   I159 @T6G_MB_LIB.T6G(SCH_1):PAGE13
  AJ59 M_D_CPU0_SA_DQ<31> @T6G_MB_LIB.T6G(SCH_1):M_D_CPU0_SA_DQ(31)   I159 @T6G_MB_LIB.T6G(SCH_1):PAGE13
  AA60 M_D_CPU0_SA_DQ<20> @T6G_MB_LIB.T6G(SCH_1):M_D_CPU0_SA_DQ(20)   I159 @T6G_MB_LIB.T6G(SCH_1):PAGE13
  AJ60 M_D_CPU0_SA_CB<0> @T6G_MB_LIB.T6G(SCH_1):M_D_CPU0_SA_CB(0)   I159 @T6G_MB_LIB.T6G(SCH_1):PAGE13
  AY58 M_D_CPU0_SA_CA<2> @T6G_MB_LIB.T6G(SCH_1):M_D_CPU0_SA_CA(2)   I159 @T6G_MB_LIB.T6G(SCH_1):PAGE13
  AV58     NC     NC   I159 @T6G_MB_LIB.T6G(SCH_1):PAGE13
  DC59 M_D_CPU0_SB_DQS_DN<8> @T6G_MB_LIB.T6G(SCH_1):M_D_CPU0_SB_DQS_DN(8)   I159 @T6G_MB_LIB.T6G(SCH_1):PAGE13
  BY58 M_D_CPU0_SB_DQS_DP<4> @T6G_MB_LIB.T6G(SCH_1):M_D_CPU0_SB_DQS_DP(4)   I159 @T6G_MB_LIB.T6G(SCH_1):PAGE13
  BH60 M_D_CPU0_SB_CA<2> @T6G_MB_LIB.T6G(SCH_1):M_D_CPU0_SB_CA(2)   I159 @T6G_MB_LIB.T6G(SCH_1):PAGE13
  AB58 M_D_CPU0_SA_DQ<21> @T6G_MB_LIB.T6G(SCH_1):M_D_CPU0_SA_DQ(21)   I159 @T6G_MB_LIB.T6G(SCH_1):PAGE13
   M60 M_D_CPU0_SA_DQ<10> @T6G_MB_LIB.T6G(SCH_1):M_D_CPU0_SA_DQ(10)   I159 @T6G_MB_LIB.T6G(SCH_1):PAGE13
  AK58 M_D_CPU0_SA_CB<1> @T6G_MB_LIB.T6G(SCH_1):M_D_CPU0_SA_CB(1)   I159 @T6G_MB_LIB.T6G(SCH_1):PAGE13
  BA59 M_D_CPU0_SA_CA<3> @T6G_MB_LIB.T6G(SCH_1):M_D_CPU0_SA_CA(3)   I159 @T6G_MB_LIB.T6G(SCH_1):PAGE13
  BW60 M_D_CPU0_SB_DQS_DN<9> @T6G_MB_LIB.T6G(SCH_1):M_D_CPU0_SB_DQS_DN(9)   I159 @T6G_MB_LIB.T6G(SCH_1):PAGE13
  CF58 M_D_CPU0_SB_DQS_DP<5> @T6G_MB_LIB.T6G(SCH_1):M_D_CPU0_SB_DQS_DP(5)   I159 @T6G_MB_LIB.T6G(SCH_1):PAGE13
  AB60 M_D_CPU0_SA_DQ<22> @T6G_MB_LIB.T6G(SCH_1):M_D_CPU0_SA_DQ(22)   I159 @T6G_MB_LIB.T6G(SCH_1):PAGE13
   N59 M_D_CPU0_SA_DQ<11> @T6G_MB_LIB.T6G(SCH_1):M_D_CPU0_SA_DQ(11)   I159 @T6G_MB_LIB.T6G(SCH_1):PAGE13
  AK60 M_D_CPU0_SA_CB<2> @T6G_MB_LIB.T6G(SCH_1):M_D_CPU0_SA_CB(2)   I159 @T6G_MB_LIB.T6G(SCH_1):PAGE13
  BA60 M_D_CPU0_SA_CA<4> @T6G_MB_LIB.T6G(SCH_1):M_D_CPU0_SA_CA(4)   I159 @T6G_MB_LIB.T6G(SCH_1):PAGE13
  CM58 M_D_CPU0_SB_DQS_DP<6> @T6G_MB_LIB.T6G(SCH_1):M_D_CPU0_SB_DQS_DP(6)   I159 @T6G_MB_LIB.T6G(SCH_1):PAGE13
  BJ59 M_D_CPU0_SB_CA<4> @T6G_MB_LIB.T6G(SCH_1):M_D_CPU0_SB_CA(4)   I159 @T6G_MB_LIB.T6G(SCH_1):PAGE13
  AC59 M_D_CPU0_SA_DQ<23> @T6G_MB_LIB.T6G(SCH_1):M_D_CPU0_SA_DQ(23)   I159 @T6G_MB_LIB.T6G(SCH_1):PAGE13
   R60 M_D_CPU0_SA_DQ<12> @T6G_MB_LIB.T6G(SCH_1):M_D_CPU0_SA_DQ(12)   I159 @T6G_MB_LIB.T6G(SCH_1):PAGE13
  AL59 M_D_CPU0_SA_CB<3> @T6G_MB_LIB.T6G(SCH_1):M_D_CPU0_SA_CB(3)   I159 @T6G_MB_LIB.T6G(SCH_1):PAGE13
  BB60 M_D_CPU0_SA_CA<5> @T6G_MB_LIB.T6G(SCH_1):M_D_CPU0_SA_CA(5)   I159 @T6G_MB_LIB.T6G(SCH_1):PAGE13
  CV58 M_D_CPU0_SB_DQS_DP<7> @T6G_MB_LIB.T6G(SCH_1):M_D_CPU0_SB_DQS_DP(7)   I159 @T6G_MB_LIB.T6G(SCH_1):PAGE13
  BK58 M_D_CPU0_SB_CA<5> @T6G_MB_LIB.T6G(SCH_1):M_D_CPU0_SB_CA(5)   I159 @T6G_MB_LIB.T6G(SCH_1):PAGE13
  BM58 M_D_CPU0_SB_CS_N<0> @T6G_MB_LIB.T6G(SCH_1):M_D_CPU0_SB_CS_N(0)   I159 @T6G_MB_LIB.T6G(SCH_1):PAGE13
   H60 M_D_CPU0_SA_DQS_DN<0> @T6G_MB_LIB.T6G(SCH_1):M_D_CPU0_SA_DQS_DN(0)   I159 @T6G_MB_LIB.T6G(SCH_1):PAGE13
  AC60 M_D_CPU0_SA_DQ<24> @T6G_MB_LIB.T6G(SCH_1):M_D_CPU0_SA_DQ(24)   I159 @T6G_MB_LIB.T6G(SCH_1):PAGE13
   T58 M_D_CPU0_SA_DQ<13> @T6G_MB_LIB.T6G(SCH_1):M_D_CPU0_SA_DQ(13)   I159 @T6G_MB_LIB.T6G(SCH_1):PAGE13
  AN60 M_D_CPU0_SA_CB<4> @T6G_MB_LIB.T6G(SCH_1):M_D_CPU0_SA_CB(4)   I159 @T6G_MB_LIB.T6G(SCH_1):PAGE13
  BB58 M_D_CPU0_SA_CA<6> @T6G_MB_LIB.T6G(SCH_1):M_D_CPU0_SA_CA(6)   I159 @T6G_MB_LIB.T6G(SCH_1):PAGE13
  DD58 M_D_CPU0_SB_DQS_DP<8> @T6G_MB_LIB.T6G(SCH_1):M_D_CPU0_SB_DQS_DP(8)   I159 @T6G_MB_LIB.T6G(SCH_1):PAGE13
  DE60 M_D_CPU0_SB_DQ<30> @T6G_MB_LIB.T6G(SCH_1):M_D_CPU0_SB_DQ(30)   I159 @T6G_MB_LIB.T6G(SCH_1):PAGE13
  BK60 M_D_CPU0_SB_CA<6> @T6G_MB_LIB.T6G(SCH_1):M_D_CPU0_SB_CA(6)   I159 @T6G_MB_LIB.T6G(SCH_1):PAGE13
  BL59     NC     NC   I159 @T6G_MB_LIB.T6G(SCH_1):PAGE13
  BN60 M_D_CPU0_SB_CS_N<1> @T6G_MB_LIB.T6G(SCH_1):M_D_CPU0_SB_CS_N(1)   I159 @T6G_MB_LIB.T6G(SCH_1):PAGE13
   P60 M_D_CPU0_SA_DQS_DN<1> @T6G_MB_LIB.T6G(SCH_1):M_D_CPU0_SA_DQS_DN(1)   I159 @T6G_MB_LIB.T6G(SCH_1):PAGE13
  AD58 M_D_CPU0_SA_DQ<25> @T6G_MB_LIB.T6G(SCH_1):M_D_CPU0_SA_DQ(25)   I159 @T6G_MB_LIB.T6G(SCH_1):PAGE13
   T60 M_D_CPU0_SA_DQ<14> @T6G_MB_LIB.T6G(SCH_1):M_D_CPU0_SA_DQ(14)   I159 @T6G_MB_LIB.T6G(SCH_1):PAGE13
  AP58 M_D_CPU0_SA_CB<5> @T6G_MB_LIB.T6G(SCH_1):M_D_CPU0_SA_CB(5)   I159 @T6G_MB_LIB.T6G(SCH_1):PAGE13
  DF60 M_D_CPU0_SB_DQ<31> @T6G_MB_LIB.T6G(SCH_1):M_D_CPU0_SB_DQ(31)   I159 @T6G_MB_LIB.T6G(SCH_1):PAGE13
  CV60 M_D_CPU0_SB_DQ<20> @T6G_MB_LIB.T6G(SCH_1):M_D_CPU0_SB_DQ(20)   I159 @T6G_MB_LIB.T6G(SCH_1):PAGE13
  BY60 M_D_CPU0_SB_CB<0> @T6G_MB_LIB.T6G(SCH_1):M_D_CPU0_SB_CB(0)   I159 @T6G_MB_LIB.T6G(SCH_1):PAGE13
  BM60     NC     NC   I159 @T6G_MB_LIB.T6G(SCH_1):PAGE13
   Y60 M_D_CPU0_SA_DQS_DN<2> @T6G_MB_LIB.T6G(SCH_1):M_D_CPU0_SA_DQS_DN(2)   I159 @T6G_MB_LIB.T6G(SCH_1):PAGE13
  AD60 M_D_CPU0_SA_DQ<26> @T6G_MB_LIB.T6G(SCH_1):M_D_CPU0_SA_DQ(26)   I159 @T6G_MB_LIB.T6G(SCH_1):PAGE13
   U59 M_D_CPU0_SA_DQ<15> @T6G_MB_LIB.T6G(SCH_1):M_D_CPU0_SA_DQ(15)   I159 @T6G_MB_LIB.T6G(SCH_1):PAGE13
   E60 M_D_CPU0_SA_DQ<0> @T6G_MB_LIB.T6G(SCH_1):M_D_CPU0_SA_DQ(0)   I159 @T6G_MB_LIB.T6G(SCH_1):PAGE13
  AP60 M_D_CPU0_SA_CB<6> @T6G_MB_LIB.T6G(SCH_1):M_D_CPU0_SA_CB(6)   I159 @T6G_MB_LIB.T6G(SCH_1):PAGE13
  CW59 M_D_CPU0_SB_DQ<21> @T6G_MB_LIB.T6G(SCH_1):M_D_CPU0_SB_DQ(21)   I159 @T6G_MB_LIB.T6G(SCH_1):PAGE13
  CJ60 M_D_CPU0_SB_DQ<10> @T6G_MB_LIB.T6G(SCH_1):M_D_CPU0_SB_DQ(10)   I159 @T6G_MB_LIB.T6G(SCH_1):PAGE13
  CB60 M_D_CPU0_SB_DQ<0> @T6G_MB_LIB.T6G(SCH_1):M_D_CPU0_SB_DQ(0)   I159 @T6G_MB_LIB.T6G(SCH_1):PAGE13
  CA59 M_D_CPU0_SB_CB<1> @T6G_MB_LIB.T6G(SCH_1):M_D_CPU0_SB_CB(1)   I159 @T6G_MB_LIB.T6G(SCH_1):PAGE13
  AF60 M_D_CPU0_SA_DQS_DN<3> @T6G_MB_LIB.T6G(SCH_1):M_D_CPU0_SA_DQS_DN(3)   I159 @T6G_MB_LIB.T6G(SCH_1):PAGE13
  AE59 M_D_CPU0_SA_DQ<27> @T6G_MB_LIB.T6G(SCH_1):M_D_CPU0_SA_DQ(27)   I159 @T6G_MB_LIB.T6G(SCH_1):PAGE13
   U60 M_D_CPU0_SA_DQ<16> @T6G_MB_LIB.T6G(SCH_1):M_D_CPU0_SA_DQ(16)   I159 @T6G_MB_LIB.T6G(SCH_1):PAGE13
   F58 M_D_CPU0_SA_DQ<1> @T6G_MB_LIB.T6G(SCH_1):M_D_CPU0_SA_DQ(1)   I159 @T6G_MB_LIB.T6G(SCH_1):PAGE13
  AR59 M_D_CPU0_SA_CB<7> @T6G_MB_LIB.T6G(SCH_1):M_D_CPU0_SA_CB(7)   I159 @T6G_MB_LIB.T6G(SCH_1):PAGE13
  BN59 M_D_CPU0_SA_RSP<0> @T6G_MB_LIB.T6G(SCH_1):M_D_CPU0_SA_RSP(0)   I159 @T6G_MB_LIB.T6G(SCH_1):PAGE13
  CW60 M_D_CPU0_SB_DQ<22> @T6G_MB_LIB.T6G(SCH_1):M_D_CPU0_SB_DQ(22)   I159 @T6G_MB_LIB.T6G(SCH_1):PAGE13
  CK58 M_D_CPU0_SB_DQ<11> @T6G_MB_LIB.T6G(SCH_1):M_D_CPU0_SB_DQ(11)   I159 @T6G_MB_LIB.T6G(SCH_1):PAGE13
  CC59 M_D_CPU0_SB_DQ<1> @T6G_MB_LIB.T6G(SCH_1):M_D_CPU0_SB_DQ(1)   I159 @T6G_MB_LIB.T6G(SCH_1):PAGE13
  CA60 M_D_CPU0_SB_CB<2> @T6G_MB_LIB.T6G(SCH_1):M_D_CPU0_SB_CB(2)   I159 @T6G_MB_LIB.T6G(SCH_1):PAGE13
  AM60 M_D_CPU0_SA_DQS_DN<4> @T6G_MB_LIB.T6G(SCH_1):M_D_CPU0_SA_DQS_DN(4)   I159 @T6G_MB_LIB.T6G(SCH_1):PAGE13
   G60 M_D_CPU0_SA_DQS_DP<0> @T6G_MB_LIB.T6G(SCH_1):M_D_CPU0_SA_DQS_DP(0)   I159 @T6G_MB_LIB.T6G(SCH_1):PAGE13
  AG60 M_D_CPU0_SA_DQ<28> @T6G_MB_LIB.T6G(SCH_1):M_D_CPU0_SA_DQ(28)   I159 @T6G_MB_LIB.T6G(SCH_1):PAGE13
   V58 M_D_CPU0_SA_DQ<17> @T6G_MB_LIB.T6G(SCH_1):M_D_CPU0_SA_DQ(17)   I159 @T6G_MB_LIB.T6G(SCH_1):PAGE13
   F60 M_D_CPU0_SA_DQ<2> @T6G_MB_LIB.T6G(SCH_1):M_D_CPU0_SA_DQ(2)   I159 @T6G_MB_LIB.T6G(SCH_1):PAGE13
  BP58     NC     NC   I159 @T6G_MB_LIB.T6G(SCH_1):PAGE13
  BC59 M_D_CPU0_SA_PAR @T6G_MB_LIB.T6G(SCH_1):M_D_CPU0_SA_PAR   I159 @T6G_MB_LIB.T6G(SCH_1):PAGE13
  BL60 M_D_CPU0_SB_PAR @T6G_MB_LIB.T6G(SCH_1):M_D_CPU0_SB_PAR   I159 @T6G_MB_LIB.T6G(SCH_1):PAGE13
  BJ60 M_D_CPU0_SB_CA<3> @T6G_MB_LIB.T6G(SCH_1):M_D_CPU0_SB_CA(3)   I159 @T6G_MB_LIB.T6G(SCH_1):PAGE13
  BV60 M_D_CPU0_SB_DQS_DP<9> @T6G_MB_LIB.T6G(SCH_1):M_D_CPU0_SB_DQS_DP(9)   I159 @T6G_MB_LIB.T6G(SCH_1):PAGE13
  BC60 M_D_CPU0_CLK_DP<0> @T6G_MB_LIB.T6G(SCH_1):M_D_CPU0_CLK_DP(0)   I159 @T6G_MB_LIB.T6G(SCH_1):PAGE13
  BD60 M_D_CPU0_CLK_DN<0> @T6G_MB_LIB.T6G(SCH_1):M_D_CPU0_CLK_DN(0)   I159 @T6G_MB_LIB.T6G(SCH_1):PAGE13
  BF60     NC     NC   I159 @T6G_MB_LIB.T6G(SCH_1):PAGE13
  BG60     NC     NC   I159 @T6G_MB_LIB.T6G(SCH_1):PAGE13
  BF58 TP_M_D_CPU0_SA_TEST39D @T6G_MB_LIB.T6G(SCH_1):TP_M_D_CPU0_SA_TEST39D   I159 @T6G_MB_LIB.T6G(SCH_1):PAGE13
  AT69 M_E_CPU0_ALERT_R_N @T6G_MB_LIB.T6G(SCH_1):M_E_CPU0_ALERT_R_N   I159 @T6G_MB_LIB.T6G(SCH_1):PAGE14
  AU69 M_E_CPU0_RESET_N @T6G_MB_LIB.T6G(SCH_1):M_E_CPU0_RESET_N   I159 @T6G_MB_LIB.T6G(SCH_1):PAGE14
  CU71 M_E_CPU0_SB_DQS_DN<2> @T6G_MB_LIB.T6G(SCH_1):M_E_CPU0_SB_DQS_DN(2)   I159 @T6G_MB_LIB.T6G(SCH_1):PAGE14
  DA71 M_E_CPU0_SB_DQ<26> @T6G_MB_LIB.T6G(SCH_1):M_E_CPU0_SB_DQ(26)   I159 @T6G_MB_LIB.T6G(SCH_1):PAGE14
  CP69 M_E_CPU0_SB_DQ<15> @T6G_MB_LIB.T6G(SCH_1):M_E_CPU0_SB_DQ(15)   I159 @T6G_MB_LIB.T6G(SCH_1):PAGE14
  BU71 M_E_CPU0_SB_CB<6> @T6G_MB_LIB.T6G(SCH_1):M_E_CPU0_SB_CB(6)   I159 @T6G_MB_LIB.T6G(SCH_1):PAGE14
  AF69 M_E_CPU0_SA_DQS_DN<8> @T6G_MB_LIB.T6G(SCH_1):M_E_CPU0_SA_DQS_DN(8)   I159 @T6G_MB_LIB.T6G(SCH_1):PAGE14
  AL71 M_E_CPU0_SA_DQS_DP<4> @T6G_MB_LIB.T6G(SCH_1):M_E_CPU0_SA_DQS_DP(4)   I159 @T6G_MB_LIB.T6G(SCH_1):PAGE14
  DC71 M_E_CPU0_SB_DQS_DN<3> @T6G_MB_LIB.T6G(SCH_1):M_E_CPU0_SB_DQS_DN(3)   I159 @T6G_MB_LIB.T6G(SCH_1):PAGE14
  DB69 M_E_CPU0_SB_DQ<27> @T6G_MB_LIB.T6G(SCH_1):M_E_CPU0_SB_DQ(27)   I159 @T6G_MB_LIB.T6G(SCH_1):PAGE14
  CP70 M_E_CPU0_SB_DQ<16> @T6G_MB_LIB.T6G(SCH_1):M_E_CPU0_SB_DQ(16)   I159 @T6G_MB_LIB.T6G(SCH_1):PAGE14
  BV69 M_E_CPU0_SB_CB<7> @T6G_MB_LIB.T6G(SCH_1):M_E_CPU0_SB_CB(7)   I159 @T6G_MB_LIB.T6G(SCH_1):PAGE14
  BR71     NC     NC   I159 @T6G_MB_LIB.T6G(SCH_1):PAGE14
  BP70 M_E_CPU0_SB_RSP<0> @T6G_MB_LIB.T6G(SCH_1):M_E_CPU0_SB_RSP(0)   I159 @T6G_MB_LIB.T6G(SCH_1):PAGE14
  AM69 M_E_CPU0_SA_DQS_DN<9> @T6G_MB_LIB.T6G(SCH_1):M_E_CPU0_SA_DQS_DN(9)   I159 @T6G_MB_LIB.T6G(SCH_1):PAGE14
   J69 M_E_CPU0_SA_DQS_DP<5> @T6G_MB_LIB.T6G(SCH_1):M_E_CPU0_SA_DQS_DP(5)   I159 @T6G_MB_LIB.T6G(SCH_1):PAGE14
  BW69 M_E_CPU0_SB_DQS_DN<4> @T6G_MB_LIB.T6G(SCH_1):M_E_CPU0_SB_DQS_DN(4)   I159 @T6G_MB_LIB.T6G(SCH_1):PAGE14
  CD70 M_E_CPU0_SB_DQS_DP<0> @T6G_MB_LIB.T6G(SCH_1):M_E_CPU0_SB_DQS_DP(0)   I159 @T6G_MB_LIB.T6G(SCH_1):PAGE14
  DD70 M_E_CPU0_SB_DQ<28> @T6G_MB_LIB.T6G(SCH_1):M_E_CPU0_SB_DQ(28)   I159 @T6G_MB_LIB.T6G(SCH_1):PAGE14
  CR69 M_E_CPU0_SB_DQ<17> @T6G_MB_LIB.T6G(SCH_1):M_E_CPU0_SB_DQ(17)   I159 @T6G_MB_LIB.T6G(SCH_1):PAGE14
   R69 M_E_CPU0_SA_DQS_DP<6> @T6G_MB_LIB.T6G(SCH_1):M_E_CPU0_SA_DQS_DP(6)   I159 @T6G_MB_LIB.T6G(SCH_1):PAGE14
  CE69 M_E_CPU0_SB_DQS_DN<5> @T6G_MB_LIB.T6G(SCH_1):M_E_CPU0_SB_DQS_DN(5)   I159 @T6G_MB_LIB.T6G(SCH_1):PAGE14
  CK70 M_E_CPU0_SB_DQS_DP<1> @T6G_MB_LIB.T6G(SCH_1):M_E_CPU0_SB_DQS_DP(1)   I159 @T6G_MB_LIB.T6G(SCH_1):PAGE14
  DE69 M_E_CPU0_SB_DQ<29> @T6G_MB_LIB.T6G(SCH_1):M_E_CPU0_SB_DQ(29)   I159 @T6G_MB_LIB.T6G(SCH_1):PAGE14
  CR71 M_E_CPU0_SB_DQ<18> @T6G_MB_LIB.T6G(SCH_1):M_E_CPU0_SB_DQ(18)   I159 @T6G_MB_LIB.T6G(SCH_1):PAGE14
  AA69 M_E_CPU0_SA_DQS_DP<7> @T6G_MB_LIB.T6G(SCH_1):M_E_CPU0_SA_DQS_DP(7)   I159 @T6G_MB_LIB.T6G(SCH_1):PAGE14
   E71 M_E_CPU0_SA_DQ<0> @T6G_MB_LIB.T6G(SCH_1):M_E_CPU0_SA_DQ(0)   I159 @T6G_MB_LIB.T6G(SCH_1):PAGE14
  AU71     NC     NC   I159 @T6G_MB_LIB.T6G(SCH_1):PAGE14
  AV70 M_E_CPU0_SA_CS_N<0> @T6G_MB_LIB.T6G(SCH_1):M_E_CPU0_SA_CS_N(0)   I159 @T6G_MB_LIB.T6G(SCH_1):PAGE14
  CL69 M_E_CPU0_SB_DQS_DN<6> @T6G_MB_LIB.T6G(SCH_1):M_E_CPU0_SB_DQS_DN(6)   I159 @T6G_MB_LIB.T6G(SCH_1):PAGE14
  CT70 M_E_CPU0_SB_DQS_DP<2> @T6G_MB_LIB.T6G(SCH_1):M_E_CPU0_SB_DQS_DP(2)   I159 @T6G_MB_LIB.T6G(SCH_1):PAGE14
  CT69 M_E_CPU0_SB_DQ<19> @T6G_MB_LIB.T6G(SCH_1):M_E_CPU0_SB_DQ(19)   I159 @T6G_MB_LIB.T6G(SCH_1):PAGE14
  CB70 M_E_CPU0_SB_DQ<0> @T6G_MB_LIB.T6G(SCH_1):M_E_CPU0_SB_DQ(0)   I159 @T6G_MB_LIB.T6G(SCH_1):PAGE14
  AG69 M_E_CPU0_SA_DQS_DP<8> @T6G_MB_LIB.T6G(SCH_1):M_E_CPU0_SA_DQS_DP(8)   I159 @T6G_MB_LIB.T6G(SCH_1):PAGE14
  AH70 M_E_CPU0_SA_DQ<30> @T6G_MB_LIB.T6G(SCH_1):M_E_CPU0_SA_DQ(30)   I159 @T6G_MB_LIB.T6G(SCH_1):PAGE14
   F69 M_E_CPU0_SA_DQ<1> @T6G_MB_LIB.T6G(SCH_1):M_E_CPU0_SA_DQ(1)   I159 @T6G_MB_LIB.T6G(SCH_1):PAGE14
  AV69     NC     NC   I159 @T6G_MB_LIB.T6G(SCH_1):PAGE14
  AW69 M_E_CPU0_SA_CS_N<1> @T6G_MB_LIB.T6G(SCH_1):M_E_CPU0_SA_CS_N(1)   I159 @T6G_MB_LIB.T6G(SCH_1):PAGE14
  CU69 M_E_CPU0_SB_DQS_DN<7> @T6G_MB_LIB.T6G(SCH_1):M_E_CPU0_SB_DQS_DN(7)   I159 @T6G_MB_LIB.T6G(SCH_1):PAGE14
  DB70 M_E_CPU0_SB_DQS_DP<3> @T6G_MB_LIB.T6G(SCH_1):M_E_CPU0_SB_DQS_DP(3)   I159 @T6G_MB_LIB.T6G(SCH_1):PAGE14
  CC69 M_E_CPU0_SB_DQ<1> @T6G_MB_LIB.T6G(SCH_1):M_E_CPU0_SB_DQ(1)   I159 @T6G_MB_LIB.T6G(SCH_1):PAGE14
  AN69 M_E_CPU0_SA_DQS_DP<9> @T6G_MB_LIB.T6G(SCH_1):M_E_CPU0_SA_DQS_DP(9)   I159 @T6G_MB_LIB.T6G(SCH_1):PAGE14
  AJ69 M_E_CPU0_SA_DQ<31> @T6G_MB_LIB.T6G(SCH_1):M_E_CPU0_SA_DQ(31)   I159 @T6G_MB_LIB.T6G(SCH_1):PAGE14
  AA71 M_E_CPU0_SA_DQ<20> @T6G_MB_LIB.T6G(SCH_1):M_E_CPU0_SA_DQ(20)   I159 @T6G_MB_LIB.T6G(SCH_1):PAGE14
   F70 M_E_CPU0_SA_DQ<2> @T6G_MB_LIB.T6G(SCH_1):M_E_CPU0_SA_DQ(2)   I159 @T6G_MB_LIB.T6G(SCH_1):PAGE14
  AJ71 M_E_CPU0_SA_CB<0> @T6G_MB_LIB.T6G(SCH_1):M_E_CPU0_SA_CB(0)   I159 @T6G_MB_LIB.T6G(SCH_1):PAGE14
  AW71 M_E_CPU0_SA_CA<0> @T6G_MB_LIB.T6G(SCH_1):M_E_CPU0_SA_CA(0)   I159 @T6G_MB_LIB.T6G(SCH_1):PAGE14
  DC69 M_E_CPU0_SB_DQS_DN<8> @T6G_MB_LIB.T6G(SCH_1):M_E_CPU0_SB_DQS_DN(8)   I159 @T6G_MB_LIB.T6G(SCH_1):PAGE14
  BY69 M_E_CPU0_SB_DQS_DP<4> @T6G_MB_LIB.T6G(SCH_1):M_E_CPU0_SB_DQS_DP(4)   I159 @T6G_MB_LIB.T6G(SCH_1):PAGE14
  CC71 M_E_CPU0_SB_DQ<2> @T6G_MB_LIB.T6G(SCH_1):M_E_CPU0_SB_DQ(2)   I159 @T6G_MB_LIB.T6G(SCH_1):PAGE14
  BG69 M_E_CPU0_SB_CA<0> @T6G_MB_LIB.T6G(SCH_1):M_E_CPU0_SB_CA(0)   I159 @T6G_MB_LIB.T6G(SCH_1):PAGE14
  AB69 M_E_CPU0_SA_DQ<21> @T6G_MB_LIB.T6G(SCH_1):M_E_CPU0_SA_DQ(21)   I159 @T6G_MB_LIB.T6G(SCH_1):PAGE14
   M70 M_E_CPU0_SA_DQ<10> @T6G_MB_LIB.T6G(SCH_1):M_E_CPU0_SA_DQ(10)   I159 @T6G_MB_LIB.T6G(SCH_1):PAGE14
   G69 M_E_CPU0_SA_DQ<3> @T6G_MB_LIB.T6G(SCH_1):M_E_CPU0_SA_DQ(3)   I159 @T6G_MB_LIB.T6G(SCH_1):PAGE14
  AK69 M_E_CPU0_SA_CB<1> @T6G_MB_LIB.T6G(SCH_1):M_E_CPU0_SA_CB(1)   I159 @T6G_MB_LIB.T6G(SCH_1):PAGE14
  AY70 M_E_CPU0_SA_CA<1> @T6G_MB_LIB.T6G(SCH_1):M_E_CPU0_SA_CA(1)   I159 @T6G_MB_LIB.T6G(SCH_1):PAGE14
  BW71 M_E_CPU0_SB_DQS_DN<9> @T6G_MB_LIB.T6G(SCH_1):M_E_CPU0_SB_DQS_DN(9)   I159 @T6G_MB_LIB.T6G(SCH_1):PAGE14
  CF69 M_E_CPU0_SB_DQS_DP<5> @T6G_MB_LIB.T6G(SCH_1):M_E_CPU0_SB_DQS_DP(5)   I159 @T6G_MB_LIB.T6G(SCH_1):PAGE14
  CD69 M_E_CPU0_SB_DQ<3> @T6G_MB_LIB.T6G(SCH_1):M_E_CPU0_SB_DQ(3)   I159 @T6G_MB_LIB.T6G(SCH_1):PAGE14
  BH69 M_E_CPU0_SB_CA<1> @T6G_MB_LIB.T6G(SCH_1):M_E_CPU0_SB_CA(1)   I159 @T6G_MB_LIB.T6G(SCH_1):PAGE14
  AB70 M_E_CPU0_SA_DQ<22> @T6G_MB_LIB.T6G(SCH_1):M_E_CPU0_SA_DQ(22)   I159 @T6G_MB_LIB.T6G(SCH_1):PAGE14
   N69 M_E_CPU0_SA_DQ<11> @T6G_MB_LIB.T6G(SCH_1):M_E_CPU0_SA_DQ(11)   I159 @T6G_MB_LIB.T6G(SCH_1):PAGE14
   J71 M_E_CPU0_SA_DQ<4> @T6G_MB_LIB.T6G(SCH_1):M_E_CPU0_SA_DQ(4)   I159 @T6G_MB_LIB.T6G(SCH_1):PAGE14
  AK70 M_E_CPU0_SA_CB<2> @T6G_MB_LIB.T6G(SCH_1):M_E_CPU0_SA_CB(2)   I159 @T6G_MB_LIB.T6G(SCH_1):PAGE14
  AY69 M_E_CPU0_SA_CA<2> @T6G_MB_LIB.T6G(SCH_1):M_E_CPU0_SA_CA(2)   I159 @T6G_MB_LIB.T6G(SCH_1):PAGE14
  CM69 M_E_CPU0_SB_DQS_DP<6> @T6G_MB_LIB.T6G(SCH_1):M_E_CPU0_SB_DQS_DP(6)   I159 @T6G_MB_LIB.T6G(SCH_1):PAGE14
  CF70 M_E_CPU0_SB_DQ<4> @T6G_MB_LIB.T6G(SCH_1):M_E_CPU0_SB_DQ(4)   I159 @T6G_MB_LIB.T6G(SCH_1):PAGE14
  BH70 M_E_CPU0_SB_CA<2> @T6G_MB_LIB.T6G(SCH_1):M_E_CPU0_SB_CA(2)   I159 @T6G_MB_LIB.T6G(SCH_1):PAGE14
  AC69 M_E_CPU0_SA_DQ<23> @T6G_MB_LIB.T6G(SCH_1):M_E_CPU0_SA_DQ(23)   I159 @T6G_MB_LIB.T6G(SCH_1):PAGE14
   R71 M_E_CPU0_SA_DQ<12> @T6G_MB_LIB.T6G(SCH_1):M_E_CPU0_SA_DQ(12)   I159 @T6G_MB_LIB.T6G(SCH_1):PAGE14
   K69 M_E_CPU0_SA_DQ<5> @T6G_MB_LIB.T6G(SCH_1):M_E_CPU0_SA_DQ(5)   I159 @T6G_MB_LIB.T6G(SCH_1):PAGE14
  AL69 M_E_CPU0_SA_CB<3> @T6G_MB_LIB.T6G(SCH_1):M_E_CPU0_SA_CB(3)   I159 @T6G_MB_LIB.T6G(SCH_1):PAGE14
  BA69 M_E_CPU0_SA_CA<3> @T6G_MB_LIB.T6G(SCH_1):M_E_CPU0_SA_CA(3)   I159 @T6G_MB_LIB.T6G(SCH_1):PAGE14
  CV69 M_E_CPU0_SB_DQS_DP<7> @T6G_MB_LIB.T6G(SCH_1):M_E_CPU0_SB_DQS_DP(7)   I159 @T6G_MB_LIB.T6G(SCH_1):PAGE14
  CG69 M_E_CPU0_SB_DQ<5> @T6G_MB_LIB.T6G(SCH_1):M_E_CPU0_SB_DQ(5)   I159 @T6G_MB_LIB.T6G(SCH_1):PAGE14
  BJ71 M_E_CPU0_SB_CA<3> @T6G_MB_LIB.T6G(SCH_1):M_E_CPU0_SB_CA(3)   I159 @T6G_MB_LIB.T6G(SCH_1):PAGE14
  BL69     NC     NC   I159 @T6G_MB_LIB.T6G(SCH_1):PAGE14
  BM69 M_E_CPU0_SB_CS_N<0> @T6G_MB_LIB.T6G(SCH_1):M_E_CPU0_SB_CS_N(0)   I159 @T6G_MB_LIB.T6G(SCH_1):PAGE14
   H70 M_E_CPU0_SA_DQS_DN<0> @T6G_MB_LIB.T6G(SCH_1):M_E_CPU0_SA_DQS_DN(0)   I159 @T6G_MB_LIB.T6G(SCH_1):PAGE14
  AC71 M_E_CPU0_SA_DQ<24> @T6G_MB_LIB.T6G(SCH_1):M_E_CPU0_SA_DQ(24)   I159 @T6G_MB_LIB.T6G(SCH_1):PAGE14
   T69 M_E_CPU0_SA_DQ<13> @T6G_MB_LIB.T6G(SCH_1):M_E_CPU0_SA_DQ(13)   I159 @T6G_MB_LIB.T6G(SCH_1):PAGE14
   K70 M_E_CPU0_SA_DQ<6> @T6G_MB_LIB.T6G(SCH_1):M_E_CPU0_SA_DQ(6)   I159 @T6G_MB_LIB.T6G(SCH_1):PAGE14
  AN71 M_E_CPU0_SA_CB<4> @T6G_MB_LIB.T6G(SCH_1):M_E_CPU0_SA_CB(4)   I159 @T6G_MB_LIB.T6G(SCH_1):PAGE14
  BA71 M_E_CPU0_SA_CA<4> @T6G_MB_LIB.T6G(SCH_1):M_E_CPU0_SA_CA(4)   I159 @T6G_MB_LIB.T6G(SCH_1):PAGE14
  DD69 M_E_CPU0_SB_DQS_DP<8> @T6G_MB_LIB.T6G(SCH_1):M_E_CPU0_SB_DQS_DP(8)   I159 @T6G_MB_LIB.T6G(SCH_1):PAGE14
  DE71 M_E_CPU0_SB_DQ<30> @T6G_MB_LIB.T6G(SCH_1):M_E_CPU0_SB_DQ(30)   I159 @T6G_MB_LIB.T6G(SCH_1):PAGE14
  CG71 M_E_CPU0_SB_DQ<6> @T6G_MB_LIB.T6G(SCH_1):M_E_CPU0_SB_DQ(6)   I159 @T6G_MB_LIB.T6G(SCH_1):PAGE14
  BJ69 M_E_CPU0_SB_CA<4> @T6G_MB_LIB.T6G(SCH_1):M_E_CPU0_SB_CA(4)   I159 @T6G_MB_LIB.T6G(SCH_1):PAGE14
  BM70     NC     NC   I159 @T6G_MB_LIB.T6G(SCH_1):PAGE14
  BN71 M_E_CPU0_SB_CS_N<1> @T6G_MB_LIB.T6G(SCH_1):M_E_CPU0_SB_CS_N(1)   I159 @T6G_MB_LIB.T6G(SCH_1):PAGE14
   P70 M_E_CPU0_SA_DQS_DN<1> @T6G_MB_LIB.T6G(SCH_1):M_E_CPU0_SA_DQS_DN(1)   I159 @T6G_MB_LIB.T6G(SCH_1):PAGE14
  AD69 M_E_CPU0_SA_DQ<25> @T6G_MB_LIB.T6G(SCH_1):M_E_CPU0_SA_DQ(25)   I159 @T6G_MB_LIB.T6G(SCH_1):PAGE14
   T70 M_E_CPU0_SA_DQ<14> @T6G_MB_LIB.T6G(SCH_1):M_E_CPU0_SA_DQ(14)   I159 @T6G_MB_LIB.T6G(SCH_1):PAGE14
   L69 M_E_CPU0_SA_DQ<7> @T6G_MB_LIB.T6G(SCH_1):M_E_CPU0_SA_DQ(7)   I159 @T6G_MB_LIB.T6G(SCH_1):PAGE14
  AP69 M_E_CPU0_SA_CB<5> @T6G_MB_LIB.T6G(SCH_1):M_E_CPU0_SA_CB(5)   I159 @T6G_MB_LIB.T6G(SCH_1):PAGE14
  BB70 M_E_CPU0_SA_CA<5> @T6G_MB_LIB.T6G(SCH_1):M_E_CPU0_SA_CA(5)   I159 @T6G_MB_LIB.T6G(SCH_1):PAGE14
  DF69 M_E_CPU0_SB_DQ<31> @T6G_MB_LIB.T6G(SCH_1):M_E_CPU0_SB_DQ(31)   I159 @T6G_MB_LIB.T6G(SCH_1):PAGE14
  CV70 M_E_CPU0_SB_DQ<20> @T6G_MB_LIB.T6G(SCH_1):M_E_CPU0_SB_DQ(20)   I159 @T6G_MB_LIB.T6G(SCH_1):PAGE14
  CH69 M_E_CPU0_SB_DQ<7> @T6G_MB_LIB.T6G(SCH_1):M_E_CPU0_SB_DQ(7)   I159 @T6G_MB_LIB.T6G(SCH_1):PAGE14
  BY70 M_E_CPU0_SB_CB<0> @T6G_MB_LIB.T6G(SCH_1):M_E_CPU0_SB_CB(0)   I159 @T6G_MB_LIB.T6G(SCH_1):PAGE14
  BK69 M_E_CPU0_SB_CA<5> @T6G_MB_LIB.T6G(SCH_1):M_E_CPU0_SB_CA(5)   I159 @T6G_MB_LIB.T6G(SCH_1):PAGE14
   Y70 M_E_CPU0_SA_DQS_DN<2> @T6G_MB_LIB.T6G(SCH_1):M_E_CPU0_SA_DQS_DN(2)   I159 @T6G_MB_LIB.T6G(SCH_1):PAGE14
  AD70 M_E_CPU0_SA_DQ<26> @T6G_MB_LIB.T6G(SCH_1):M_E_CPU0_SA_DQ(26)   I159 @T6G_MB_LIB.T6G(SCH_1):PAGE14
   U69 M_E_CPU0_SA_DQ<15> @T6G_MB_LIB.T6G(SCH_1):M_E_CPU0_SA_DQ(15)   I159 @T6G_MB_LIB.T6G(SCH_1):PAGE14
   L71 M_E_CPU0_SA_DQ<8> @T6G_MB_LIB.T6G(SCH_1):M_E_CPU0_SA_DQ(8)   I159 @T6G_MB_LIB.T6G(SCH_1):PAGE14
  AP70 M_E_CPU0_SA_CB<6> @T6G_MB_LIB.T6G(SCH_1):M_E_CPU0_SA_CB(6)   I159 @T6G_MB_LIB.T6G(SCH_1):PAGE14
  BB69 M_E_CPU0_SA_CA<6> @T6G_MB_LIB.T6G(SCH_1):M_E_CPU0_SA_CA(6)   I159 @T6G_MB_LIB.T6G(SCH_1):PAGE14
  CW69 M_E_CPU0_SB_DQ<21> @T6G_MB_LIB.T6G(SCH_1):M_E_CPU0_SB_DQ(21)   I159 @T6G_MB_LIB.T6G(SCH_1):PAGE14
  CJ71 M_E_CPU0_SB_DQ<10> @T6G_MB_LIB.T6G(SCH_1):M_E_CPU0_SB_DQ(10)   I159 @T6G_MB_LIB.T6G(SCH_1):PAGE14
  CH70 M_E_CPU0_SB_DQ<8> @T6G_MB_LIB.T6G(SCH_1):M_E_CPU0_SB_DQ(8)   I159 @T6G_MB_LIB.T6G(SCH_1):PAGE14
  CA69 M_E_CPU0_SB_CB<1> @T6G_MB_LIB.T6G(SCH_1):M_E_CPU0_SB_CB(1)   I159 @T6G_MB_LIB.T6G(SCH_1):PAGE14
  BK70 M_E_CPU0_SB_CA<6> @T6G_MB_LIB.T6G(SCH_1):M_E_CPU0_SB_CA(6)   I159 @T6G_MB_LIB.T6G(SCH_1):PAGE14
  AF70 M_E_CPU0_SA_DQS_DN<3> @T6G_MB_LIB.T6G(SCH_1):M_E_CPU0_SA_DQS_DN(3)   I159 @T6G_MB_LIB.T6G(SCH_1):PAGE14
  AE69 M_E_CPU0_SA_DQ<27> @T6G_MB_LIB.T6G(SCH_1):M_E_CPU0_SA_DQ(27)   I159 @T6G_MB_LIB.T6G(SCH_1):PAGE14
   U71 M_E_CPU0_SA_DQ<16> @T6G_MB_LIB.T6G(SCH_1):M_E_CPU0_SA_DQ(16)   I159 @T6G_MB_LIB.T6G(SCH_1):PAGE14
   M69 M_E_CPU0_SA_DQ<9> @T6G_MB_LIB.T6G(SCH_1):M_E_CPU0_SA_DQ(9)   I159 @T6G_MB_LIB.T6G(SCH_1):PAGE14
  AR69 M_E_CPU0_SA_CB<7> @T6G_MB_LIB.T6G(SCH_1):M_E_CPU0_SA_CB(7)   I159 @T6G_MB_LIB.T6G(SCH_1):PAGE14
  BP69     NC     NC   I159 @T6G_MB_LIB.T6G(SCH_1):PAGE14
  BN69 M_E_CPU0_SA_RSP<0> @T6G_MB_LIB.T6G(SCH_1):M_E_CPU0_SA_RSP(0)   I159 @T6G_MB_LIB.T6G(SCH_1):PAGE14
  CW71 M_E_CPU0_SB_DQ<22> @T6G_MB_LIB.T6G(SCH_1):M_E_CPU0_SB_DQ(22)   I159 @T6G_MB_LIB.T6G(SCH_1):PAGE14
  CK69 M_E_CPU0_SB_DQ<11> @T6G_MB_LIB.T6G(SCH_1):M_E_CPU0_SB_DQ(11)   I159 @T6G_MB_LIB.T6G(SCH_1):PAGE14
  CJ69 M_E_CPU0_SB_DQ<9> @T6G_MB_LIB.T6G(SCH_1):M_E_CPU0_SB_DQ(9)   I159 @T6G_MB_LIB.T6G(SCH_1):PAGE14
  CA71 M_E_CPU0_SB_CB<2> @T6G_MB_LIB.T6G(SCH_1):M_E_CPU0_SB_CB(2)   I159 @T6G_MB_LIB.T6G(SCH_1):PAGE14
  AM70 M_E_CPU0_SA_DQS_DN<4> @T6G_MB_LIB.T6G(SCH_1):M_E_CPU0_SA_DQS_DN(4)   I159 @T6G_MB_LIB.T6G(SCH_1):PAGE14
   G71 M_E_CPU0_SA_DQS_DP<0> @T6G_MB_LIB.T6G(SCH_1):M_E_CPU0_SA_DQS_DP(0)   I159 @T6G_MB_LIB.T6G(SCH_1):PAGE14
  AG71 M_E_CPU0_SA_DQ<28> @T6G_MB_LIB.T6G(SCH_1):M_E_CPU0_SA_DQ(28)   I159 @T6G_MB_LIB.T6G(SCH_1):PAGE14
   V69 M_E_CPU0_SA_DQ<17> @T6G_MB_LIB.T6G(SCH_1):M_E_CPU0_SA_DQ(17)   I159 @T6G_MB_LIB.T6G(SCH_1):PAGE14
  CY69 M_E_CPU0_SB_DQ<23> @T6G_MB_LIB.T6G(SCH_1):M_E_CPU0_SB_DQ(23)   I159 @T6G_MB_LIB.T6G(SCH_1):PAGE14
  CM70 M_E_CPU0_SB_DQ<12> @T6G_MB_LIB.T6G(SCH_1):M_E_CPU0_SB_DQ(12)   I159 @T6G_MB_LIB.T6G(SCH_1):PAGE14
  CB69 M_E_CPU0_SB_CB<3> @T6G_MB_LIB.T6G(SCH_1):M_E_CPU0_SB_CB(3)   I159 @T6G_MB_LIB.T6G(SCH_1):PAGE14
   H69 M_E_CPU0_SA_DQS_DN<5> @T6G_MB_LIB.T6G(SCH_1):M_E_CPU0_SA_DQS_DN(5)   I159 @T6G_MB_LIB.T6G(SCH_1):PAGE14
   N71 M_E_CPU0_SA_DQS_DP<1> @T6G_MB_LIB.T6G(SCH_1):M_E_CPU0_SA_DQS_DP(1)   I159 @T6G_MB_LIB.T6G(SCH_1):PAGE14
  AH69 M_E_CPU0_SA_DQ<29> @T6G_MB_LIB.T6G(SCH_1):M_E_CPU0_SA_DQ(29)   I159 @T6G_MB_LIB.T6G(SCH_1):PAGE14
   V70 M_E_CPU0_SA_DQ<18> @T6G_MB_LIB.T6G(SCH_1):M_E_CPU0_SA_DQ(18)   I159 @T6G_MB_LIB.T6G(SCH_1):PAGE14
  CE71 M_E_CPU0_SB_DQS_DN<0> @T6G_MB_LIB.T6G(SCH_1):M_E_CPU0_SB_DQS_DN(0)   I159 @T6G_MB_LIB.T6G(SCH_1):PAGE14
  CY70 M_E_CPU0_SB_DQ<24> @T6G_MB_LIB.T6G(SCH_1):M_E_CPU0_SB_DQ(24)   I159 @T6G_MB_LIB.T6G(SCH_1):PAGE14
  CN69 M_E_CPU0_SB_DQ<13> @T6G_MB_LIB.T6G(SCH_1):M_E_CPU0_SB_DQ(13)   I159 @T6G_MB_LIB.T6G(SCH_1):PAGE14
  BT70 M_E_CPU0_SB_CB<4> @T6G_MB_LIB.T6G(SCH_1):M_E_CPU0_SB_CB(4)   I159 @T6G_MB_LIB.T6G(SCH_1):PAGE14
   P69 M_E_CPU0_SA_DQS_DN<6> @T6G_MB_LIB.T6G(SCH_1):M_E_CPU0_SA_DQS_DN(6)   I159 @T6G_MB_LIB.T6G(SCH_1):PAGE14
   W71 M_E_CPU0_SA_DQS_DP<2> @T6G_MB_LIB.T6G(SCH_1):M_E_CPU0_SA_DQS_DP(2)   I159 @T6G_MB_LIB.T6G(SCH_1):PAGE14
   W69 M_E_CPU0_SA_DQ<19> @T6G_MB_LIB.T6G(SCH_1):M_E_CPU0_SA_DQ(19)   I159 @T6G_MB_LIB.T6G(SCH_1):PAGE14
  CL71 M_E_CPU0_SB_DQS_DN<1> @T6G_MB_LIB.T6G(SCH_1):M_E_CPU0_SB_DQS_DN(1)   I159 @T6G_MB_LIB.T6G(SCH_1):PAGE14
  DA69 M_E_CPU0_SB_DQ<25> @T6G_MB_LIB.T6G(SCH_1):M_E_CPU0_SB_DQ(25)   I159 @T6G_MB_LIB.T6G(SCH_1):PAGE14
  CN71 M_E_CPU0_SB_DQ<14> @T6G_MB_LIB.T6G(SCH_1):M_E_CPU0_SB_DQ(14)   I159 @T6G_MB_LIB.T6G(SCH_1):PAGE14
  BU69 M_E_CPU0_SB_CB<5> @T6G_MB_LIB.T6G(SCH_1):M_E_CPU0_SB_CB(5)   I159 @T6G_MB_LIB.T6G(SCH_1):PAGE14
   Y69 M_E_CPU0_SA_DQS_DN<7> @T6G_MB_LIB.T6G(SCH_1):M_E_CPU0_SA_DQS_DN(7)   I159 @T6G_MB_LIB.T6G(SCH_1):PAGE14
  AE71 M_E_CPU0_SA_DQS_DP<3> @T6G_MB_LIB.T6G(SCH_1):M_E_CPU0_SA_DQS_DP(3)   I159 @T6G_MB_LIB.T6G(SCH_1):PAGE14
  BC69 M_E_CPU0_SA_PAR @T6G_MB_LIB.T6G(SCH_1):M_E_CPU0_SA_PAR   I159 @T6G_MB_LIB.T6G(SCH_1):PAGE14
  BL71 M_E_CPU0_SB_PAR @T6G_MB_LIB.T6G(SCH_1):M_E_CPU0_SB_PAR   I159 @T6G_MB_LIB.T6G(SCH_1):PAGE14
  BV70 M_E_CPU0_SB_DQS_DP<9> @T6G_MB_LIB.T6G(SCH_1):M_E_CPU0_SB_DQS_DP(9)   I159 @T6G_MB_LIB.T6G(SCH_1):PAGE14
  BC71 M_E_CPU0_CLK_DP<0> @T6G_MB_LIB.T6G(SCH_1):M_E_CPU0_CLK_DP(0)   I159 @T6G_MB_LIB.T6G(SCH_1):PAGE14
  BD70 M_E_CPU0_CLK_DN<0> @T6G_MB_LIB.T6G(SCH_1):M_E_CPU0_CLK_DN(0)   I159 @T6G_MB_LIB.T6G(SCH_1):PAGE14
  BF70     NC     NC   I159 @T6G_MB_LIB.T6G(SCH_1):PAGE14
  BG71     NC     NC   I159 @T6G_MB_LIB.T6G(SCH_1):PAGE14
  BF69 TP_M_E_CPU0_SA_TEST39E @T6G_MB_LIB.T6G(SCH_1):TP_M_E_CPU0_SA_TEST39E   I159 @T6G_MB_LIB.T6G(SCH_1):PAGE14
  AT65 M_F_CPU0_ALERT_R_N @T6G_MB_LIB.T6G(SCH_1):M_F_CPU0_ALERT_R_N   I159 @T6G_MB_LIB.T6G(SCH_1):PAGE15
  AU66 M_F_CPU0_RESET_N @T6G_MB_LIB.T6G(SCH_1):M_F_CPU0_RESET_N   I159 @T6G_MB_LIB.T6G(SCH_1):PAGE15
  CL66 M_F_CPU0_SB_DQS_DN<6> @T6G_MB_LIB.T6G(SCH_1):M_F_CPU0_SB_DQS_DN(6)   I159 @T6G_MB_LIB.T6G(SCH_1):PAGE15
  CT67 M_F_CPU0_SB_DQS_DP<2> @T6G_MB_LIB.T6G(SCH_1):M_F_CPU0_SB_DQS_DP(2)   I159 @T6G_MB_LIB.T6G(SCH_1):PAGE15
  CT65 M_F_CPU0_SB_DQ<19> @T6G_MB_LIB.T6G(SCH_1):M_F_CPU0_SB_DQ(19)   I159 @T6G_MB_LIB.T6G(SCH_1):PAGE15
  CH65 M_F_CPU0_SB_DQ<7> @T6G_MB_LIB.T6G(SCH_1):M_F_CPU0_SB_DQ(7)   I159 @T6G_MB_LIB.T6G(SCH_1):PAGE15
  AG66 M_F_CPU0_SA_DQS_DP<8> @T6G_MB_LIB.T6G(SCH_1):M_F_CPU0_SA_DQS_DP(8)   I159 @T6G_MB_LIB.T6G(SCH_1):PAGE15
  AH67 M_F_CPU0_SA_DQ<30> @T6G_MB_LIB.T6G(SCH_1):M_F_CPU0_SA_DQ(30)   I159 @T6G_MB_LIB.T6G(SCH_1):PAGE15
   L67 M_F_CPU0_SA_DQ<8> @T6G_MB_LIB.T6G(SCH_1):M_F_CPU0_SA_DQ(8)   I159 @T6G_MB_LIB.T6G(SCH_1):PAGE15
  AU67     NC     NC   I159 @T6G_MB_LIB.T6G(SCH_1):PAGE15
  AW66 M_F_CPU0_SA_CS_N<1> @T6G_MB_LIB.T6G(SCH_1):M_F_CPU0_SA_CS_N(1)   I159 @T6G_MB_LIB.T6G(SCH_1):PAGE15
  CU66 M_F_CPU0_SB_DQS_DN<7> @T6G_MB_LIB.T6G(SCH_1):M_F_CPU0_SB_DQS_DN(7)   I159 @T6G_MB_LIB.T6G(SCH_1):PAGE15
  DB67 M_F_CPU0_SB_DQS_DP<3> @T6G_MB_LIB.T6G(SCH_1):M_F_CPU0_SB_DQS_DP(3)   I159 @T6G_MB_LIB.T6G(SCH_1):PAGE15
  CH67 M_F_CPU0_SB_DQ<8> @T6G_MB_LIB.T6G(SCH_1):M_F_CPU0_SB_DQ(8)   I159 @T6G_MB_LIB.T6G(SCH_1):PAGE15
  AN66 M_F_CPU0_SA_DQS_DP<9> @T6G_MB_LIB.T6G(SCH_1):M_F_CPU0_SA_DQS_DP(9)   I159 @T6G_MB_LIB.T6G(SCH_1):PAGE15
  AJ66 M_F_CPU0_SA_DQ<31> @T6G_MB_LIB.T6G(SCH_1):M_F_CPU0_SA_DQ(31)   I159 @T6G_MB_LIB.T6G(SCH_1):PAGE15
  AA67 M_F_CPU0_SA_DQ<20> @T6G_MB_LIB.T6G(SCH_1):M_F_CPU0_SA_DQ(20)   I159 @T6G_MB_LIB.T6G(SCH_1):PAGE15
   M65 M_F_CPU0_SA_DQ<9> @T6G_MB_LIB.T6G(SCH_1):M_F_CPU0_SA_DQ(9)   I159 @T6G_MB_LIB.T6G(SCH_1):PAGE15
  AJ67 M_F_CPU0_SA_CB<0> @T6G_MB_LIB.T6G(SCH_1):M_F_CPU0_SA_CB(0)   I159 @T6G_MB_LIB.T6G(SCH_1):PAGE15
  AV65     NC     NC   I159 @T6G_MB_LIB.T6G(SCH_1):PAGE15
  DC66 M_F_CPU0_SB_DQS_DN<8> @T6G_MB_LIB.T6G(SCH_1):M_F_CPU0_SB_DQS_DN(8)   I159 @T6G_MB_LIB.T6G(SCH_1):PAGE15
  BY65 M_F_CPU0_SB_DQS_DP<4> @T6G_MB_LIB.T6G(SCH_1):M_F_CPU0_SB_DQS_DP(4)   I159 @T6G_MB_LIB.T6G(SCH_1):PAGE15
  CJ66 M_F_CPU0_SB_DQ<9> @T6G_MB_LIB.T6G(SCH_1):M_F_CPU0_SB_DQ(9)   I159 @T6G_MB_LIB.T6G(SCH_1):PAGE15
  AB65 M_F_CPU0_SA_DQ<21> @T6G_MB_LIB.T6G(SCH_1):M_F_CPU0_SA_DQ(21)   I159 @T6G_MB_LIB.T6G(SCH_1):PAGE15
   M67 M_F_CPU0_SA_DQ<10> @T6G_MB_LIB.T6G(SCH_1):M_F_CPU0_SA_DQ(10)   I159 @T6G_MB_LIB.T6G(SCH_1):PAGE15
  AK65 M_F_CPU0_SA_CB<1> @T6G_MB_LIB.T6G(SCH_1):M_F_CPU0_SA_CB(1)   I159 @T6G_MB_LIB.T6G(SCH_1):PAGE15
  BW67 M_F_CPU0_SB_DQS_DN<9> @T6G_MB_LIB.T6G(SCH_1):M_F_CPU0_SB_DQS_DN(9)   I159 @T6G_MB_LIB.T6G(SCH_1):PAGE15
  CF65 M_F_CPU0_SB_DQS_DP<5> @T6G_MB_LIB.T6G(SCH_1):M_F_CPU0_SB_DQS_DP(5)   I159 @T6G_MB_LIB.T6G(SCH_1):PAGE15
  AB67 M_F_CPU0_SA_DQ<22> @T6G_MB_LIB.T6G(SCH_1):M_F_CPU0_SA_DQ(22)   I159 @T6G_MB_LIB.T6G(SCH_1):PAGE15
   N66 M_F_CPU0_SA_DQ<11> @T6G_MB_LIB.T6G(SCH_1):M_F_CPU0_SA_DQ(11)   I159 @T6G_MB_LIB.T6G(SCH_1):PAGE15
  AK67 M_F_CPU0_SA_CB<2> @T6G_MB_LIB.T6G(SCH_1):M_F_CPU0_SA_CB(2)   I159 @T6G_MB_LIB.T6G(SCH_1):PAGE15
  CM65 M_F_CPU0_SB_DQS_DP<6> @T6G_MB_LIB.T6G(SCH_1):M_F_CPU0_SB_DQS_DP(6)   I159 @T6G_MB_LIB.T6G(SCH_1):PAGE15
  AC66 M_F_CPU0_SA_DQ<23> @T6G_MB_LIB.T6G(SCH_1):M_F_CPU0_SA_DQ(23)   I159 @T6G_MB_LIB.T6G(SCH_1):PAGE15
   R67 M_F_CPU0_SA_DQ<12> @T6G_MB_LIB.T6G(SCH_1):M_F_CPU0_SA_DQ(12)   I159 @T6G_MB_LIB.T6G(SCH_1):PAGE15
  AL66 M_F_CPU0_SA_CB<3> @T6G_MB_LIB.T6G(SCH_1):M_F_CPU0_SA_CB(3)   I159 @T6G_MB_LIB.T6G(SCH_1):PAGE15
  AW67 M_F_CPU0_SA_CA<0> @T6G_MB_LIB.T6G(SCH_1):M_F_CPU0_SA_CA(0)   I159 @T6G_MB_LIB.T6G(SCH_1):PAGE15
  CV65 M_F_CPU0_SB_DQS_DP<7> @T6G_MB_LIB.T6G(SCH_1):M_F_CPU0_SB_DQS_DP(7)   I159 @T6G_MB_LIB.T6G(SCH_1):PAGE15
  BG66 M_F_CPU0_SB_CA<0> @T6G_MB_LIB.T6G(SCH_1):M_F_CPU0_SB_CA(0)   I159 @T6G_MB_LIB.T6G(SCH_1):PAGE15
  BM65 M_F_CPU0_SB_CS_N<0> @T6G_MB_LIB.T6G(SCH_1):M_F_CPU0_SB_CS_N(0)   I159 @T6G_MB_LIB.T6G(SCH_1):PAGE15
   H67 M_F_CPU0_SA_DQS_DN<0> @T6G_MB_LIB.T6G(SCH_1):M_F_CPU0_SA_DQS_DN(0)   I159 @T6G_MB_LIB.T6G(SCH_1):PAGE15
  AC67 M_F_CPU0_SA_DQ<24> @T6G_MB_LIB.T6G(SCH_1):M_F_CPU0_SA_DQ(24)   I159 @T6G_MB_LIB.T6G(SCH_1):PAGE15
   T65 M_F_CPU0_SA_DQ<13> @T6G_MB_LIB.T6G(SCH_1):M_F_CPU0_SA_DQ(13)   I159 @T6G_MB_LIB.T6G(SCH_1):PAGE15
  AN67 M_F_CPU0_SA_CB<4> @T6G_MB_LIB.T6G(SCH_1):M_F_CPU0_SA_CB(4)   I159 @T6G_MB_LIB.T6G(SCH_1):PAGE15
  AY67 M_F_CPU0_SA_CA<1> @T6G_MB_LIB.T6G(SCH_1):M_F_CPU0_SA_CA(1)   I159 @T6G_MB_LIB.T6G(SCH_1):PAGE15
  DD65 M_F_CPU0_SB_DQS_DP<8> @T6G_MB_LIB.T6G(SCH_1):M_F_CPU0_SB_DQS_DP(8)   I159 @T6G_MB_LIB.T6G(SCH_1):PAGE15
  DE67 M_F_CPU0_SB_DQ<30> @T6G_MB_LIB.T6G(SCH_1):M_F_CPU0_SB_DQ(30)   I159 @T6G_MB_LIB.T6G(SCH_1):PAGE15
  BH65 M_F_CPU0_SB_CA<1> @T6G_MB_LIB.T6G(SCH_1):M_F_CPU0_SB_CA(1)   I159 @T6G_MB_LIB.T6G(SCH_1):PAGE15
  BL66     NC     NC   I159 @T6G_MB_LIB.T6G(SCH_1):PAGE15
  BN67 M_F_CPU0_SB_CS_N<1> @T6G_MB_LIB.T6G(SCH_1):M_F_CPU0_SB_CS_N(1)   I159 @T6G_MB_LIB.T6G(SCH_1):PAGE15
   P67 M_F_CPU0_SA_DQS_DN<1> @T6G_MB_LIB.T6G(SCH_1):M_F_CPU0_SA_DQS_DN(1)   I159 @T6G_MB_LIB.T6G(SCH_1):PAGE15
  AD65 M_F_CPU0_SA_DQ<25> @T6G_MB_LIB.T6G(SCH_1):M_F_CPU0_SA_DQ(25)   I159 @T6G_MB_LIB.T6G(SCH_1):PAGE15
   T67 M_F_CPU0_SA_DQ<14> @T6G_MB_LIB.T6G(SCH_1):M_F_CPU0_SA_DQ(14)   I159 @T6G_MB_LIB.T6G(SCH_1):PAGE15
  AP65 M_F_CPU0_SA_CB<5> @T6G_MB_LIB.T6G(SCH_1):M_F_CPU0_SA_CB(5)   I159 @T6G_MB_LIB.T6G(SCH_1):PAGE15
  AY65 M_F_CPU0_SA_CA<2> @T6G_MB_LIB.T6G(SCH_1):M_F_CPU0_SA_CA(2)   I159 @T6G_MB_LIB.T6G(SCH_1):PAGE15
  DF67 M_F_CPU0_SB_DQ<31> @T6G_MB_LIB.T6G(SCH_1):M_F_CPU0_SB_DQ(31)   I159 @T6G_MB_LIB.T6G(SCH_1):PAGE15
  CV67 M_F_CPU0_SB_DQ<20> @T6G_MB_LIB.T6G(SCH_1):M_F_CPU0_SB_DQ(20)   I159 @T6G_MB_LIB.T6G(SCH_1):PAGE15
  BY67 M_F_CPU0_SB_CB<0> @T6G_MB_LIB.T6G(SCH_1):M_F_CPU0_SB_CB(0)   I159 @T6G_MB_LIB.T6G(SCH_1):PAGE15
  BH67 M_F_CPU0_SB_CA<2> @T6G_MB_LIB.T6G(SCH_1):M_F_CPU0_SB_CA(2)   I159 @T6G_MB_LIB.T6G(SCH_1):PAGE15
  BM67     NC     NC   I159 @T6G_MB_LIB.T6G(SCH_1):PAGE15
   Y67 M_F_CPU0_SA_DQS_DN<2> @T6G_MB_LIB.T6G(SCH_1):M_F_CPU0_SA_DQS_DN(2)   I159 @T6G_MB_LIB.T6G(SCH_1):PAGE15
  AD67 M_F_CPU0_SA_DQ<26> @T6G_MB_LIB.T6G(SCH_1):M_F_CPU0_SA_DQ(26)   I159 @T6G_MB_LIB.T6G(SCH_1):PAGE15
   U66 M_F_CPU0_SA_DQ<15> @T6G_MB_LIB.T6G(SCH_1):M_F_CPU0_SA_DQ(15)   I159 @T6G_MB_LIB.T6G(SCH_1):PAGE15
  AP67 M_F_CPU0_SA_CB<6> @T6G_MB_LIB.T6G(SCH_1):M_F_CPU0_SA_CB(6)   I159 @T6G_MB_LIB.T6G(SCH_1):PAGE15
  BA66 M_F_CPU0_SA_CA<3> @T6G_MB_LIB.T6G(SCH_1):M_F_CPU0_SA_CA(3)   I159 @T6G_MB_LIB.T6G(SCH_1):PAGE15
  CW66 M_F_CPU0_SB_DQ<21> @T6G_MB_LIB.T6G(SCH_1):M_F_CPU0_SB_DQ(21)   I159 @T6G_MB_LIB.T6G(SCH_1):PAGE15
  CJ67 M_F_CPU0_SB_DQ<10> @T6G_MB_LIB.T6G(SCH_1):M_F_CPU0_SB_DQ(10)   I159 @T6G_MB_LIB.T6G(SCH_1):PAGE15
  CA66 M_F_CPU0_SB_CB<1> @T6G_MB_LIB.T6G(SCH_1):M_F_CPU0_SB_CB(1)   I159 @T6G_MB_LIB.T6G(SCH_1):PAGE15
  BJ67 M_F_CPU0_SB_CA<3> @T6G_MB_LIB.T6G(SCH_1):M_F_CPU0_SB_CA(3)   I159 @T6G_MB_LIB.T6G(SCH_1):PAGE15
  AF67 M_F_CPU0_SA_DQS_DN<3> @T6G_MB_LIB.T6G(SCH_1):M_F_CPU0_SA_DQS_DN(3)   I159 @T6G_MB_LIB.T6G(SCH_1):PAGE15
  AE66 M_F_CPU0_SA_DQ<27> @T6G_MB_LIB.T6G(SCH_1):M_F_CPU0_SA_DQ(27)   I159 @T6G_MB_LIB.T6G(SCH_1):PAGE15
   U67 M_F_CPU0_SA_DQ<16> @T6G_MB_LIB.T6G(SCH_1):M_F_CPU0_SA_DQ(16)   I159 @T6G_MB_LIB.T6G(SCH_1):PAGE15
  AR66 M_F_CPU0_SA_CB<7> @T6G_MB_LIB.T6G(SCH_1):M_F_CPU0_SA_CB(7)   I159 @T6G_MB_LIB.T6G(SCH_1):PAGE15
  BA67 M_F_CPU0_SA_CA<4> @T6G_MB_LIB.T6G(SCH_1):M_F_CPU0_SA_CA(4)   I159 @T6G_MB_LIB.T6G(SCH_1):PAGE15
  BN66 M_F_CPU0_SA_RSP<0> @T6G_MB_LIB.T6G(SCH_1):M_F_CPU0_SA_RSP(0)   I159 @T6G_MB_LIB.T6G(SCH_1):PAGE15
  CW67 M_F_CPU0_SB_DQ<22> @T6G_MB_LIB.T6G(SCH_1):M_F_CPU0_SB_DQ(22)   I159 @T6G_MB_LIB.T6G(SCH_1):PAGE15
  CK65 M_F_CPU0_SB_DQ<11> @T6G_MB_LIB.T6G(SCH_1):M_F_CPU0_SB_DQ(11)   I159 @T6G_MB_LIB.T6G(SCH_1):PAGE15
  CA67 M_F_CPU0_SB_CB<2> @T6G_MB_LIB.T6G(SCH_1):M_F_CPU0_SB_CB(2)   I159 @T6G_MB_LIB.T6G(SCH_1):PAGE15
  BJ66 M_F_CPU0_SB_CA<4> @T6G_MB_LIB.T6G(SCH_1):M_F_CPU0_SB_CA(4)   I159 @T6G_MB_LIB.T6G(SCH_1):PAGE15
  AM67 M_F_CPU0_SA_DQS_DN<4> @T6G_MB_LIB.T6G(SCH_1):M_F_CPU0_SA_DQS_DN(4)   I159 @T6G_MB_LIB.T6G(SCH_1):PAGE15
   G67 M_F_CPU0_SA_DQS_DP<0> @T6G_MB_LIB.T6G(SCH_1):M_F_CPU0_SA_DQS_DP(0)   I159 @T6G_MB_LIB.T6G(SCH_1):PAGE15
  AG67 M_F_CPU0_SA_DQ<28> @T6G_MB_LIB.T6G(SCH_1):M_F_CPU0_SA_DQ(28)   I159 @T6G_MB_LIB.T6G(SCH_1):PAGE15
   V65 M_F_CPU0_SA_DQ<17> @T6G_MB_LIB.T6G(SCH_1):M_F_CPU0_SA_DQ(17)   I159 @T6G_MB_LIB.T6G(SCH_1):PAGE15
   E67 M_F_CPU0_SA_DQ<0> @T6G_MB_LIB.T6G(SCH_1):M_F_CPU0_SA_DQ(0)   I159 @T6G_MB_LIB.T6G(SCH_1):PAGE15
  BB67 M_F_CPU0_SA_CA<5> @T6G_MB_LIB.T6G(SCH_1):M_F_CPU0_SA_CA(5)   I159 @T6G_MB_LIB.T6G(SCH_1):PAGE15
  BP65     NC     NC   I159 @T6G_MB_LIB.T6G(SCH_1):PAGE15
  CY65 M_F_CPU0_SB_DQ<23> @T6G_MB_LIB.T6G(SCH_1):M_F_CPU0_SB_DQ(23)   I159 @T6G_MB_LIB.T6G(SCH_1):PAGE15
  CM67 M_F_CPU0_SB_DQ<12> @T6G_MB_LIB.T6G(SCH_1):M_F_CPU0_SB_DQ(12)   I159 @T6G_MB_LIB.T6G(SCH_1):PAGE15
  CB67 M_F_CPU0_SB_DQ<0> @T6G_MB_LIB.T6G(SCH_1):M_F_CPU0_SB_DQ(0)   I159 @T6G_MB_LIB.T6G(SCH_1):PAGE15
  CB65 M_F_CPU0_SB_CB<3> @T6G_MB_LIB.T6G(SCH_1):M_F_CPU0_SB_CB(3)   I159 @T6G_MB_LIB.T6G(SCH_1):PAGE15
  BK65 M_F_CPU0_SB_CA<5> @T6G_MB_LIB.T6G(SCH_1):M_F_CPU0_SB_CA(5)   I159 @T6G_MB_LIB.T6G(SCH_1):PAGE15
   H65 M_F_CPU0_SA_DQS_DN<5> @T6G_MB_LIB.T6G(SCH_1):M_F_CPU0_SA_DQS_DN(5)   I159 @T6G_MB_LIB.T6G(SCH_1):PAGE15
   N67 M_F_CPU0_SA_DQS_DP<1> @T6G_MB_LIB.T6G(SCH_1):M_F_CPU0_SA_DQS_DP(1)   I159 @T6G_MB_LIB.T6G(SCH_1):PAGE15
  AH65 M_F_CPU0_SA_DQ<29> @T6G_MB_LIB.T6G(SCH_1):M_F_CPU0_SA_DQ(29)   I159 @T6G_MB_LIB.T6G(SCH_1):PAGE15
   V67 M_F_CPU0_SA_DQ<18> @T6G_MB_LIB.T6G(SCH_1):M_F_CPU0_SA_DQ(18)   I159 @T6G_MB_LIB.T6G(SCH_1):PAGE15
   F65 M_F_CPU0_SA_DQ<1> @T6G_MB_LIB.T6G(SCH_1):M_F_CPU0_SA_DQ(1)   I159 @T6G_MB_LIB.T6G(SCH_1):PAGE15
  BB65 M_F_CPU0_SA_CA<6> @T6G_MB_LIB.T6G(SCH_1):M_F_CPU0_SA_CA(6)   I159 @T6G_MB_LIB.T6G(SCH_1):PAGE15
  CE67 M_F_CPU0_SB_DQS_DN<0> @T6G_MB_LIB.T6G(SCH_1):M_F_CPU0_SB_DQS_DN(0)   I159 @T6G_MB_LIB.T6G(SCH_1):PAGE15
  CY67 M_F_CPU0_SB_DQ<24> @T6G_MB_LIB.T6G(SCH_1):M_F_CPU0_SB_DQ(24)   I159 @T6G_MB_LIB.T6G(SCH_1):PAGE15
  CN66 M_F_CPU0_SB_DQ<13> @T6G_MB_LIB.T6G(SCH_1):M_F_CPU0_SB_DQ(13)   I159 @T6G_MB_LIB.T6G(SCH_1):PAGE15
  CC66 M_F_CPU0_SB_DQ<1> @T6G_MB_LIB.T6G(SCH_1):M_F_CPU0_SB_DQ(1)   I159 @T6G_MB_LIB.T6G(SCH_1):PAGE15
  BT67 M_F_CPU0_SB_CB<4> @T6G_MB_LIB.T6G(SCH_1):M_F_CPU0_SB_CB(4)   I159 @T6G_MB_LIB.T6G(SCH_1):PAGE15
  BK67 M_F_CPU0_SB_CA<6> @T6G_MB_LIB.T6G(SCH_1):M_F_CPU0_SB_CA(6)   I159 @T6G_MB_LIB.T6G(SCH_1):PAGE15
   P65 M_F_CPU0_SA_DQS_DN<6> @T6G_MB_LIB.T6G(SCH_1):M_F_CPU0_SA_DQS_DN(6)   I159 @T6G_MB_LIB.T6G(SCH_1):PAGE15
   W67 M_F_CPU0_SA_DQS_DP<2> @T6G_MB_LIB.T6G(SCH_1):M_F_CPU0_SA_DQS_DP(2)   I159 @T6G_MB_LIB.T6G(SCH_1):PAGE15
   W66 M_F_CPU0_SA_DQ<19> @T6G_MB_LIB.T6G(SCH_1):M_F_CPU0_SA_DQ(19)   I159 @T6G_MB_LIB.T6G(SCH_1):PAGE15
   F67 M_F_CPU0_SA_DQ<2> @T6G_MB_LIB.T6G(SCH_1):M_F_CPU0_SA_DQ(2)   I159 @T6G_MB_LIB.T6G(SCH_1):PAGE15
  CL67 M_F_CPU0_SB_DQS_DN<1> @T6G_MB_LIB.T6G(SCH_1):M_F_CPU0_SB_DQS_DN(1)   I159 @T6G_MB_LIB.T6G(SCH_1):PAGE15
  DA66 M_F_CPU0_SB_DQ<25> @T6G_MB_LIB.T6G(SCH_1):M_F_CPU0_SB_DQ(25)   I159 @T6G_MB_LIB.T6G(SCH_1):PAGE15
  CN67 M_F_CPU0_SB_DQ<14> @T6G_MB_LIB.T6G(SCH_1):M_F_CPU0_SB_DQ(14)   I159 @T6G_MB_LIB.T6G(SCH_1):PAGE15
  CC67 M_F_CPU0_SB_DQ<2> @T6G_MB_LIB.T6G(SCH_1):M_F_CPU0_SB_DQ(2)   I159 @T6G_MB_LIB.T6G(SCH_1):PAGE15
  BU66 M_F_CPU0_SB_CB<5> @T6G_MB_LIB.T6G(SCH_1):M_F_CPU0_SB_CB(5)   I159 @T6G_MB_LIB.T6G(SCH_1):PAGE15
   Y65 M_F_CPU0_SA_DQS_DN<7> @T6G_MB_LIB.T6G(SCH_1):M_F_CPU0_SA_DQS_DN(7)   I159 @T6G_MB_LIB.T6G(SCH_1):PAGE15
  AE67 M_F_CPU0_SA_DQS_DP<3> @T6G_MB_LIB.T6G(SCH_1):M_F_CPU0_SA_DQS_DP(3)   I159 @T6G_MB_LIB.T6G(SCH_1):PAGE15
   G66 M_F_CPU0_SA_DQ<3> @T6G_MB_LIB.T6G(SCH_1):M_F_CPU0_SA_DQ(3)   I159 @T6G_MB_LIB.T6G(SCH_1):PAGE15
  CU67 M_F_CPU0_SB_DQS_DN<2> @T6G_MB_LIB.T6G(SCH_1):M_F_CPU0_SB_DQS_DN(2)   I159 @T6G_MB_LIB.T6G(SCH_1):PAGE15
  DA67 M_F_CPU0_SB_DQ<26> @T6G_MB_LIB.T6G(SCH_1):M_F_CPU0_SB_DQ(26)   I159 @T6G_MB_LIB.T6G(SCH_1):PAGE15
  CP65 M_F_CPU0_SB_DQ<15> @T6G_MB_LIB.T6G(SCH_1):M_F_CPU0_SB_DQ(15)   I159 @T6G_MB_LIB.T6G(SCH_1):PAGE15
  CD65 M_F_CPU0_SB_DQ<3> @T6G_MB_LIB.T6G(SCH_1):M_F_CPU0_SB_DQ(3)   I159 @T6G_MB_LIB.T6G(SCH_1):PAGE15
  BU67 M_F_CPU0_SB_CB<6> @T6G_MB_LIB.T6G(SCH_1):M_F_CPU0_SB_CB(6)   I159 @T6G_MB_LIB.T6G(SCH_1):PAGE15
  AF65 M_F_CPU0_SA_DQS_DN<8> @T6G_MB_LIB.T6G(SCH_1):M_F_CPU0_SA_DQS_DN(8)   I159 @T6G_MB_LIB.T6G(SCH_1):PAGE15
  AL67 M_F_CPU0_SA_DQS_DP<4> @T6G_MB_LIB.T6G(SCH_1):M_F_CPU0_SA_DQS_DP(4)   I159 @T6G_MB_LIB.T6G(SCH_1):PAGE15
   J67 M_F_CPU0_SA_DQ<4> @T6G_MB_LIB.T6G(SCH_1):M_F_CPU0_SA_DQ(4)   I159 @T6G_MB_LIB.T6G(SCH_1):PAGE15
  DC67 M_F_CPU0_SB_DQS_DN<3> @T6G_MB_LIB.T6G(SCH_1):M_F_CPU0_SB_DQS_DN(3)   I159 @T6G_MB_LIB.T6G(SCH_1):PAGE15
  DB65 M_F_CPU0_SB_DQ<27> @T6G_MB_LIB.T6G(SCH_1):M_F_CPU0_SB_DQ(27)   I159 @T6G_MB_LIB.T6G(SCH_1):PAGE15
  CP67 M_F_CPU0_SB_DQ<16> @T6G_MB_LIB.T6G(SCH_1):M_F_CPU0_SB_DQ(16)   I159 @T6G_MB_LIB.T6G(SCH_1):PAGE15
  CF67 M_F_CPU0_SB_DQ<4> @T6G_MB_LIB.T6G(SCH_1):M_F_CPU0_SB_DQ(4)   I159 @T6G_MB_LIB.T6G(SCH_1):PAGE15
  BV65 M_F_CPU0_SB_CB<7> @T6G_MB_LIB.T6G(SCH_1):M_F_CPU0_SB_CB(7)   I159 @T6G_MB_LIB.T6G(SCH_1):PAGE15
  BP67 M_F_CPU0_SB_RSP<0> @T6G_MB_LIB.T6G(SCH_1):M_F_CPU0_SB_RSP(0)   I159 @T6G_MB_LIB.T6G(SCH_1):PAGE15
  AM65 M_F_CPU0_SA_DQS_DN<9> @T6G_MB_LIB.T6G(SCH_1):M_F_CPU0_SA_DQS_DN(9)   I159 @T6G_MB_LIB.T6G(SCH_1):PAGE15
   J66 M_F_CPU0_SA_DQS_DP<5> @T6G_MB_LIB.T6G(SCH_1):M_F_CPU0_SA_DQS_DP(5)   I159 @T6G_MB_LIB.T6G(SCH_1):PAGE15
   K65 M_F_CPU0_SA_DQ<5> @T6G_MB_LIB.T6G(SCH_1):M_F_CPU0_SA_DQ(5)   I159 @T6G_MB_LIB.T6G(SCH_1):PAGE15
  BW66 M_F_CPU0_SB_DQS_DN<4> @T6G_MB_LIB.T6G(SCH_1):M_F_CPU0_SB_DQS_DN(4)   I159 @T6G_MB_LIB.T6G(SCH_1):PAGE15
  CD67 M_F_CPU0_SB_DQS_DP<0> @T6G_MB_LIB.T6G(SCH_1):M_F_CPU0_SB_DQS_DP(0)   I159 @T6G_MB_LIB.T6G(SCH_1):PAGE15
  DD67 M_F_CPU0_SB_DQ<28> @T6G_MB_LIB.T6G(SCH_1):M_F_CPU0_SB_DQ(28)   I159 @T6G_MB_LIB.T6G(SCH_1):PAGE15
  CR66 M_F_CPU0_SB_DQ<17> @T6G_MB_LIB.T6G(SCH_1):M_F_CPU0_SB_DQ(17)   I159 @T6G_MB_LIB.T6G(SCH_1):PAGE15
  CG66 M_F_CPU0_SB_DQ<5> @T6G_MB_LIB.T6G(SCH_1):M_F_CPU0_SB_DQ(5)   I159 @T6G_MB_LIB.T6G(SCH_1):PAGE15
  BR67     NC     NC   I159 @T6G_MB_LIB.T6G(SCH_1):PAGE15
   R66 M_F_CPU0_SA_DQS_DP<6> @T6G_MB_LIB.T6G(SCH_1):M_F_CPU0_SA_DQS_DP(6)   I159 @T6G_MB_LIB.T6G(SCH_1):PAGE15
   K67 M_F_CPU0_SA_DQ<6> @T6G_MB_LIB.T6G(SCH_1):M_F_CPU0_SA_DQ(6)   I159 @T6G_MB_LIB.T6G(SCH_1):PAGE15
  CE66 M_F_CPU0_SB_DQS_DN<5> @T6G_MB_LIB.T6G(SCH_1):M_F_CPU0_SB_DQS_DN(5)   I159 @T6G_MB_LIB.T6G(SCH_1):PAGE15
  CK67 M_F_CPU0_SB_DQS_DP<1> @T6G_MB_LIB.T6G(SCH_1):M_F_CPU0_SB_DQS_DP(1)   I159 @T6G_MB_LIB.T6G(SCH_1):PAGE15
  DE66 M_F_CPU0_SB_DQ<29> @T6G_MB_LIB.T6G(SCH_1):M_F_CPU0_SB_DQ(29)   I159 @T6G_MB_LIB.T6G(SCH_1):PAGE15
  CR67 M_F_CPU0_SB_DQ<18> @T6G_MB_LIB.T6G(SCH_1):M_F_CPU0_SB_DQ(18)   I159 @T6G_MB_LIB.T6G(SCH_1):PAGE15
  CG67 M_F_CPU0_SB_DQ<6> @T6G_MB_LIB.T6G(SCH_1):M_F_CPU0_SB_DQ(6)   I159 @T6G_MB_LIB.T6G(SCH_1):PAGE15
  AA66 M_F_CPU0_SA_DQS_DP<7> @T6G_MB_LIB.T6G(SCH_1):M_F_CPU0_SA_DQS_DP(7)   I159 @T6G_MB_LIB.T6G(SCH_1):PAGE15
   L66 M_F_CPU0_SA_DQ<7> @T6G_MB_LIB.T6G(SCH_1):M_F_CPU0_SA_DQ(7)   I159 @T6G_MB_LIB.T6G(SCH_1):PAGE15
  AV67 M_F_CPU0_SA_CS_N<0> @T6G_MB_LIB.T6G(SCH_1):M_F_CPU0_SA_CS_N(0)   I159 @T6G_MB_LIB.T6G(SCH_1):PAGE15
  BC66 M_F_CPU0_SA_PAR @T6G_MB_LIB.T6G(SCH_1):M_F_CPU0_SA_PAR   I159 @T6G_MB_LIB.T6G(SCH_1):PAGE15
  BL67 M_F_CPU0_SB_PAR @T6G_MB_LIB.T6G(SCH_1):M_F_CPU0_SB_PAR   I159 @T6G_MB_LIB.T6G(SCH_1):PAGE15
  BV67 M_F_CPU0_SB_DQS_DP<9> @T6G_MB_LIB.T6G(SCH_1):M_F_CPU0_SB_DQS_DP(9)   I159 @T6G_MB_LIB.T6G(SCH_1):PAGE15
  BC67 M_F_CPU0_CLK_DP<0> @T6G_MB_LIB.T6G(SCH_1):M_F_CPU0_CLK_DP(0)   I159 @T6G_MB_LIB.T6G(SCH_1):PAGE15
  BD67 M_F_CPU0_CLK_DN<0> @T6G_MB_LIB.T6G(SCH_1):M_F_CPU0_CLK_DN(0)   I159 @T6G_MB_LIB.T6G(SCH_1):PAGE15
  BF67     NC     NC   I159 @T6G_MB_LIB.T6G(SCH_1):PAGE15
  BG67     NC     NC   I159 @T6G_MB_LIB.T6G(SCH_1):PAGE15
  BF65 TP_M_F_CPU0_SA_TEST39F @T6G_MB_LIB.T6G(SCH_1):TP_M_F_CPU0_SA_TEST39F   I159 @T6G_MB_LIB.T6G(SCH_1):PAGE15
   AR2 M_G_CPU0_ALERT_R_N @T6G_MB_LIB.T6G(SCH_1):M_G_CPU0_ALERT_R_N   I167 @T6G_MB_LIB.T6G(SCH_1):PAGE16
   AT2 M_G_CPU0_RESET_N @T6G_MB_LIB.T6G(SCH_1):M_G_CPU0_RESET_N   I167 @T6G_MB_LIB.T6G(SCH_1):PAGE16
   BW2 M_G_CPU0_SB_DQS_DN<9> @T6G_MB_LIB.T6G(SCH_1):M_G_CPU0_SB_DQS_DN(9)   I167 @T6G_MB_LIB.T6G(SCH_1):PAGE16
   CF4 M_G_CPU0_SB_DQS_DP<5> @T6G_MB_LIB.T6G(SCH_1):M_G_CPU0_SB_DQS_DP(5)   I167 @T6G_MB_LIB.T6G(SCH_1):PAGE16
   CC3 M_G_CPU0_SB_DQ<1> @T6G_MB_LIB.T6G(SCH_1):M_G_CPU0_SB_DQ(1)   I167 @T6G_MB_LIB.T6G(SCH_1):PAGE16
   AB2 M_G_CPU0_SA_DQ<22> @T6G_MB_LIB.T6G(SCH_1):M_G_CPU0_SA_DQ(22)   I167 @T6G_MB_LIB.T6G(SCH_1):PAGE16
    N3 M_G_CPU0_SA_DQ<11> @T6G_MB_LIB.T6G(SCH_1):M_G_CPU0_SA_DQ(11)   I167 @T6G_MB_LIB.T6G(SCH_1):PAGE16
    F4 M_G_CPU0_SA_DQ<1> @T6G_MB_LIB.T6G(SCH_1):M_G_CPU0_SA_DQ(1)   I167 @T6G_MB_LIB.T6G(SCH_1):PAGE16
   AK2 M_G_CPU0_SA_CB<2> @T6G_MB_LIB.T6G(SCH_1):M_G_CPU0_SA_CB(2)   I167 @T6G_MB_LIB.T6G(SCH_1):PAGE16
   CM4 M_G_CPU0_SB_DQS_DP<6> @T6G_MB_LIB.T6G(SCH_1):M_G_CPU0_SB_DQS_DP(6)   I167 @T6G_MB_LIB.T6G(SCH_1):PAGE16
   CC2 M_G_CPU0_SB_DQ<2> @T6G_MB_LIB.T6G(SCH_1):M_G_CPU0_SB_DQ(2)   I167 @T6G_MB_LIB.T6G(SCH_1):PAGE16
   AC3 M_G_CPU0_SA_DQ<23> @T6G_MB_LIB.T6G(SCH_1):M_G_CPU0_SA_DQ(23)   I167 @T6G_MB_LIB.T6G(SCH_1):PAGE16
    R2 M_G_CPU0_SA_DQ<12> @T6G_MB_LIB.T6G(SCH_1):M_G_CPU0_SA_DQ(12)   I167 @T6G_MB_LIB.T6G(SCH_1):PAGE16
    F2 M_G_CPU0_SA_DQ<2> @T6G_MB_LIB.T6G(SCH_1):M_G_CPU0_SA_DQ(2)   I167 @T6G_MB_LIB.T6G(SCH_1):PAGE16
   AL3 M_G_CPU0_SA_CB<3> @T6G_MB_LIB.T6G(SCH_1):M_G_CPU0_SA_CB(3)   I167 @T6G_MB_LIB.T6G(SCH_1):PAGE16
   CV4 M_G_CPU0_SB_DQS_DP<7> @T6G_MB_LIB.T6G(SCH_1):M_G_CPU0_SB_DQS_DP(7)   I167 @T6G_MB_LIB.T6G(SCH_1):PAGE16
   CD4 M_G_CPU0_SB_DQ<3> @T6G_MB_LIB.T6G(SCH_1):M_G_CPU0_SB_DQ(3)   I167 @T6G_MB_LIB.T6G(SCH_1):PAGE16
   BL2     NC     NC   I167 @T6G_MB_LIB.T6G(SCH_1):PAGE16
   BM4 M_G_CPU0_SB_CS_N<0> @T6G_MB_LIB.T6G(SCH_1):M_G_CPU0_SB_CS_N(0)   I167 @T6G_MB_LIB.T6G(SCH_1):PAGE16
    H2 M_G_CPU0_SA_DQS_DN<0> @T6G_MB_LIB.T6G(SCH_1):M_G_CPU0_SA_DQS_DN(0)   I167 @T6G_MB_LIB.T6G(SCH_1):PAGE16
   AC2 M_G_CPU0_SA_DQ<24> @T6G_MB_LIB.T6G(SCH_1):M_G_CPU0_SA_DQ(24)   I167 @T6G_MB_LIB.T6G(SCH_1):PAGE16
    T4 M_G_CPU0_SA_DQ<13> @T6G_MB_LIB.T6G(SCH_1):M_G_CPU0_SA_DQ(13)   I167 @T6G_MB_LIB.T6G(SCH_1):PAGE16
    G3 M_G_CPU0_SA_DQ<3> @T6G_MB_LIB.T6G(SCH_1):M_G_CPU0_SA_DQ(3)   I167 @T6G_MB_LIB.T6G(SCH_1):PAGE16
   AN2 M_G_CPU0_SA_CB<4> @T6G_MB_LIB.T6G(SCH_1):M_G_CPU0_SA_CB(4)   I167 @T6G_MB_LIB.T6G(SCH_1):PAGE16
   DD4 M_G_CPU0_SB_DQS_DP<8> @T6G_MB_LIB.T6G(SCH_1):M_G_CPU0_SB_DQS_DP(8)   I167 @T6G_MB_LIB.T6G(SCH_1):PAGE16
   DE2 M_G_CPU0_SB_DQ<30> @T6G_MB_LIB.T6G(SCH_1):M_G_CPU0_SB_DQ(30)   I167 @T6G_MB_LIB.T6G(SCH_1):PAGE16
   CF2 M_G_CPU0_SB_DQ<4> @T6G_MB_LIB.T6G(SCH_1):M_G_CPU0_SB_DQ(4)   I167 @T6G_MB_LIB.T6G(SCH_1):PAGE16
   BM2     NC     NC   I167 @T6G_MB_LIB.T6G(SCH_1):PAGE16
   BN2 M_G_CPU0_SB_CS_N<1> @T6G_MB_LIB.T6G(SCH_1):M_G_CPU0_SB_CS_N(1)   I167 @T6G_MB_LIB.T6G(SCH_1):PAGE16
    P2 M_G_CPU0_SA_DQS_DN<1> @T6G_MB_LIB.T6G(SCH_1):M_G_CPU0_SA_DQS_DN(1)   I167 @T6G_MB_LIB.T6G(SCH_1):PAGE16
   AD4 M_G_CPU0_SA_DQ<25> @T6G_MB_LIB.T6G(SCH_1):M_G_CPU0_SA_DQ(25)   I167 @T6G_MB_LIB.T6G(SCH_1):PAGE16
    T2 M_G_CPU0_SA_DQ<14> @T6G_MB_LIB.T6G(SCH_1):M_G_CPU0_SA_DQ(14)   I167 @T6G_MB_LIB.T6G(SCH_1):PAGE16
    J2 M_G_CPU0_SA_DQ<4> @T6G_MB_LIB.T6G(SCH_1):M_G_CPU0_SA_DQ(4)   I167 @T6G_MB_LIB.T6G(SCH_1):PAGE16
   AP4 M_G_CPU0_SA_CB<5> @T6G_MB_LIB.T6G(SCH_1):M_G_CPU0_SA_CB(5)   I167 @T6G_MB_LIB.T6G(SCH_1):PAGE16
   AW2 M_G_CPU0_SA_CA<0> @T6G_MB_LIB.T6G(SCH_1):M_G_CPU0_SA_CA(0)   I167 @T6G_MB_LIB.T6G(SCH_1):PAGE16
   DF2 M_G_CPU0_SB_DQ<31> @T6G_MB_LIB.T6G(SCH_1):M_G_CPU0_SB_DQ(31)   I167 @T6G_MB_LIB.T6G(SCH_1):PAGE16
   CV2 M_G_CPU0_SB_DQ<20> @T6G_MB_LIB.T6G(SCH_1):M_G_CPU0_SB_DQ(20)   I167 @T6G_MB_LIB.T6G(SCH_1):PAGE16
   CG3 M_G_CPU0_SB_DQ<5> @T6G_MB_LIB.T6G(SCH_1):M_G_CPU0_SB_DQ(5)   I167 @T6G_MB_LIB.T6G(SCH_1):PAGE16
   BY2 M_G_CPU0_SB_CB<0> @T6G_MB_LIB.T6G(SCH_1):M_G_CPU0_SB_CB(0)   I167 @T6G_MB_LIB.T6G(SCH_1):PAGE16
   BG3 M_G_CPU0_SB_CA<0> @T6G_MB_LIB.T6G(SCH_1):M_G_CPU0_SB_CA(0)   I167 @T6G_MB_LIB.T6G(SCH_1):PAGE16
    Y2 M_G_CPU0_SA_DQS_DN<2> @T6G_MB_LIB.T6G(SCH_1):M_G_CPU0_SA_DQS_DN(2)   I167 @T6G_MB_LIB.T6G(SCH_1):PAGE16
   AD2 M_G_CPU0_SA_DQ<26> @T6G_MB_LIB.T6G(SCH_1):M_G_CPU0_SA_DQ(26)   I167 @T6G_MB_LIB.T6G(SCH_1):PAGE16
    U3 M_G_CPU0_SA_DQ<15> @T6G_MB_LIB.T6G(SCH_1):M_G_CPU0_SA_DQ(15)   I167 @T6G_MB_LIB.T6G(SCH_1):PAGE16
    K4 M_G_CPU0_SA_DQ<5> @T6G_MB_LIB.T6G(SCH_1):M_G_CPU0_SA_DQ(5)   I167 @T6G_MB_LIB.T6G(SCH_1):PAGE16
   AP2 M_G_CPU0_SA_CB<6> @T6G_MB_LIB.T6G(SCH_1):M_G_CPU0_SA_CB(6)   I167 @T6G_MB_LIB.T6G(SCH_1):PAGE16
   AY2 M_G_CPU0_SA_CA<1> @T6G_MB_LIB.T6G(SCH_1):M_G_CPU0_SA_CA(1)   I167 @T6G_MB_LIB.T6G(SCH_1):PAGE16
   CW3 M_G_CPU0_SB_DQ<21> @T6G_MB_LIB.T6G(SCH_1):M_G_CPU0_SB_DQ(21)   I167 @T6G_MB_LIB.T6G(SCH_1):PAGE16
   CJ2 M_G_CPU0_SB_DQ<10> @T6G_MB_LIB.T6G(SCH_1):M_G_CPU0_SB_DQ(10)   I167 @T6G_MB_LIB.T6G(SCH_1):PAGE16
   CG2 M_G_CPU0_SB_DQ<6> @T6G_MB_LIB.T6G(SCH_1):M_G_CPU0_SB_DQ(6)   I167 @T6G_MB_LIB.T6G(SCH_1):PAGE16
   CA3 M_G_CPU0_SB_CB<1> @T6G_MB_LIB.T6G(SCH_1):M_G_CPU0_SB_CB(1)   I167 @T6G_MB_LIB.T6G(SCH_1):PAGE16
   BH4 M_G_CPU0_SB_CA<1> @T6G_MB_LIB.T6G(SCH_1):M_G_CPU0_SB_CA(1)   I167 @T6G_MB_LIB.T6G(SCH_1):PAGE16
   AF2 M_G_CPU0_SA_DQS_DN<3> @T6G_MB_LIB.T6G(SCH_1):M_G_CPU0_SA_DQS_DN(3)   I167 @T6G_MB_LIB.T6G(SCH_1):PAGE16
   AE3 M_G_CPU0_SA_DQ<27> @T6G_MB_LIB.T6G(SCH_1):M_G_CPU0_SA_DQ(27)   I167 @T6G_MB_LIB.T6G(SCH_1):PAGE16
    U2 M_G_CPU0_SA_DQ<16> @T6G_MB_LIB.T6G(SCH_1):M_G_CPU0_SA_DQ(16)   I167 @T6G_MB_LIB.T6G(SCH_1):PAGE16
    K2 M_G_CPU0_SA_DQ<6> @T6G_MB_LIB.T6G(SCH_1):M_G_CPU0_SA_DQ(6)   I167 @T6G_MB_LIB.T6G(SCH_1):PAGE16
   AR3 M_G_CPU0_SA_CB<7> @T6G_MB_LIB.T6G(SCH_1):M_G_CPU0_SA_CB(7)   I167 @T6G_MB_LIB.T6G(SCH_1):PAGE16
   AY4 M_G_CPU0_SA_CA<2> @T6G_MB_LIB.T6G(SCH_1):M_G_CPU0_SA_CA(2)   I167 @T6G_MB_LIB.T6G(SCH_1):PAGE16
   BP4     NC     NC   I167 @T6G_MB_LIB.T6G(SCH_1):PAGE16
   BN3 M_G_CPU0_SA_RSP<0> @T6G_MB_LIB.T6G(SCH_1):M_G_CPU0_SA_RSP(0)   I167 @T6G_MB_LIB.T6G(SCH_1):PAGE16
   CW2 M_G_CPU0_SB_DQ<22> @T6G_MB_LIB.T6G(SCH_1):M_G_CPU0_SB_DQ(22)   I167 @T6G_MB_LIB.T6G(SCH_1):PAGE16
   CK4 M_G_CPU0_SB_DQ<11> @T6G_MB_LIB.T6G(SCH_1):M_G_CPU0_SB_DQ(11)   I167 @T6G_MB_LIB.T6G(SCH_1):PAGE16
   CH4 M_G_CPU0_SB_DQ<7> @T6G_MB_LIB.T6G(SCH_1):M_G_CPU0_SB_DQ(7)   I167 @T6G_MB_LIB.T6G(SCH_1):PAGE16
   CA2 M_G_CPU0_SB_CB<2> @T6G_MB_LIB.T6G(SCH_1):M_G_CPU0_SB_CB(2)   I167 @T6G_MB_LIB.T6G(SCH_1):PAGE16
   BH2 M_G_CPU0_SB_CA<2> @T6G_MB_LIB.T6G(SCH_1):M_G_CPU0_SB_CA(2)   I167 @T6G_MB_LIB.T6G(SCH_1):PAGE16
   AM2 M_G_CPU0_SA_DQS_DN<4> @T6G_MB_LIB.T6G(SCH_1):M_G_CPU0_SA_DQS_DN(4)   I167 @T6G_MB_LIB.T6G(SCH_1):PAGE16
    G2 M_G_CPU0_SA_DQS_DP<0> @T6G_MB_LIB.T6G(SCH_1):M_G_CPU0_SA_DQS_DP(0)   I167 @T6G_MB_LIB.T6G(SCH_1):PAGE16
   AG2 M_G_CPU0_SA_DQ<28> @T6G_MB_LIB.T6G(SCH_1):M_G_CPU0_SA_DQ(28)   I167 @T6G_MB_LIB.T6G(SCH_1):PAGE16
    V4 M_G_CPU0_SA_DQ<17> @T6G_MB_LIB.T6G(SCH_1):M_G_CPU0_SA_DQ(17)   I167 @T6G_MB_LIB.T6G(SCH_1):PAGE16
    L3 M_G_CPU0_SA_DQ<7> @T6G_MB_LIB.T6G(SCH_1):M_G_CPU0_SA_DQ(7)   I167 @T6G_MB_LIB.T6G(SCH_1):PAGE16
   BA3 M_G_CPU0_SA_CA<3> @T6G_MB_LIB.T6G(SCH_1):M_G_CPU0_SA_CA(3)   I167 @T6G_MB_LIB.T6G(SCH_1):PAGE16
   CY4 M_G_CPU0_SB_DQ<23> @T6G_MB_LIB.T6G(SCH_1):M_G_CPU0_SB_DQ(23)   I167 @T6G_MB_LIB.T6G(SCH_1):PAGE16
   CM2 M_G_CPU0_SB_DQ<12> @T6G_MB_LIB.T6G(SCH_1):M_G_CPU0_SB_DQ(12)   I167 @T6G_MB_LIB.T6G(SCH_1):PAGE16
   CH2 M_G_CPU0_SB_DQ<8> @T6G_MB_LIB.T6G(SCH_1):M_G_CPU0_SB_DQ(8)   I167 @T6G_MB_LIB.T6G(SCH_1):PAGE16
   CB4 M_G_CPU0_SB_CB<3> @T6G_MB_LIB.T6G(SCH_1):M_G_CPU0_SB_CB(3)   I167 @T6G_MB_LIB.T6G(SCH_1):PAGE16
   BJ2 M_G_CPU0_SB_CA<3> @T6G_MB_LIB.T6G(SCH_1):M_G_CPU0_SB_CA(3)   I167 @T6G_MB_LIB.T6G(SCH_1):PAGE16
    H4 M_G_CPU0_SA_DQS_DN<5> @T6G_MB_LIB.T6G(SCH_1):M_G_CPU0_SA_DQS_DN(5)   I167 @T6G_MB_LIB.T6G(SCH_1):PAGE16
    N2 M_G_CPU0_SA_DQS_DP<1> @T6G_MB_LIB.T6G(SCH_1):M_G_CPU0_SA_DQS_DP(1)   I167 @T6G_MB_LIB.T6G(SCH_1):PAGE16
   AH4 M_G_CPU0_SA_DQ<29> @T6G_MB_LIB.T6G(SCH_1):M_G_CPU0_SA_DQ(29)   I167 @T6G_MB_LIB.T6G(SCH_1):PAGE16
    V2 M_G_CPU0_SA_DQ<18> @T6G_MB_LIB.T6G(SCH_1):M_G_CPU0_SA_DQ(18)   I167 @T6G_MB_LIB.T6G(SCH_1):PAGE16
    L2 M_G_CPU0_SA_DQ<8> @T6G_MB_LIB.T6G(SCH_1):M_G_CPU0_SA_DQ(8)   I167 @T6G_MB_LIB.T6G(SCH_1):PAGE16
   BA2 M_G_CPU0_SA_CA<4> @T6G_MB_LIB.T6G(SCH_1):M_G_CPU0_SA_CA(4)   I167 @T6G_MB_LIB.T6G(SCH_1):PAGE16
   CE2 M_G_CPU0_SB_DQS_DN<0> @T6G_MB_LIB.T6G(SCH_1):M_G_CPU0_SB_DQS_DN(0)   I167 @T6G_MB_LIB.T6G(SCH_1):PAGE16
   CY2 M_G_CPU0_SB_DQ<24> @T6G_MB_LIB.T6G(SCH_1):M_G_CPU0_SB_DQ(24)   I167 @T6G_MB_LIB.T6G(SCH_1):PAGE16
   CN3 M_G_CPU0_SB_DQ<13> @T6G_MB_LIB.T6G(SCH_1):M_G_CPU0_SB_DQ(13)   I167 @T6G_MB_LIB.T6G(SCH_1):PAGE16
   CJ3 M_G_CPU0_SB_DQ<9> @T6G_MB_LIB.T6G(SCH_1):M_G_CPU0_SB_DQ(9)   I167 @T6G_MB_LIB.T6G(SCH_1):PAGE16
   BT2 M_G_CPU0_SB_CB<4> @T6G_MB_LIB.T6G(SCH_1):M_G_CPU0_SB_CB(4)   I167 @T6G_MB_LIB.T6G(SCH_1):PAGE16
   BJ3 M_G_CPU0_SB_CA<4> @T6G_MB_LIB.T6G(SCH_1):M_G_CPU0_SB_CA(4)   I167 @T6G_MB_LIB.T6G(SCH_1):PAGE16
    P4 M_G_CPU0_SA_DQS_DN<6> @T6G_MB_LIB.T6G(SCH_1):M_G_CPU0_SA_DQS_DN(6)   I167 @T6G_MB_LIB.T6G(SCH_1):PAGE16
    W2 M_G_CPU0_SA_DQS_DP<2> @T6G_MB_LIB.T6G(SCH_1):M_G_CPU0_SA_DQS_DP(2)   I167 @T6G_MB_LIB.T6G(SCH_1):PAGE16
    W3 M_G_CPU0_SA_DQ<19> @T6G_MB_LIB.T6G(SCH_1):M_G_CPU0_SA_DQ(19)   I167 @T6G_MB_LIB.T6G(SCH_1):PAGE16
    M4 M_G_CPU0_SA_DQ<9> @T6G_MB_LIB.T6G(SCH_1):M_G_CPU0_SA_DQ(9)   I167 @T6G_MB_LIB.T6G(SCH_1):PAGE16
   BB2 M_G_CPU0_SA_CA<5> @T6G_MB_LIB.T6G(SCH_1):M_G_CPU0_SA_CA(5)   I167 @T6G_MB_LIB.T6G(SCH_1):PAGE16
   CL2 M_G_CPU0_SB_DQS_DN<1> @T6G_MB_LIB.T6G(SCH_1):M_G_CPU0_SB_DQS_DN(1)   I167 @T6G_MB_LIB.T6G(SCH_1):PAGE16
   DA3 M_G_CPU0_SB_DQ<25> @T6G_MB_LIB.T6G(SCH_1):M_G_CPU0_SB_DQ(25)   I167 @T6G_MB_LIB.T6G(SCH_1):PAGE16
   CN2 M_G_CPU0_SB_DQ<14> @T6G_MB_LIB.T6G(SCH_1):M_G_CPU0_SB_DQ(14)   I167 @T6G_MB_LIB.T6G(SCH_1):PAGE16
   BU3 M_G_CPU0_SB_CB<5> @T6G_MB_LIB.T6G(SCH_1):M_G_CPU0_SB_CB(5)   I167 @T6G_MB_LIB.T6G(SCH_1):PAGE16
   BK4 M_G_CPU0_SB_CA<5> @T6G_MB_LIB.T6G(SCH_1):M_G_CPU0_SB_CA(5)   I167 @T6G_MB_LIB.T6G(SCH_1):PAGE16
    Y4 M_G_CPU0_SA_DQS_DN<7> @T6G_MB_LIB.T6G(SCH_1):M_G_CPU0_SA_DQS_DN(7)   I167 @T6G_MB_LIB.T6G(SCH_1):PAGE16
   AE2 M_G_CPU0_SA_DQS_DP<3> @T6G_MB_LIB.T6G(SCH_1):M_G_CPU0_SA_DQS_DP(3)   I167 @T6G_MB_LIB.T6G(SCH_1):PAGE16
   BB4 M_G_CPU0_SA_CA<6> @T6G_MB_LIB.T6G(SCH_1):M_G_CPU0_SA_CA(6)   I167 @T6G_MB_LIB.T6G(SCH_1):PAGE16
   CU2 M_G_CPU0_SB_DQS_DN<2> @T6G_MB_LIB.T6G(SCH_1):M_G_CPU0_SB_DQS_DN(2)   I167 @T6G_MB_LIB.T6G(SCH_1):PAGE16
   DA2 M_G_CPU0_SB_DQ<26> @T6G_MB_LIB.T6G(SCH_1):M_G_CPU0_SB_DQ(26)   I167 @T6G_MB_LIB.T6G(SCH_1):PAGE16
   CP4 M_G_CPU0_SB_DQ<15> @T6G_MB_LIB.T6G(SCH_1):M_G_CPU0_SB_DQ(15)   I167 @T6G_MB_LIB.T6G(SCH_1):PAGE16
   BU2 M_G_CPU0_SB_CB<6> @T6G_MB_LIB.T6G(SCH_1):M_G_CPU0_SB_CB(6)   I167 @T6G_MB_LIB.T6G(SCH_1):PAGE16
   BK2 M_G_CPU0_SB_CA<6> @T6G_MB_LIB.T6G(SCH_1):M_G_CPU0_SB_CA(6)   I167 @T6G_MB_LIB.T6G(SCH_1):PAGE16
   AF4 M_G_CPU0_SA_DQS_DN<8> @T6G_MB_LIB.T6G(SCH_1):M_G_CPU0_SA_DQS_DN(8)   I167 @T6G_MB_LIB.T6G(SCH_1):PAGE16
   AL2 M_G_CPU0_SA_DQS_DP<4> @T6G_MB_LIB.T6G(SCH_1):M_G_CPU0_SA_DQS_DP(4)   I167 @T6G_MB_LIB.T6G(SCH_1):PAGE16
   DC2 M_G_CPU0_SB_DQS_DN<3> @T6G_MB_LIB.T6G(SCH_1):M_G_CPU0_SB_DQS_DN(3)   I167 @T6G_MB_LIB.T6G(SCH_1):PAGE16
   DB4 M_G_CPU0_SB_DQ<27> @T6G_MB_LIB.T6G(SCH_1):M_G_CPU0_SB_DQ(27)   I167 @T6G_MB_LIB.T6G(SCH_1):PAGE16
   CP2 M_G_CPU0_SB_DQ<16> @T6G_MB_LIB.T6G(SCH_1):M_G_CPU0_SB_DQ(16)   I167 @T6G_MB_LIB.T6G(SCH_1):PAGE16
   BV4 M_G_CPU0_SB_CB<7> @T6G_MB_LIB.T6G(SCH_1):M_G_CPU0_SB_CB(7)   I167 @T6G_MB_LIB.T6G(SCH_1):PAGE16
   BR2     NC     NC   I167 @T6G_MB_LIB.T6G(SCH_1):PAGE16
   BP2 M_G_CPU0_SB_RSP<0> @T6G_MB_LIB.T6G(SCH_1):M_G_CPU0_SB_RSP(0)   I167 @T6G_MB_LIB.T6G(SCH_1):PAGE16
   AM4 M_G_CPU0_SA_DQS_DN<9> @T6G_MB_LIB.T6G(SCH_1):M_G_CPU0_SA_DQS_DN(9)   I167 @T6G_MB_LIB.T6G(SCH_1):PAGE16
    J3 M_G_CPU0_SA_DQS_DP<5> @T6G_MB_LIB.T6G(SCH_1):M_G_CPU0_SA_DQS_DP(5)   I167 @T6G_MB_LIB.T6G(SCH_1):PAGE16
   BW3 M_G_CPU0_SB_DQS_DN<4> @T6G_MB_LIB.T6G(SCH_1):M_G_CPU0_SB_DQS_DN(4)   I167 @T6G_MB_LIB.T6G(SCH_1):PAGE16
   CD2 M_G_CPU0_SB_DQS_DP<0> @T6G_MB_LIB.T6G(SCH_1):M_G_CPU0_SB_DQS_DP(0)   I167 @T6G_MB_LIB.T6G(SCH_1):PAGE16
   DD2 M_G_CPU0_SB_DQ<28> @T6G_MB_LIB.T6G(SCH_1):M_G_CPU0_SB_DQ(28)   I167 @T6G_MB_LIB.T6G(SCH_1):PAGE16
   CR3 M_G_CPU0_SB_DQ<17> @T6G_MB_LIB.T6G(SCH_1):M_G_CPU0_SB_DQ(17)   I167 @T6G_MB_LIB.T6G(SCH_1):PAGE16
    R3 M_G_CPU0_SA_DQS_DP<6> @T6G_MB_LIB.T6G(SCH_1):M_G_CPU0_SA_DQS_DP(6)   I167 @T6G_MB_LIB.T6G(SCH_1):PAGE16
   CE3 M_G_CPU0_SB_DQS_DN<5> @T6G_MB_LIB.T6G(SCH_1):M_G_CPU0_SB_DQS_DN(5)   I167 @T6G_MB_LIB.T6G(SCH_1):PAGE16
   CK2 M_G_CPU0_SB_DQS_DP<1> @T6G_MB_LIB.T6G(SCH_1):M_G_CPU0_SB_DQS_DP(1)   I167 @T6G_MB_LIB.T6G(SCH_1):PAGE16
   DE3 M_G_CPU0_SB_DQ<29> @T6G_MB_LIB.T6G(SCH_1):M_G_CPU0_SB_DQ(29)   I167 @T6G_MB_LIB.T6G(SCH_1):PAGE16
   CR2 M_G_CPU0_SB_DQ<18> @T6G_MB_LIB.T6G(SCH_1):M_G_CPU0_SB_DQ(18)   I167 @T6G_MB_LIB.T6G(SCH_1):PAGE16
   AA3 M_G_CPU0_SA_DQS_DP<7> @T6G_MB_LIB.T6G(SCH_1):M_G_CPU0_SA_DQS_DP(7)   I167 @T6G_MB_LIB.T6G(SCH_1):PAGE16
   AV2     NC     NC   I167 @T6G_MB_LIB.T6G(SCH_1):PAGE16
   AU2 M_G_CPU0_SA_CS_N<0> @T6G_MB_LIB.T6G(SCH_1):M_G_CPU0_SA_CS_N(0)   I167 @T6G_MB_LIB.T6G(SCH_1):PAGE16
   CL3 M_G_CPU0_SB_DQS_DN<6> @T6G_MB_LIB.T6G(SCH_1):M_G_CPU0_SB_DQS_DN(6)   I167 @T6G_MB_LIB.T6G(SCH_1):PAGE16
   CT2 M_G_CPU0_SB_DQS_DP<2> @T6G_MB_LIB.T6G(SCH_1):M_G_CPU0_SB_DQS_DP(2)   I167 @T6G_MB_LIB.T6G(SCH_1):PAGE16
   CT4 M_G_CPU0_SB_DQ<19> @T6G_MB_LIB.T6G(SCH_1):M_G_CPU0_SB_DQ(19)   I167 @T6G_MB_LIB.T6G(SCH_1):PAGE16
   AG3 M_G_CPU0_SA_DQS_DP<8> @T6G_MB_LIB.T6G(SCH_1):M_G_CPU0_SA_DQS_DP(8)   I167 @T6G_MB_LIB.T6G(SCH_1):PAGE16
   AH2 M_G_CPU0_SA_DQ<30> @T6G_MB_LIB.T6G(SCH_1):M_G_CPU0_SA_DQ(30)   I167 @T6G_MB_LIB.T6G(SCH_1):PAGE16
   AW3     NC     NC   I167 @T6G_MB_LIB.T6G(SCH_1):PAGE16
   AV4 M_G_CPU0_SA_CS_N<1> @T6G_MB_LIB.T6G(SCH_1):M_G_CPU0_SA_CS_N(1)   I167 @T6G_MB_LIB.T6G(SCH_1):PAGE16
   CU3 M_G_CPU0_SB_DQS_DN<7> @T6G_MB_LIB.T6G(SCH_1):M_G_CPU0_SB_DQS_DN(7)   I167 @T6G_MB_LIB.T6G(SCH_1):PAGE16
   DB2 M_G_CPU0_SB_DQS_DP<3> @T6G_MB_LIB.T6G(SCH_1):M_G_CPU0_SB_DQS_DP(3)   I167 @T6G_MB_LIB.T6G(SCH_1):PAGE16
   AN3 M_G_CPU0_SA_DQS_DP<9> @T6G_MB_LIB.T6G(SCH_1):M_G_CPU0_SA_DQS_DP(9)   I167 @T6G_MB_LIB.T6G(SCH_1):PAGE16
   AJ3 M_G_CPU0_SA_DQ<31> @T6G_MB_LIB.T6G(SCH_1):M_G_CPU0_SA_DQ(31)   I167 @T6G_MB_LIB.T6G(SCH_1):PAGE16
   AA2 M_G_CPU0_SA_DQ<20> @T6G_MB_LIB.T6G(SCH_1):M_G_CPU0_SA_DQ(20)   I167 @T6G_MB_LIB.T6G(SCH_1):PAGE16
   AJ2 M_G_CPU0_SA_CB<0> @T6G_MB_LIB.T6G(SCH_1):M_G_CPU0_SA_CB(0)   I167 @T6G_MB_LIB.T6G(SCH_1):PAGE16
   DC3 M_G_CPU0_SB_DQS_DN<8> @T6G_MB_LIB.T6G(SCH_1):M_G_CPU0_SB_DQS_DN(8)   I167 @T6G_MB_LIB.T6G(SCH_1):PAGE16
   BY4 M_G_CPU0_SB_DQS_DP<4> @T6G_MB_LIB.T6G(SCH_1):M_G_CPU0_SB_DQS_DP(4)   I167 @T6G_MB_LIB.T6G(SCH_1):PAGE16
   CB2 M_G_CPU0_SB_DQ<0> @T6G_MB_LIB.T6G(SCH_1):M_G_CPU0_SB_DQ(0)   I167 @T6G_MB_LIB.T6G(SCH_1):PAGE16
   AB4 M_G_CPU0_SA_DQ<21> @T6G_MB_LIB.T6G(SCH_1):M_G_CPU0_SA_DQ(21)   I167 @T6G_MB_LIB.T6G(SCH_1):PAGE16
    M2 M_G_CPU0_SA_DQ<10> @T6G_MB_LIB.T6G(SCH_1):M_G_CPU0_SA_DQ(10)   I167 @T6G_MB_LIB.T6G(SCH_1):PAGE16
    E2 M_G_CPU0_SA_DQ<0> @T6G_MB_LIB.T6G(SCH_1):M_G_CPU0_SA_DQ(0)   I167 @T6G_MB_LIB.T6G(SCH_1):PAGE16
   AK4 M_G_CPU0_SA_CB<1> @T6G_MB_LIB.T6G(SCH_1):M_G_CPU0_SA_CB(1)   I167 @T6G_MB_LIB.T6G(SCH_1):PAGE16
   BL3 M_G_CPU0_SB_PAR @T6G_MB_LIB.T6G(SCH_1):M_G_CPU0_SB_PAR   I167 @T6G_MB_LIB.T6G(SCH_1):PAGE16
   BV2 M_G_CPU0_SB_DQS_DP<9> @T6G_MB_LIB.T6G(SCH_1):M_G_CPU0_SB_DQS_DP(9)   I167 @T6G_MB_LIB.T6G(SCH_1):PAGE16
   BC3 M_G_CPU0_SA_PAR @T6G_MB_LIB.T6G(SCH_1):M_G_CPU0_SA_PAR   I167 @T6G_MB_LIB.T6G(SCH_1):PAGE16
   BC2 M_G_CPU0_CLK_DP<0> @T6G_MB_LIB.T6G(SCH_1):M_G_CPU0_CLK_DP(0)   I167 @T6G_MB_LIB.T6G(SCH_1):PAGE16
   BD2 M_G_CPU0_CLK_DN<0> @T6G_MB_LIB.T6G(SCH_1):M_G_CPU0_CLK_DN(0)   I167 @T6G_MB_LIB.T6G(SCH_1):PAGE16
   BF2     NC     NC   I167 @T6G_MB_LIB.T6G(SCH_1):PAGE16
   BG2     NC     NC   I167 @T6G_MB_LIB.T6G(SCH_1):PAGE16
   BF4 TP_M_G_CPU0_SA_TEST39G @T6G_MB_LIB.T6G(SCH_1):TP_M_G_CPU0_SA_TEST39G   I167 @T6G_MB_LIB.T6G(SCH_1):PAGE16
  AT14 M_H_CPU0_ALERT_R_N @T6G_MB_LIB.T6G(SCH_1):M_H_CPU0_ALERT_R_N   I159 @T6G_MB_LIB.T6G(SCH_1):PAGE17
  AU14 M_H_CPU0_RESET_N @T6G_MB_LIB.T6G(SCH_1):M_H_CPU0_RESET_N   I159 @T6G_MB_LIB.T6G(SCH_1):PAGE17
  DF14 M_H_CPU0_SB_DQ<31> @T6G_MB_LIB.T6G(SCH_1):M_H_CPU0_SB_DQ(31)   I159 @T6G_MB_LIB.T6G(SCH_1):PAGE17
  CV13 M_H_CPU0_SB_DQ<20> @T6G_MB_LIB.T6G(SCH_1):M_H_CPU0_SB_DQ(20)   I159 @T6G_MB_LIB.T6G(SCH_1):PAGE17
  BY13 M_H_CPU0_SB_CB<0> @T6G_MB_LIB.T6G(SCH_1):M_H_CPU0_SB_CB(0)   I159 @T6G_MB_LIB.T6G(SCH_1):PAGE17
  BM13     NC     NC   I159 @T6G_MB_LIB.T6G(SCH_1):PAGE17
   Y13 M_H_CPU0_SA_DQS_DN<2> @T6G_MB_LIB.T6G(SCH_1):M_H_CPU0_SA_DQS_DN(2)   I159 @T6G_MB_LIB.T6G(SCH_1):PAGE17
  AD13 M_H_CPU0_SA_DQ<26> @T6G_MB_LIB.T6G(SCH_1):M_H_CPU0_SA_DQ(26)   I159 @T6G_MB_LIB.T6G(SCH_1):PAGE17
   U14 M_H_CPU0_SA_DQ<15> @T6G_MB_LIB.T6G(SCH_1):M_H_CPU0_SA_DQ(15)   I159 @T6G_MB_LIB.T6G(SCH_1):PAGE17
  AP13 M_H_CPU0_SA_CB<6> @T6G_MB_LIB.T6G(SCH_1):M_H_CPU0_SA_CB(6)   I159 @T6G_MB_LIB.T6G(SCH_1):PAGE17
  CW14 M_H_CPU0_SB_DQ<21> @T6G_MB_LIB.T6G(SCH_1):M_H_CPU0_SB_DQ(21)   I159 @T6G_MB_LIB.T6G(SCH_1):PAGE17
  CJ12 M_H_CPU0_SB_DQ<10> @T6G_MB_LIB.T6G(SCH_1):M_H_CPU0_SB_DQ(10)   I159 @T6G_MB_LIB.T6G(SCH_1):PAGE17
  CA14 M_H_CPU0_SB_CB<1> @T6G_MB_LIB.T6G(SCH_1):M_H_CPU0_SB_CB(1)   I159 @T6G_MB_LIB.T6G(SCH_1):PAGE17
  AF13 M_H_CPU0_SA_DQS_DN<3> @T6G_MB_LIB.T6G(SCH_1):M_H_CPU0_SA_DQS_DN(3)   I159 @T6G_MB_LIB.T6G(SCH_1):PAGE17
  AE14 M_H_CPU0_SA_DQ<27> @T6G_MB_LIB.T6G(SCH_1):M_H_CPU0_SA_DQ(27)   I159 @T6G_MB_LIB.T6G(SCH_1):PAGE17
   U12 M_H_CPU0_SA_DQ<16> @T6G_MB_LIB.T6G(SCH_1):M_H_CPU0_SA_DQ(16)   I159 @T6G_MB_LIB.T6G(SCH_1):PAGE17
  AR14 M_H_CPU0_SA_CB<7> @T6G_MB_LIB.T6G(SCH_1):M_H_CPU0_SA_CB(7)   I159 @T6G_MB_LIB.T6G(SCH_1):PAGE17
  BN14 M_H_CPU0_SA_RSP<0> @T6G_MB_LIB.T6G(SCH_1):M_H_CPU0_SA_RSP(0)   I159 @T6G_MB_LIB.T6G(SCH_1):PAGE17
  CW12 M_H_CPU0_SB_DQ<22> @T6G_MB_LIB.T6G(SCH_1):M_H_CPU0_SB_DQ(22)   I159 @T6G_MB_LIB.T6G(SCH_1):PAGE17
  CK14 M_H_CPU0_SB_DQ<11> @T6G_MB_LIB.T6G(SCH_1):M_H_CPU0_SB_DQ(11)   I159 @T6G_MB_LIB.T6G(SCH_1):PAGE17
  CA12 M_H_CPU0_SB_CB<2> @T6G_MB_LIB.T6G(SCH_1):M_H_CPU0_SB_CB(2)   I159 @T6G_MB_LIB.T6G(SCH_1):PAGE17
  AM13 M_H_CPU0_SA_DQS_DN<4> @T6G_MB_LIB.T6G(SCH_1):M_H_CPU0_SA_DQS_DN(4)   I159 @T6G_MB_LIB.T6G(SCH_1):PAGE17
   G12 M_H_CPU0_SA_DQS_DP<0> @T6G_MB_LIB.T6G(SCH_1):M_H_CPU0_SA_DQS_DP(0)   I159 @T6G_MB_LIB.T6G(SCH_1):PAGE17
  AG12 M_H_CPU0_SA_DQ<28> @T6G_MB_LIB.T6G(SCH_1):M_H_CPU0_SA_DQ(28)   I159 @T6G_MB_LIB.T6G(SCH_1):PAGE17
   V14 M_H_CPU0_SA_DQ<17> @T6G_MB_LIB.T6G(SCH_1):M_H_CPU0_SA_DQ(17)   I159 @T6G_MB_LIB.T6G(SCH_1):PAGE17
  AW12 M_H_CPU0_SA_CA<0> @T6G_MB_LIB.T6G(SCH_1):M_H_CPU0_SA_CA(0)   I159 @T6G_MB_LIB.T6G(SCH_1):PAGE17
  BP14     NC     NC   I159 @T6G_MB_LIB.T6G(SCH_1):PAGE17
  CY14 M_H_CPU0_SB_DQ<23> @T6G_MB_LIB.T6G(SCH_1):M_H_CPU0_SB_DQ(23)   I159 @T6G_MB_LIB.T6G(SCH_1):PAGE17
  CM13 M_H_CPU0_SB_DQ<12> @T6G_MB_LIB.T6G(SCH_1):M_H_CPU0_SB_DQ(12)   I159 @T6G_MB_LIB.T6G(SCH_1):PAGE17
  CB14 M_H_CPU0_SB_CB<3> @T6G_MB_LIB.T6G(SCH_1):M_H_CPU0_SB_CB(3)   I159 @T6G_MB_LIB.T6G(SCH_1):PAGE17
  BG14 M_H_CPU0_SB_CA<0> @T6G_MB_LIB.T6G(SCH_1):M_H_CPU0_SB_CA(0)   I159 @T6G_MB_LIB.T6G(SCH_1):PAGE17
   H14 M_H_CPU0_SA_DQS_DN<5> @T6G_MB_LIB.T6G(SCH_1):M_H_CPU0_SA_DQS_DN(5)   I159 @T6G_MB_LIB.T6G(SCH_1):PAGE17
   N12 M_H_CPU0_SA_DQS_DP<1> @T6G_MB_LIB.T6G(SCH_1):M_H_CPU0_SA_DQS_DP(1)   I159 @T6G_MB_LIB.T6G(SCH_1):PAGE17
  AH14 M_H_CPU0_SA_DQ<29> @T6G_MB_LIB.T6G(SCH_1):M_H_CPU0_SA_DQ(29)   I159 @T6G_MB_LIB.T6G(SCH_1):PAGE17
   V13 M_H_CPU0_SA_DQ<18> @T6G_MB_LIB.T6G(SCH_1):M_H_CPU0_SA_DQ(18)   I159 @T6G_MB_LIB.T6G(SCH_1):PAGE17
  AY13 M_H_CPU0_SA_CA<1> @T6G_MB_LIB.T6G(SCH_1):M_H_CPU0_SA_CA(1)   I159 @T6G_MB_LIB.T6G(SCH_1):PAGE17
  CE12 M_H_CPU0_SB_DQS_DN<0> @T6G_MB_LIB.T6G(SCH_1):M_H_CPU0_SB_DQS_DN(0)   I159 @T6G_MB_LIB.T6G(SCH_1):PAGE17
  CY13 M_H_CPU0_SB_DQ<24> @T6G_MB_LIB.T6G(SCH_1):M_H_CPU0_SB_DQ(24)   I159 @T6G_MB_LIB.T6G(SCH_1):PAGE17
  CN14 M_H_CPU0_SB_DQ<13> @T6G_MB_LIB.T6G(SCH_1):M_H_CPU0_SB_DQ(13)   I159 @T6G_MB_LIB.T6G(SCH_1):PAGE17
  BT13 M_H_CPU0_SB_CB<4> @T6G_MB_LIB.T6G(SCH_1):M_H_CPU0_SB_CB(4)   I159 @T6G_MB_LIB.T6G(SCH_1):PAGE17
  BH14 M_H_CPU0_SB_CA<1> @T6G_MB_LIB.T6G(SCH_1):M_H_CPU0_SB_CA(1)   I159 @T6G_MB_LIB.T6G(SCH_1):PAGE17
   P14 M_H_CPU0_SA_DQS_DN<6> @T6G_MB_LIB.T6G(SCH_1):M_H_CPU0_SA_DQS_DN(6)   I159 @T6G_MB_LIB.T6G(SCH_1):PAGE17
   W12 M_H_CPU0_SA_DQS_DP<2> @T6G_MB_LIB.T6G(SCH_1):M_H_CPU0_SA_DQS_DP(2)   I159 @T6G_MB_LIB.T6G(SCH_1):PAGE17
   W14 M_H_CPU0_SA_DQ<19> @T6G_MB_LIB.T6G(SCH_1):M_H_CPU0_SA_DQ(19)   I159 @T6G_MB_LIB.T6G(SCH_1):PAGE17
  AY14 M_H_CPU0_SA_CA<2> @T6G_MB_LIB.T6G(SCH_1):M_H_CPU0_SA_CA(2)   I159 @T6G_MB_LIB.T6G(SCH_1):PAGE17
  CL12 M_H_CPU0_SB_DQS_DN<1> @T6G_MB_LIB.T6G(SCH_1):M_H_CPU0_SB_DQS_DN(1)   I159 @T6G_MB_LIB.T6G(SCH_1):PAGE17
  DA14 M_H_CPU0_SB_DQ<25> @T6G_MB_LIB.T6G(SCH_1):M_H_CPU0_SB_DQ(25)   I159 @T6G_MB_LIB.T6G(SCH_1):PAGE17
  CN12 M_H_CPU0_SB_DQ<14> @T6G_MB_LIB.T6G(SCH_1):M_H_CPU0_SB_DQ(14)   I159 @T6G_MB_LIB.T6G(SCH_1):PAGE17
  CB13 M_H_CPU0_SB_DQ<0> @T6G_MB_LIB.T6G(SCH_1):M_H_CPU0_SB_DQ(0)   I159 @T6G_MB_LIB.T6G(SCH_1):PAGE17
  BU14 M_H_CPU0_SB_CB<5> @T6G_MB_LIB.T6G(SCH_1):M_H_CPU0_SB_CB(5)   I159 @T6G_MB_LIB.T6G(SCH_1):PAGE17
  BH13 M_H_CPU0_SB_CA<2> @T6G_MB_LIB.T6G(SCH_1):M_H_CPU0_SB_CA(2)   I159 @T6G_MB_LIB.T6G(SCH_1):PAGE17
   Y14 M_H_CPU0_SA_DQS_DN<7> @T6G_MB_LIB.T6G(SCH_1):M_H_CPU0_SA_DQS_DN(7)   I159 @T6G_MB_LIB.T6G(SCH_1):PAGE17
  AE12 M_H_CPU0_SA_DQS_DP<3> @T6G_MB_LIB.T6G(SCH_1):M_H_CPU0_SA_DQS_DP(3)   I159 @T6G_MB_LIB.T6G(SCH_1):PAGE17
   E12 M_H_CPU0_SA_DQ<0> @T6G_MB_LIB.T6G(SCH_1):M_H_CPU0_SA_DQ(0)   I159 @T6G_MB_LIB.T6G(SCH_1):PAGE17
  BA14 M_H_CPU0_SA_CA<3> @T6G_MB_LIB.T6G(SCH_1):M_H_CPU0_SA_CA(3)   I159 @T6G_MB_LIB.T6G(SCH_1):PAGE17
  CU12 M_H_CPU0_SB_DQS_DN<2> @T6G_MB_LIB.T6G(SCH_1):M_H_CPU0_SB_DQS_DN(2)   I159 @T6G_MB_LIB.T6G(SCH_1):PAGE17
  DA12 M_H_CPU0_SB_DQ<26> @T6G_MB_LIB.T6G(SCH_1):M_H_CPU0_SB_DQ(26)   I159 @T6G_MB_LIB.T6G(SCH_1):PAGE17
  CP14 M_H_CPU0_SB_DQ<15> @T6G_MB_LIB.T6G(SCH_1):M_H_CPU0_SB_DQ(15)   I159 @T6G_MB_LIB.T6G(SCH_1):PAGE17
  CC14 M_H_CPU0_SB_DQ<1> @T6G_MB_LIB.T6G(SCH_1):M_H_CPU0_SB_DQ(1)   I159 @T6G_MB_LIB.T6G(SCH_1):PAGE17
  BU12 M_H_CPU0_SB_CB<6> @T6G_MB_LIB.T6G(SCH_1):M_H_CPU0_SB_CB(6)   I159 @T6G_MB_LIB.T6G(SCH_1):PAGE17
  BJ12 M_H_CPU0_SB_CA<3> @T6G_MB_LIB.T6G(SCH_1):M_H_CPU0_SB_CA(3)   I159 @T6G_MB_LIB.T6G(SCH_1):PAGE17
  AF14 M_H_CPU0_SA_DQS_DN<8> @T6G_MB_LIB.T6G(SCH_1):M_H_CPU0_SA_DQS_DN(8)   I159 @T6G_MB_LIB.T6G(SCH_1):PAGE17
  AL12 M_H_CPU0_SA_DQS_DP<4> @T6G_MB_LIB.T6G(SCH_1):M_H_CPU0_SA_DQS_DP(4)   I159 @T6G_MB_LIB.T6G(SCH_1):PAGE17
   F14 M_H_CPU0_SA_DQ<1> @T6G_MB_LIB.T6G(SCH_1):M_H_CPU0_SA_DQ(1)   I159 @T6G_MB_LIB.T6G(SCH_1):PAGE17
  BA12 M_H_CPU0_SA_CA<4> @T6G_MB_LIB.T6G(SCH_1):M_H_CPU0_SA_CA(4)   I159 @T6G_MB_LIB.T6G(SCH_1):PAGE17
  DC12 M_H_CPU0_SB_DQS_DN<3> @T6G_MB_LIB.T6G(SCH_1):M_H_CPU0_SB_DQS_DN(3)   I159 @T6G_MB_LIB.T6G(SCH_1):PAGE17
  DB14 M_H_CPU0_SB_DQ<27> @T6G_MB_LIB.T6G(SCH_1):M_H_CPU0_SB_DQ(27)   I159 @T6G_MB_LIB.T6G(SCH_1):PAGE17
  CP13 M_H_CPU0_SB_DQ<16> @T6G_MB_LIB.T6G(SCH_1):M_H_CPU0_SB_DQ(16)   I159 @T6G_MB_LIB.T6G(SCH_1):PAGE17
  CC12 M_H_CPU0_SB_DQ<2> @T6G_MB_LIB.T6G(SCH_1):M_H_CPU0_SB_DQ(2)   I159 @T6G_MB_LIB.T6G(SCH_1):PAGE17
  BV14 M_H_CPU0_SB_CB<7> @T6G_MB_LIB.T6G(SCH_1):M_H_CPU0_SB_CB(7)   I159 @T6G_MB_LIB.T6G(SCH_1):PAGE17
  BJ14 M_H_CPU0_SB_CA<4> @T6G_MB_LIB.T6G(SCH_1):M_H_CPU0_SB_CA(4)   I159 @T6G_MB_LIB.T6G(SCH_1):PAGE17
  BP13 M_H_CPU0_SB_RSP<0> @T6G_MB_LIB.T6G(SCH_1):M_H_CPU0_SB_RSP(0)   I159 @T6G_MB_LIB.T6G(SCH_1):PAGE17
  AM14 M_H_CPU0_SA_DQS_DN<9> @T6G_MB_LIB.T6G(SCH_1):M_H_CPU0_SA_DQS_DN(9)   I159 @T6G_MB_LIB.T6G(SCH_1):PAGE17
   J14 M_H_CPU0_SA_DQS_DP<5> @T6G_MB_LIB.T6G(SCH_1):M_H_CPU0_SA_DQS_DP(5)   I159 @T6G_MB_LIB.T6G(SCH_1):PAGE17
   F13 M_H_CPU0_SA_DQ<2> @T6G_MB_LIB.T6G(SCH_1):M_H_CPU0_SA_DQ(2)   I159 @T6G_MB_LIB.T6G(SCH_1):PAGE17
  BB13 M_H_CPU0_SA_CA<5> @T6G_MB_LIB.T6G(SCH_1):M_H_CPU0_SA_CA(5)   I159 @T6G_MB_LIB.T6G(SCH_1):PAGE17
  BW14 M_H_CPU0_SB_DQS_DN<4> @T6G_MB_LIB.T6G(SCH_1):M_H_CPU0_SB_DQS_DN(4)   I159 @T6G_MB_LIB.T6G(SCH_1):PAGE17
  CD13 M_H_CPU0_SB_DQS_DP<0> @T6G_MB_LIB.T6G(SCH_1):M_H_CPU0_SB_DQS_DP(0)   I159 @T6G_MB_LIB.T6G(SCH_1):PAGE17
  DD13 M_H_CPU0_SB_DQ<28> @T6G_MB_LIB.T6G(SCH_1):M_H_CPU0_SB_DQ(28)   I159 @T6G_MB_LIB.T6G(SCH_1):PAGE17
  CR14 M_H_CPU0_SB_DQ<17> @T6G_MB_LIB.T6G(SCH_1):M_H_CPU0_SB_DQ(17)   I159 @T6G_MB_LIB.T6G(SCH_1):PAGE17
  CD14 M_H_CPU0_SB_DQ<3> @T6G_MB_LIB.T6G(SCH_1):M_H_CPU0_SB_DQ(3)   I159 @T6G_MB_LIB.T6G(SCH_1):PAGE17
  BK14 M_H_CPU0_SB_CA<5> @T6G_MB_LIB.T6G(SCH_1):M_H_CPU0_SB_CA(5)   I159 @T6G_MB_LIB.T6G(SCH_1):PAGE17
  BR12     NC     NC   I159 @T6G_MB_LIB.T6G(SCH_1):PAGE17
   R14 M_H_CPU0_SA_DQS_DP<6> @T6G_MB_LIB.T6G(SCH_1):M_H_CPU0_SA_DQS_DP(6)   I159 @T6G_MB_LIB.T6G(SCH_1):PAGE17
   G14 M_H_CPU0_SA_DQ<3> @T6G_MB_LIB.T6G(SCH_1):M_H_CPU0_SA_DQ(3)   I159 @T6G_MB_LIB.T6G(SCH_1):PAGE17
  BB14 M_H_CPU0_SA_CA<6> @T6G_MB_LIB.T6G(SCH_1):M_H_CPU0_SA_CA(6)   I159 @T6G_MB_LIB.T6G(SCH_1):PAGE17
  CE14 M_H_CPU0_SB_DQS_DN<5> @T6G_MB_LIB.T6G(SCH_1):M_H_CPU0_SB_DQS_DN(5)   I159 @T6G_MB_LIB.T6G(SCH_1):PAGE17
  CK13 M_H_CPU0_SB_DQS_DP<1> @T6G_MB_LIB.T6G(SCH_1):M_H_CPU0_SB_DQS_DP(1)   I159 @T6G_MB_LIB.T6G(SCH_1):PAGE17
  DE14 M_H_CPU0_SB_DQ<29> @T6G_MB_LIB.T6G(SCH_1):M_H_CPU0_SB_DQ(29)   I159 @T6G_MB_LIB.T6G(SCH_1):PAGE17
  CR12 M_H_CPU0_SB_DQ<18> @T6G_MB_LIB.T6G(SCH_1):M_H_CPU0_SB_DQ(18)   I159 @T6G_MB_LIB.T6G(SCH_1):PAGE17
  CF13 M_H_CPU0_SB_DQ<4> @T6G_MB_LIB.T6G(SCH_1):M_H_CPU0_SB_DQ(4)   I159 @T6G_MB_LIB.T6G(SCH_1):PAGE17
  BK13 M_H_CPU0_SB_CA<6> @T6G_MB_LIB.T6G(SCH_1):M_H_CPU0_SB_CA(6)   I159 @T6G_MB_LIB.T6G(SCH_1):PAGE17
  AA14 M_H_CPU0_SA_DQS_DP<7> @T6G_MB_LIB.T6G(SCH_1):M_H_CPU0_SA_DQS_DP(7)   I159 @T6G_MB_LIB.T6G(SCH_1):PAGE17
   J12 M_H_CPU0_SA_DQ<4> @T6G_MB_LIB.T6G(SCH_1):M_H_CPU0_SA_DQ(4)   I159 @T6G_MB_LIB.T6G(SCH_1):PAGE17
  AU12 M_H_CPU0_SA_CS_N<0> @T6G_MB_LIB.T6G(SCH_1):M_H_CPU0_SA_CS_N(0)   I159 @T6G_MB_LIB.T6G(SCH_1):PAGE17
  CL14 M_H_CPU0_SB_DQS_DN<6> @T6G_MB_LIB.T6G(SCH_1):M_H_CPU0_SB_DQS_DN(6)   I159 @T6G_MB_LIB.T6G(SCH_1):PAGE17
  CT13 M_H_CPU0_SB_DQS_DP<2> @T6G_MB_LIB.T6G(SCH_1):M_H_CPU0_SB_DQS_DP(2)   I159 @T6G_MB_LIB.T6G(SCH_1):PAGE17
  CT14 M_H_CPU0_SB_DQ<19> @T6G_MB_LIB.T6G(SCH_1):M_H_CPU0_SB_DQ(19)   I159 @T6G_MB_LIB.T6G(SCH_1):PAGE17
  CG14 M_H_CPU0_SB_DQ<5> @T6G_MB_LIB.T6G(SCH_1):M_H_CPU0_SB_DQ(5)   I159 @T6G_MB_LIB.T6G(SCH_1):PAGE17
  AG14 M_H_CPU0_SA_DQS_DP<8> @T6G_MB_LIB.T6G(SCH_1):M_H_CPU0_SA_DQS_DP(8)   I159 @T6G_MB_LIB.T6G(SCH_1):PAGE17
  AH13 M_H_CPU0_SA_DQ<30> @T6G_MB_LIB.T6G(SCH_1):M_H_CPU0_SA_DQ(30)   I159 @T6G_MB_LIB.T6G(SCH_1):PAGE17
   K14 M_H_CPU0_SA_DQ<5> @T6G_MB_LIB.T6G(SCH_1):M_H_CPU0_SA_DQ(5)   I159 @T6G_MB_LIB.T6G(SCH_1):PAGE17
  AV13     NC     NC   I159 @T6G_MB_LIB.T6G(SCH_1):PAGE17
  AV14 M_H_CPU0_SA_CS_N<1> @T6G_MB_LIB.T6G(SCH_1):M_H_CPU0_SA_CS_N(1)   I159 @T6G_MB_LIB.T6G(SCH_1):PAGE17
  CU14 M_H_CPU0_SB_DQS_DN<7> @T6G_MB_LIB.T6G(SCH_1):M_H_CPU0_SB_DQS_DN(7)   I159 @T6G_MB_LIB.T6G(SCH_1):PAGE17
  DB13 M_H_CPU0_SB_DQS_DP<3> @T6G_MB_LIB.T6G(SCH_1):M_H_CPU0_SB_DQS_DP(3)   I159 @T6G_MB_LIB.T6G(SCH_1):PAGE17
  CG12 M_H_CPU0_SB_DQ<6> @T6G_MB_LIB.T6G(SCH_1):M_H_CPU0_SB_DQ(6)   I159 @T6G_MB_LIB.T6G(SCH_1):PAGE17
  AN14 M_H_CPU0_SA_DQS_DP<9> @T6G_MB_LIB.T6G(SCH_1):M_H_CPU0_SA_DQS_DP(9)   I159 @T6G_MB_LIB.T6G(SCH_1):PAGE17
  AJ14 M_H_CPU0_SA_DQ<31> @T6G_MB_LIB.T6G(SCH_1):M_H_CPU0_SA_DQ(31)   I159 @T6G_MB_LIB.T6G(SCH_1):PAGE17
  AA12 M_H_CPU0_SA_DQ<20> @T6G_MB_LIB.T6G(SCH_1):M_H_CPU0_SA_DQ(20)   I159 @T6G_MB_LIB.T6G(SCH_1):PAGE17
   K13 M_H_CPU0_SA_DQ<6> @T6G_MB_LIB.T6G(SCH_1):M_H_CPU0_SA_DQ(6)   I159 @T6G_MB_LIB.T6G(SCH_1):PAGE17
  AJ12 M_H_CPU0_SA_CB<0> @T6G_MB_LIB.T6G(SCH_1):M_H_CPU0_SA_CB(0)   I159 @T6G_MB_LIB.T6G(SCH_1):PAGE17
  AW14     NC     NC   I159 @T6G_MB_LIB.T6G(SCH_1):PAGE17
  DC14 M_H_CPU0_SB_DQS_DN<8> @T6G_MB_LIB.T6G(SCH_1):M_H_CPU0_SB_DQS_DN(8)   I159 @T6G_MB_LIB.T6G(SCH_1):PAGE17
  BY14 M_H_CPU0_SB_DQS_DP<4> @T6G_MB_LIB.T6G(SCH_1):M_H_CPU0_SB_DQS_DP(4)   I159 @T6G_MB_LIB.T6G(SCH_1):PAGE17
  CH14 M_H_CPU0_SB_DQ<7> @T6G_MB_LIB.T6G(SCH_1):M_H_CPU0_SB_DQ(7)   I159 @T6G_MB_LIB.T6G(SCH_1):PAGE17
  AB14 M_H_CPU0_SA_DQ<21> @T6G_MB_LIB.T6G(SCH_1):M_H_CPU0_SA_DQ(21)   I159 @T6G_MB_LIB.T6G(SCH_1):PAGE17
   M13 M_H_CPU0_SA_DQ<10> @T6G_MB_LIB.T6G(SCH_1):M_H_CPU0_SA_DQ(10)   I159 @T6G_MB_LIB.T6G(SCH_1):PAGE17
   L14 M_H_CPU0_SA_DQ<7> @T6G_MB_LIB.T6G(SCH_1):M_H_CPU0_SA_DQ(7)   I159 @T6G_MB_LIB.T6G(SCH_1):PAGE17
  AK14 M_H_CPU0_SA_CB<1> @T6G_MB_LIB.T6G(SCH_1):M_H_CPU0_SA_CB(1)   I159 @T6G_MB_LIB.T6G(SCH_1):PAGE17
  BW12 M_H_CPU0_SB_DQS_DN<9> @T6G_MB_LIB.T6G(SCH_1):M_H_CPU0_SB_DQS_DN(9)   I159 @T6G_MB_LIB.T6G(SCH_1):PAGE17
  CF14 M_H_CPU0_SB_DQS_DP<5> @T6G_MB_LIB.T6G(SCH_1):M_H_CPU0_SB_DQS_DP(5)   I159 @T6G_MB_LIB.T6G(SCH_1):PAGE17
  CH13 M_H_CPU0_SB_DQ<8> @T6G_MB_LIB.T6G(SCH_1):M_H_CPU0_SB_DQ(8)   I159 @T6G_MB_LIB.T6G(SCH_1):PAGE17
  AB13 M_H_CPU0_SA_DQ<22> @T6G_MB_LIB.T6G(SCH_1):M_H_CPU0_SA_DQ(22)   I159 @T6G_MB_LIB.T6G(SCH_1):PAGE17
   N14 M_H_CPU0_SA_DQ<11> @T6G_MB_LIB.T6G(SCH_1):M_H_CPU0_SA_DQ(11)   I159 @T6G_MB_LIB.T6G(SCH_1):PAGE17
   L12 M_H_CPU0_SA_DQ<8> @T6G_MB_LIB.T6G(SCH_1):M_H_CPU0_SA_DQ(8)   I159 @T6G_MB_LIB.T6G(SCH_1):PAGE17
  AK13 M_H_CPU0_SA_CB<2> @T6G_MB_LIB.T6G(SCH_1):M_H_CPU0_SA_CB(2)   I159 @T6G_MB_LIB.T6G(SCH_1):PAGE17
  CM14 M_H_CPU0_SB_DQS_DP<6> @T6G_MB_LIB.T6G(SCH_1):M_H_CPU0_SB_DQS_DP(6)   I159 @T6G_MB_LIB.T6G(SCH_1):PAGE17
  CJ14 M_H_CPU0_SB_DQ<9> @T6G_MB_LIB.T6G(SCH_1):M_H_CPU0_SB_DQ(9)   I159 @T6G_MB_LIB.T6G(SCH_1):PAGE17
  AC14 M_H_CPU0_SA_DQ<23> @T6G_MB_LIB.T6G(SCH_1):M_H_CPU0_SA_DQ(23)   I159 @T6G_MB_LIB.T6G(SCH_1):PAGE17
   R12 M_H_CPU0_SA_DQ<12> @T6G_MB_LIB.T6G(SCH_1):M_H_CPU0_SA_DQ(12)   I159 @T6G_MB_LIB.T6G(SCH_1):PAGE17
   M14 M_H_CPU0_SA_DQ<9> @T6G_MB_LIB.T6G(SCH_1):M_H_CPU0_SA_DQ(9)   I159 @T6G_MB_LIB.T6G(SCH_1):PAGE17
  AL14 M_H_CPU0_SA_CB<3> @T6G_MB_LIB.T6G(SCH_1):M_H_CPU0_SA_CB(3)   I159 @T6G_MB_LIB.T6G(SCH_1):PAGE17
  CV14 M_H_CPU0_SB_DQS_DP<7> @T6G_MB_LIB.T6G(SCH_1):M_H_CPU0_SB_DQS_DP(7)   I159 @T6G_MB_LIB.T6G(SCH_1):PAGE17
  BM14 M_H_CPU0_SB_CS_N<0> @T6G_MB_LIB.T6G(SCH_1):M_H_CPU0_SB_CS_N(0)   I159 @T6G_MB_LIB.T6G(SCH_1):PAGE17
   H13 M_H_CPU0_SA_DQS_DN<0> @T6G_MB_LIB.T6G(SCH_1):M_H_CPU0_SA_DQS_DN(0)   I159 @T6G_MB_LIB.T6G(SCH_1):PAGE17
  AC12 M_H_CPU0_SA_DQ<24> @T6G_MB_LIB.T6G(SCH_1):M_H_CPU0_SA_DQ(24)   I159 @T6G_MB_LIB.T6G(SCH_1):PAGE17
   T14 M_H_CPU0_SA_DQ<13> @T6G_MB_LIB.T6G(SCH_1):M_H_CPU0_SA_DQ(13)   I159 @T6G_MB_LIB.T6G(SCH_1):PAGE17
  AN12 M_H_CPU0_SA_CB<4> @T6G_MB_LIB.T6G(SCH_1):M_H_CPU0_SA_CB(4)   I159 @T6G_MB_LIB.T6G(SCH_1):PAGE17
  DD14 M_H_CPU0_SB_DQS_DP<8> @T6G_MB_LIB.T6G(SCH_1):M_H_CPU0_SB_DQS_DP(8)   I159 @T6G_MB_LIB.T6G(SCH_1):PAGE17
  DE12 M_H_CPU0_SB_DQ<30> @T6G_MB_LIB.T6G(SCH_1):M_H_CPU0_SB_DQ(30)   I159 @T6G_MB_LIB.T6G(SCH_1):PAGE17
  BL12     NC     NC   I159 @T6G_MB_LIB.T6G(SCH_1):PAGE17
  BN12 M_H_CPU0_SB_CS_N<1> @T6G_MB_LIB.T6G(SCH_1):M_H_CPU0_SB_CS_N(1)   I159 @T6G_MB_LIB.T6G(SCH_1):PAGE17
   P13 M_H_CPU0_SA_DQS_DN<1> @T6G_MB_LIB.T6G(SCH_1):M_H_CPU0_SA_DQS_DN(1)   I159 @T6G_MB_LIB.T6G(SCH_1):PAGE17
  AD14 M_H_CPU0_SA_DQ<25> @T6G_MB_LIB.T6G(SCH_1):M_H_CPU0_SA_DQ(25)   I159 @T6G_MB_LIB.T6G(SCH_1):PAGE17
   T13 M_H_CPU0_SA_DQ<14> @T6G_MB_LIB.T6G(SCH_1):M_H_CPU0_SA_DQ(14)   I159 @T6G_MB_LIB.T6G(SCH_1):PAGE17
  AP14 M_H_CPU0_SA_CB<5> @T6G_MB_LIB.T6G(SCH_1):M_H_CPU0_SA_CB(5)   I159 @T6G_MB_LIB.T6G(SCH_1):PAGE17
  BV13 M_H_CPU0_SB_DQS_DP<9> @T6G_MB_LIB.T6G(SCH_1):M_H_CPU0_SB_DQS_DP(9)   I159 @T6G_MB_LIB.T6G(SCH_1):PAGE17
  BC14 M_H_CPU0_SA_PAR @T6G_MB_LIB.T6G(SCH_1):M_H_CPU0_SA_PAR   I159 @T6G_MB_LIB.T6G(SCH_1):PAGE17
  BL14 M_H_CPU0_SB_PAR @T6G_MB_LIB.T6G(SCH_1):M_H_CPU0_SB_PAR   I159 @T6G_MB_LIB.T6G(SCH_1):PAGE17
  BC12 M_H_CPU0_CLK_DP<0> @T6G_MB_LIB.T6G(SCH_1):M_H_CPU0_CLK_DP(0)   I159 @T6G_MB_LIB.T6G(SCH_1):PAGE17
  BD13 M_H_CPU0_CLK_DN<0> @T6G_MB_LIB.T6G(SCH_1):M_H_CPU0_CLK_DN(0)   I159 @T6G_MB_LIB.T6G(SCH_1):PAGE17
  BF13     NC     NC   I159 @T6G_MB_LIB.T6G(SCH_1):PAGE17
  BG12     NC     NC   I159 @T6G_MB_LIB.T6G(SCH_1):PAGE17
  BF14 TP_M_H_CPU0_SA_TEST39H @T6G_MB_LIB.T6G(SCH_1):TP_M_H_CPU0_SA_TEST39H   I159 @T6G_MB_LIB.T6G(SCH_1):PAGE17
  CY21 M_I_CPU0_SB_DQ<23> @T6G_MB_LIB.T6G(SCH_1):M_I_CPU0_SB_DQ(23)   I159 @T6G_MB_LIB.T6G(SCH_1):PAGE18
  CM20 M_I_CPU0_SB_DQ<12> @T6G_MB_LIB.T6G(SCH_1):M_I_CPU0_SB_DQ(12)   I159 @T6G_MB_LIB.T6G(SCH_1):PAGE18
  CG19 M_I_CPU0_SB_DQ<6> @T6G_MB_LIB.T6G(SCH_1):M_I_CPU0_SB_DQ(6)   I159 @T6G_MB_LIB.T6G(SCH_1):PAGE18
  CB21 M_I_CPU0_SB_CB<3> @T6G_MB_LIB.T6G(SCH_1):M_I_CPU0_SB_CB(3)   I159 @T6G_MB_LIB.T6G(SCH_1):PAGE18
   H21 M_I_CPU0_SA_DQS_DN<5> @T6G_MB_LIB.T6G(SCH_1):M_I_CPU0_SA_DQS_DN(5)   I159 @T6G_MB_LIB.T6G(SCH_1):PAGE18
   N19 M_I_CPU0_SA_DQS_DP<1> @T6G_MB_LIB.T6G(SCH_1):M_I_CPU0_SA_DQS_DP(1)   I159 @T6G_MB_LIB.T6G(SCH_1):PAGE18
  AH21 M_I_CPU0_SA_DQ<29> @T6G_MB_LIB.T6G(SCH_1):M_I_CPU0_SA_DQ(29)   I159 @T6G_MB_LIB.T6G(SCH_1):PAGE18
   V20 M_I_CPU0_SA_DQ<18> @T6G_MB_LIB.T6G(SCH_1):M_I_CPU0_SA_DQ(18)   I159 @T6G_MB_LIB.T6G(SCH_1):PAGE18
   K20 M_I_CPU0_SA_DQ<6> @T6G_MB_LIB.T6G(SCH_1):M_I_CPU0_SA_DQ(6)   I159 @T6G_MB_LIB.T6G(SCH_1):PAGE18
  CE19 M_I_CPU0_SB_DQS_DN<0> @T6G_MB_LIB.T6G(SCH_1):M_I_CPU0_SB_DQS_DN(0)   I159 @T6G_MB_LIB.T6G(SCH_1):PAGE18
  CY20 M_I_CPU0_SB_DQ<24> @T6G_MB_LIB.T6G(SCH_1):M_I_CPU0_SB_DQ(24)   I159 @T6G_MB_LIB.T6G(SCH_1):PAGE18
  CN21 M_I_CPU0_SB_DQ<13> @T6G_MB_LIB.T6G(SCH_1):M_I_CPU0_SB_DQ(13)   I159 @T6G_MB_LIB.T6G(SCH_1):PAGE18
  CH21 M_I_CPU0_SB_DQ<7> @T6G_MB_LIB.T6G(SCH_1):M_I_CPU0_SB_DQ(7)   I159 @T6G_MB_LIB.T6G(SCH_1):PAGE18
  BT20 M_I_CPU0_SB_CB<4> @T6G_MB_LIB.T6G(SCH_1):M_I_CPU0_SB_CB(4)   I159 @T6G_MB_LIB.T6G(SCH_1):PAGE18
   P21 M_I_CPU0_SA_DQS_DN<6> @T6G_MB_LIB.T6G(SCH_1):M_I_CPU0_SA_DQS_DN(6)   I159 @T6G_MB_LIB.T6G(SCH_1):PAGE18
   W19 M_I_CPU0_SA_DQS_DP<2> @T6G_MB_LIB.T6G(SCH_1):M_I_CPU0_SA_DQS_DP(2)   I159 @T6G_MB_LIB.T6G(SCH_1):PAGE18
   W21 M_I_CPU0_SA_DQ<19> @T6G_MB_LIB.T6G(SCH_1):M_I_CPU0_SA_DQ(19)   I159 @T6G_MB_LIB.T6G(SCH_1):PAGE18
   L21 M_I_CPU0_SA_DQ<7> @T6G_MB_LIB.T6G(SCH_1):M_I_CPU0_SA_DQ(7)   I159 @T6G_MB_LIB.T6G(SCH_1):PAGE18
  AW19 M_I_CPU0_SA_CA<0> @T6G_MB_LIB.T6G(SCH_1):M_I_CPU0_SA_CA(0)   I159 @T6G_MB_LIB.T6G(SCH_1):PAGE18
  CL19 M_I_CPU0_SB_DQS_DN<1> @T6G_MB_LIB.T6G(SCH_1):M_I_CPU0_SB_DQS_DN(1)   I159 @T6G_MB_LIB.T6G(SCH_1):PAGE18
  DA21 M_I_CPU0_SB_DQ<25> @T6G_MB_LIB.T6G(SCH_1):M_I_CPU0_SB_DQ(25)   I159 @T6G_MB_LIB.T6G(SCH_1):PAGE18
  CN19 M_I_CPU0_SB_DQ<14> @T6G_MB_LIB.T6G(SCH_1):M_I_CPU0_SB_DQ(14)   I159 @T6G_MB_LIB.T6G(SCH_1):PAGE18
  CH20 M_I_CPU0_SB_DQ<8> @T6G_MB_LIB.T6G(SCH_1):M_I_CPU0_SB_DQ(8)   I159 @T6G_MB_LIB.T6G(SCH_1):PAGE18
  BU21 M_I_CPU0_SB_CB<5> @T6G_MB_LIB.T6G(SCH_1):M_I_CPU0_SB_CB(5)   I159 @T6G_MB_LIB.T6G(SCH_1):PAGE18
  BG21 M_I_CPU0_SB_CA<0> @T6G_MB_LIB.T6G(SCH_1):M_I_CPU0_SB_CA(0)   I159 @T6G_MB_LIB.T6G(SCH_1):PAGE18
   Y21 M_I_CPU0_SA_DQS_DN<7> @T6G_MB_LIB.T6G(SCH_1):M_I_CPU0_SA_DQS_DN(7)   I159 @T6G_MB_LIB.T6G(SCH_1):PAGE18
  AE19 M_I_CPU0_SA_DQS_DP<3> @T6G_MB_LIB.T6G(SCH_1):M_I_CPU0_SA_DQS_DP(3)   I159 @T6G_MB_LIB.T6G(SCH_1):PAGE18
   L19 M_I_CPU0_SA_DQ<8> @T6G_MB_LIB.T6G(SCH_1):M_I_CPU0_SA_DQ(8)   I159 @T6G_MB_LIB.T6G(SCH_1):PAGE18
  AY20 M_I_CPU0_SA_CA<1> @T6G_MB_LIB.T6G(SCH_1):M_I_CPU0_SA_CA(1)   I159 @T6G_MB_LIB.T6G(SCH_1):PAGE18
  CU19 M_I_CPU0_SB_DQS_DN<2> @T6G_MB_LIB.T6G(SCH_1):M_I_CPU0_SB_DQS_DN(2)   I159 @T6G_MB_LIB.T6G(SCH_1):PAGE18
  DA19 M_I_CPU0_SB_DQ<26> @T6G_MB_LIB.T6G(SCH_1):M_I_CPU0_SB_DQ(26)   I159 @T6G_MB_LIB.T6G(SCH_1):PAGE18
  CP21 M_I_CPU0_SB_DQ<15> @T6G_MB_LIB.T6G(SCH_1):M_I_CPU0_SB_DQ(15)   I159 @T6G_MB_LIB.T6G(SCH_1):PAGE18
  CJ21 M_I_CPU0_SB_DQ<9> @T6G_MB_LIB.T6G(SCH_1):M_I_CPU0_SB_DQ(9)   I159 @T6G_MB_LIB.T6G(SCH_1):PAGE18
  BU19 M_I_CPU0_SB_CB<6> @T6G_MB_LIB.T6G(SCH_1):M_I_CPU0_SB_CB(6)   I159 @T6G_MB_LIB.T6G(SCH_1):PAGE18
  BH21 M_I_CPU0_SB_CA<1> @T6G_MB_LIB.T6G(SCH_1):M_I_CPU0_SB_CA(1)   I159 @T6G_MB_LIB.T6G(SCH_1):PAGE18
  AF21 M_I_CPU0_SA_DQS_DN<8> @T6G_MB_LIB.T6G(SCH_1):M_I_CPU0_SA_DQS_DN(8)   I159 @T6G_MB_LIB.T6G(SCH_1):PAGE18
  AL19 M_I_CPU0_SA_DQS_DP<4> @T6G_MB_LIB.T6G(SCH_1):M_I_CPU0_SA_DQS_DP(4)   I159 @T6G_MB_LIB.T6G(SCH_1):PAGE18
   M21 M_I_CPU0_SA_DQ<9> @T6G_MB_LIB.T6G(SCH_1):M_I_CPU0_SA_DQ(9)   I159 @T6G_MB_LIB.T6G(SCH_1):PAGE18
  AY21 M_I_CPU0_SA_CA<2> @T6G_MB_LIB.T6G(SCH_1):M_I_CPU0_SA_CA(2)   I159 @T6G_MB_LIB.T6G(SCH_1):PAGE18
  DC19 M_I_CPU0_SB_DQS_DN<3> @T6G_MB_LIB.T6G(SCH_1):M_I_CPU0_SB_DQS_DN(3)   I159 @T6G_MB_LIB.T6G(SCH_1):PAGE18
  DB21 M_I_CPU0_SB_DQ<27> @T6G_MB_LIB.T6G(SCH_1):M_I_CPU0_SB_DQ(27)   I159 @T6G_MB_LIB.T6G(SCH_1):PAGE18
  CP20 M_I_CPU0_SB_DQ<16> @T6G_MB_LIB.T6G(SCH_1):M_I_CPU0_SB_DQ(16)   I159 @T6G_MB_LIB.T6G(SCH_1):PAGE18
  BV21 M_I_CPU0_SB_CB<7> @T6G_MB_LIB.T6G(SCH_1):M_I_CPU0_SB_CB(7)   I159 @T6G_MB_LIB.T6G(SCH_1):PAGE18
  BH20 M_I_CPU0_SB_CA<2> @T6G_MB_LIB.T6G(SCH_1):M_I_CPU0_SB_CA(2)   I159 @T6G_MB_LIB.T6G(SCH_1):PAGE18
  BP20 M_I_CPU0_SB_RSP<0> @T6G_MB_LIB.T6G(SCH_1):M_I_CPU0_SB_RSP(0)   I159 @T6G_MB_LIB.T6G(SCH_1):PAGE18
  AM21 M_I_CPU0_SA_DQS_DN<9> @T6G_MB_LIB.T6G(SCH_1):M_I_CPU0_SA_DQS_DN(9)   I159 @T6G_MB_LIB.T6G(SCH_1):PAGE18
   J21 M_I_CPU0_SA_DQS_DP<5> @T6G_MB_LIB.T6G(SCH_1):M_I_CPU0_SA_DQS_DP(5)   I159 @T6G_MB_LIB.T6G(SCH_1):PAGE18
  BA21 M_I_CPU0_SA_CA<3> @T6G_MB_LIB.T6G(SCH_1):M_I_CPU0_SA_CA(3)   I159 @T6G_MB_LIB.T6G(SCH_1):PAGE18
  BW21 M_I_CPU0_SB_DQS_DN<4> @T6G_MB_LIB.T6G(SCH_1):M_I_CPU0_SB_DQS_DN(4)   I159 @T6G_MB_LIB.T6G(SCH_1):PAGE18
  CD20 M_I_CPU0_SB_DQS_DP<0> @T6G_MB_LIB.T6G(SCH_1):M_I_CPU0_SB_DQS_DP(0)   I159 @T6G_MB_LIB.T6G(SCH_1):PAGE18
  DD20 M_I_CPU0_SB_DQ<28> @T6G_MB_LIB.T6G(SCH_1):M_I_CPU0_SB_DQ(28)   I159 @T6G_MB_LIB.T6G(SCH_1):PAGE18
  CR21 M_I_CPU0_SB_DQ<17> @T6G_MB_LIB.T6G(SCH_1):M_I_CPU0_SB_DQ(17)   I159 @T6G_MB_LIB.T6G(SCH_1):PAGE18
  BJ19 M_I_CPU0_SB_CA<3> @T6G_MB_LIB.T6G(SCH_1):M_I_CPU0_SB_CA(3)   I159 @T6G_MB_LIB.T6G(SCH_1):PAGE18
  BR19     NC     NC   I159 @T6G_MB_LIB.T6G(SCH_1):PAGE18
   R21 M_I_CPU0_SA_DQS_DP<6> @T6G_MB_LIB.T6G(SCH_1):M_I_CPU0_SA_DQS_DP(6)   I159 @T6G_MB_LIB.T6G(SCH_1):PAGE18
  BA19 M_I_CPU0_SA_CA<4> @T6G_MB_LIB.T6G(SCH_1):M_I_CPU0_SA_CA(4)   I159 @T6G_MB_LIB.T6G(SCH_1):PAGE18
  CE21 M_I_CPU0_SB_DQS_DN<5> @T6G_MB_LIB.T6G(SCH_1):M_I_CPU0_SB_DQS_DN(5)   I159 @T6G_MB_LIB.T6G(SCH_1):PAGE18
  CK20 M_I_CPU0_SB_DQS_DP<1> @T6G_MB_LIB.T6G(SCH_1):M_I_CPU0_SB_DQS_DP(1)   I159 @T6G_MB_LIB.T6G(SCH_1):PAGE18
  DE21 M_I_CPU0_SB_DQ<29> @T6G_MB_LIB.T6G(SCH_1):M_I_CPU0_SB_DQ(29)   I159 @T6G_MB_LIB.T6G(SCH_1):PAGE18
  CR19 M_I_CPU0_SB_DQ<18> @T6G_MB_LIB.T6G(SCH_1):M_I_CPU0_SB_DQ(18)   I159 @T6G_MB_LIB.T6G(SCH_1):PAGE18
  BJ21 M_I_CPU0_SB_CA<4> @T6G_MB_LIB.T6G(SCH_1):M_I_CPU0_SB_CA(4)   I159 @T6G_MB_LIB.T6G(SCH_1):PAGE18
  AA21 M_I_CPU0_SA_DQS_DP<7> @T6G_MB_LIB.T6G(SCH_1):M_I_CPU0_SA_DQS_DP(7)   I159 @T6G_MB_LIB.T6G(SCH_1):PAGE18
  BB20 M_I_CPU0_SA_CA<5> @T6G_MB_LIB.T6G(SCH_1):M_I_CPU0_SA_CA(5)   I159 @T6G_MB_LIB.T6G(SCH_1):PAGE18
  AV20     NC     NC   I159 @T6G_MB_LIB.T6G(SCH_1):PAGE18
  AU19 M_I_CPU0_SA_CS_N<0> @T6G_MB_LIB.T6G(SCH_1):M_I_CPU0_SA_CS_N(0)   I159 @T6G_MB_LIB.T6G(SCH_1):PAGE18
  BF20     NC     NC   I159 @T6G_MB_LIB.T6G(SCH_1):PAGE18
  BC19 M_I_CPU0_CLK_DP<0> @T6G_MB_LIB.T6G(SCH_1):M_I_CPU0_CLK_DP(0)   I159 @T6G_MB_LIB.T6G(SCH_1):PAGE18
  CL21 M_I_CPU0_SB_DQS_DN<6> @T6G_MB_LIB.T6G(SCH_1):M_I_CPU0_SB_DQS_DN(6)   I159 @T6G_MB_LIB.T6G(SCH_1):PAGE18
  CT20 M_I_CPU0_SB_DQS_DP<2> @T6G_MB_LIB.T6G(SCH_1):M_I_CPU0_SB_DQS_DP(2)   I159 @T6G_MB_LIB.T6G(SCH_1):PAGE18
  CT21 M_I_CPU0_SB_DQ<19> @T6G_MB_LIB.T6G(SCH_1):M_I_CPU0_SB_DQ(19)   I159 @T6G_MB_LIB.T6G(SCH_1):PAGE18
  BK21 M_I_CPU0_SB_CA<5> @T6G_MB_LIB.T6G(SCH_1):M_I_CPU0_SB_CA(5)   I159 @T6G_MB_LIB.T6G(SCH_1):PAGE18
  AG21 M_I_CPU0_SA_DQS_DP<8> @T6G_MB_LIB.T6G(SCH_1):M_I_CPU0_SA_DQS_DP(8)   I159 @T6G_MB_LIB.T6G(SCH_1):PAGE18
  AH20 M_I_CPU0_SA_DQ<30> @T6G_MB_LIB.T6G(SCH_1):M_I_CPU0_SA_DQ(30)   I159 @T6G_MB_LIB.T6G(SCH_1):PAGE18
  BB21 M_I_CPU0_SA_CA<6> @T6G_MB_LIB.T6G(SCH_1):M_I_CPU0_SA_CA(6)   I159 @T6G_MB_LIB.T6G(SCH_1):PAGE18
  AW21     NC     NC   I159 @T6G_MB_LIB.T6G(SCH_1):PAGE18
  AV21 M_I_CPU0_SA_CS_N<1> @T6G_MB_LIB.T6G(SCH_1):M_I_CPU0_SA_CS_N(1)   I159 @T6G_MB_LIB.T6G(SCH_1):PAGE18
  CU21 M_I_CPU0_SB_DQS_DN<7> @T6G_MB_LIB.T6G(SCH_1):M_I_CPU0_SB_DQS_DN(7)   I159 @T6G_MB_LIB.T6G(SCH_1):PAGE18
  DB20 M_I_CPU0_SB_DQS_DP<3> @T6G_MB_LIB.T6G(SCH_1):M_I_CPU0_SB_DQS_DP(3)   I159 @T6G_MB_LIB.T6G(SCH_1):PAGE18
  BK20 M_I_CPU0_SB_CA<6> @T6G_MB_LIB.T6G(SCH_1):M_I_CPU0_SB_CA(6)   I159 @T6G_MB_LIB.T6G(SCH_1):PAGE18
  AN21 M_I_CPU0_SA_DQS_DP<9> @T6G_MB_LIB.T6G(SCH_1):M_I_CPU0_SA_DQS_DP(9)   I159 @T6G_MB_LIB.T6G(SCH_1):PAGE18
  AJ21 M_I_CPU0_SA_DQ<31> @T6G_MB_LIB.T6G(SCH_1):M_I_CPU0_SA_DQ(31)   I159 @T6G_MB_LIB.T6G(SCH_1):PAGE18
  AA19 M_I_CPU0_SA_DQ<20> @T6G_MB_LIB.T6G(SCH_1):M_I_CPU0_SA_DQ(20)   I159 @T6G_MB_LIB.T6G(SCH_1):PAGE18
  AJ19 M_I_CPU0_SA_CB<0> @T6G_MB_LIB.T6G(SCH_1):M_I_CPU0_SA_CB(0)   I159 @T6G_MB_LIB.T6G(SCH_1):PAGE18
  DC21 M_I_CPU0_SB_DQS_DN<8> @T6G_MB_LIB.T6G(SCH_1):M_I_CPU0_SB_DQS_DN(8)   I159 @T6G_MB_LIB.T6G(SCH_1):PAGE18
  BY21 M_I_CPU0_SB_DQS_DP<4> @T6G_MB_LIB.T6G(SCH_1):M_I_CPU0_SB_DQS_DP(4)   I159 @T6G_MB_LIB.T6G(SCH_1):PAGE18
  AB21 M_I_CPU0_SA_DQ<21> @T6G_MB_LIB.T6G(SCH_1):M_I_CPU0_SA_DQ(21)   I159 @T6G_MB_LIB.T6G(SCH_1):PAGE18
   M20 M_I_CPU0_SA_DQ<10> @T6G_MB_LIB.T6G(SCH_1):M_I_CPU0_SA_DQ(10)   I159 @T6G_MB_LIB.T6G(SCH_1):PAGE18
  AK21 M_I_CPU0_SA_CB<1> @T6G_MB_LIB.T6G(SCH_1):M_I_CPU0_SA_CB(1)   I159 @T6G_MB_LIB.T6G(SCH_1):PAGE18
  BW19 M_I_CPU0_SB_DQS_DN<9> @T6G_MB_LIB.T6G(SCH_1):M_I_CPU0_SB_DQS_DN(9)   I159 @T6G_MB_LIB.T6G(SCH_1):PAGE18
  CF21 M_I_CPU0_SB_DQS_DP<5> @T6G_MB_LIB.T6G(SCH_1):M_I_CPU0_SB_DQS_DP(5)   I159 @T6G_MB_LIB.T6G(SCH_1):PAGE18
  AB20 M_I_CPU0_SA_DQ<22> @T6G_MB_LIB.T6G(SCH_1):M_I_CPU0_SA_DQ(22)   I159 @T6G_MB_LIB.T6G(SCH_1):PAGE18
   N21 M_I_CPU0_SA_DQ<11> @T6G_MB_LIB.T6G(SCH_1):M_I_CPU0_SA_DQ(11)   I159 @T6G_MB_LIB.T6G(SCH_1):PAGE18
  AK20 M_I_CPU0_SA_CB<2> @T6G_MB_LIB.T6G(SCH_1):M_I_CPU0_SA_CB(2)   I159 @T6G_MB_LIB.T6G(SCH_1):PAGE18
  BG19     NC     NC   I159 @T6G_MB_LIB.T6G(SCH_1):PAGE18
  BD20 M_I_CPU0_CLK_DN<0> @T6G_MB_LIB.T6G(SCH_1):M_I_CPU0_CLK_DN(0)   I159 @T6G_MB_LIB.T6G(SCH_1):PAGE18
  AU21 M_I_CPU0_RESET_N @T6G_MB_LIB.T6G(SCH_1):M_I_CPU0_RESET_N   I159 @T6G_MB_LIB.T6G(SCH_1):PAGE18
  CM21 M_I_CPU0_SB_DQS_DP<6> @T6G_MB_LIB.T6G(SCH_1):M_I_CPU0_SB_DQS_DP(6)   I159 @T6G_MB_LIB.T6G(SCH_1):PAGE18
  CB20 M_I_CPU0_SB_DQ<0> @T6G_MB_LIB.T6G(SCH_1):M_I_CPU0_SB_DQ(0)   I159 @T6G_MB_LIB.T6G(SCH_1):PAGE18
  AC21 M_I_CPU0_SA_DQ<23> @T6G_MB_LIB.T6G(SCH_1):M_I_CPU0_SA_DQ(23)   I159 @T6G_MB_LIB.T6G(SCH_1):PAGE18
   R19 M_I_CPU0_SA_DQ<12> @T6G_MB_LIB.T6G(SCH_1):M_I_CPU0_SA_DQ(12)   I159 @T6G_MB_LIB.T6G(SCH_1):PAGE18
   E19 M_I_CPU0_SA_DQ<0> @T6G_MB_LIB.T6G(SCH_1):M_I_CPU0_SA_DQ(0)   I159 @T6G_MB_LIB.T6G(SCH_1):PAGE18
  AL21 M_I_CPU0_SA_CB<3> @T6G_MB_LIB.T6G(SCH_1):M_I_CPU0_SA_CB(3)   I159 @T6G_MB_LIB.T6G(SCH_1):PAGE18
  CV21 M_I_CPU0_SB_DQS_DP<7> @T6G_MB_LIB.T6G(SCH_1):M_I_CPU0_SB_DQS_DP(7)   I159 @T6G_MB_LIB.T6G(SCH_1):PAGE18
  CC21 M_I_CPU0_SB_DQ<1> @T6G_MB_LIB.T6G(SCH_1):M_I_CPU0_SB_DQ(1)   I159 @T6G_MB_LIB.T6G(SCH_1):PAGE18
  BM21 M_I_CPU0_SB_CS_N<0> @T6G_MB_LIB.T6G(SCH_1):M_I_CPU0_SB_CS_N(0)   I159 @T6G_MB_LIB.T6G(SCH_1):PAGE18
   H20 M_I_CPU0_SA_DQS_DN<0> @T6G_MB_LIB.T6G(SCH_1):M_I_CPU0_SA_DQS_DN(0)   I159 @T6G_MB_LIB.T6G(SCH_1):PAGE18
  AC19 M_I_CPU0_SA_DQ<24> @T6G_MB_LIB.T6G(SCH_1):M_I_CPU0_SA_DQ(24)   I159 @T6G_MB_LIB.T6G(SCH_1):PAGE18
   T21 M_I_CPU0_SA_DQ<13> @T6G_MB_LIB.T6G(SCH_1):M_I_CPU0_SA_DQ(13)   I159 @T6G_MB_LIB.T6G(SCH_1):PAGE18
   F21 M_I_CPU0_SA_DQ<1> @T6G_MB_LIB.T6G(SCH_1):M_I_CPU0_SA_DQ(1)   I159 @T6G_MB_LIB.T6G(SCH_1):PAGE18
  AN19 M_I_CPU0_SA_CB<4> @T6G_MB_LIB.T6G(SCH_1):M_I_CPU0_SA_CB(4)   I159 @T6G_MB_LIB.T6G(SCH_1):PAGE18
  DD21 M_I_CPU0_SB_DQS_DP<8> @T6G_MB_LIB.T6G(SCH_1):M_I_CPU0_SB_DQS_DP(8)   I159 @T6G_MB_LIB.T6G(SCH_1):PAGE18
  DE19 M_I_CPU0_SB_DQ<30> @T6G_MB_LIB.T6G(SCH_1):M_I_CPU0_SB_DQ(30)   I159 @T6G_MB_LIB.T6G(SCH_1):PAGE18
  CC19 M_I_CPU0_SB_DQ<2> @T6G_MB_LIB.T6G(SCH_1):M_I_CPU0_SB_DQ(2)   I159 @T6G_MB_LIB.T6G(SCH_1):PAGE18
  BL19     NC     NC   I159 @T6G_MB_LIB.T6G(SCH_1):PAGE18
  BN19 M_I_CPU0_SB_CS_N<1> @T6G_MB_LIB.T6G(SCH_1):M_I_CPU0_SB_CS_N(1)   I159 @T6G_MB_LIB.T6G(SCH_1):PAGE18
   P20 M_I_CPU0_SA_DQS_DN<1> @T6G_MB_LIB.T6G(SCH_1):M_I_CPU0_SA_DQS_DN(1)   I159 @T6G_MB_LIB.T6G(SCH_1):PAGE18
  AD21 M_I_CPU0_SA_DQ<25> @T6G_MB_LIB.T6G(SCH_1):M_I_CPU0_SA_DQ(25)   I159 @T6G_MB_LIB.T6G(SCH_1):PAGE18
   T20 M_I_CPU0_SA_DQ<14> @T6G_MB_LIB.T6G(SCH_1):M_I_CPU0_SA_DQ(14)   I159 @T6G_MB_LIB.T6G(SCH_1):PAGE18
   F20 M_I_CPU0_SA_DQ<2> @T6G_MB_LIB.T6G(SCH_1):M_I_CPU0_SA_DQ(2)   I159 @T6G_MB_LIB.T6G(SCH_1):PAGE18
  AP21 M_I_CPU0_SA_CB<5> @T6G_MB_LIB.T6G(SCH_1):M_I_CPU0_SA_CB(5)   I159 @T6G_MB_LIB.T6G(SCH_1):PAGE18
  BV20 M_I_CPU0_SB_DQS_DP<9> @T6G_MB_LIB.T6G(SCH_1):M_I_CPU0_SB_DQS_DP(9)   I159 @T6G_MB_LIB.T6G(SCH_1):PAGE18
  DF21 M_I_CPU0_SB_DQ<31> @T6G_MB_LIB.T6G(SCH_1):M_I_CPU0_SB_DQ(31)   I159 @T6G_MB_LIB.T6G(SCH_1):PAGE18
  CV20 M_I_CPU0_SB_DQ<20> @T6G_MB_LIB.T6G(SCH_1):M_I_CPU0_SB_DQ(20)   I159 @T6G_MB_LIB.T6G(SCH_1):PAGE18
  CD21 M_I_CPU0_SB_DQ<3> @T6G_MB_LIB.T6G(SCH_1):M_I_CPU0_SB_DQ(3)   I159 @T6G_MB_LIB.T6G(SCH_1):PAGE18
  BY20 M_I_CPU0_SB_CB<0> @T6G_MB_LIB.T6G(SCH_1):M_I_CPU0_SB_CB(0)   I159 @T6G_MB_LIB.T6G(SCH_1):PAGE18
  BM20     NC     NC   I159 @T6G_MB_LIB.T6G(SCH_1):PAGE18
  BC21 M_I_CPU0_SA_PAR @T6G_MB_LIB.T6G(SCH_1):M_I_CPU0_SA_PAR   I159 @T6G_MB_LIB.T6G(SCH_1):PAGE18
   Y20 M_I_CPU0_SA_DQS_DN<2> @T6G_MB_LIB.T6G(SCH_1):M_I_CPU0_SA_DQS_DN(2)   I159 @T6G_MB_LIB.T6G(SCH_1):PAGE18
  AD20 M_I_CPU0_SA_DQ<26> @T6G_MB_LIB.T6G(SCH_1):M_I_CPU0_SA_DQ(26)   I159 @T6G_MB_LIB.T6G(SCH_1):PAGE18
   U21 M_I_CPU0_SA_DQ<15> @T6G_MB_LIB.T6G(SCH_1):M_I_CPU0_SA_DQ(15)   I159 @T6G_MB_LIB.T6G(SCH_1):PAGE18
   G21 M_I_CPU0_SA_DQ<3> @T6G_MB_LIB.T6G(SCH_1):M_I_CPU0_SA_DQ(3)   I159 @T6G_MB_LIB.T6G(SCH_1):PAGE18
  AP20 M_I_CPU0_SA_CB<6> @T6G_MB_LIB.T6G(SCH_1):M_I_CPU0_SA_CB(6)   I159 @T6G_MB_LIB.T6G(SCH_1):PAGE18
  BL21 M_I_CPU0_SB_PAR @T6G_MB_LIB.T6G(SCH_1):M_I_CPU0_SB_PAR   I159 @T6G_MB_LIB.T6G(SCH_1):PAGE18
  CW21 M_I_CPU0_SB_DQ<21> @T6G_MB_LIB.T6G(SCH_1):M_I_CPU0_SB_DQ(21)   I159 @T6G_MB_LIB.T6G(SCH_1):PAGE18
  CJ19 M_I_CPU0_SB_DQ<10> @T6G_MB_LIB.T6G(SCH_1):M_I_CPU0_SB_DQ(10)   I159 @T6G_MB_LIB.T6G(SCH_1):PAGE18
  CF20 M_I_CPU0_SB_DQ<4> @T6G_MB_LIB.T6G(SCH_1):M_I_CPU0_SB_DQ(4)   I159 @T6G_MB_LIB.T6G(SCH_1):PAGE18
  CA21 M_I_CPU0_SB_CB<1> @T6G_MB_LIB.T6G(SCH_1):M_I_CPU0_SB_CB(1)   I159 @T6G_MB_LIB.T6G(SCH_1):PAGE18
  AF20 M_I_CPU0_SA_DQS_DN<3> @T6G_MB_LIB.T6G(SCH_1):M_I_CPU0_SA_DQS_DN(3)   I159 @T6G_MB_LIB.T6G(SCH_1):PAGE18
  AE21 M_I_CPU0_SA_DQ<27> @T6G_MB_LIB.T6G(SCH_1):M_I_CPU0_SA_DQ(27)   I159 @T6G_MB_LIB.T6G(SCH_1):PAGE18
   U19 M_I_CPU0_SA_DQ<16> @T6G_MB_LIB.T6G(SCH_1):M_I_CPU0_SA_DQ(16)   I159 @T6G_MB_LIB.T6G(SCH_1):PAGE18
   J19 M_I_CPU0_SA_DQ<4> @T6G_MB_LIB.T6G(SCH_1):M_I_CPU0_SA_DQ(4)   I159 @T6G_MB_LIB.T6G(SCH_1):PAGE18
  AR21 M_I_CPU0_SA_CB<7> @T6G_MB_LIB.T6G(SCH_1):M_I_CPU0_SA_CB(7)   I159 @T6G_MB_LIB.T6G(SCH_1):PAGE18
  BP21     NC     NC   I159 @T6G_MB_LIB.T6G(SCH_1):PAGE18
  BN21 M_I_CPU0_SA_RSP<0> @T6G_MB_LIB.T6G(SCH_1):M_I_CPU0_SA_RSP(0)   I159 @T6G_MB_LIB.T6G(SCH_1):PAGE18
  AT21 M_I_CPU0_ALERT_R_N @T6G_MB_LIB.T6G(SCH_1):M_I_CPU0_ALERT_R_N   I159 @T6G_MB_LIB.T6G(SCH_1):PAGE18
  CW19 M_I_CPU0_SB_DQ<22> @T6G_MB_LIB.T6G(SCH_1):M_I_CPU0_SB_DQ(22)   I159 @T6G_MB_LIB.T6G(SCH_1):PAGE18
  CK21 M_I_CPU0_SB_DQ<11> @T6G_MB_LIB.T6G(SCH_1):M_I_CPU0_SB_DQ(11)   I159 @T6G_MB_LIB.T6G(SCH_1):PAGE18
  CG21 M_I_CPU0_SB_DQ<5> @T6G_MB_LIB.T6G(SCH_1):M_I_CPU0_SB_DQ(5)   I159 @T6G_MB_LIB.T6G(SCH_1):PAGE18
  CA19 M_I_CPU0_SB_CB<2> @T6G_MB_LIB.T6G(SCH_1):M_I_CPU0_SB_CB(2)   I159 @T6G_MB_LIB.T6G(SCH_1):PAGE18
  AM20 M_I_CPU0_SA_DQS_DN<4> @T6G_MB_LIB.T6G(SCH_1):M_I_CPU0_SA_DQS_DN(4)   I159 @T6G_MB_LIB.T6G(SCH_1):PAGE18
   G19 M_I_CPU0_SA_DQS_DP<0> @T6G_MB_LIB.T6G(SCH_1):M_I_CPU0_SA_DQS_DP(0)   I159 @T6G_MB_LIB.T6G(SCH_1):PAGE18
  AG19 M_I_CPU0_SA_DQ<28> @T6G_MB_LIB.T6G(SCH_1):M_I_CPU0_SA_DQ(28)   I159 @T6G_MB_LIB.T6G(SCH_1):PAGE18
   V21 M_I_CPU0_SA_DQ<17> @T6G_MB_LIB.T6G(SCH_1):M_I_CPU0_SA_DQ(17)   I159 @T6G_MB_LIB.T6G(SCH_1):PAGE18
   K21 M_I_CPU0_SA_DQ<5> @T6G_MB_LIB.T6G(SCH_1):M_I_CPU0_SA_DQ(5)   I159 @T6G_MB_LIB.T6G(SCH_1):PAGE18
  BF21 TP_M_I_CPU0_SA_TEST39I @T6G_MB_LIB.T6G(SCH_1):TP_M_I_CPU0_SA_TEST39I   I159 @T6G_MB_LIB.T6G(SCH_1):PAGE18
  AU17 M_J_CPU0_RESET_N @T6G_MB_LIB.T6G(SCH_1):M_J_CPU0_RESET_N   I159 @T6G_MB_LIB.T6G(SCH_1):PAGE19
  AT18 M_J_CPU0_ALERT_R_N @T6G_MB_LIB.T6G(SCH_1):M_J_CPU0_ALERT_R_N   I159 @T6G_MB_LIB.T6G(SCH_1):PAGE19
  BL17 M_J_CPU0_SB_PAR @T6G_MB_LIB.T6G(SCH_1):M_J_CPU0_SB_PAR   I159 @T6G_MB_LIB.T6G(SCH_1):PAGE19
  BW16 M_J_CPU0_SB_DQS_DN<9> @T6G_MB_LIB.T6G(SCH_1):M_J_CPU0_SB_DQS_DN(9)   I159 @T6G_MB_LIB.T6G(SCH_1):PAGE19
  DC17 M_J_CPU0_SB_DQS_DN<8> @T6G_MB_LIB.T6G(SCH_1):M_J_CPU0_SB_DQS_DN(8)   I159 @T6G_MB_LIB.T6G(SCH_1):PAGE19
  CU17 M_J_CPU0_SB_DQS_DN<7> @T6G_MB_LIB.T6G(SCH_1):M_J_CPU0_SB_DQS_DN(7)   I159 @T6G_MB_LIB.T6G(SCH_1):PAGE19
  CL17 M_J_CPU0_SB_DQS_DN<6> @T6G_MB_LIB.T6G(SCH_1):M_J_CPU0_SB_DQS_DN(6)   I159 @T6G_MB_LIB.T6G(SCH_1):PAGE19
  CE17 M_J_CPU0_SB_DQS_DN<5> @T6G_MB_LIB.T6G(SCH_1):M_J_CPU0_SB_DQS_DN(5)   I159 @T6G_MB_LIB.T6G(SCH_1):PAGE19
  DC16 M_J_CPU0_SB_DQS_DN<3> @T6G_MB_LIB.T6G(SCH_1):M_J_CPU0_SB_DQS_DN(3)   I159 @T6G_MB_LIB.T6G(SCH_1):PAGE19
  CU16 M_J_CPU0_SB_DQS_DN<2> @T6G_MB_LIB.T6G(SCH_1):M_J_CPU0_SB_DQS_DN(2)   I159 @T6G_MB_LIB.T6G(SCH_1):PAGE19
  CL16 M_J_CPU0_SB_DQS_DN<1> @T6G_MB_LIB.T6G(SCH_1):M_J_CPU0_SB_DQS_DN(1)   I159 @T6G_MB_LIB.T6G(SCH_1):PAGE19
  BV16 M_J_CPU0_SB_DQS_DP<9> @T6G_MB_LIB.T6G(SCH_1):M_J_CPU0_SB_DQS_DP(9)   I159 @T6G_MB_LIB.T6G(SCH_1):PAGE19
  DD18 M_J_CPU0_SB_DQS_DP<8> @T6G_MB_LIB.T6G(SCH_1):M_J_CPU0_SB_DQS_DP(8)   I159 @T6G_MB_LIB.T6G(SCH_1):PAGE19
  CV18 M_J_CPU0_SB_DQS_DP<7> @T6G_MB_LIB.T6G(SCH_1):M_J_CPU0_SB_DQS_DP(7)   I159 @T6G_MB_LIB.T6G(SCH_1):PAGE19
  CM18 M_J_CPU0_SB_DQS_DP<6> @T6G_MB_LIB.T6G(SCH_1):M_J_CPU0_SB_DQS_DP(6)   I159 @T6G_MB_LIB.T6G(SCH_1):PAGE19
  BY18 M_J_CPU0_SB_DQS_DP<4> @T6G_MB_LIB.T6G(SCH_1):M_J_CPU0_SB_DQS_DP(4)   I159 @T6G_MB_LIB.T6G(SCH_1):PAGE19
  DB16 M_J_CPU0_SB_DQS_DP<3> @T6G_MB_LIB.T6G(SCH_1):M_J_CPU0_SB_DQS_DP(3)   I159 @T6G_MB_LIB.T6G(SCH_1):PAGE19
  CT16 M_J_CPU0_SB_DQS_DP<2> @T6G_MB_LIB.T6G(SCH_1):M_J_CPU0_SB_DQS_DP(2)   I159 @T6G_MB_LIB.T6G(SCH_1):PAGE19
  CK16 M_J_CPU0_SB_DQS_DP<1> @T6G_MB_LIB.T6G(SCH_1):M_J_CPU0_SB_DQS_DP(1)   I159 @T6G_MB_LIB.T6G(SCH_1):PAGE19
  CD16 M_J_CPU0_SB_DQS_DP<0> @T6G_MB_LIB.T6G(SCH_1):M_J_CPU0_SB_DQS_DP(0)   I159 @T6G_MB_LIB.T6G(SCH_1):PAGE19
  DF16 M_J_CPU0_SB_DQ<31> @T6G_MB_LIB.T6G(SCH_1):M_J_CPU0_SB_DQ(31)   I159 @T6G_MB_LIB.T6G(SCH_1):PAGE19
  DE16 M_J_CPU0_SB_DQ<30> @T6G_MB_LIB.T6G(SCH_1):M_J_CPU0_SB_DQ(30)   I159 @T6G_MB_LIB.T6G(SCH_1):PAGE19
  DE17 M_J_CPU0_SB_DQ<29> @T6G_MB_LIB.T6G(SCH_1):M_J_CPU0_SB_DQ(29)   I159 @T6G_MB_LIB.T6G(SCH_1):PAGE19
  DD16 M_J_CPU0_SB_DQ<28> @T6G_MB_LIB.T6G(SCH_1):M_J_CPU0_SB_DQ(28)   I159 @T6G_MB_LIB.T6G(SCH_1):PAGE19
  DB18 M_J_CPU0_SB_DQ<27> @T6G_MB_LIB.T6G(SCH_1):M_J_CPU0_SB_DQ(27)   I159 @T6G_MB_LIB.T6G(SCH_1):PAGE19
  DA16 M_J_CPU0_SB_DQ<26> @T6G_MB_LIB.T6G(SCH_1):M_J_CPU0_SB_DQ(26)   I159 @T6G_MB_LIB.T6G(SCH_1):PAGE19
  DA17 M_J_CPU0_SB_DQ<25> @T6G_MB_LIB.T6G(SCH_1):M_J_CPU0_SB_DQ(25)   I159 @T6G_MB_LIB.T6G(SCH_1):PAGE19
  CY16 M_J_CPU0_SB_DQ<24> @T6G_MB_LIB.T6G(SCH_1):M_J_CPU0_SB_DQ(24)   I159 @T6G_MB_LIB.T6G(SCH_1):PAGE19
  CY18 M_J_CPU0_SB_DQ<23> @T6G_MB_LIB.T6G(SCH_1):M_J_CPU0_SB_DQ(23)   I159 @T6G_MB_LIB.T6G(SCH_1):PAGE19
  CW16 M_J_CPU0_SB_DQ<22> @T6G_MB_LIB.T6G(SCH_1):M_J_CPU0_SB_DQ(22)   I159 @T6G_MB_LIB.T6G(SCH_1):PAGE19
  CW17 M_J_CPU0_SB_DQ<21> @T6G_MB_LIB.T6G(SCH_1):M_J_CPU0_SB_DQ(21)   I159 @T6G_MB_LIB.T6G(SCH_1):PAGE19
  CV16 M_J_CPU0_SB_DQ<20> @T6G_MB_LIB.T6G(SCH_1):M_J_CPU0_SB_DQ(20)   I159 @T6G_MB_LIB.T6G(SCH_1):PAGE19
  CT18 M_J_CPU0_SB_DQ<19> @T6G_MB_LIB.T6G(SCH_1):M_J_CPU0_SB_DQ(19)   I159 @T6G_MB_LIB.T6G(SCH_1):PAGE19
  CR16 M_J_CPU0_SB_DQ<18> @T6G_MB_LIB.T6G(SCH_1):M_J_CPU0_SB_DQ(18)   I159 @T6G_MB_LIB.T6G(SCH_1):PAGE19
  CR17 M_J_CPU0_SB_DQ<17> @T6G_MB_LIB.T6G(SCH_1):M_J_CPU0_SB_DQ(17)   I159 @T6G_MB_LIB.T6G(SCH_1):PAGE19
  CP16 M_J_CPU0_SB_DQ<16> @T6G_MB_LIB.T6G(SCH_1):M_J_CPU0_SB_DQ(16)   I159 @T6G_MB_LIB.T6G(SCH_1):PAGE19
  CP18 M_J_CPU0_SB_DQ<15> @T6G_MB_LIB.T6G(SCH_1):M_J_CPU0_SB_DQ(15)   I159 @T6G_MB_LIB.T6G(SCH_1):PAGE19
  CN16 M_J_CPU0_SB_DQ<14> @T6G_MB_LIB.T6G(SCH_1):M_J_CPU0_SB_DQ(14)   I159 @T6G_MB_LIB.T6G(SCH_1):PAGE19
  CN17 M_J_CPU0_SB_DQ<13> @T6G_MB_LIB.T6G(SCH_1):M_J_CPU0_SB_DQ(13)   I159 @T6G_MB_LIB.T6G(SCH_1):PAGE19
  CM16 M_J_CPU0_SB_DQ<12> @T6G_MB_LIB.T6G(SCH_1):M_J_CPU0_SB_DQ(12)   I159 @T6G_MB_LIB.T6G(SCH_1):PAGE19
  CK18 M_J_CPU0_SB_DQ<11> @T6G_MB_LIB.T6G(SCH_1):M_J_CPU0_SB_DQ(11)   I159 @T6G_MB_LIB.T6G(SCH_1):PAGE19
  CJ16 M_J_CPU0_SB_DQ<10> @T6G_MB_LIB.T6G(SCH_1):M_J_CPU0_SB_DQ(10)   I159 @T6G_MB_LIB.T6G(SCH_1):PAGE19
  CJ17 M_J_CPU0_SB_DQ<9> @T6G_MB_LIB.T6G(SCH_1):M_J_CPU0_SB_DQ(9)   I159 @T6G_MB_LIB.T6G(SCH_1):PAGE19
  CH16 M_J_CPU0_SB_DQ<8> @T6G_MB_LIB.T6G(SCH_1):M_J_CPU0_SB_DQ(8)   I159 @T6G_MB_LIB.T6G(SCH_1):PAGE19
  CC16 M_J_CPU0_SB_DQ<2> @T6G_MB_LIB.T6G(SCH_1):M_J_CPU0_SB_DQ(2)   I159 @T6G_MB_LIB.T6G(SCH_1):PAGE19
  CC17 M_J_CPU0_SB_DQ<1> @T6G_MB_LIB.T6G(SCH_1):M_J_CPU0_SB_DQ(1)   I159 @T6G_MB_LIB.T6G(SCH_1):PAGE19
  BV18 M_J_CPU0_SB_CB<7> @T6G_MB_LIB.T6G(SCH_1):M_J_CPU0_SB_CB(7)   I159 @T6G_MB_LIB.T6G(SCH_1):PAGE19
  BU16 M_J_CPU0_SB_CB<6> @T6G_MB_LIB.T6G(SCH_1):M_J_CPU0_SB_CB(6)   I159 @T6G_MB_LIB.T6G(SCH_1):PAGE19
  BU17 M_J_CPU0_SB_CB<5> @T6G_MB_LIB.T6G(SCH_1):M_J_CPU0_SB_CB(5)   I159 @T6G_MB_LIB.T6G(SCH_1):PAGE19
  BT16 M_J_CPU0_SB_CB<4> @T6G_MB_LIB.T6G(SCH_1):M_J_CPU0_SB_CB(4)   I159 @T6G_MB_LIB.T6G(SCH_1):PAGE19
  CB18 M_J_CPU0_SB_CB<3> @T6G_MB_LIB.T6G(SCH_1):M_J_CPU0_SB_CB(3)   I159 @T6G_MB_LIB.T6G(SCH_1):PAGE19
  CA16 M_J_CPU0_SB_CB<2> @T6G_MB_LIB.T6G(SCH_1):M_J_CPU0_SB_CB(2)   I159 @T6G_MB_LIB.T6G(SCH_1):PAGE19
  CA17 M_J_CPU0_SB_CB<1> @T6G_MB_LIB.T6G(SCH_1):M_J_CPU0_SB_CB(1)   I159 @T6G_MB_LIB.T6G(SCH_1):PAGE19
  BY16 M_J_CPU0_SB_CB<0> @T6G_MB_LIB.T6G(SCH_1):M_J_CPU0_SB_CB(0)   I159 @T6G_MB_LIB.T6G(SCH_1):PAGE19
  BK16 M_J_CPU0_SB_CA<6> @T6G_MB_LIB.T6G(SCH_1):M_J_CPU0_SB_CA(6)   I159 @T6G_MB_LIB.T6G(SCH_1):PAGE19
  BK18 M_J_CPU0_SB_CA<5> @T6G_MB_LIB.T6G(SCH_1):M_J_CPU0_SB_CA(5)   I159 @T6G_MB_LIB.T6G(SCH_1):PAGE19
  BJ17 M_J_CPU0_SB_CA<4> @T6G_MB_LIB.T6G(SCH_1):M_J_CPU0_SB_CA(4)   I159 @T6G_MB_LIB.T6G(SCH_1):PAGE19
  BJ16 M_J_CPU0_SB_CA<3> @T6G_MB_LIB.T6G(SCH_1):M_J_CPU0_SB_CA(3)   I159 @T6G_MB_LIB.T6G(SCH_1):PAGE19
  BH16 M_J_CPU0_SB_CA<2> @T6G_MB_LIB.T6G(SCH_1):M_J_CPU0_SB_CA(2)   I159 @T6G_MB_LIB.T6G(SCH_1):PAGE19
  BH18 M_J_CPU0_SB_CA<1> @T6G_MB_LIB.T6G(SCH_1):M_J_CPU0_SB_CA(1)   I159 @T6G_MB_LIB.T6G(SCH_1):PAGE19
  BG17 M_J_CPU0_SB_CA<0> @T6G_MB_LIB.T6G(SCH_1):M_J_CPU0_SB_CA(0)   I159 @T6G_MB_LIB.T6G(SCH_1):PAGE19
  BR16     NC     NC   I159 @T6G_MB_LIB.T6G(SCH_1):PAGE19
  BM16     NC     NC   I159 @T6G_MB_LIB.T6G(SCH_1):PAGE19
  BL16     NC     NC   I159 @T6G_MB_LIB.T6G(SCH_1):PAGE19
  BP16 M_J_CPU0_SB_RSP<0> @T6G_MB_LIB.T6G(SCH_1):M_J_CPU0_SB_RSP(0)   I159 @T6G_MB_LIB.T6G(SCH_1):PAGE19
  BN16 M_J_CPU0_SB_CS_N<1> @T6G_MB_LIB.T6G(SCH_1):M_J_CPU0_SB_CS_N(1)   I159 @T6G_MB_LIB.T6G(SCH_1):PAGE19
  BM18 M_J_CPU0_SB_CS_N<0> @T6G_MB_LIB.T6G(SCH_1):M_J_CPU0_SB_CS_N(0)   I159 @T6G_MB_LIB.T6G(SCH_1):PAGE19
  BC17 M_J_CPU0_SA_PAR @T6G_MB_LIB.T6G(SCH_1):M_J_CPU0_SA_PAR   I159 @T6G_MB_LIB.T6G(SCH_1):PAGE19
  AM18 M_J_CPU0_SA_DQS_DN<9> @T6G_MB_LIB.T6G(SCH_1):M_J_CPU0_SA_DQS_DN(9)   I159 @T6G_MB_LIB.T6G(SCH_1):PAGE19
  AF18 M_J_CPU0_SA_DQS_DN<8> @T6G_MB_LIB.T6G(SCH_1):M_J_CPU0_SA_DQS_DN(8)   I159 @T6G_MB_LIB.T6G(SCH_1):PAGE19
   P18 M_J_CPU0_SA_DQS_DN<6> @T6G_MB_LIB.T6G(SCH_1):M_J_CPU0_SA_DQS_DN(6)   I159 @T6G_MB_LIB.T6G(SCH_1):PAGE19
  AF16 M_J_CPU0_SA_DQS_DN<3> @T6G_MB_LIB.T6G(SCH_1):M_J_CPU0_SA_DQS_DN(3)   I159 @T6G_MB_LIB.T6G(SCH_1):PAGE19
   Y16 M_J_CPU0_SA_DQS_DN<2> @T6G_MB_LIB.T6G(SCH_1):M_J_CPU0_SA_DQS_DN(2)   I159 @T6G_MB_LIB.T6G(SCH_1):PAGE19
   P16 M_J_CPU0_SA_DQS_DN<1> @T6G_MB_LIB.T6G(SCH_1):M_J_CPU0_SA_DQS_DN(1)   I159 @T6G_MB_LIB.T6G(SCH_1):PAGE19
   H16 M_J_CPU0_SA_DQS_DN<0> @T6G_MB_LIB.T6G(SCH_1):M_J_CPU0_SA_DQS_DN(0)   I159 @T6G_MB_LIB.T6G(SCH_1):PAGE19
  AN17 M_J_CPU0_SA_DQS_DP<9> @T6G_MB_LIB.T6G(SCH_1):M_J_CPU0_SA_DQS_DP(9)   I159 @T6G_MB_LIB.T6G(SCH_1):PAGE19
  AA17 M_J_CPU0_SA_DQS_DP<7> @T6G_MB_LIB.T6G(SCH_1):M_J_CPU0_SA_DQS_DP(7)   I159 @T6G_MB_LIB.T6G(SCH_1):PAGE19
   R17 M_J_CPU0_SA_DQS_DP<6> @T6G_MB_LIB.T6G(SCH_1):M_J_CPU0_SA_DQS_DP(6)   I159 @T6G_MB_LIB.T6G(SCH_1):PAGE19
   J17 M_J_CPU0_SA_DQS_DP<5> @T6G_MB_LIB.T6G(SCH_1):M_J_CPU0_SA_DQS_DP(5)   I159 @T6G_MB_LIB.T6G(SCH_1):PAGE19
  AE16 M_J_CPU0_SA_DQS_DP<3> @T6G_MB_LIB.T6G(SCH_1):M_J_CPU0_SA_DQS_DP(3)   I159 @T6G_MB_LIB.T6G(SCH_1):PAGE19
   W16 M_J_CPU0_SA_DQS_DP<2> @T6G_MB_LIB.T6G(SCH_1):M_J_CPU0_SA_DQS_DP(2)   I159 @T6G_MB_LIB.T6G(SCH_1):PAGE19
   N16 M_J_CPU0_SA_DQS_DP<1> @T6G_MB_LIB.T6G(SCH_1):M_J_CPU0_SA_DQS_DP(1)   I159 @T6G_MB_LIB.T6G(SCH_1):PAGE19
   G16 M_J_CPU0_SA_DQS_DP<0> @T6G_MB_LIB.T6G(SCH_1):M_J_CPU0_SA_DQS_DP(0)   I159 @T6G_MB_LIB.T6G(SCH_1):PAGE19
  AH16 M_J_CPU0_SA_DQ<30> @T6G_MB_LIB.T6G(SCH_1):M_J_CPU0_SA_DQ(30)   I159 @T6G_MB_LIB.T6G(SCH_1):PAGE19
  AH18 M_J_CPU0_SA_DQ<29> @T6G_MB_LIB.T6G(SCH_1):M_J_CPU0_SA_DQ(29)   I159 @T6G_MB_LIB.T6G(SCH_1):PAGE19
  AG16 M_J_CPU0_SA_DQ<28> @T6G_MB_LIB.T6G(SCH_1):M_J_CPU0_SA_DQ(28)   I159 @T6G_MB_LIB.T6G(SCH_1):PAGE19
  AE17 M_J_CPU0_SA_DQ<27> @T6G_MB_LIB.T6G(SCH_1):M_J_CPU0_SA_DQ(27)   I159 @T6G_MB_LIB.T6G(SCH_1):PAGE19
  AD16 M_J_CPU0_SA_DQ<26> @T6G_MB_LIB.T6G(SCH_1):M_J_CPU0_SA_DQ(26)   I159 @T6G_MB_LIB.T6G(SCH_1):PAGE19
  AD18 M_J_CPU0_SA_DQ<25> @T6G_MB_LIB.T6G(SCH_1):M_J_CPU0_SA_DQ(25)   I159 @T6G_MB_LIB.T6G(SCH_1):PAGE19
  AC16 M_J_CPU0_SA_DQ<24> @T6G_MB_LIB.T6G(SCH_1):M_J_CPU0_SA_DQ(24)   I159 @T6G_MB_LIB.T6G(SCH_1):PAGE19
  AC17 M_J_CPU0_SA_DQ<23> @T6G_MB_LIB.T6G(SCH_1):M_J_CPU0_SA_DQ(23)   I159 @T6G_MB_LIB.T6G(SCH_1):PAGE19
  AB18 M_J_CPU0_SA_DQ<21> @T6G_MB_LIB.T6G(SCH_1):M_J_CPU0_SA_DQ(21)   I159 @T6G_MB_LIB.T6G(SCH_1):PAGE19
  AA16 M_J_CPU0_SA_DQ<20> @T6G_MB_LIB.T6G(SCH_1):M_J_CPU0_SA_DQ(20)   I159 @T6G_MB_LIB.T6G(SCH_1):PAGE19
   W17 M_J_CPU0_SA_DQ<19> @T6G_MB_LIB.T6G(SCH_1):M_J_CPU0_SA_DQ(19)   I159 @T6G_MB_LIB.T6G(SCH_1):PAGE19
   V16 M_J_CPU0_SA_DQ<18> @T6G_MB_LIB.T6G(SCH_1):M_J_CPU0_SA_DQ(18)   I159 @T6G_MB_LIB.T6G(SCH_1):PAGE19
   V18 M_J_CPU0_SA_DQ<17> @T6G_MB_LIB.T6G(SCH_1):M_J_CPU0_SA_DQ(17)   I159 @T6G_MB_LIB.T6G(SCH_1):PAGE19
   U16 M_J_CPU0_SA_DQ<16> @T6G_MB_LIB.T6G(SCH_1):M_J_CPU0_SA_DQ(16)   I159 @T6G_MB_LIB.T6G(SCH_1):PAGE19
   U17 M_J_CPU0_SA_DQ<15> @T6G_MB_LIB.T6G(SCH_1):M_J_CPU0_SA_DQ(15)   I159 @T6G_MB_LIB.T6G(SCH_1):PAGE19
   T16 M_J_CPU0_SA_DQ<14> @T6G_MB_LIB.T6G(SCH_1):M_J_CPU0_SA_DQ(14)   I159 @T6G_MB_LIB.T6G(SCH_1):PAGE19
   T18 M_J_CPU0_SA_DQ<13> @T6G_MB_LIB.T6G(SCH_1):M_J_CPU0_SA_DQ(13)   I159 @T6G_MB_LIB.T6G(SCH_1):PAGE19
   R16 M_J_CPU0_SA_DQ<12> @T6G_MB_LIB.T6G(SCH_1):M_J_CPU0_SA_DQ(12)   I159 @T6G_MB_LIB.T6G(SCH_1):PAGE19
   N17 M_J_CPU0_SA_DQ<11> @T6G_MB_LIB.T6G(SCH_1):M_J_CPU0_SA_DQ(11)   I159 @T6G_MB_LIB.T6G(SCH_1):PAGE19
   M16 M_J_CPU0_SA_DQ<10> @T6G_MB_LIB.T6G(SCH_1):M_J_CPU0_SA_DQ(10)   I159 @T6G_MB_LIB.T6G(SCH_1):PAGE19
   M18 M_J_CPU0_SA_DQ<9> @T6G_MB_LIB.T6G(SCH_1):M_J_CPU0_SA_DQ(9)   I159 @T6G_MB_LIB.T6G(SCH_1):PAGE19
   L16 M_J_CPU0_SA_DQ<8> @T6G_MB_LIB.T6G(SCH_1):M_J_CPU0_SA_DQ(8)   I159 @T6G_MB_LIB.T6G(SCH_1):PAGE19
   L17 M_J_CPU0_SA_DQ<7> @T6G_MB_LIB.T6G(SCH_1):M_J_CPU0_SA_DQ(7)   I159 @T6G_MB_LIB.T6G(SCH_1):PAGE19
   K16 M_J_CPU0_SA_DQ<6> @T6G_MB_LIB.T6G(SCH_1):M_J_CPU0_SA_DQ(6)   I159 @T6G_MB_LIB.T6G(SCH_1):PAGE19
   K18 M_J_CPU0_SA_DQ<5> @T6G_MB_LIB.T6G(SCH_1):M_J_CPU0_SA_DQ(5)   I159 @T6G_MB_LIB.T6G(SCH_1):PAGE19
   J16 M_J_CPU0_SA_DQ<4> @T6G_MB_LIB.T6G(SCH_1):M_J_CPU0_SA_DQ(4)   I159 @T6G_MB_LIB.T6G(SCH_1):PAGE19
   G17 M_J_CPU0_SA_DQ<3> @T6G_MB_LIB.T6G(SCH_1):M_J_CPU0_SA_DQ(3)   I159 @T6G_MB_LIB.T6G(SCH_1):PAGE19
   F16 M_J_CPU0_SA_DQ<2> @T6G_MB_LIB.T6G(SCH_1):M_J_CPU0_SA_DQ(2)   I159 @T6G_MB_LIB.T6G(SCH_1):PAGE19
   F18 M_J_CPU0_SA_DQ<1> @T6G_MB_LIB.T6G(SCH_1):M_J_CPU0_SA_DQ(1)   I159 @T6G_MB_LIB.T6G(SCH_1):PAGE19
   E16 M_J_CPU0_SA_DQ<0> @T6G_MB_LIB.T6G(SCH_1):M_J_CPU0_SA_DQ(0)   I159 @T6G_MB_LIB.T6G(SCH_1):PAGE19
  AR17 M_J_CPU0_SA_CB<7> @T6G_MB_LIB.T6G(SCH_1):M_J_CPU0_SA_CB(7)   I159 @T6G_MB_LIB.T6G(SCH_1):PAGE19
  AP16 M_J_CPU0_SA_CB<6> @T6G_MB_LIB.T6G(SCH_1):M_J_CPU0_SA_CB(6)   I159 @T6G_MB_LIB.T6G(SCH_1):PAGE19
  AP18 M_J_CPU0_SA_CB<5> @T6G_MB_LIB.T6G(SCH_1):M_J_CPU0_SA_CB(5)   I159 @T6G_MB_LIB.T6G(SCH_1):PAGE19
  AN16 M_J_CPU0_SA_CB<4> @T6G_MB_LIB.T6G(SCH_1):M_J_CPU0_SA_CB(4)   I159 @T6G_MB_LIB.T6G(SCH_1):PAGE19
  AL17 M_J_CPU0_SA_CB<3> @T6G_MB_LIB.T6G(SCH_1):M_J_CPU0_SA_CB(3)   I159 @T6G_MB_LIB.T6G(SCH_1):PAGE19
  AK16 M_J_CPU0_SA_CB<2> @T6G_MB_LIB.T6G(SCH_1):M_J_CPU0_SA_CB(2)   I159 @T6G_MB_LIB.T6G(SCH_1):PAGE19
  AK18 M_J_CPU0_SA_CB<1> @T6G_MB_LIB.T6G(SCH_1):M_J_CPU0_SA_CB(1)   I159 @T6G_MB_LIB.T6G(SCH_1):PAGE19
  AJ16 M_J_CPU0_SA_CB<0> @T6G_MB_LIB.T6G(SCH_1):M_J_CPU0_SA_CB(0)   I159 @T6G_MB_LIB.T6G(SCH_1):PAGE19
  BA16 M_J_CPU0_SA_CA<4> @T6G_MB_LIB.T6G(SCH_1):M_J_CPU0_SA_CA(4)   I159 @T6G_MB_LIB.T6G(SCH_1):PAGE19
  BA17 M_J_CPU0_SA_CA<3> @T6G_MB_LIB.T6G(SCH_1):M_J_CPU0_SA_CA(3)   I159 @T6G_MB_LIB.T6G(SCH_1):PAGE19
  AY18 M_J_CPU0_SA_CA<2> @T6G_MB_LIB.T6G(SCH_1):M_J_CPU0_SA_CA(2)   I159 @T6G_MB_LIB.T6G(SCH_1):PAGE19
  AY16 M_J_CPU0_SA_CA<1> @T6G_MB_LIB.T6G(SCH_1):M_J_CPU0_SA_CA(1)   I159 @T6G_MB_LIB.T6G(SCH_1):PAGE19
  AW16 M_J_CPU0_SA_CA<0> @T6G_MB_LIB.T6G(SCH_1):M_J_CPU0_SA_CA(0)   I159 @T6G_MB_LIB.T6G(SCH_1):PAGE19
  BP18     NC     NC   I159 @T6G_MB_LIB.T6G(SCH_1):PAGE19
  AW17     NC     NC   I159 @T6G_MB_LIB.T6G(SCH_1):PAGE19
  AV16     NC     NC   I159 @T6G_MB_LIB.T6G(SCH_1):PAGE19
  BN17 M_J_CPU0_SA_RSP<0> @T6G_MB_LIB.T6G(SCH_1):M_J_CPU0_SA_RSP(0)   I159 @T6G_MB_LIB.T6G(SCH_1):PAGE19
  AV18 M_J_CPU0_SA_CS_N<1> @T6G_MB_LIB.T6G(SCH_1):M_J_CPU0_SA_CS_N(1)   I159 @T6G_MB_LIB.T6G(SCH_1):PAGE19
  AU16 M_J_CPU0_SA_CS_N<0> @T6G_MB_LIB.T6G(SCH_1):M_J_CPU0_SA_CS_N(0)   I159 @T6G_MB_LIB.T6G(SCH_1):PAGE19
  BG16     NC     NC   I159 @T6G_MB_LIB.T6G(SCH_1):PAGE19
  BF16     NC     NC   I159 @T6G_MB_LIB.T6G(SCH_1):PAGE19
  BD16 M_J_CPU0_CLK_DN<0> @T6G_MB_LIB.T6G(SCH_1):M_J_CPU0_CLK_DN(0)   I159 @T6G_MB_LIB.T6G(SCH_1):PAGE19
  BC16 M_J_CPU0_CLK_DP<0> @T6G_MB_LIB.T6G(SCH_1):M_J_CPU0_CLK_DP(0)   I159 @T6G_MB_LIB.T6G(SCH_1):PAGE19
  BB18 M_J_CPU0_SA_CA<6> @T6G_MB_LIB.T6G(SCH_1):M_J_CPU0_SA_CA(6)   I159 @T6G_MB_LIB.T6G(SCH_1):PAGE19
  BB16 M_J_CPU0_SA_CA<5> @T6G_MB_LIB.T6G(SCH_1):M_J_CPU0_SA_CA(5)   I159 @T6G_MB_LIB.T6G(SCH_1):PAGE19
  AB16 M_J_CPU0_SA_DQ<22> @T6G_MB_LIB.T6G(SCH_1):M_J_CPU0_SA_DQ(22)   I159 @T6G_MB_LIB.T6G(SCH_1):PAGE19
   Y18 M_J_CPU0_SA_DQS_DN<7> @T6G_MB_LIB.T6G(SCH_1):M_J_CPU0_SA_DQS_DN(7)   I159 @T6G_MB_LIB.T6G(SCH_1):PAGE19
   H18 M_J_CPU0_SA_DQS_DN<5> @T6G_MB_LIB.T6G(SCH_1):M_J_CPU0_SA_DQS_DN(5)   I159 @T6G_MB_LIB.T6G(SCH_1):PAGE19
  AM16 M_J_CPU0_SA_DQS_DN<4> @T6G_MB_LIB.T6G(SCH_1):M_J_CPU0_SA_DQS_DN(4)   I159 @T6G_MB_LIB.T6G(SCH_1):PAGE19
  AG17 M_J_CPU0_SA_DQS_DP<8> @T6G_MB_LIB.T6G(SCH_1):M_J_CPU0_SA_DQS_DP(8)   I159 @T6G_MB_LIB.T6G(SCH_1):PAGE19
  AL16 M_J_CPU0_SA_DQS_DP<4> @T6G_MB_LIB.T6G(SCH_1):M_J_CPU0_SA_DQS_DP(4)   I159 @T6G_MB_LIB.T6G(SCH_1):PAGE19
  CF16 M_J_CPU0_SB_DQ<4> @T6G_MB_LIB.T6G(SCH_1):M_J_CPU0_SB_DQ(4)   I159 @T6G_MB_LIB.T6G(SCH_1):PAGE19
  CD18 M_J_CPU0_SB_DQ<3> @T6G_MB_LIB.T6G(SCH_1):M_J_CPU0_SB_DQ(3)   I159 @T6G_MB_LIB.T6G(SCH_1):PAGE19
  CB16 M_J_CPU0_SB_DQ<0> @T6G_MB_LIB.T6G(SCH_1):M_J_CPU0_SB_DQ(0)   I159 @T6G_MB_LIB.T6G(SCH_1):PAGE19
  AJ17 M_J_CPU0_SA_DQ<31> @T6G_MB_LIB.T6G(SCH_1):M_J_CPU0_SA_DQ(31)   I159 @T6G_MB_LIB.T6G(SCH_1):PAGE19
  CE16 M_J_CPU0_SB_DQS_DN<0> @T6G_MB_LIB.T6G(SCH_1):M_J_CPU0_SB_DQS_DN(0)   I159 @T6G_MB_LIB.T6G(SCH_1):PAGE19
  BW17 M_J_CPU0_SB_DQS_DN<4> @T6G_MB_LIB.T6G(SCH_1):M_J_CPU0_SB_DQS_DN(4)   I159 @T6G_MB_LIB.T6G(SCH_1):PAGE19
  CF18 M_J_CPU0_SB_DQS_DP<5> @T6G_MB_LIB.T6G(SCH_1):M_J_CPU0_SB_DQS_DP(5)   I159 @T6G_MB_LIB.T6G(SCH_1):PAGE19
  CG17 M_J_CPU0_SB_DQ<5> @T6G_MB_LIB.T6G(SCH_1):M_J_CPU0_SB_DQ(5)   I159 @T6G_MB_LIB.T6G(SCH_1):PAGE19
  CG16 M_J_CPU0_SB_DQ<6> @T6G_MB_LIB.T6G(SCH_1):M_J_CPU0_SB_DQ(6)   I159 @T6G_MB_LIB.T6G(SCH_1):PAGE19
  CH18 M_J_CPU0_SB_DQ<7> @T6G_MB_LIB.T6G(SCH_1):M_J_CPU0_SB_DQ(7)   I159 @T6G_MB_LIB.T6G(SCH_1):PAGE19
  BF18 TP_M_J_CPU0_SA_TEST39J @T6G_MB_LIB.T6G(SCH_1):TP_M_J_CPU0_SA_TEST39J   I159 @T6G_MB_LIB.T6G(SCH_1):PAGE19
   M40 GMI_CPU1_G2_CPU0_G0_TX_DN<0> @T6G_MB_LIB.T6G(SCH_1):GMI_CPU1_G2_CPU0_G0_TX_DN(0)   I207 @T6G_MB_LIB.T6G(SCH_1):PAGE22
   K40 GMI_CPU1_G2_CPU0_G0_TX_DN<1> @T6G_MB_LIB.T6G(SCH_1):GMI_CPU1_G2_CPU0_G0_TX_DN(1)   I207 @T6G_MB_LIB.T6G(SCH_1):PAGE22
   H40 GMI_CPU1_G2_CPU0_G0_TX_DN<2> @T6G_MB_LIB.T6G(SCH_1):GMI_CPU1_G2_CPU0_G0_TX_DN(2)   I207 @T6G_MB_LIB.T6G(SCH_1):PAGE22
   L43 GMI_CPU1_G2_CPU0_G0_TX_DN<3> @T6G_MB_LIB.T6G(SCH_1):GMI_CPU1_G2_CPU0_G0_TX_DN(3)   I207 @T6G_MB_LIB.T6G(SCH_1):PAGE22
   G43 GMI_CPU1_G2_CPU0_G0_TX_DN<4> @T6G_MB_LIB.T6G(SCH_1):GMI_CPU1_G2_CPU0_G0_TX_DN(4)   I207 @T6G_MB_LIB.T6G(SCH_1):PAGE22
   J43 GMI_CPU1_G2_CPU0_G0_TX_DN<5> @T6G_MB_LIB.T6G(SCH_1):GMI_CPU1_G2_CPU0_G0_TX_DN(5)   I207 @T6G_MB_LIB.T6G(SCH_1):PAGE22
   L46 GMI_CPU1_G2_CPU0_G0_TX_DN<6> @T6G_MB_LIB.T6G(SCH_1):GMI_CPU1_G2_CPU0_G0_TX_DN(6)   I207 @T6G_MB_LIB.T6G(SCH_1):PAGE22
   G46 GMI_CPU1_G2_CPU0_G0_TX_DN<7> @T6G_MB_LIB.T6G(SCH_1):GMI_CPU1_G2_CPU0_G0_TX_DN(7)   I207 @T6G_MB_LIB.T6G(SCH_1):PAGE22
   J46 GMI_CPU1_G2_CPU0_G0_TX_DN<8> @T6G_MB_LIB.T6G(SCH_1):GMI_CPU1_G2_CPU0_G0_TX_DN(8)   I207 @T6G_MB_LIB.T6G(SCH_1):PAGE22
   L49 GMI_CPU1_G2_CPU0_G0_TX_DN<9> @T6G_MB_LIB.T6G(SCH_1):GMI_CPU1_G2_CPU0_G0_TX_DN(9)   I207 @T6G_MB_LIB.T6G(SCH_1):PAGE22
   G49 GMI_CPU1_G2_CPU0_G0_TX_DN<10> @T6G_MB_LIB.T6G(SCH_1):GMI_CPU1_G2_CPU0_G0_TX_DN(10)   I207 @T6G_MB_LIB.T6G(SCH_1):PAGE22
   J49 GMI_CPU1_G2_CPU0_G0_TX_DN<11> @T6G_MB_LIB.T6G(SCH_1):GMI_CPU1_G2_CPU0_G0_TX_DN(11)   I207 @T6G_MB_LIB.T6G(SCH_1):PAGE22
   L52 GMI_CPU1_G2_CPU0_G0_TX_DN<12> @T6G_MB_LIB.T6G(SCH_1):GMI_CPU1_G2_CPU0_G0_TX_DN(12)   I207 @T6G_MB_LIB.T6G(SCH_1):PAGE22
   G52 GMI_CPU1_G2_CPU0_G0_TX_DN<13> @T6G_MB_LIB.T6G(SCH_1):GMI_CPU1_G2_CPU0_G0_TX_DN(13)   I207 @T6G_MB_LIB.T6G(SCH_1):PAGE22
   J52 GMI_CPU1_G2_CPU0_G0_TX_DN<14> @T6G_MB_LIB.T6G(SCH_1):GMI_CPU1_G2_CPU0_G0_TX_DN(14)   I207 @T6G_MB_LIB.T6G(SCH_1):PAGE22
   N52 GMI_CPU1_G2_CPU0_G0_TX_DN<15> @T6G_MB_LIB.T6G(SCH_1):GMI_CPU1_G2_CPU0_G0_TX_DN(15)   I207 @T6G_MB_LIB.T6G(SCH_1):PAGE22
   M41 GMI_CPU1_G2_CPU0_G0_TX_DP<0> @T6G_MB_LIB.T6G(SCH_1):GMI_CPU1_G2_CPU0_G0_TX_DP(0)   I207 @T6G_MB_LIB.T6G(SCH_1):PAGE22
   K41 GMI_CPU1_G2_CPU0_G0_TX_DP<1> @T6G_MB_LIB.T6G(SCH_1):GMI_CPU1_G2_CPU0_G0_TX_DP(1)   I207 @T6G_MB_LIB.T6G(SCH_1):PAGE22
   H41 GMI_CPU1_G2_CPU0_G0_TX_DP<2> @T6G_MB_LIB.T6G(SCH_1):GMI_CPU1_G2_CPU0_G0_TX_DP(2)   I207 @T6G_MB_LIB.T6G(SCH_1):PAGE22
   L44 GMI_CPU1_G2_CPU0_G0_TX_DP<3> @T6G_MB_LIB.T6G(SCH_1):GMI_CPU1_G2_CPU0_G0_TX_DP(3)   I207 @T6G_MB_LIB.T6G(SCH_1):PAGE22
   G44 GMI_CPU1_G2_CPU0_G0_TX_DP<4> @T6G_MB_LIB.T6G(SCH_1):GMI_CPU1_G2_CPU0_G0_TX_DP(4)   I207 @T6G_MB_LIB.T6G(SCH_1):PAGE22
   J44 GMI_CPU1_G2_CPU0_G0_TX_DP<5> @T6G_MB_LIB.T6G(SCH_1):GMI_CPU1_G2_CPU0_G0_TX_DP(5)   I207 @T6G_MB_LIB.T6G(SCH_1):PAGE22
   L47 GMI_CPU1_G2_CPU0_G0_TX_DP<6> @T6G_MB_LIB.T6G(SCH_1):GMI_CPU1_G2_CPU0_G0_TX_DP(6)   I207 @T6G_MB_LIB.T6G(SCH_1):PAGE22
   G47 GMI_CPU1_G2_CPU0_G0_TX_DP<7> @T6G_MB_LIB.T6G(SCH_1):GMI_CPU1_G2_CPU0_G0_TX_DP(7)   I207 @T6G_MB_LIB.T6G(SCH_1):PAGE22
   J47 GMI_CPU1_G2_CPU0_G0_TX_DP<8> @T6G_MB_LIB.T6G(SCH_1):GMI_CPU1_G2_CPU0_G0_TX_DP(8)   I207 @T6G_MB_LIB.T6G(SCH_1):PAGE22
   L50 GMI_CPU1_G2_CPU0_G0_TX_DP<9> @T6G_MB_LIB.T6G(SCH_1):GMI_CPU1_G2_CPU0_G0_TX_DP(9)   I207 @T6G_MB_LIB.T6G(SCH_1):PAGE22
   G50 GMI_CPU1_G2_CPU0_G0_TX_DP<10> @T6G_MB_LIB.T6G(SCH_1):GMI_CPU1_G2_CPU0_G0_TX_DP(10)   I207 @T6G_MB_LIB.T6G(SCH_1):PAGE22
   J50 GMI_CPU1_G2_CPU0_G0_TX_DP<11> @T6G_MB_LIB.T6G(SCH_1):GMI_CPU1_G2_CPU0_G0_TX_DP(11)   I207 @T6G_MB_LIB.T6G(SCH_1):PAGE22
   L53 GMI_CPU1_G2_CPU0_G0_TX_DP<12> @T6G_MB_LIB.T6G(SCH_1):GMI_CPU1_G2_CPU0_G0_TX_DP(12)   I207 @T6G_MB_LIB.T6G(SCH_1):PAGE22
   G53 GMI_CPU1_G2_CPU0_G0_TX_DP<13> @T6G_MB_LIB.T6G(SCH_1):GMI_CPU1_G2_CPU0_G0_TX_DP(13)   I207 @T6G_MB_LIB.T6G(SCH_1):PAGE22
   J53 GMI_CPU1_G2_CPU0_G0_TX_DP<14> @T6G_MB_LIB.T6G(SCH_1):GMI_CPU1_G2_CPU0_G0_TX_DP(14)   I207 @T6G_MB_LIB.T6G(SCH_1):PAGE22
   N53 GMI_CPU1_G2_CPU0_G0_TX_DP<15> @T6G_MB_LIB.T6G(SCH_1):GMI_CPU1_G2_CPU0_G0_TX_DP(15)   I207 @T6G_MB_LIB.T6G(SCH_1):PAGE22
  AF41 GMI_CPU0_G0_CPU1_G2_TX_DN<0> @T6G_MB_LIB.T6G(SCH_1):GMI_CPU0_G0_CPU1_G2_TX_DN(0)   I207 @T6G_MB_LIB.T6G(SCH_1):PAGE22
  AD41 GMI_CPU0_G0_CPU1_G2_TX_DN<1> @T6G_MB_LIB.T6G(SCH_1):GMI_CPU0_G0_CPU1_G2_TX_DN(1)   I207 @T6G_MB_LIB.T6G(SCH_1):PAGE22
  AB41 GMI_CPU0_G0_CPU1_G2_TX_DN<2> @T6G_MB_LIB.T6G(SCH_1):GMI_CPU0_G0_CPU1_G2_TX_DN(2)   I207 @T6G_MB_LIB.T6G(SCH_1):PAGE22
  AG44 GMI_CPU0_G0_CPU1_G2_TX_DN<3> @T6G_MB_LIB.T6G(SCH_1):GMI_CPU0_G0_CPU1_G2_TX_DN(3)   I207 @T6G_MB_LIB.T6G(SCH_1):PAGE22
  AA44 GMI_CPU0_G0_CPU1_G2_TX_DN<4> @T6G_MB_LIB.T6G(SCH_1):GMI_CPU0_G0_CPU1_G2_TX_DN(4)   I207 @T6G_MB_LIB.T6G(SCH_1):PAGE22
  AC44 GMI_CPU0_G0_CPU1_G2_TX_DN<5> @T6G_MB_LIB.T6G(SCH_1):GMI_CPU0_G0_CPU1_G2_TX_DN(5)   I207 @T6G_MB_LIB.T6G(SCH_1):PAGE22
  AE44 GMI_CPU0_G0_CPU1_G2_TX_DN<6> @T6G_MB_LIB.T6G(SCH_1):GMI_CPU0_G0_CPU1_G2_TX_DN(6)   I207 @T6G_MB_LIB.T6G(SCH_1):PAGE22
  AG47 GMI_CPU0_G0_CPU1_G2_TX_DN<7> @T6G_MB_LIB.T6G(SCH_1):GMI_CPU0_G0_CPU1_G2_TX_DN(7)   I207 @T6G_MB_LIB.T6G(SCH_1):PAGE22
  AC47 GMI_CPU0_G0_CPU1_G2_TX_DN<8> @T6G_MB_LIB.T6G(SCH_1):GMI_CPU0_G0_CPU1_G2_TX_DN(8)   I207 @T6G_MB_LIB.T6G(SCH_1):PAGE22
  AE47 GMI_CPU0_G0_CPU1_G2_TX_DN<9> @T6G_MB_LIB.T6G(SCH_1):GMI_CPU0_G0_CPU1_G2_TX_DN(9)   I207 @T6G_MB_LIB.T6G(SCH_1):PAGE22
  AG50 GMI_CPU0_G0_CPU1_G2_TX_DN<10> @T6G_MB_LIB.T6G(SCH_1):GMI_CPU0_G0_CPU1_G2_TX_DN(10)   I207 @T6G_MB_LIB.T6G(SCH_1):PAGE22
  AC50 GMI_CPU0_G0_CPU1_G2_TX_DN<11> @T6G_MB_LIB.T6G(SCH_1):GMI_CPU0_G0_CPU1_G2_TX_DN(11)   I207 @T6G_MB_LIB.T6G(SCH_1):PAGE22
  AE50 GMI_CPU0_G0_CPU1_G2_TX_DN<12> @T6G_MB_LIB.T6G(SCH_1):GMI_CPU0_G0_CPU1_G2_TX_DN(12)   I207 @T6G_MB_LIB.T6G(SCH_1):PAGE22
  AG53 GMI_CPU0_G0_CPU1_G2_TX_DN<13> @T6G_MB_LIB.T6G(SCH_1):GMI_CPU0_G0_CPU1_G2_TX_DN(13)   I207 @T6G_MB_LIB.T6G(SCH_1):PAGE22
  AC53 GMI_CPU0_G0_CPU1_G2_TX_DN<14> @T6G_MB_LIB.T6G(SCH_1):GMI_CPU0_G0_CPU1_G2_TX_DN(14)   I207 @T6G_MB_LIB.T6G(SCH_1):PAGE22
  AE53 GMI_CPU0_G0_CPU1_G2_TX_DN<15> @T6G_MB_LIB.T6G(SCH_1):GMI_CPU0_G0_CPU1_G2_TX_DN(15)   I207 @T6G_MB_LIB.T6G(SCH_1):PAGE22
  AF40 GMI_CPU0_G0_CPU1_G2_TX_DP<0> @T6G_MB_LIB.T6G(SCH_1):GMI_CPU0_G0_CPU1_G2_TX_DP(0)   I207 @T6G_MB_LIB.T6G(SCH_1):PAGE22
  AD40 GMI_CPU0_G0_CPU1_G2_TX_DP<1> @T6G_MB_LIB.T6G(SCH_1):GMI_CPU0_G0_CPU1_G2_TX_DP(1)   I207 @T6G_MB_LIB.T6G(SCH_1):PAGE22
  AB40 GMI_CPU0_G0_CPU1_G2_TX_DP<2> @T6G_MB_LIB.T6G(SCH_1):GMI_CPU0_G0_CPU1_G2_TX_DP(2)   I207 @T6G_MB_LIB.T6G(SCH_1):PAGE22
  AG43 GMI_CPU0_G0_CPU1_G2_TX_DP<3> @T6G_MB_LIB.T6G(SCH_1):GMI_CPU0_G0_CPU1_G2_TX_DP(3)   I207 @T6G_MB_LIB.T6G(SCH_1):PAGE22
  AA43 GMI_CPU0_G0_CPU1_G2_TX_DP<4> @T6G_MB_LIB.T6G(SCH_1):GMI_CPU0_G0_CPU1_G2_TX_DP(4)   I207 @T6G_MB_LIB.T6G(SCH_1):PAGE22
  AC43 GMI_CPU0_G0_CPU1_G2_TX_DP<5> @T6G_MB_LIB.T6G(SCH_1):GMI_CPU0_G0_CPU1_G2_TX_DP(5)   I207 @T6G_MB_LIB.T6G(SCH_1):PAGE22
  AE43 GMI_CPU0_G0_CPU1_G2_TX_DP<6> @T6G_MB_LIB.T6G(SCH_1):GMI_CPU0_G0_CPU1_G2_TX_DP(6)   I207 @T6G_MB_LIB.T6G(SCH_1):PAGE22
  AG46 GMI_CPU0_G0_CPU1_G2_TX_DP<7> @T6G_MB_LIB.T6G(SCH_1):GMI_CPU0_G0_CPU1_G2_TX_DP(7)   I207 @T6G_MB_LIB.T6G(SCH_1):PAGE22
  AC46 GMI_CPU0_G0_CPU1_G2_TX_DP<8> @T6G_MB_LIB.T6G(SCH_1):GMI_CPU0_G0_CPU1_G2_TX_DP(8)   I207 @T6G_MB_LIB.T6G(SCH_1):PAGE22
  AE46 GMI_CPU0_G0_CPU1_G2_TX_DP<9> @T6G_MB_LIB.T6G(SCH_1):GMI_CPU0_G0_CPU1_G2_TX_DP(9)   I207 @T6G_MB_LIB.T6G(SCH_1):PAGE22
  AG49 GMI_CPU0_G0_CPU1_G2_TX_DP<10> @T6G_MB_LIB.T6G(SCH_1):GMI_CPU0_G0_CPU1_G2_TX_DP(10)   I207 @T6G_MB_LIB.T6G(SCH_1):PAGE22
  AC49 GMI_CPU0_G0_CPU1_G2_TX_DP<11> @T6G_MB_LIB.T6G(SCH_1):GMI_CPU0_G0_CPU1_G2_TX_DP(11)   I207 @T6G_MB_LIB.T6G(SCH_1):PAGE22
  AE49 GMI_CPU0_G0_CPU1_G2_TX_DP<12> @T6G_MB_LIB.T6G(SCH_1):GMI_CPU0_G0_CPU1_G2_TX_DP(12)   I207 @T6G_MB_LIB.T6G(SCH_1):PAGE22
  AG52 GMI_CPU0_G0_CPU1_G2_TX_DP<13> @T6G_MB_LIB.T6G(SCH_1):GMI_CPU0_G0_CPU1_G2_TX_DP(13)   I207 @T6G_MB_LIB.T6G(SCH_1):PAGE22
  AC52 GMI_CPU0_G0_CPU1_G2_TX_DP<14> @T6G_MB_LIB.T6G(SCH_1):GMI_CPU0_G0_CPU1_G2_TX_DP(14)   I207 @T6G_MB_LIB.T6G(SCH_1):PAGE22
  AE52 GMI_CPU0_G0_CPU1_G2_TX_DP<15> @T6G_MB_LIB.T6G(SCH_1):GMI_CPU0_G0_CPU1_G2_TX_DP(15)   I207 @T6G_MB_LIB.T6G(SCH_1):PAGE22
  AL52 GMI_CPU0_G1_CPU1_G3_TX_DP<15> @T6G_MB_LIB.T6G(SCH_1):GMI_CPU0_G1_CPU1_G3_TX_DP(15)   I208 @T6G_MB_LIB.T6G(SCH_1):PAGE22
  AJ52 GMI_CPU0_G1_CPU1_G3_TX_DP<14> @T6G_MB_LIB.T6G(SCH_1):GMI_CPU0_G1_CPU1_G3_TX_DP(14)   I208 @T6G_MB_LIB.T6G(SCH_1):PAGE22
  AN52 GMI_CPU0_G1_CPU1_G3_TX_DP<13> @T6G_MB_LIB.T6G(SCH_1):GMI_CPU0_G1_CPU1_G3_TX_DP(13)   I208 @T6G_MB_LIB.T6G(SCH_1):PAGE22
  AL49 GMI_CPU0_G1_CPU1_G3_TX_DP<12> @T6G_MB_LIB.T6G(SCH_1):GMI_CPU0_G1_CPU1_G3_TX_DP(12)   I208 @T6G_MB_LIB.T6G(SCH_1):PAGE22
  AJ49 GMI_CPU0_G1_CPU1_G3_TX_DP<11> @T6G_MB_LIB.T6G(SCH_1):GMI_CPU0_G1_CPU1_G3_TX_DP(11)   I208 @T6G_MB_LIB.T6G(SCH_1):PAGE22
  AN49 GMI_CPU0_G1_CPU1_G3_TX_DP<10> @T6G_MB_LIB.T6G(SCH_1):GMI_CPU0_G1_CPU1_G3_TX_DP(10)   I208 @T6G_MB_LIB.T6G(SCH_1):PAGE22
  AL46 GMI_CPU0_G1_CPU1_G3_TX_DP<9> @T6G_MB_LIB.T6G(SCH_1):GMI_CPU0_G1_CPU1_G3_TX_DP(9)   I208 @T6G_MB_LIB.T6G(SCH_1):PAGE22
  AJ46 GMI_CPU0_G1_CPU1_G3_TX_DP<8> @T6G_MB_LIB.T6G(SCH_1):GMI_CPU0_G1_CPU1_G3_TX_DP(8)   I208 @T6G_MB_LIB.T6G(SCH_1):PAGE22
  AL53 GMI_CPU0_G1_CPU1_G3_TX_DN<15> @T6G_MB_LIB.T6G(SCH_1):GMI_CPU0_G1_CPU1_G3_TX_DN(15)   I208 @T6G_MB_LIB.T6G(SCH_1):PAGE22
  AJ53 GMI_CPU0_G1_CPU1_G3_TX_DN<14> @T6G_MB_LIB.T6G(SCH_1):GMI_CPU0_G1_CPU1_G3_TX_DN(14)   I208 @T6G_MB_LIB.T6G(SCH_1):PAGE22
  AN53 GMI_CPU0_G1_CPU1_G3_TX_DN<13> @T6G_MB_LIB.T6G(SCH_1):GMI_CPU0_G1_CPU1_G3_TX_DN(13)   I208 @T6G_MB_LIB.T6G(SCH_1):PAGE22
  AL50 GMI_CPU0_G1_CPU1_G3_TX_DN<12> @T6G_MB_LIB.T6G(SCH_1):GMI_CPU0_G1_CPU1_G3_TX_DN(12)   I208 @T6G_MB_LIB.T6G(SCH_1):PAGE22
  AJ50 GMI_CPU0_G1_CPU1_G3_TX_DN<11> @T6G_MB_LIB.T6G(SCH_1):GMI_CPU0_G1_CPU1_G3_TX_DN(11)   I208 @T6G_MB_LIB.T6G(SCH_1):PAGE22
  AN50 GMI_CPU0_G1_CPU1_G3_TX_DN<10> @T6G_MB_LIB.T6G(SCH_1):GMI_CPU0_G1_CPU1_G3_TX_DN(10)   I208 @T6G_MB_LIB.T6G(SCH_1):PAGE22
  AL47 GMI_CPU0_G1_CPU1_G3_TX_DN<9> @T6G_MB_LIB.T6G(SCH_1):GMI_CPU0_G1_CPU1_G3_TX_DN(9)   I208 @T6G_MB_LIB.T6G(SCH_1):PAGE22
  AJ47 GMI_CPU0_G1_CPU1_G3_TX_DN<8> @T6G_MB_LIB.T6G(SCH_1):GMI_CPU0_G1_CPU1_G3_TX_DN(8)   I208 @T6G_MB_LIB.T6G(SCH_1):PAGE22
   U53 GMI_CPU1_G3_CPU0_G1_TX_DP<15> @T6G_MB_LIB.T6G(SCH_1):GMI_CPU1_G3_CPU0_G1_TX_DP(15)   I208 @T6G_MB_LIB.T6G(SCH_1):PAGE22
   R53 GMI_CPU1_G3_CPU0_G1_TX_DP<14> @T6G_MB_LIB.T6G(SCH_1):GMI_CPU1_G3_CPU0_G1_TX_DP(14)   I208 @T6G_MB_LIB.T6G(SCH_1):PAGE22
   W53 GMI_CPU1_G3_CPU0_G1_TX_DP<13> @T6G_MB_LIB.T6G(SCH_1):GMI_CPU1_G3_CPU0_G1_TX_DP(13)   I208 @T6G_MB_LIB.T6G(SCH_1):PAGE22
   U50 GMI_CPU1_G3_CPU0_G1_TX_DP<12> @T6G_MB_LIB.T6G(SCH_1):GMI_CPU1_G3_CPU0_G1_TX_DP(12)   I208 @T6G_MB_LIB.T6G(SCH_1):PAGE22
   R50 GMI_CPU1_G3_CPU0_G1_TX_DP<11> @T6G_MB_LIB.T6G(SCH_1):GMI_CPU1_G3_CPU0_G1_TX_DP(11)   I208 @T6G_MB_LIB.T6G(SCH_1):PAGE22
   N50 GMI_CPU1_G3_CPU0_G1_TX_DP<10> @T6G_MB_LIB.T6G(SCH_1):GMI_CPU1_G3_CPU0_G1_TX_DP(10)   I208 @T6G_MB_LIB.T6G(SCH_1):PAGE22
   W50 GMI_CPU1_G3_CPU0_G1_TX_DP<9> @T6G_MB_LIB.T6G(SCH_1):GMI_CPU1_G3_CPU0_G1_TX_DP(9)   I208 @T6G_MB_LIB.T6G(SCH_1):PAGE22
   R47 GMI_CPU1_G3_CPU0_G1_TX_DP<8> @T6G_MB_LIB.T6G(SCH_1):GMI_CPU1_G3_CPU0_G1_TX_DP(8)   I208 @T6G_MB_LIB.T6G(SCH_1):PAGE22
   U52 GMI_CPU1_G3_CPU0_G1_TX_DN<15> @T6G_MB_LIB.T6G(SCH_1):GMI_CPU1_G3_CPU0_G1_TX_DN(15)   I208 @T6G_MB_LIB.T6G(SCH_1):PAGE22
   R52 GMI_CPU1_G3_CPU0_G1_TX_DN<14> @T6G_MB_LIB.T6G(SCH_1):GMI_CPU1_G3_CPU0_G1_TX_DN(14)   I208 @T6G_MB_LIB.T6G(SCH_1):PAGE22
   W52 GMI_CPU1_G3_CPU0_G1_TX_DN<13> @T6G_MB_LIB.T6G(SCH_1):GMI_CPU1_G3_CPU0_G1_TX_DN(13)   I208 @T6G_MB_LIB.T6G(SCH_1):PAGE22
   U49 GMI_CPU1_G3_CPU0_G1_TX_DN<12> @T6G_MB_LIB.T6G(SCH_1):GMI_CPU1_G3_CPU0_G1_TX_DN(12)   I208 @T6G_MB_LIB.T6G(SCH_1):PAGE22
   R49 GMI_CPU1_G3_CPU0_G1_TX_DN<11> @T6G_MB_LIB.T6G(SCH_1):GMI_CPU1_G3_CPU0_G1_TX_DN(11)   I208 @T6G_MB_LIB.T6G(SCH_1):PAGE22
   N49 GMI_CPU1_G3_CPU0_G1_TX_DN<10> @T6G_MB_LIB.T6G(SCH_1):GMI_CPU1_G3_CPU0_G1_TX_DN(10)   I208 @T6G_MB_LIB.T6G(SCH_1):PAGE22
   W49 GMI_CPU1_G3_CPU0_G1_TX_DN<9> @T6G_MB_LIB.T6G(SCH_1):GMI_CPU1_G3_CPU0_G1_TX_DN(9)   I208 @T6G_MB_LIB.T6G(SCH_1):PAGE22
   R46 GMI_CPU1_G3_CPU0_G1_TX_DN<8> @T6G_MB_LIB.T6G(SCH_1):GMI_CPU1_G3_CPU0_G1_TX_DN(8)   I208 @T6G_MB_LIB.T6G(SCH_1):PAGE22
  AP40 GMI_CPU0_G1_CPU1_G3_TX_DP<0> @T6G_MB_LIB.T6G(SCH_1):GMI_CPU0_G1_CPU1_G3_TX_DP(0)   I208 @T6G_MB_LIB.T6G(SCH_1):PAGE22
  AM40 GMI_CPU0_G1_CPU1_G3_TX_DP<1> @T6G_MB_LIB.T6G(SCH_1):GMI_CPU0_G1_CPU1_G3_TX_DP(1)   I208 @T6G_MB_LIB.T6G(SCH_1):PAGE22
  AH40 GMI_CPU0_G1_CPU1_G3_TX_DP<2> @T6G_MB_LIB.T6G(SCH_1):GMI_CPU0_G1_CPU1_G3_TX_DP(2)   I208 @T6G_MB_LIB.T6G(SCH_1):PAGE22
  AP41 GMI_CPU0_G1_CPU1_G3_TX_DN<0> @T6G_MB_LIB.T6G(SCH_1):GMI_CPU0_G1_CPU1_G3_TX_DN(0)   I208 @T6G_MB_LIB.T6G(SCH_1):PAGE22
   V41 GMI_CPU1_G3_CPU0_G1_TX_DP<0> @T6G_MB_LIB.T6G(SCH_1):GMI_CPU1_G3_CPU0_G1_TX_DP(0)   I208 @T6G_MB_LIB.T6G(SCH_1):PAGE22
  AK40 GMI_CPU0_G1_CPU1_G3_TX_DP<3> @T6G_MB_LIB.T6G(SCH_1):GMI_CPU0_G1_CPU1_G3_TX_DP(3)   I208 @T6G_MB_LIB.T6G(SCH_1):PAGE22
  AM41 GMI_CPU0_G1_CPU1_G3_TX_DN<1> @T6G_MB_LIB.T6G(SCH_1):GMI_CPU0_G1_CPU1_G3_TX_DN(1)   I208 @T6G_MB_LIB.T6G(SCH_1):PAGE22
   T41 GMI_CPU1_G3_CPU0_G1_TX_DP<1> @T6G_MB_LIB.T6G(SCH_1):GMI_CPU1_G3_CPU0_G1_TX_DP(1)   I208 @T6G_MB_LIB.T6G(SCH_1):PAGE22
  AN43 GMI_CPU0_G1_CPU1_G3_TX_DP<4> @T6G_MB_LIB.T6G(SCH_1):GMI_CPU0_G1_CPU1_G3_TX_DP(4)   I208 @T6G_MB_LIB.T6G(SCH_1):PAGE22
  AH41 GMI_CPU0_G1_CPU1_G3_TX_DN<2> @T6G_MB_LIB.T6G(SCH_1):GMI_CPU0_G1_CPU1_G3_TX_DN(2)   I208 @T6G_MB_LIB.T6G(SCH_1):PAGE22
   P41 GMI_CPU1_G3_CPU0_G1_TX_DP<2> @T6G_MB_LIB.T6G(SCH_1):GMI_CPU1_G3_CPU0_G1_TX_DP(2)   I208 @T6G_MB_LIB.T6G(SCH_1):PAGE22
   V40 GMI_CPU1_G3_CPU0_G1_TX_DN<0> @T6G_MB_LIB.T6G(SCH_1):GMI_CPU1_G3_CPU0_G1_TX_DN(0)   I208 @T6G_MB_LIB.T6G(SCH_1):PAGE22
  AJ43 GMI_CPU0_G1_CPU1_G3_TX_DP<5> @T6G_MB_LIB.T6G(SCH_1):GMI_CPU0_G1_CPU1_G3_TX_DP(5)   I208 @T6G_MB_LIB.T6G(SCH_1):PAGE22
  AK41 GMI_CPU0_G1_CPU1_G3_TX_DN<3> @T6G_MB_LIB.T6G(SCH_1):GMI_CPU0_G1_CPU1_G3_TX_DN(3)   I208 @T6G_MB_LIB.T6G(SCH_1):PAGE22
   U44 GMI_CPU1_G3_CPU0_G1_TX_DP<3> @T6G_MB_LIB.T6G(SCH_1):GMI_CPU1_G3_CPU0_G1_TX_DP(3)   I208 @T6G_MB_LIB.T6G(SCH_1):PAGE22
   T40 GMI_CPU1_G3_CPU0_G1_TX_DN<1> @T6G_MB_LIB.T6G(SCH_1):GMI_CPU1_G3_CPU0_G1_TX_DN(1)   I208 @T6G_MB_LIB.T6G(SCH_1):PAGE22
  AL43 GMI_CPU0_G1_CPU1_G3_TX_DP<6> @T6G_MB_LIB.T6G(SCH_1):GMI_CPU0_G1_CPU1_G3_TX_DP(6)   I208 @T6G_MB_LIB.T6G(SCH_1):PAGE22
  AN44 GMI_CPU0_G1_CPU1_G3_TX_DN<4> @T6G_MB_LIB.T6G(SCH_1):GMI_CPU0_G1_CPU1_G3_TX_DN(4)   I208 @T6G_MB_LIB.T6G(SCH_1):PAGE22
   N44 GMI_CPU1_G3_CPU0_G1_TX_DP<4> @T6G_MB_LIB.T6G(SCH_1):GMI_CPU1_G3_CPU0_G1_TX_DP(4)   I208 @T6G_MB_LIB.T6G(SCH_1):PAGE22
   P40 GMI_CPU1_G3_CPU0_G1_TX_DN<2> @T6G_MB_LIB.T6G(SCH_1):GMI_CPU1_G3_CPU0_G1_TX_DN(2)   I208 @T6G_MB_LIB.T6G(SCH_1):PAGE22
  AN46 GMI_CPU0_G1_CPU1_G3_TX_DP<7> @T6G_MB_LIB.T6G(SCH_1):GMI_CPU0_G1_CPU1_G3_TX_DP(7)   I208 @T6G_MB_LIB.T6G(SCH_1):PAGE22
  AJ44 GMI_CPU0_G1_CPU1_G3_TX_DN<5> @T6G_MB_LIB.T6G(SCH_1):GMI_CPU0_G1_CPU1_G3_TX_DN(5)   I208 @T6G_MB_LIB.T6G(SCH_1):PAGE22
   R44 GMI_CPU1_G3_CPU0_G1_TX_DP<5> @T6G_MB_LIB.T6G(SCH_1):GMI_CPU1_G3_CPU0_G1_TX_DP(5)   I208 @T6G_MB_LIB.T6G(SCH_1):PAGE22
   U43 GMI_CPU1_G3_CPU0_G1_TX_DN<3> @T6G_MB_LIB.T6G(SCH_1):GMI_CPU1_G3_CPU0_G1_TX_DN(3)   I208 @T6G_MB_LIB.T6G(SCH_1):PAGE22
  AL44 GMI_CPU0_G1_CPU1_G3_TX_DN<6> @T6G_MB_LIB.T6G(SCH_1):GMI_CPU0_G1_CPU1_G3_TX_DN(6)   I208 @T6G_MB_LIB.T6G(SCH_1):PAGE22
   U47 GMI_CPU1_G3_CPU0_G1_TX_DP<6> @T6G_MB_LIB.T6G(SCH_1):GMI_CPU1_G3_CPU0_G1_TX_DP(6)   I208 @T6G_MB_LIB.T6G(SCH_1):PAGE22
   N43 GMI_CPU1_G3_CPU0_G1_TX_DN<4> @T6G_MB_LIB.T6G(SCH_1):GMI_CPU1_G3_CPU0_G1_TX_DN(4)   I208 @T6G_MB_LIB.T6G(SCH_1):PAGE22
  AN47 GMI_CPU0_G1_CPU1_G3_TX_DN<7> @T6G_MB_LIB.T6G(SCH_1):GMI_CPU0_G1_CPU1_G3_TX_DN(7)   I208 @T6G_MB_LIB.T6G(SCH_1):PAGE22
   N47 GMI_CPU1_G3_CPU0_G1_TX_DP<7> @T6G_MB_LIB.T6G(SCH_1):GMI_CPU1_G3_CPU0_G1_TX_DP(7)   I208 @T6G_MB_LIB.T6G(SCH_1):PAGE22
   R43 GMI_CPU1_G3_CPU0_G1_TX_DN<5> @T6G_MB_LIB.T6G(SCH_1):GMI_CPU1_G3_CPU0_G1_TX_DN(5)   I208 @T6G_MB_LIB.T6G(SCH_1):PAGE22
   U46 GMI_CPU1_G3_CPU0_G1_TX_DN<6> @T6G_MB_LIB.T6G(SCH_1):GMI_CPU1_G3_CPU0_G1_TX_DN(6)   I208 @T6G_MB_LIB.T6G(SCH_1):PAGE22
   N46 GMI_CPU1_G3_CPU0_G1_TX_DN<7> @T6G_MB_LIB.T6G(SCH_1):GMI_CPU1_G3_CPU0_G1_TX_DN(7)   I208 @T6G_MB_LIB.T6G(SCH_1):PAGE22
   G29 GMI_CPU0_G2_CPU1_G0_TX_DP<8> @T6G_MB_LIB.T6G(SCH_1):GMI_CPU0_G2_CPU1_G0_TX_DP(8)   I215 @T6G_MB_LIB.T6G(SCH_1):PAGE23
   G30 GMI_CPU0_G2_CPU1_G0_TX_DN<8> @T6G_MB_LIB.T6G(SCH_1):GMI_CPU0_G2_CPU1_G0_TX_DN(8)   I215 @T6G_MB_LIB.T6G(SCH_1):PAGE23
   J32 GMI_CPU0_G2_CPU1_G0_TX_DP<10> @T6G_MB_LIB.T6G(SCH_1):GMI_CPU0_G2_CPU1_G0_TX_DP(10)   I215 @T6G_MB_LIB.T6G(SCH_1):PAGE23
   J33 GMI_CPU0_G2_CPU1_G0_TX_DN<10> @T6G_MB_LIB.T6G(SCH_1):GMI_CPU0_G2_CPU1_G0_TX_DN(10)   I215 @T6G_MB_LIB.T6G(SCH_1):PAGE23
   L32 GMI_CPU0_G2_CPU1_G0_TX_DP<12> @T6G_MB_LIB.T6G(SCH_1):GMI_CPU0_G2_CPU1_G0_TX_DP(12)   I215 @T6G_MB_LIB.T6G(SCH_1):PAGE23
   L33 GMI_CPU0_G2_CPU1_G0_TX_DN<12> @T6G_MB_LIB.T6G(SCH_1):GMI_CPU0_G2_CPU1_G0_TX_DN(12)   I215 @T6G_MB_LIB.T6G(SCH_1):PAGE23
   K35 GMI_CPU0_G2_CPU1_G0_TX_DP<14> @T6G_MB_LIB.T6G(SCH_1):GMI_CPU0_G2_CPU1_G0_TX_DP(14)   I215 @T6G_MB_LIB.T6G(SCH_1):PAGE23
   K36 GMI_CPU0_G2_CPU1_G0_TX_DN<14> @T6G_MB_LIB.T6G(SCH_1):GMI_CPU0_G2_CPU1_G0_TX_DN(14)   I215 @T6G_MB_LIB.T6G(SCH_1):PAGE23
   L29 GMI_CPU0_G2_CPU1_G0_TX_DP<9> @T6G_MB_LIB.T6G(SCH_1):GMI_CPU0_G2_CPU1_G0_TX_DP(9)   I215 @T6G_MB_LIB.T6G(SCH_1):PAGE23
   L30 GMI_CPU0_G2_CPU1_G0_TX_DN<9> @T6G_MB_LIB.T6G(SCH_1):GMI_CPU0_G2_CPU1_G0_TX_DN(9)   I215 @T6G_MB_LIB.T6G(SCH_1):PAGE23
   G32 GMI_CPU0_G2_CPU1_G0_TX_DP<11> @T6G_MB_LIB.T6G(SCH_1):GMI_CPU0_G2_CPU1_G0_TX_DP(11)   I215 @T6G_MB_LIB.T6G(SCH_1):PAGE23
   G33 GMI_CPU0_G2_CPU1_G0_TX_DN<11> @T6G_MB_LIB.T6G(SCH_1):GMI_CPU0_G2_CPU1_G0_TX_DN(11)   I215 @T6G_MB_LIB.T6G(SCH_1):PAGE23
   H35 GMI_CPU0_G2_CPU1_G0_TX_DP<13> @T6G_MB_LIB.T6G(SCH_1):GMI_CPU0_G2_CPU1_G0_TX_DP(13)   I215 @T6G_MB_LIB.T6G(SCH_1):PAGE23
   H36 GMI_CPU0_G2_CPU1_G0_TX_DN<13> @T6G_MB_LIB.T6G(SCH_1):GMI_CPU0_G2_CPU1_G0_TX_DN(13)   I215 @T6G_MB_LIB.T6G(SCH_1):PAGE23
   M35 GMI_CPU0_G2_CPU1_G0_TX_DP<15> @T6G_MB_LIB.T6G(SCH_1):GMI_CPU0_G2_CPU1_G0_TX_DP(15)   I215 @T6G_MB_LIB.T6G(SCH_1):PAGE23
   M36 GMI_CPU0_G2_CPU1_G0_TX_DN<15> @T6G_MB_LIB.T6G(SCH_1):GMI_CPU0_G2_CPU1_G0_TX_DN(15)   I215 @T6G_MB_LIB.T6G(SCH_1):PAGE23
  AG30 GMI_CPU1_G0_CPU0_G2_TX_DP<8> @T6G_MB_LIB.T6G(SCH_1):GMI_CPU1_G0_CPU0_G2_TX_DP(8)   I215 @T6G_MB_LIB.T6G(SCH_1):PAGE23
  AG29 GMI_CPU1_G0_CPU0_G2_TX_DN<8> @T6G_MB_LIB.T6G(SCH_1):GMI_CPU1_G0_CPU0_G2_TX_DN(8)   I215 @T6G_MB_LIB.T6G(SCH_1):PAGE23
  AC33 GMI_CPU1_G0_CPU0_G2_TX_DP<10> @T6G_MB_LIB.T6G(SCH_1):GMI_CPU1_G0_CPU0_G2_TX_DP(10)   I215 @T6G_MB_LIB.T6G(SCH_1):PAGE23
  AC32 GMI_CPU1_G0_CPU0_G2_TX_DN<10> @T6G_MB_LIB.T6G(SCH_1):GMI_CPU1_G0_CPU0_G2_TX_DN(10)   I215 @T6G_MB_LIB.T6G(SCH_1):PAGE23
  AG33 GMI_CPU1_G0_CPU0_G2_TX_DP<12> @T6G_MB_LIB.T6G(SCH_1):GMI_CPU1_G0_CPU0_G2_TX_DP(12)   I215 @T6G_MB_LIB.T6G(SCH_1):PAGE23
  AG32 GMI_CPU1_G0_CPU0_G2_TX_DN<12> @T6G_MB_LIB.T6G(SCH_1):GMI_CPU1_G0_CPU0_G2_TX_DN(12)   I215 @T6G_MB_LIB.T6G(SCH_1):PAGE23
  AD36 GMI_CPU1_G0_CPU0_G2_TX_DP<14> @T6G_MB_LIB.T6G(SCH_1):GMI_CPU1_G0_CPU0_G2_TX_DP(14)   I215 @T6G_MB_LIB.T6G(SCH_1):PAGE23
  AD35 GMI_CPU1_G0_CPU0_G2_TX_DN<14> @T6G_MB_LIB.T6G(SCH_1):GMI_CPU1_G0_CPU0_G2_TX_DN(14)   I215 @T6G_MB_LIB.T6G(SCH_1):PAGE23
  AE33 GMI_CPU1_G0_CPU0_G2_TX_DP<9> @T6G_MB_LIB.T6G(SCH_1):GMI_CPU1_G0_CPU0_G2_TX_DP(9)   I215 @T6G_MB_LIB.T6G(SCH_1):PAGE23
  AE32 GMI_CPU1_G0_CPU0_G2_TX_DN<9> @T6G_MB_LIB.T6G(SCH_1):GMI_CPU1_G0_CPU0_G2_TX_DN(9)   I215 @T6G_MB_LIB.T6G(SCH_1):PAGE23
  AA33 GMI_CPU1_G0_CPU0_G2_TX_DP<11> @T6G_MB_LIB.T6G(SCH_1):GMI_CPU1_G0_CPU0_G2_TX_DP(11)   I215 @T6G_MB_LIB.T6G(SCH_1):PAGE23
  AA32 GMI_CPU1_G0_CPU0_G2_TX_DN<11> @T6G_MB_LIB.T6G(SCH_1):GMI_CPU1_G0_CPU0_G2_TX_DN(11)   I215 @T6G_MB_LIB.T6G(SCH_1):PAGE23
  AB36 GMI_CPU1_G0_CPU0_G2_TX_DP<13> @T6G_MB_LIB.T6G(SCH_1):GMI_CPU1_G0_CPU0_G2_TX_DP(13)   I215 @T6G_MB_LIB.T6G(SCH_1):PAGE23
  AB35 GMI_CPU1_G0_CPU0_G2_TX_DN<13> @T6G_MB_LIB.T6G(SCH_1):GMI_CPU1_G0_CPU0_G2_TX_DN(13)   I215 @T6G_MB_LIB.T6G(SCH_1):PAGE23
  AF36 GMI_CPU1_G0_CPU0_G2_TX_DP<15> @T6G_MB_LIB.T6G(SCH_1):GMI_CPU1_G0_CPU0_G2_TX_DP(15)   I215 @T6G_MB_LIB.T6G(SCH_1):PAGE23
  AF35 GMI_CPU1_G0_CPU0_G2_TX_DN<15> @T6G_MB_LIB.T6G(SCH_1):GMI_CPU1_G0_CPU0_G2_TX_DN(15)   I215 @T6G_MB_LIB.T6G(SCH_1):PAGE23
   J23 GMI_CPU0_G2_CPU1_G0_TX_DP<1> @T6G_MB_LIB.T6G(SCH_1):GMI_CPU0_G2_CPU1_G0_TX_DP(1)   I215 @T6G_MB_LIB.T6G(SCH_1):PAGE23
   G23 GMI_CPU0_G2_CPU1_G0_TX_DP<2> @T6G_MB_LIB.T6G(SCH_1):GMI_CPU0_G2_CPU1_G0_TX_DP(2)   I215 @T6G_MB_LIB.T6G(SCH_1):PAGE23
   N24 GMI_CPU0_G2_CPU1_G0_TX_DN<0> @T6G_MB_LIB.T6G(SCH_1):GMI_CPU0_G2_CPU1_G0_TX_DN(0)   I215 @T6G_MB_LIB.T6G(SCH_1):PAGE23
  AE24 GMI_CPU1_G0_CPU0_G2_TX_DP<0> @T6G_MB_LIB.T6G(SCH_1):GMI_CPU1_G0_CPU0_G2_TX_DP(0)   I215 @T6G_MB_LIB.T6G(SCH_1):PAGE23
   L23 GMI_CPU0_G2_CPU1_G0_TX_DP<3> @T6G_MB_LIB.T6G(SCH_1):GMI_CPU0_G2_CPU1_G0_TX_DP(3)   I215 @T6G_MB_LIB.T6G(SCH_1):PAGE23
   J24 GMI_CPU0_G2_CPU1_G0_TX_DN<1> @T6G_MB_LIB.T6G(SCH_1):GMI_CPU0_G2_CPU1_G0_TX_DN(1)   I215 @T6G_MB_LIB.T6G(SCH_1):PAGE23
  AC24 GMI_CPU1_G0_CPU0_G2_TX_DP<1> @T6G_MB_LIB.T6G(SCH_1):GMI_CPU1_G0_CPU0_G2_TX_DP(1)   I215 @T6G_MB_LIB.T6G(SCH_1):PAGE23
   J26 GMI_CPU0_G2_CPU1_G0_TX_DP<4> @T6G_MB_LIB.T6G(SCH_1):GMI_CPU0_G2_CPU1_G0_TX_DP(4)   I215 @T6G_MB_LIB.T6G(SCH_1):PAGE23
   G24 GMI_CPU0_G2_CPU1_G0_TX_DN<2> @T6G_MB_LIB.T6G(SCH_1):GMI_CPU0_G2_CPU1_G0_TX_DN(2)   I215 @T6G_MB_LIB.T6G(SCH_1):PAGE23
  AG24 GMI_CPU1_G0_CPU0_G2_TX_DP<2> @T6G_MB_LIB.T6G(SCH_1):GMI_CPU1_G0_CPU0_G2_TX_DP(2)   I215 @T6G_MB_LIB.T6G(SCH_1):PAGE23
  AE23 GMI_CPU1_G0_CPU0_G2_TX_DN<0> @T6G_MB_LIB.T6G(SCH_1):GMI_CPU1_G0_CPU0_G2_TX_DN(0)   I215 @T6G_MB_LIB.T6G(SCH_1):PAGE23
   G26 GMI_CPU0_G2_CPU1_G0_TX_DP<5> @T6G_MB_LIB.T6G(SCH_1):GMI_CPU0_G2_CPU1_G0_TX_DP(5)   I215 @T6G_MB_LIB.T6G(SCH_1):PAGE23
   L24 GMI_CPU0_G2_CPU1_G0_TX_DN<3> @T6G_MB_LIB.T6G(SCH_1):GMI_CPU0_G2_CPU1_G0_TX_DN(3)   I215 @T6G_MB_LIB.T6G(SCH_1):PAGE23
  AE27 GMI_CPU1_G0_CPU0_G2_TX_DP<3> @T6G_MB_LIB.T6G(SCH_1):GMI_CPU1_G0_CPU0_G2_TX_DP(3)   I215 @T6G_MB_LIB.T6G(SCH_1):PAGE23
  AC23 GMI_CPU1_G0_CPU0_G2_TX_DN<1> @T6G_MB_LIB.T6G(SCH_1):GMI_CPU1_G0_CPU0_G2_TX_DN(1)   I215 @T6G_MB_LIB.T6G(SCH_1):PAGE23
   L26 GMI_CPU0_G2_CPU1_G0_TX_DP<6> @T6G_MB_LIB.T6G(SCH_1):GMI_CPU0_G2_CPU1_G0_TX_DP(6)   I215 @T6G_MB_LIB.T6G(SCH_1):PAGE23
   J27 GMI_CPU0_G2_CPU1_G0_TX_DN<4> @T6G_MB_LIB.T6G(SCH_1):GMI_CPU0_G2_CPU1_G0_TX_DN(4)   I215 @T6G_MB_LIB.T6G(SCH_1):PAGE23
  AC27 GMI_CPU1_G0_CPU0_G2_TX_DP<4> @T6G_MB_LIB.T6G(SCH_1):GMI_CPU1_G0_CPU0_G2_TX_DP(4)   I215 @T6G_MB_LIB.T6G(SCH_1):PAGE23
  AG23 GMI_CPU1_G0_CPU0_G2_TX_DN<2> @T6G_MB_LIB.T6G(SCH_1):GMI_CPU1_G0_CPU0_G2_TX_DN(2)   I215 @T6G_MB_LIB.T6G(SCH_1):PAGE23
   J29 GMI_CPU0_G2_CPU1_G0_TX_DP<7> @T6G_MB_LIB.T6G(SCH_1):GMI_CPU0_G2_CPU1_G0_TX_DP(7)   I215 @T6G_MB_LIB.T6G(SCH_1):PAGE23
   G27 GMI_CPU0_G2_CPU1_G0_TX_DN<5> @T6G_MB_LIB.T6G(SCH_1):GMI_CPU0_G2_CPU1_G0_TX_DN(5)   I215 @T6G_MB_LIB.T6G(SCH_1):PAGE23
  AG27 GMI_CPU1_G0_CPU0_G2_TX_DP<5> @T6G_MB_LIB.T6G(SCH_1):GMI_CPU1_G0_CPU0_G2_TX_DP(5)   I215 @T6G_MB_LIB.T6G(SCH_1):PAGE23
  AE26 GMI_CPU1_G0_CPU0_G2_TX_DN<3> @T6G_MB_LIB.T6G(SCH_1):GMI_CPU1_G0_CPU0_G2_TX_DN(3)   I215 @T6G_MB_LIB.T6G(SCH_1):PAGE23
   L27 GMI_CPU0_G2_CPU1_G0_TX_DN<6> @T6G_MB_LIB.T6G(SCH_1):GMI_CPU0_G2_CPU1_G0_TX_DN(6)   I215 @T6G_MB_LIB.T6G(SCH_1):PAGE23
  AE30 GMI_CPU1_G0_CPU0_G2_TX_DP<6> @T6G_MB_LIB.T6G(SCH_1):GMI_CPU1_G0_CPU0_G2_TX_DP(6)   I215 @T6G_MB_LIB.T6G(SCH_1):PAGE23
  AC26 GMI_CPU1_G0_CPU0_G2_TX_DN<4> @T6G_MB_LIB.T6G(SCH_1):GMI_CPU1_G0_CPU0_G2_TX_DN(4)   I215 @T6G_MB_LIB.T6G(SCH_1):PAGE23
   J30 GMI_CPU0_G2_CPU1_G0_TX_DN<7> @T6G_MB_LIB.T6G(SCH_1):GMI_CPU0_G2_CPU1_G0_TX_DN(7)   I215 @T6G_MB_LIB.T6G(SCH_1):PAGE23
  AC30 GMI_CPU1_G0_CPU0_G2_TX_DP<7> @T6G_MB_LIB.T6G(SCH_1):GMI_CPU1_G0_CPU0_G2_TX_DP(7)   I215 @T6G_MB_LIB.T6G(SCH_1):PAGE23
  AG26 GMI_CPU1_G0_CPU0_G2_TX_DN<5> @T6G_MB_LIB.T6G(SCH_1):GMI_CPU1_G0_CPU0_G2_TX_DN(5)   I215 @T6G_MB_LIB.T6G(SCH_1):PAGE23
  AE29 GMI_CPU1_G0_CPU0_G2_TX_DN<6> @T6G_MB_LIB.T6G(SCH_1):GMI_CPU1_G0_CPU0_G2_TX_DN(6)   I215 @T6G_MB_LIB.T6G(SCH_1):PAGE23
  AC29 GMI_CPU1_G0_CPU0_G2_TX_DN<7> @T6G_MB_LIB.T6G(SCH_1):GMI_CPU1_G0_CPU0_G2_TX_DN(7)   I215 @T6G_MB_LIB.T6G(SCH_1):PAGE23
   N23 GMI_CPU0_G2_CPU1_G0_TX_DP<0> @T6G_MB_LIB.T6G(SCH_1):GMI_CPU0_G2_CPU1_G0_TX_DP(0)   I215 @T6G_MB_LIB.T6G(SCH_1):PAGE23
   P35 P5E_CPU0_G3_TX_DP<13> @T6G_MB_LIB.T6G(SCH_1):P5E_CPU0_G3_TX_DP(13)   I216 @T6G_MB_LIB.T6G(SCH_1):PAGE23
   R32 P5E_CPU0_G3_TX_DP<10> @T6G_MB_LIB.T6G(SCH_1):P5E_CPU0_G3_TX_DP(10)   I216 @T6G_MB_LIB.T6G(SCH_1):PAGE23
  AN26 P5E_CPU0_G3_RX_DN<5> @T6G_MB_LIB.T6G(SCH_1):P5E_CPU0_G3_RX_DN(5)   I216 @T6G_MB_LIB.T6G(SCH_1):PAGE23
   W24 P5E_CPU0_G3_TX_DN<2> @T6G_MB_LIB.T6G(SCH_1):P5E_CPU0_G3_TX_DN(2)   I216 @T6G_MB_LIB.T6G(SCH_1):PAGE23
  AK36 P5E_CPU0_G3_RX_DP<12> @T6G_MB_LIB.T6G(SCH_1):P5E_CPU0_G3_RX_DP(12)   I216 @T6G_MB_LIB.T6G(SCH_1):PAGE23
  AL24 P5E_CPU0_G3_RX_DP<0> @T6G_MB_LIB.T6G(SCH_1):P5E_CPU0_G3_RX_DP(0)   I216 @T6G_MB_LIB.T6G(SCH_1):PAGE23
   T36 P5E_CPU0_G3_TX_DN<14> @T6G_MB_LIB.T6G(SCH_1):P5E_CPU0_G3_TX_DN(14)   I216 @T6G_MB_LIB.T6G(SCH_1):PAGE23
   N33 P5E_CPU0_G3_TX_DN<11> @T6G_MB_LIB.T6G(SCH_1):P5E_CPU0_G3_TX_DN(11)   I216 @T6G_MB_LIB.T6G(SCH_1):PAGE23
   N27 P5E_CPU0_G3_TX_DN<5> @T6G_MB_LIB.T6G(SCH_1):P5E_CPU0_G3_TX_DN(5)   I216 @T6G_MB_LIB.T6G(SCH_1):PAGE23
  AP36 P5E_CPU0_G3_RX_DP<15> @T6G_MB_LIB.T6G(SCH_1):P5E_CPU0_G3_RX_DP(15)   I216 @T6G_MB_LIB.T6G(SCH_1):PAGE23
  AL30 P5E_CPU0_G3_RX_DP<6> @T6G_MB_LIB.T6G(SCH_1):P5E_CPU0_G3_RX_DP(6)   I216 @T6G_MB_LIB.T6G(SCH_1):PAGE23
  AL27 P5E_CPU0_G3_RX_DP<3> @T6G_MB_LIB.T6G(SCH_1):P5E_CPU0_G3_RX_DP(3)   I216 @T6G_MB_LIB.T6G(SCH_1):PAGE23
   U26 P5E_CPU0_G3_TX_DP<3> @T6G_MB_LIB.T6G(SCH_1):P5E_CPU0_G3_TX_DP(3)   I216 @T6G_MB_LIB.T6G(SCH_1):PAGE23
   U23 P5E_CPU0_G3_TX_DP<0> @T6G_MB_LIB.T6G(SCH_1):P5E_CPU0_G3_TX_DP(0)   I216 @T6G_MB_LIB.T6G(SCH_1):PAGE23
  AJ32 P5E_CPU0_G3_RX_DN<10> @T6G_MB_LIB.T6G(SCH_1):P5E_CPU0_G3_RX_DN(10)   I216 @T6G_MB_LIB.T6G(SCH_1):PAGE23
   W26 P5E_CPU0_G3_TX_DP<6> @T6G_MB_LIB.T6G(SCH_1):P5E_CPU0_G3_TX_DP(6)   I216 @T6G_MB_LIB.T6G(SCH_1):PAGE23
  AH35 P5E_CPU0_G3_RX_DN<13> @T6G_MB_LIB.T6G(SCH_1):P5E_CPU0_G3_RX_DN(13)   I216 @T6G_MB_LIB.T6G(SCH_1):PAGE23
   N32 P5E_CPU0_G3_TX_DP<11> @T6G_MB_LIB.T6G(SCH_1):P5E_CPU0_G3_TX_DP(11)   I216 @T6G_MB_LIB.T6G(SCH_1):PAGE23
  AN30 P5E_CPU0_G3_RX_DP<8> @T6G_MB_LIB.T6G(SCH_1):P5E_CPU0_G3_RX_DP(8)   I216 @T6G_MB_LIB.T6G(SCH_1):PAGE23
  AL26 P5E_CPU0_G3_RX_DN<3> @T6G_MB_LIB.T6G(SCH_1):P5E_CPU0_G3_RX_DN(3)   I216 @T6G_MB_LIB.T6G(SCH_1):PAGE23
  AL23 P5E_CPU0_G3_RX_DN<0> @T6G_MB_LIB.T6G(SCH_1):P5E_CPU0_G3_RX_DN(0)   I216 @T6G_MB_LIB.T6G(SCH_1):PAGE23
   T35 P5E_CPU0_G3_TX_DP<14> @T6G_MB_LIB.T6G(SCH_1):P5E_CPU0_G3_TX_DP(14)   I216 @T6G_MB_LIB.T6G(SCH_1):PAGE23
   N29 P5E_CPU0_G3_TX_DP<8> @T6G_MB_LIB.T6G(SCH_1):P5E_CPU0_G3_TX_DP(8)   I216 @T6G_MB_LIB.T6G(SCH_1):PAGE23
   U24 P5E_CPU0_G3_TX_DN<0> @T6G_MB_LIB.T6G(SCH_1):P5E_CPU0_G3_TX_DN(0)   I216 @T6G_MB_LIB.T6G(SCH_1):PAGE23
  AL29 P5E_CPU0_G3_RX_DN<6> @T6G_MB_LIB.T6G(SCH_1):P5E_CPU0_G3_RX_DN(6)   I216 @T6G_MB_LIB.T6G(SCH_1):PAGE23
   W27 P5E_CPU0_G3_TX_DN<6> @T6G_MB_LIB.T6G(SCH_1):P5E_CPU0_G3_TX_DN(6)   I216 @T6G_MB_LIB.T6G(SCH_1):PAGE23
   U27 P5E_CPU0_G3_TX_DN<3> @T6G_MB_LIB.T6G(SCH_1):P5E_CPU0_G3_TX_DN(3)   I216 @T6G_MB_LIB.T6G(SCH_1):PAGE23
  AH36 P5E_CPU0_G3_RX_DP<13> @T6G_MB_LIB.T6G(SCH_1):P5E_CPU0_G3_RX_DP(13)   I216 @T6G_MB_LIB.T6G(SCH_1):PAGE23
  AJ33 P5E_CPU0_G3_RX_DP<10> @T6G_MB_LIB.T6G(SCH_1):P5E_CPU0_G3_RX_DP(10)   I216 @T6G_MB_LIB.T6G(SCH_1):PAGE23
  AJ27 P5E_CPU0_G3_RX_DP<4> @T6G_MB_LIB.T6G(SCH_1):P5E_CPU0_G3_RX_DP(4)   I216 @T6G_MB_LIB.T6G(SCH_1):PAGE23
  AJ24 P5E_CPU0_G3_RX_DP<1> @T6G_MB_LIB.T6G(SCH_1):P5E_CPU0_G3_RX_DP(1)   I216 @T6G_MB_LIB.T6G(SCH_1):PAGE23
   V36 P5E_CPU0_G3_TX_DN<15> @T6G_MB_LIB.T6G(SCH_1):P5E_CPU0_G3_TX_DN(15)   I216 @T6G_MB_LIB.T6G(SCH_1):PAGE23
   U33 P5E_CPU0_G3_TX_DN<12> @T6G_MB_LIB.T6G(SCH_1):P5E_CPU0_G3_TX_DN(12)   I216 @T6G_MB_LIB.T6G(SCH_1):PAGE23
  AN29 P5E_CPU0_G3_RX_DN<8> @T6G_MB_LIB.T6G(SCH_1):P5E_CPU0_G3_RX_DN(8)   I216 @T6G_MB_LIB.T6G(SCH_1):PAGE23
  AJ30 P5E_CPU0_G3_RX_DP<7> @T6G_MB_LIB.T6G(SCH_1):P5E_CPU0_G3_RX_DP(7)   I216 @T6G_MB_LIB.T6G(SCH_1):PAGE23
   R26 P5E_CPU0_G3_TX_DP<4> @T6G_MB_LIB.T6G(SCH_1):P5E_CPU0_G3_TX_DP(4)   I216 @T6G_MB_LIB.T6G(SCH_1):PAGE23
   R23 P5E_CPU0_G3_TX_DP<1> @T6G_MB_LIB.T6G(SCH_1):P5E_CPU0_G3_TX_DP(1)   I216 @T6G_MB_LIB.T6G(SCH_1):PAGE23
  AM35 P5E_CPU0_G3_RX_DN<14> @T6G_MB_LIB.T6G(SCH_1):P5E_CPU0_G3_RX_DN(14)   I216 @T6G_MB_LIB.T6G(SCH_1):PAGE23
  AN32 P5E_CPU0_G3_RX_DN<11> @T6G_MB_LIB.T6G(SCH_1):P5E_CPU0_G3_RX_DN(11)   I216 @T6G_MB_LIB.T6G(SCH_1):PAGE23
   N30 P5E_CPU0_G3_TX_DN<8> @T6G_MB_LIB.T6G(SCH_1):P5E_CPU0_G3_TX_DN(8)   I216 @T6G_MB_LIB.T6G(SCH_1):PAGE23
   R29 P5E_CPU0_G3_TX_DP<7> @T6G_MB_LIB.T6G(SCH_1):P5E_CPU0_G3_TX_DP(7)   I216 @T6G_MB_LIB.T6G(SCH_1):PAGE23
  AL33 P5E_CPU0_G3_RX_DP<9> @T6G_MB_LIB.T6G(SCH_1):P5E_CPU0_G3_RX_DP(9)   I216 @T6G_MB_LIB.T6G(SCH_1):PAGE23
   U32 P5E_CPU0_G3_TX_DP<12> @T6G_MB_LIB.T6G(SCH_1):P5E_CPU0_G3_TX_DP(12)   I216 @T6G_MB_LIB.T6G(SCH_1):PAGE23
  AJ29 P5E_CPU0_G3_RX_DN<7> @T6G_MB_LIB.T6G(SCH_1):P5E_CPU0_G3_RX_DN(7)   I216 @T6G_MB_LIB.T6G(SCH_1):PAGE23
  AJ26 P5E_CPU0_G3_RX_DN<4> @T6G_MB_LIB.T6G(SCH_1):P5E_CPU0_G3_RX_DN(4)   I216 @T6G_MB_LIB.T6G(SCH_1):PAGE23
  AJ23 P5E_CPU0_G3_RX_DN<1> @T6G_MB_LIB.T6G(SCH_1):P5E_CPU0_G3_RX_DN(1)   I216 @T6G_MB_LIB.T6G(SCH_1):PAGE23
   V35 P5E_CPU0_G3_TX_DP<15> @T6G_MB_LIB.T6G(SCH_1):P5E_CPU0_G3_TX_DP(15)   I216 @T6G_MB_LIB.T6G(SCH_1):PAGE23
   U29 P5E_CPU0_G3_TX_DP<9> @T6G_MB_LIB.T6G(SCH_1):P5E_CPU0_G3_TX_DP(9)   I216 @T6G_MB_LIB.T6G(SCH_1):PAGE23
   R24 P5E_CPU0_G3_TX_DN<1> @T6G_MB_LIB.T6G(SCH_1):P5E_CPU0_G3_TX_DN(1)   I216 @T6G_MB_LIB.T6G(SCH_1):PAGE23
  AN33 P5E_CPU0_G3_RX_DP<11> @T6G_MB_LIB.T6G(SCH_1):P5E_CPU0_G3_RX_DP(11)   I216 @T6G_MB_LIB.T6G(SCH_1):PAGE23
   P36 P5E_CPU0_G3_TX_DN<13> @T6G_MB_LIB.T6G(SCH_1):P5E_CPU0_G3_TX_DN(13)   I216 @T6G_MB_LIB.T6G(SCH_1):PAGE23
   R33 P5E_CPU0_G3_TX_DN<10> @T6G_MB_LIB.T6G(SCH_1):P5E_CPU0_G3_TX_DN(10)   I216 @T6G_MB_LIB.T6G(SCH_1):PAGE23
   R30 P5E_CPU0_G3_TX_DN<7> @T6G_MB_LIB.T6G(SCH_1):P5E_CPU0_G3_TX_DN(7)   I216 @T6G_MB_LIB.T6G(SCH_1):PAGE23
   R27 P5E_CPU0_G3_TX_DN<4> @T6G_MB_LIB.T6G(SCH_1):P5E_CPU0_G3_TX_DN(4)   I216 @T6G_MB_LIB.T6G(SCH_1):PAGE23
  AM36 P5E_CPU0_G3_RX_DP<14> @T6G_MB_LIB.T6G(SCH_1):P5E_CPU0_G3_RX_DP(14)   I216 @T6G_MB_LIB.T6G(SCH_1):PAGE23
  AN27 P5E_CPU0_G3_RX_DP<5> @T6G_MB_LIB.T6G(SCH_1):P5E_CPU0_G3_RX_DP(5)   I216 @T6G_MB_LIB.T6G(SCH_1):PAGE23
  AN24 P5E_CPU0_G3_RX_DP<2> @T6G_MB_LIB.T6G(SCH_1):P5E_CPU0_G3_RX_DP(2)   I216 @T6G_MB_LIB.T6G(SCH_1):PAGE23
   W23 P5E_CPU0_G3_TX_DP<2> @T6G_MB_LIB.T6G(SCH_1):P5E_CPU0_G3_TX_DP(2)   I216 @T6G_MB_LIB.T6G(SCH_1):PAGE23
  AL32 P5E_CPU0_G3_RX_DN<9> @T6G_MB_LIB.T6G(SCH_1):P5E_CPU0_G3_RX_DN(9)   I216 @T6G_MB_LIB.T6G(SCH_1):PAGE23
   N26 P5E_CPU0_G3_TX_DP<5> @T6G_MB_LIB.T6G(SCH_1):P5E_CPU0_G3_TX_DP(5)   I216 @T6G_MB_LIB.T6G(SCH_1):PAGE23
  AP35 P5E_CPU0_G3_RX_DN<15> @T6G_MB_LIB.T6G(SCH_1):P5E_CPU0_G3_RX_DN(15)   I216 @T6G_MB_LIB.T6G(SCH_1):PAGE23
  AK35 P5E_CPU0_G3_RX_DN<12> @T6G_MB_LIB.T6G(SCH_1):P5E_CPU0_G3_RX_DN(12)   I216 @T6G_MB_LIB.T6G(SCH_1):PAGE23
   U30 P5E_CPU0_G3_TX_DN<9> @T6G_MB_LIB.T6G(SCH_1):P5E_CPU0_G3_TX_DN(9)   I216 @T6G_MB_LIB.T6G(SCH_1):PAGE23
  AN23 P5E_CPU0_G3_RX_DN<2> @T6G_MB_LIB.T6G(SCH_1):P5E_CPU0_G3_RX_DN(2)   I216 @T6G_MB_LIB.T6G(SCH_1):PAGE23
  BW53 P5E_CPU0_P0_RX_DN<0> @T6G_MB_LIB.T6G(SCH_1):P5E_CPU0_P0_RX_DN(0)   I148 @T6G_MB_LIB.T6G(SCH_1):PAGE24
  BW47 P5E_CPU0_P0_RX_DN<6> @T6G_MB_LIB.T6G(SCH_1):P5E_CPU0_P0_RX_DN(6)   I148 @T6G_MB_LIB.T6G(SCH_1):PAGE24
  BW50 P5E_CPU0_P0_RX_DN<3> @T6G_MB_LIB.T6G(SCH_1):P5E_CPU0_P0_RX_DN(3)   I148 @T6G_MB_LIB.T6G(SCH_1):PAGE24
  CN49 P5E_CPU0_P0_TX_DN<3> @T6G_MB_LIB.T6G(SCH_1):P5E_CPU0_P0_TX_DN(3)   I148 @T6G_MB_LIB.T6G(SCH_1):PAGE24
  CN52 P5E_CPU0_P0_TX_DN<0> @T6G_MB_LIB.T6G(SCH_1):P5E_CPU0_P0_TX_DN(0)   I148 @T6G_MB_LIB.T6G(SCH_1):PAGE24
  CA52 P5E_CPU0_P0_RX_DP<1> @T6G_MB_LIB.T6G(SCH_1):P5E_CPU0_P0_RX_DP(1)   I148 @T6G_MB_LIB.T6G(SCH_1):PAGE24
  CL49 P5E_CPU0_P0_TX_DN<6> @T6G_MB_LIB.T6G(SCH_1):P5E_CPU0_P0_TX_DN(6)   I148 @T6G_MB_LIB.T6G(SCH_1):PAGE24
  CA46 P5E_CPU0_P0_RX_DP<7> @T6G_MB_LIB.T6G(SCH_1):P5E_CPU0_P0_RX_DP(7)   I148 @T6G_MB_LIB.T6G(SCH_1):PAGE24
  CA49 P5E_CPU0_P0_RX_DP<4> @T6G_MB_LIB.T6G(SCH_1):P5E_CPU0_P0_RX_DP(4)   I148 @T6G_MB_LIB.T6G(SCH_1):PAGE24
  CR50 P5E_CPU0_P0_TX_DP<4> @T6G_MB_LIB.T6G(SCH_1):P5E_CPU0_P0_TX_DP(4)   I148 @T6G_MB_LIB.T6G(SCH_1):PAGE24
  CR53 P5E_CPU0_P0_TX_DP<1> @T6G_MB_LIB.T6G(SCH_1):P5E_CPU0_P0_TX_DP(1)   I148 @T6G_MB_LIB.T6G(SCH_1):PAGE24
  CR47 P5E_CPU0_P0_TX_DP<7> @T6G_MB_LIB.T6G(SCH_1):P5E_CPU0_P0_TX_DP(7)   I148 @T6G_MB_LIB.T6G(SCH_1):PAGE24
  CA50 P5E_CPU0_P0_RX_DN<4> @T6G_MB_LIB.T6G(SCH_1):P5E_CPU0_P0_RX_DN(4)   I148 @T6G_MB_LIB.T6G(SCH_1):PAGE24
  CA53 P5E_CPU0_P0_RX_DN<1> @T6G_MB_LIB.T6G(SCH_1):P5E_CPU0_P0_RX_DN(1)   I148 @T6G_MB_LIB.T6G(SCH_1):PAGE24
  CA47 P5E_CPU0_P0_RX_DN<7> @T6G_MB_LIB.T6G(SCH_1):P5E_CPU0_P0_RX_DN(7)   I148 @T6G_MB_LIB.T6G(SCH_1):PAGE24
  CR49 P5E_CPU0_P0_TX_DN<4> @T6G_MB_LIB.T6G(SCH_1):P5E_CPU0_P0_TX_DN(4)   I148 @T6G_MB_LIB.T6G(SCH_1):PAGE24
  CR46 P5E_CPU0_P0_TX_DN<7> @T6G_MB_LIB.T6G(SCH_1):P5E_CPU0_P0_TX_DN(7)   I148 @T6G_MB_LIB.T6G(SCH_1):PAGE24
  CR52 P5E_CPU0_P0_TX_DN<1> @T6G_MB_LIB.T6G(SCH_1):P5E_CPU0_P0_TX_DN(1)   I148 @T6G_MB_LIB.T6G(SCH_1):PAGE24
  BU52 P5E_CPU0_P0_RX_DP<2> @T6G_MB_LIB.T6G(SCH_1):P5E_CPU0_P0_RX_DP(2)   I148 @T6G_MB_LIB.T6G(SCH_1):PAGE24
  BU49 P5E_CPU0_P0_RX_DP<5> @T6G_MB_LIB.T6G(SCH_1):P5E_CPU0_P0_RX_DP(5)   I148 @T6G_MB_LIB.T6G(SCH_1):PAGE24
  CU50 P5E_CPU0_P0_TX_DP<5> @T6G_MB_LIB.T6G(SCH_1):P5E_CPU0_P0_TX_DP(5)   I148 @T6G_MB_LIB.T6G(SCH_1):PAGE24
  CL53 P5E_CPU0_P0_TX_DP<2> @T6G_MB_LIB.T6G(SCH_1):P5E_CPU0_P0_TX_DP(2)   I148 @T6G_MB_LIB.T6G(SCH_1):PAGE24
  BU50 P5E_CPU0_P0_RX_DN<5> @T6G_MB_LIB.T6G(SCH_1):P5E_CPU0_P0_RX_DN(5)   I148 @T6G_MB_LIB.T6G(SCH_1):PAGE24
  BU53 P5E_CPU0_P0_RX_DN<2> @T6G_MB_LIB.T6G(SCH_1):P5E_CPU0_P0_RX_DN(2)   I148 @T6G_MB_LIB.T6G(SCH_1):PAGE24
  CL52 P5E_CPU0_P0_TX_DN<2> @T6G_MB_LIB.T6G(SCH_1):P5E_CPU0_P0_TX_DN(2)   I148 @T6G_MB_LIB.T6G(SCH_1):PAGE24
  BW52 P5E_CPU0_P0_RX_DP<0> @T6G_MB_LIB.T6G(SCH_1):P5E_CPU0_P0_RX_DP(0)   I148 @T6G_MB_LIB.T6G(SCH_1):PAGE24
  CU49 P5E_CPU0_P0_TX_DN<5> @T6G_MB_LIB.T6G(SCH_1):P5E_CPU0_P0_TX_DN(5)   I148 @T6G_MB_LIB.T6G(SCH_1):PAGE24
  BW46 P5E_CPU0_P0_RX_DP<6> @T6G_MB_LIB.T6G(SCH_1):P5E_CPU0_P0_RX_DP(6)   I148 @T6G_MB_LIB.T6G(SCH_1):PAGE24
  BW49 P5E_CPU0_P0_RX_DP<3> @T6G_MB_LIB.T6G(SCH_1):P5E_CPU0_P0_RX_DP(3)   I148 @T6G_MB_LIB.T6G(SCH_1):PAGE24
  CN53 P5E_CPU0_P0_TX_DP<0> @T6G_MB_LIB.T6G(SCH_1):P5E_CPU0_P0_TX_DP(0)   I148 @T6G_MB_LIB.T6G(SCH_1):PAGE24
  CL50 P5E_CPU0_P0_TX_DP<6> @T6G_MB_LIB.T6G(SCH_1):P5E_CPU0_P0_TX_DP(6)   I148 @T6G_MB_LIB.T6G(SCH_1):PAGE24
  CN50 P5E_CPU0_P0_TX_DP<3> @T6G_MB_LIB.T6G(SCH_1):P5E_CPU0_P0_TX_DP(3)   I148 @T6G_MB_LIB.T6G(SCH_1):PAGE24
  CT40 P5E_CPU0_P0_TX_DN<13> @T6G_MB_LIB.T6G(SCH_1):P5E_CPU0_P0_TX_DN(13)   I148 @T6G_MB_LIB.T6G(SCH_1):PAGE24
  CR43 P5E_CPU0_P0_TX_DN<10> @T6G_MB_LIB.T6G(SCH_1):P5E_CPU0_P0_TX_DN(10)   I148 @T6G_MB_LIB.T6G(SCH_1):PAGE24
  BV40 P5E_CPU0_P0_RX_DP<14> @T6G_MB_LIB.T6G(SCH_1):P5E_CPU0_P0_RX_DP(14)   I148 @T6G_MB_LIB.T6G(SCH_1):PAGE24
  BU46 P5E_CPU0_P0_RX_DP<8> @T6G_MB_LIB.T6G(SCH_1):P5E_CPU0_P0_RX_DP(8)   I148 @T6G_MB_LIB.T6G(SCH_1):PAGE24
  BY41 P5E_CPU0_P0_RX_DN<12> @T6G_MB_LIB.T6G(SCH_1):P5E_CPU0_P0_RX_DN(12)   I148 @T6G_MB_LIB.T6G(SCH_1):PAGE24
  CU47 P5E_CPU0_P0_TX_DP<8> @T6G_MB_LIB.T6G(SCH_1):P5E_CPU0_P0_TX_DP(8)   I148 @T6G_MB_LIB.T6G(SCH_1):PAGE24
  BT41 P5E_CPU0_P0_RX_DN<15> @T6G_MB_LIB.T6G(SCH_1):P5E_CPU0_P0_RX_DN(15)   I148 @T6G_MB_LIB.T6G(SCH_1):PAGE24
  CR44 P5E_CPU0_P0_TX_DP<10> @T6G_MB_LIB.T6G(SCH_1):P5E_CPU0_P0_TX_DP(10)   I148 @T6G_MB_LIB.T6G(SCH_1):PAGE24
  CT41 P5E_CPU0_P0_TX_DP<13> @T6G_MB_LIB.T6G(SCH_1):P5E_CPU0_P0_TX_DP(13)   I148 @T6G_MB_LIB.T6G(SCH_1):PAGE24
  BU47 P5E_CPU0_P0_RX_DN<8> @T6G_MB_LIB.T6G(SCH_1):P5E_CPU0_P0_RX_DN(8)   I148 @T6G_MB_LIB.T6G(SCH_1):PAGE24
  CU43 P5E_CPU0_P0_TX_DN<11> @T6G_MB_LIB.T6G(SCH_1):P5E_CPU0_P0_TX_DN(11)   I148 @T6G_MB_LIB.T6G(SCH_1):PAGE24
  CU46 P5E_CPU0_P0_TX_DN<8> @T6G_MB_LIB.T6G(SCH_1):P5E_CPU0_P0_TX_DN(8)   I148 @T6G_MB_LIB.T6G(SCH_1):PAGE24
  BT40 P5E_CPU0_P0_RX_DP<15> @T6G_MB_LIB.T6G(SCH_1):P5E_CPU0_P0_RX_DP(15)   I148 @T6G_MB_LIB.T6G(SCH_1):PAGE24
  BY40 P5E_CPU0_P0_RX_DP<12> @T6G_MB_LIB.T6G(SCH_1):P5E_CPU0_P0_RX_DP(12)   I148 @T6G_MB_LIB.T6G(SCH_1):PAGE24
  CP40 P5E_CPU0_P0_TX_DN<14> @T6G_MB_LIB.T6G(SCH_1):P5E_CPU0_P0_TX_DN(14)   I148 @T6G_MB_LIB.T6G(SCH_1):PAGE24
  BW43 P5E_CPU0_P0_RX_DP<9> @T6G_MB_LIB.T6G(SCH_1):P5E_CPU0_P0_RX_DP(9)   I148 @T6G_MB_LIB.T6G(SCH_1):PAGE24
  CN47 P5E_CPU0_P0_TX_DP<9> @T6G_MB_LIB.T6G(SCH_1):P5E_CPU0_P0_TX_DP(9)   I148 @T6G_MB_LIB.T6G(SCH_1):PAGE24
  CB41 P5E_CPU0_P0_RX_DN<13> @T6G_MB_LIB.T6G(SCH_1):P5E_CPU0_P0_RX_DN(13)   I148 @T6G_MB_LIB.T6G(SCH_1):PAGE24
  CA44 P5E_CPU0_P0_RX_DN<10> @T6G_MB_LIB.T6G(SCH_1):P5E_CPU0_P0_RX_DN(10)   I148 @T6G_MB_LIB.T6G(SCH_1):PAGE24
  CP41 P5E_CPU0_P0_TX_DP<14> @T6G_MB_LIB.T6G(SCH_1):P5E_CPU0_P0_TX_DP(14)   I148 @T6G_MB_LIB.T6G(SCH_1):PAGE24
  CU44 P5E_CPU0_P0_TX_DP<11> @T6G_MB_LIB.T6G(SCH_1):P5E_CPU0_P0_TX_DP(11)   I148 @T6G_MB_LIB.T6G(SCH_1):PAGE24
  BW44 P5E_CPU0_P0_RX_DN<9> @T6G_MB_LIB.T6G(SCH_1):P5E_CPU0_P0_RX_DN(9)   I148 @T6G_MB_LIB.T6G(SCH_1):PAGE24
  CA43 P5E_CPU0_P0_RX_DP<10> @T6G_MB_LIB.T6G(SCH_1):P5E_CPU0_P0_RX_DP(10)   I148 @T6G_MB_LIB.T6G(SCH_1):PAGE24
  CN43 P5E_CPU0_P0_TX_DN<12> @T6G_MB_LIB.T6G(SCH_1):P5E_CPU0_P0_TX_DN(12)   I148 @T6G_MB_LIB.T6G(SCH_1):PAGE24
  CN46 P5E_CPU0_P0_TX_DN<9> @T6G_MB_LIB.T6G(SCH_1):P5E_CPU0_P0_TX_DN(9)   I148 @T6G_MB_LIB.T6G(SCH_1):PAGE24
  CB40 P5E_CPU0_P0_RX_DP<13> @T6G_MB_LIB.T6G(SCH_1):P5E_CPU0_P0_RX_DP(13)   I148 @T6G_MB_LIB.T6G(SCH_1):PAGE24
  CM40 P5E_CPU0_P0_TX_DN<15> @T6G_MB_LIB.T6G(SCH_1):P5E_CPU0_P0_TX_DN(15)   I148 @T6G_MB_LIB.T6G(SCH_1):PAGE24
  BV41 P5E_CPU0_P0_RX_DN<14> @T6G_MB_LIB.T6G(SCH_1):P5E_CPU0_P0_RX_DN(14)   I148 @T6G_MB_LIB.T6G(SCH_1):PAGE24
  BU44 P5E_CPU0_P0_RX_DN<11> @T6G_MB_LIB.T6G(SCH_1):P5E_CPU0_P0_RX_DN(11)   I148 @T6G_MB_LIB.T6G(SCH_1):PAGE24
  CM41 P5E_CPU0_P0_TX_DP<15> @T6G_MB_LIB.T6G(SCH_1):P5E_CPU0_P0_TX_DP(15)   I148 @T6G_MB_LIB.T6G(SCH_1):PAGE24
  CN44 P5E_CPU0_P0_TX_DP<12> @T6G_MB_LIB.T6G(SCH_1):P5E_CPU0_P0_TX_DP(12)   I148 @T6G_MB_LIB.T6G(SCH_1):PAGE24
  BU43 P5E_CPU0_P0_RX_DP<11> @T6G_MB_LIB.T6G(SCH_1):P5E_CPU0_P0_RX_DP(11)   I148 @T6G_MB_LIB.T6G(SCH_1):PAGE24
  CC46 P5E_CPU0_P1_RX_DP<8> @T6G_MB_LIB.T6G(SCH_1):P5E_CPU0_P1_RX_DP(8)   I149 @T6G_MB_LIB.T6G(SCH_1):PAGE24
  CC47 P5E_CPU0_P1_RX_DN<8> @T6G_MB_LIB.T6G(SCH_1):P5E_CPU0_P1_RX_DN(8)   I149 @T6G_MB_LIB.T6G(SCH_1):PAGE24
  CE43 P5E_CPU0_P1_RX_DP<9> @T6G_MB_LIB.T6G(SCH_1):P5E_CPU0_P1_RX_DP(9)   I149 @T6G_MB_LIB.T6G(SCH_1):PAGE24
  CE44 P5E_CPU0_P1_RX_DN<9> @T6G_MB_LIB.T6G(SCH_1):P5E_CPU0_P1_RX_DN(9)   I149 @T6G_MB_LIB.T6G(SCH_1):PAGE24
  CG43 P5E_CPU0_P1_RX_DP<10> @T6G_MB_LIB.T6G(SCH_1):P5E_CPU0_P1_RX_DP(10)   I149 @T6G_MB_LIB.T6G(SCH_1):PAGE24
  CG44 P5E_CPU0_P1_RX_DN<10> @T6G_MB_LIB.T6G(SCH_1):P5E_CPU0_P1_RX_DN(10)   I149 @T6G_MB_LIB.T6G(SCH_1):PAGE24
  CJ43 P5E_CPU0_P1_RX_DP<11> @T6G_MB_LIB.T6G(SCH_1):P5E_CPU0_P1_RX_DP(11)   I149 @T6G_MB_LIB.T6G(SCH_1):PAGE24
  CJ44 P5E_CPU0_P1_RX_DN<11> @T6G_MB_LIB.T6G(SCH_1):P5E_CPU0_P1_RX_DN(11)   I149 @T6G_MB_LIB.T6G(SCH_1):PAGE24
  CC43 P5E_CPU0_P1_RX_DP<12> @T6G_MB_LIB.T6G(SCH_1):P5E_CPU0_P1_RX_DP(12)   I149 @T6G_MB_LIB.T6G(SCH_1):PAGE24
  CC44 P5E_CPU0_P1_RX_DN<12> @T6G_MB_LIB.T6G(SCH_1):P5E_CPU0_P1_RX_DN(12)   I149 @T6G_MB_LIB.T6G(SCH_1):PAGE24
  CH40 P5E_CPU0_P1_RX_DP<13> @T6G_MB_LIB.T6G(SCH_1):P5E_CPU0_P1_RX_DP(13)   I149 @T6G_MB_LIB.T6G(SCH_1):PAGE24
  CH41 P5E_CPU0_P1_RX_DN<13> @T6G_MB_LIB.T6G(SCH_1):P5E_CPU0_P1_RX_DN(13)   I149 @T6G_MB_LIB.T6G(SCH_1):PAGE24
  CF40 P5E_CPU0_P1_RX_DP<14> @T6G_MB_LIB.T6G(SCH_1):P5E_CPU0_P1_RX_DP(14)   I149 @T6G_MB_LIB.T6G(SCH_1):PAGE24
  CF41 P5E_CPU0_P1_RX_DN<14> @T6G_MB_LIB.T6G(SCH_1):P5E_CPU0_P1_RX_DN(14)   I149 @T6G_MB_LIB.T6G(SCH_1):PAGE24
  CD40 P5E_CPU0_P1_RX_DP<15> @T6G_MB_LIB.T6G(SCH_1):P5E_CPU0_P1_RX_DP(15)   I149 @T6G_MB_LIB.T6G(SCH_1):PAGE24
  CD41 P5E_CPU0_P1_RX_DN<15> @T6G_MB_LIB.T6G(SCH_1):P5E_CPU0_P1_RX_DN(15)   I149 @T6G_MB_LIB.T6G(SCH_1):PAGE24
  DC47 P5E_CPU0_P1_TX_DP<8> @T6G_MB_LIB.T6G(SCH_1):P5E_CPU0_P1_TX_DP(8)   I149 @T6G_MB_LIB.T6G(SCH_1):PAGE24
  DC46 P5E_CPU0_P1_TX_DN<8> @T6G_MB_LIB.T6G(SCH_1):P5E_CPU0_P1_TX_DN(8)   I149 @T6G_MB_LIB.T6G(SCH_1):PAGE24
  CW47 P5E_CPU0_P1_TX_DP<9> @T6G_MB_LIB.T6G(SCH_1):P5E_CPU0_P1_TX_DP(9)   I149 @T6G_MB_LIB.T6G(SCH_1):PAGE24
  CW46 P5E_CPU0_P1_TX_DN<9> @T6G_MB_LIB.T6G(SCH_1):P5E_CPU0_P1_TX_DN(9)   I149 @T6G_MB_LIB.T6G(SCH_1):PAGE24
  DA44 P5E_CPU0_P1_TX_DP<10> @T6G_MB_LIB.T6G(SCH_1):P5E_CPU0_P1_TX_DP(10)   I149 @T6G_MB_LIB.T6G(SCH_1):PAGE24
  DA43 P5E_CPU0_P1_TX_DN<10> @T6G_MB_LIB.T6G(SCH_1):P5E_CPU0_P1_TX_DN(10)   I149 @T6G_MB_LIB.T6G(SCH_1):PAGE24
  DC44 P5E_CPU0_P1_TX_DP<11> @T6G_MB_LIB.T6G(SCH_1):P5E_CPU0_P1_TX_DP(11)   I149 @T6G_MB_LIB.T6G(SCH_1):PAGE24
  DC43 P5E_CPU0_P1_TX_DN<11> @T6G_MB_LIB.T6G(SCH_1):P5E_CPU0_P1_TX_DN(11)   I149 @T6G_MB_LIB.T6G(SCH_1):PAGE24
  CW44 P5E_CPU0_P1_TX_DP<12> @T6G_MB_LIB.T6G(SCH_1):P5E_CPU0_P1_TX_DP(12)   I149 @T6G_MB_LIB.T6G(SCH_1):PAGE24
  CW43 P5E_CPU0_P1_TX_DN<12> @T6G_MB_LIB.T6G(SCH_1):P5E_CPU0_P1_TX_DN(12)   I149 @T6G_MB_LIB.T6G(SCH_1):PAGE24
  DB41 P5E_CPU0_P1_TX_DP<13> @T6G_MB_LIB.T6G(SCH_1):P5E_CPU0_P1_TX_DP(13)   I149 @T6G_MB_LIB.T6G(SCH_1):PAGE24
  DB40 P5E_CPU0_P1_TX_DN<13> @T6G_MB_LIB.T6G(SCH_1):P5E_CPU0_P1_TX_DN(13)   I149 @T6G_MB_LIB.T6G(SCH_1):PAGE24
  CY41 P5E_CPU0_P1_TX_DP<14> @T6G_MB_LIB.T6G(SCH_1):P5E_CPU0_P1_TX_DP(14)   I149 @T6G_MB_LIB.T6G(SCH_1):PAGE24
  CY40 P5E_CPU0_P1_TX_DN<14> @T6G_MB_LIB.T6G(SCH_1):P5E_CPU0_P1_TX_DN(14)   I149 @T6G_MB_LIB.T6G(SCH_1):PAGE24
  CV41 P5E_CPU0_P1_TX_DP<15> @T6G_MB_LIB.T6G(SCH_1):P5E_CPU0_P1_TX_DP(15)   I149 @T6G_MB_LIB.T6G(SCH_1):PAGE24
  CV40 P5E_CPU0_P1_TX_DN<15> @T6G_MB_LIB.T6G(SCH_1):P5E_CPU0_P1_TX_DN(15)   I149 @T6G_MB_LIB.T6G(SCH_1):PAGE24
  CG47 P5E_CPU0_P1_RX_DN<7> @T6G_MB_LIB.T6G(SCH_1):P5E_CPU0_P1_RX_DN(7)   I149 @T6G_MB_LIB.T6G(SCH_1):PAGE24
  CU53 P5E_CPU0_P1_TX_DP<0> @T6G_MB_LIB.T6G(SCH_1):P5E_CPU0_P1_TX_DP(0)   I149 @T6G_MB_LIB.T6G(SCH_1):PAGE24
  DA53 P5E_CPU0_P1_TX_DP<1> @T6G_MB_LIB.T6G(SCH_1):P5E_CPU0_P1_TX_DP(1)   I149 @T6G_MB_LIB.T6G(SCH_1):PAGE24
  DC53 P5E_CPU0_P1_TX_DP<2> @T6G_MB_LIB.T6G(SCH_1):P5E_CPU0_P1_TX_DP(2)   I149 @T6G_MB_LIB.T6G(SCH_1):PAGE24
  CU52 P5E_CPU0_P1_TX_DN<0> @T6G_MB_LIB.T6G(SCH_1):P5E_CPU0_P1_TX_DN(0)   I149 @T6G_MB_LIB.T6G(SCH_1):PAGE24
  CE52 P5E_CPU0_P1_RX_DP<0> @T6G_MB_LIB.T6G(SCH_1):P5E_CPU0_P1_RX_DP(0)   I149 @T6G_MB_LIB.T6G(SCH_1):PAGE24
  CW53 P5E_CPU0_P1_TX_DP<3> @T6G_MB_LIB.T6G(SCH_1):P5E_CPU0_P1_TX_DP(3)   I149 @T6G_MB_LIB.T6G(SCH_1):PAGE24
  DA52 P5E_CPU0_P1_TX_DN<1> @T6G_MB_LIB.T6G(SCH_1):P5E_CPU0_P1_TX_DN(1)   I149 @T6G_MB_LIB.T6G(SCH_1):PAGE24
  CG52 P5E_CPU0_P1_RX_DP<1> @T6G_MB_LIB.T6G(SCH_1):P5E_CPU0_P1_RX_DP(1)   I149 @T6G_MB_LIB.T6G(SCH_1):PAGE24
  DA50 P5E_CPU0_P1_TX_DP<4> @T6G_MB_LIB.T6G(SCH_1):P5E_CPU0_P1_TX_DP(4)   I149 @T6G_MB_LIB.T6G(SCH_1):PAGE24
  DC52 P5E_CPU0_P1_TX_DN<2> @T6G_MB_LIB.T6G(SCH_1):P5E_CPU0_P1_TX_DN(2)   I149 @T6G_MB_LIB.T6G(SCH_1):PAGE24
  CC52 P5E_CPU0_P1_RX_DP<2> @T6G_MB_LIB.T6G(SCH_1):P5E_CPU0_P1_RX_DP(2)   I149 @T6G_MB_LIB.T6G(SCH_1):PAGE24
  CE53 P5E_CPU0_P1_RX_DN<0> @T6G_MB_LIB.T6G(SCH_1):P5E_CPU0_P1_RX_DN(0)   I149 @T6G_MB_LIB.T6G(SCH_1):PAGE24
  DC50 P5E_CPU0_P1_TX_DP<5> @T6G_MB_LIB.T6G(SCH_1):P5E_CPU0_P1_TX_DP(5)   I149 @T6G_MB_LIB.T6G(SCH_1):PAGE24
  CW52 P5E_CPU0_P1_TX_DN<3> @T6G_MB_LIB.T6G(SCH_1):P5E_CPU0_P1_TX_DN(3)   I149 @T6G_MB_LIB.T6G(SCH_1):PAGE24
  CE49 P5E_CPU0_P1_RX_DP<3> @T6G_MB_LIB.T6G(SCH_1):P5E_CPU0_P1_RX_DP(3)   I149 @T6G_MB_LIB.T6G(SCH_1):PAGE24
  CG53 P5E_CPU0_P1_RX_DN<1> @T6G_MB_LIB.T6G(SCH_1):P5E_CPU0_P1_RX_DN(1)   I149 @T6G_MB_LIB.T6G(SCH_1):PAGE24
  CW50 P5E_CPU0_P1_TX_DP<6> @T6G_MB_LIB.T6G(SCH_1):P5E_CPU0_P1_TX_DP(6)   I149 @T6G_MB_LIB.T6G(SCH_1):PAGE24
  DA49 P5E_CPU0_P1_TX_DN<4> @T6G_MB_LIB.T6G(SCH_1):P5E_CPU0_P1_TX_DN(4)   I149 @T6G_MB_LIB.T6G(SCH_1):PAGE24
  CG49 P5E_CPU0_P1_RX_DP<4> @T6G_MB_LIB.T6G(SCH_1):P5E_CPU0_P1_RX_DP(4)   I149 @T6G_MB_LIB.T6G(SCH_1):PAGE24
  CC53 P5E_CPU0_P1_RX_DN<2> @T6G_MB_LIB.T6G(SCH_1):P5E_CPU0_P1_RX_DN(2)   I149 @T6G_MB_LIB.T6G(SCH_1):PAGE24
  DA47 P5E_CPU0_P1_TX_DP<7> @T6G_MB_LIB.T6G(SCH_1):P5E_CPU0_P1_TX_DP(7)   I149 @T6G_MB_LIB.T6G(SCH_1):PAGE24
  DC49 P5E_CPU0_P1_TX_DN<5> @T6G_MB_LIB.T6G(SCH_1):P5E_CPU0_P1_TX_DN(5)   I149 @T6G_MB_LIB.T6G(SCH_1):PAGE24
  CC49 P5E_CPU0_P1_RX_DP<5> @T6G_MB_LIB.T6G(SCH_1):P5E_CPU0_P1_RX_DP(5)   I149 @T6G_MB_LIB.T6G(SCH_1):PAGE24
  CE50 P5E_CPU0_P1_RX_DN<3> @T6G_MB_LIB.T6G(SCH_1):P5E_CPU0_P1_RX_DN(3)   I149 @T6G_MB_LIB.T6G(SCH_1):PAGE24
  CW49 P5E_CPU0_P1_TX_DN<6> @T6G_MB_LIB.T6G(SCH_1):P5E_CPU0_P1_TX_DN(6)   I149 @T6G_MB_LIB.T6G(SCH_1):PAGE24
  CE46 P5E_CPU0_P1_RX_DP<6> @T6G_MB_LIB.T6G(SCH_1):P5E_CPU0_P1_RX_DP(6)   I149 @T6G_MB_LIB.T6G(SCH_1):PAGE24
  CG50 P5E_CPU0_P1_RX_DN<4> @T6G_MB_LIB.T6G(SCH_1):P5E_CPU0_P1_RX_DN(4)   I149 @T6G_MB_LIB.T6G(SCH_1):PAGE24
  DA46 P5E_CPU0_P1_TX_DN<7> @T6G_MB_LIB.T6G(SCH_1):P5E_CPU0_P1_TX_DN(7)   I149 @T6G_MB_LIB.T6G(SCH_1):PAGE24
  CG46 P5E_CPU0_P1_RX_DP<7> @T6G_MB_LIB.T6G(SCH_1):P5E_CPU0_P1_RX_DP(7)   I149 @T6G_MB_LIB.T6G(SCH_1):PAGE24
  CC50 P5E_CPU0_P1_RX_DN<5> @T6G_MB_LIB.T6G(SCH_1):P5E_CPU0_P1_RX_DN(5)   I149 @T6G_MB_LIB.T6G(SCH_1):PAGE24
  CE47 P5E_CPU0_P1_RX_DN<6> @T6G_MB_LIB.T6G(SCH_1):P5E_CPU0_P1_RX_DN(6)   I149 @T6G_MB_LIB.T6G(SCH_1):PAGE24
  CR29 P5E_CPU0_P2_RX_DP<8> @T6G_MB_LIB.T6G(SCH_1):P5E_CPU0_P2_RX_DP(8)   I147 @T6G_MB_LIB.T6G(SCH_1):PAGE25
  CR30 P5E_CPU0_P2_RX_DN<8> @T6G_MB_LIB.T6G(SCH_1):P5E_CPU0_P2_RX_DN(8)   I147 @T6G_MB_LIB.T6G(SCH_1):PAGE25
  CL26 P5E_CPU0_P2_RX_DP<9> @T6G_MB_LIB.T6G(SCH_1):P5E_CPU0_P2_RX_DP(9)   I147 @T6G_MB_LIB.T6G(SCH_1):PAGE25
  CL27 P5E_CPU0_P2_RX_DN<9> @T6G_MB_LIB.T6G(SCH_1):P5E_CPU0_P2_RX_DN(9)   I147 @T6G_MB_LIB.T6G(SCH_1):PAGE25
  CU26 P5E_CPU0_P2_RX_DP<10> @T6G_MB_LIB.T6G(SCH_1):P5E_CPU0_P2_RX_DP(10)   I147 @T6G_MB_LIB.T6G(SCH_1):PAGE25
  CU27 P5E_CPU0_P2_RX_DN<10> @T6G_MB_LIB.T6G(SCH_1):P5E_CPU0_P2_RX_DN(10)   I147 @T6G_MB_LIB.T6G(SCH_1):PAGE25
  CR26 P5E_CPU0_P2_RX_DP<11> @T6G_MB_LIB.T6G(SCH_1):P5E_CPU0_P2_RX_DP(11)   I147 @T6G_MB_LIB.T6G(SCH_1):PAGE25
  CR27 P5E_CPU0_P2_RX_DN<11> @T6G_MB_LIB.T6G(SCH_1):P5E_CPU0_P2_RX_DN(11)   I147 @T6G_MB_LIB.T6G(SCH_1):PAGE25
  CN26 P5E_CPU0_P2_RX_DP<12> @T6G_MB_LIB.T6G(SCH_1):P5E_CPU0_P2_RX_DP(12)   I147 @T6G_MB_LIB.T6G(SCH_1):PAGE25
  CN27 P5E_CPU0_P2_RX_DN<12> @T6G_MB_LIB.T6G(SCH_1):P5E_CPU0_P2_RX_DN(12)   I147 @T6G_MB_LIB.T6G(SCH_1):PAGE25
  CL23 P5E_CPU0_P2_RX_DP<13> @T6G_MB_LIB.T6G(SCH_1):P5E_CPU0_P2_RX_DP(13)   I147 @T6G_MB_LIB.T6G(SCH_1):PAGE25
  CL24 P5E_CPU0_P2_RX_DN<13> @T6G_MB_LIB.T6G(SCH_1):P5E_CPU0_P2_RX_DN(13)   I147 @T6G_MB_LIB.T6G(SCH_1):PAGE25
  CR23 P5E_CPU0_P2_RX_DP<14> @T6G_MB_LIB.T6G(SCH_1):P5E_CPU0_P2_RX_DP(14)   I147 @T6G_MB_LIB.T6G(SCH_1):PAGE25
  CR24 P5E_CPU0_P2_RX_DN<14> @T6G_MB_LIB.T6G(SCH_1):P5E_CPU0_P2_RX_DN(14)   I147 @T6G_MB_LIB.T6G(SCH_1):PAGE25
  CN23 P5E_CPU0_P2_RX_DP<15> @T6G_MB_LIB.T6G(SCH_1):P5E_CPU0_P2_RX_DP(15)   I147 @T6G_MB_LIB.T6G(SCH_1):PAGE25
  CN24 P5E_CPU0_P2_RX_DN<15> @T6G_MB_LIB.T6G(SCH_1):P5E_CPU0_P2_RX_DN(15)   I147 @T6G_MB_LIB.T6G(SCH_1):PAGE25
  CA30 P5E_CPU0_P2_TX_DP<8> @T6G_MB_LIB.T6G(SCH_1):P5E_CPU0_P2_TX_DP(8)   I147 @T6G_MB_LIB.T6G(SCH_1):PAGE25
  CA29 P5E_CPU0_P2_TX_DN<8> @T6G_MB_LIB.T6G(SCH_1):P5E_CPU0_P2_TX_DN(8)   I147 @T6G_MB_LIB.T6G(SCH_1):PAGE25
  BW30 P5E_CPU0_P2_TX_DP<9> @T6G_MB_LIB.T6G(SCH_1):P5E_CPU0_P2_TX_DP(9)   I147 @T6G_MB_LIB.T6G(SCH_1):PAGE25
  BW29 P5E_CPU0_P2_TX_DN<9> @T6G_MB_LIB.T6G(SCH_1):P5E_CPU0_P2_TX_DN(9)   I147 @T6G_MB_LIB.T6G(SCH_1):PAGE25
  BU27 P5E_CPU0_P2_TX_DP<10> @T6G_MB_LIB.T6G(SCH_1):P5E_CPU0_P2_TX_DP(10)   I147 @T6G_MB_LIB.T6G(SCH_1):PAGE25
  BU26 P5E_CPU0_P2_TX_DN<10> @T6G_MB_LIB.T6G(SCH_1):P5E_CPU0_P2_TX_DN(10)   I147 @T6G_MB_LIB.T6G(SCH_1):PAGE25
  CA27 P5E_CPU0_P2_TX_DP<11> @T6G_MB_LIB.T6G(SCH_1):P5E_CPU0_P2_TX_DP(11)   I147 @T6G_MB_LIB.T6G(SCH_1):PAGE25
  CA26 P5E_CPU0_P2_TX_DN<11> @T6G_MB_LIB.T6G(SCH_1):P5E_CPU0_P2_TX_DN(11)   I147 @T6G_MB_LIB.T6G(SCH_1):PAGE25
  BW27 P5E_CPU0_P2_TX_DP<12> @T6G_MB_LIB.T6G(SCH_1):P5E_CPU0_P2_TX_DP(12)   I147 @T6G_MB_LIB.T6G(SCH_1):PAGE25
  BW26 P5E_CPU0_P2_TX_DN<12> @T6G_MB_LIB.T6G(SCH_1):P5E_CPU0_P2_TX_DN(12)   I147 @T6G_MB_LIB.T6G(SCH_1):PAGE25
  BU24 P5E_CPU0_P2_TX_DP<13> @T6G_MB_LIB.T6G(SCH_1):P5E_CPU0_P2_TX_DP(13)   I147 @T6G_MB_LIB.T6G(SCH_1):PAGE25
  BU23 P5E_CPU0_P2_TX_DN<13> @T6G_MB_LIB.T6G(SCH_1):P5E_CPU0_P2_TX_DN(13)   I147 @T6G_MB_LIB.T6G(SCH_1):PAGE25
  CA24 P5E_CPU0_P2_TX_DP<14> @T6G_MB_LIB.T6G(SCH_1):P5E_CPU0_P2_TX_DP(14)   I147 @T6G_MB_LIB.T6G(SCH_1):PAGE25
  CA23 P5E_CPU0_P2_TX_DN<14> @T6G_MB_LIB.T6G(SCH_1):P5E_CPU0_P2_TX_DN(14)   I147 @T6G_MB_LIB.T6G(SCH_1):PAGE25
  BW24 P5E_CPU0_P2_TX_DP<15> @T6G_MB_LIB.T6G(SCH_1):P5E_CPU0_P2_TX_DP(15)   I147 @T6G_MB_LIB.T6G(SCH_1):PAGE25
  BW23 P5E_CPU0_P2_TX_DN<15> @T6G_MB_LIB.T6G(SCH_1):P5E_CPU0_P2_TX_DN(15)   I147 @T6G_MB_LIB.T6G(SCH_1):PAGE25
  BT36 P5E_CPU0_P2_TX_DP<0> @T6G_MB_LIB.T6G(SCH_1):P5E_CPU0_P2_TX_DP(0)   I147 @T6G_MB_LIB.T6G(SCH_1):PAGE25
  BV36 P5E_CPU0_P2_TX_DP<1> @T6G_MB_LIB.T6G(SCH_1):P5E_CPU0_P2_TX_DP(1)   I147 @T6G_MB_LIB.T6G(SCH_1):PAGE25
  CB36 P5E_CPU0_P2_TX_DP<2> @T6G_MB_LIB.T6G(SCH_1):P5E_CPU0_P2_TX_DP(2)   I147 @T6G_MB_LIB.T6G(SCH_1):PAGE25
  BT35 P5E_CPU0_P2_TX_DN<0> @T6G_MB_LIB.T6G(SCH_1):P5E_CPU0_P2_TX_DN(0)   I147 @T6G_MB_LIB.T6G(SCH_1):PAGE25
  CM35 P5E_CPU0_P2_RX_DP<0> @T6G_MB_LIB.T6G(SCH_1):P5E_CPU0_P2_RX_DP(0)   I147 @T6G_MB_LIB.T6G(SCH_1):PAGE25
  BY36 P5E_CPU0_P2_TX_DP<3> @T6G_MB_LIB.T6G(SCH_1):P5E_CPU0_P2_TX_DP(3)   I147 @T6G_MB_LIB.T6G(SCH_1):PAGE25
  BV35 P5E_CPU0_P2_TX_DN<1> @T6G_MB_LIB.T6G(SCH_1):P5E_CPU0_P2_TX_DN(1)   I147 @T6G_MB_LIB.T6G(SCH_1):PAGE25
  CP35 P5E_CPU0_P2_RX_DP<1> @T6G_MB_LIB.T6G(SCH_1):P5E_CPU0_P2_RX_DP(1)   I147 @T6G_MB_LIB.T6G(SCH_1):PAGE25
  BU33 P5E_CPU0_P2_TX_DP<4> @T6G_MB_LIB.T6G(SCH_1):P5E_CPU0_P2_TX_DP(4)   I147 @T6G_MB_LIB.T6G(SCH_1):PAGE25
  CB35 P5E_CPU0_P2_TX_DN<2> @T6G_MB_LIB.T6G(SCH_1):P5E_CPU0_P2_TX_DN(2)   I147 @T6G_MB_LIB.T6G(SCH_1):PAGE25
  CT35 P5E_CPU0_P2_RX_DP<2> @T6G_MB_LIB.T6G(SCH_1):P5E_CPU0_P2_RX_DP(2)   I147 @T6G_MB_LIB.T6G(SCH_1):PAGE25
  CM36 P5E_CPU0_P2_RX_DN<0> @T6G_MB_LIB.T6G(SCH_1):P5E_CPU0_P2_RX_DN(0)   I147 @T6G_MB_LIB.T6G(SCH_1):PAGE25
  CA33 P5E_CPU0_P2_TX_DP<5> @T6G_MB_LIB.T6G(SCH_1):P5E_CPU0_P2_TX_DP(5)   I147 @T6G_MB_LIB.T6G(SCH_1):PAGE25
  BY35 P5E_CPU0_P2_TX_DN<3> @T6G_MB_LIB.T6G(SCH_1):P5E_CPU0_P2_TX_DN(3)   I147 @T6G_MB_LIB.T6G(SCH_1):PAGE25
  CN32 P5E_CPU0_P2_RX_DP<3> @T6G_MB_LIB.T6G(SCH_1):P5E_CPU0_P2_RX_DP(3)   I147 @T6G_MB_LIB.T6G(SCH_1):PAGE25
  CP36 P5E_CPU0_P2_RX_DN<1> @T6G_MB_LIB.T6G(SCH_1):P5E_CPU0_P2_RX_DN(1)   I147 @T6G_MB_LIB.T6G(SCH_1):PAGE25
  BW33 P5E_CPU0_P2_TX_DP<6> @T6G_MB_LIB.T6G(SCH_1):P5E_CPU0_P2_TX_DP(6)   I147 @T6G_MB_LIB.T6G(SCH_1):PAGE25
  BU32 P5E_CPU0_P2_TX_DN<4> @T6G_MB_LIB.T6G(SCH_1):P5E_CPU0_P2_TX_DN(4)   I147 @T6G_MB_LIB.T6G(SCH_1):PAGE25
  CU32 P5E_CPU0_P2_RX_DP<4> @T6G_MB_LIB.T6G(SCH_1):P5E_CPU0_P2_RX_DP(4)   I147 @T6G_MB_LIB.T6G(SCH_1):PAGE25
  CT36 P5E_CPU0_P2_RX_DN<2> @T6G_MB_LIB.T6G(SCH_1):P5E_CPU0_P2_RX_DN(2)   I147 @T6G_MB_LIB.T6G(SCH_1):PAGE25
  BU30 P5E_CPU0_P2_TX_DP<7> @T6G_MB_LIB.T6G(SCH_1):P5E_CPU0_P2_TX_DP(7)   I147 @T6G_MB_LIB.T6G(SCH_1):PAGE25
  CA32 P5E_CPU0_P2_TX_DN<5> @T6G_MB_LIB.T6G(SCH_1):P5E_CPU0_P2_TX_DN(5)   I147 @T6G_MB_LIB.T6G(SCH_1):PAGE25
  CR32 P5E_CPU0_P2_RX_DP<5> @T6G_MB_LIB.T6G(SCH_1):P5E_CPU0_P2_RX_DP(5)   I147 @T6G_MB_LIB.T6G(SCH_1):PAGE25
  CN33 P5E_CPU0_P2_RX_DN<3> @T6G_MB_LIB.T6G(SCH_1):P5E_CPU0_P2_RX_DN(3)   I147 @T6G_MB_LIB.T6G(SCH_1):PAGE25
  BW32 P5E_CPU0_P2_TX_DN<6> @T6G_MB_LIB.T6G(SCH_1):P5E_CPU0_P2_TX_DN(6)   I147 @T6G_MB_LIB.T6G(SCH_1):PAGE25
  CN29 P5E_CPU0_P2_RX_DP<6> @T6G_MB_LIB.T6G(SCH_1):P5E_CPU0_P2_RX_DP(6)   I147 @T6G_MB_LIB.T6G(SCH_1):PAGE25
  CU33 P5E_CPU0_P2_RX_DN<4> @T6G_MB_LIB.T6G(SCH_1):P5E_CPU0_P2_RX_DN(4)   I147 @T6G_MB_LIB.T6G(SCH_1):PAGE25
  BU29 P5E_CPU0_P2_TX_DN<7> @T6G_MB_LIB.T6G(SCH_1):P5E_CPU0_P2_TX_DN(7)   I147 @T6G_MB_LIB.T6G(SCH_1):PAGE25
  CU29 P5E_CPU0_P2_RX_DP<7> @T6G_MB_LIB.T6G(SCH_1):P5E_CPU0_P2_RX_DP(7)   I147 @T6G_MB_LIB.T6G(SCH_1):PAGE25
  CR33 P5E_CPU0_P2_RX_DN<5> @T6G_MB_LIB.T6G(SCH_1):P5E_CPU0_P2_RX_DN(5)   I147 @T6G_MB_LIB.T6G(SCH_1):PAGE25
  CN30 P5E_CPU0_P2_RX_DN<6> @T6G_MB_LIB.T6G(SCH_1):P5E_CPU0_P2_RX_DN(6)   I147 @T6G_MB_LIB.T6G(SCH_1):PAGE25
  CU30 P5E_CPU0_P2_RX_DN<7> @T6G_MB_LIB.T6G(SCH_1):P5E_CPU0_P2_RX_DN(7)   I147 @T6G_MB_LIB.T6G(SCH_1):PAGE25
  CV35 P5E_CPU0_P3_RX_DP<0> @T6G_MB_LIB.T6G(SCH_1):P5E_CPU0_P3_RX_DP(0)   I148 @T6G_MB_LIB.T6G(SCH_1):PAGE25
  CV36 P5E_CPU0_P3_RX_DN<0> @T6G_MB_LIB.T6G(SCH_1):P5E_CPU0_P3_RX_DN(0)   I148 @T6G_MB_LIB.T6G(SCH_1):PAGE25
  CY35 P5E_CPU0_P3_RX_DP<1> @T6G_MB_LIB.T6G(SCH_1):P5E_CPU0_P3_RX_DP(1)   I148 @T6G_MB_LIB.T6G(SCH_1):PAGE25
  CY36 P5E_CPU0_P3_RX_DN<1> @T6G_MB_LIB.T6G(SCH_1):P5E_CPU0_P3_RX_DN(1)   I148 @T6G_MB_LIB.T6G(SCH_1):PAGE25
  DB35 P5E_CPU0_P3_RX_DP<2> @T6G_MB_LIB.T6G(SCH_1):P5E_CPU0_P3_RX_DP(2)   I148 @T6G_MB_LIB.T6G(SCH_1):PAGE25
  DB36 P5E_CPU0_P3_RX_DN<2> @T6G_MB_LIB.T6G(SCH_1):P5E_CPU0_P3_RX_DN(2)   I148 @T6G_MB_LIB.T6G(SCH_1):PAGE25
  CW32 P5E_CPU0_P3_RX_DP<3> @T6G_MB_LIB.T6G(SCH_1):P5E_CPU0_P3_RX_DP(3)   I148 @T6G_MB_LIB.T6G(SCH_1):PAGE25
  CW33 P5E_CPU0_P3_RX_DN<3> @T6G_MB_LIB.T6G(SCH_1):P5E_CPU0_P3_RX_DN(3)   I148 @T6G_MB_LIB.T6G(SCH_1):PAGE25
  DC32 P5E_CPU0_P3_RX_DP<4> @T6G_MB_LIB.T6G(SCH_1):P5E_CPU0_P3_RX_DP(4)   I148 @T6G_MB_LIB.T6G(SCH_1):PAGE25
  DC33 P5E_CPU0_P3_RX_DN<4> @T6G_MB_LIB.T6G(SCH_1):P5E_CPU0_P3_RX_DN(4)   I148 @T6G_MB_LIB.T6G(SCH_1):PAGE25
  DA32 P5E_CPU0_P3_RX_DP<5> @T6G_MB_LIB.T6G(SCH_1):P5E_CPU0_P3_RX_DP(5)   I148 @T6G_MB_LIB.T6G(SCH_1):PAGE25
  DA33 P5E_CPU0_P3_RX_DN<5> @T6G_MB_LIB.T6G(SCH_1):P5E_CPU0_P3_RX_DN(5)   I148 @T6G_MB_LIB.T6G(SCH_1):PAGE25
  CW29 P5E_CPU0_P3_RX_DP<6> @T6G_MB_LIB.T6G(SCH_1):P5E_CPU0_P3_RX_DP(6)   I148 @T6G_MB_LIB.T6G(SCH_1):PAGE25
  CW30 P5E_CPU0_P3_RX_DN<6> @T6G_MB_LIB.T6G(SCH_1):P5E_CPU0_P3_RX_DN(6)   I148 @T6G_MB_LIB.T6G(SCH_1):PAGE25
  DC29 P5E_CPU0_P3_RX_DP<7> @T6G_MB_LIB.T6G(SCH_1):P5E_CPU0_P3_RX_DP(7)   I148 @T6G_MB_LIB.T6G(SCH_1):PAGE25
  DC30 P5E_CPU0_P3_RX_DN<7> @T6G_MB_LIB.T6G(SCH_1):P5E_CPU0_P3_RX_DN(7)   I148 @T6G_MB_LIB.T6G(SCH_1):PAGE25
  DA29 P5E_CPU0_P3_RX_DP<8> @T6G_MB_LIB.T6G(SCH_1):P5E_CPU0_P3_RX_DP(8)   I148 @T6G_MB_LIB.T6G(SCH_1):PAGE25
  DA30 P5E_CPU0_P3_RX_DN<8> @T6G_MB_LIB.T6G(SCH_1):P5E_CPU0_P3_RX_DN(8)   I148 @T6G_MB_LIB.T6G(SCH_1):PAGE25
  CW26 P5E_CPU0_P3_RX_DP<9> @T6G_MB_LIB.T6G(SCH_1):P5E_CPU0_P3_RX_DP(9)   I148 @T6G_MB_LIB.T6G(SCH_1):PAGE25
  CW27 P5E_CPU0_P3_RX_DN<9> @T6G_MB_LIB.T6G(SCH_1):P5E_CPU0_P3_RX_DN(9)   I148 @T6G_MB_LIB.T6G(SCH_1):PAGE25
  DC26 P5E_CPU0_P3_RX_DP<10> @T6G_MB_LIB.T6G(SCH_1):P5E_CPU0_P3_RX_DP(10)   I148 @T6G_MB_LIB.T6G(SCH_1):PAGE25
  DC27 P5E_CPU0_P3_RX_DN<10> @T6G_MB_LIB.T6G(SCH_1):P5E_CPU0_P3_RX_DN(10)   I148 @T6G_MB_LIB.T6G(SCH_1):PAGE25
  DA26 P5E_CPU0_P3_RX_DP<11> @T6G_MB_LIB.T6G(SCH_1):P5E_CPU0_P3_RX_DP(11)   I148 @T6G_MB_LIB.T6G(SCH_1):PAGE25
  DA27 P5E_CPU0_P3_RX_DN<11> @T6G_MB_LIB.T6G(SCH_1):P5E_CPU0_P3_RX_DN(11)   I148 @T6G_MB_LIB.T6G(SCH_1):PAGE25
  CW23 P5E_CPU0_P3_RX_DP<12> @T6G_MB_LIB.T6G(SCH_1):P5E_CPU0_P3_RX_DP(12)   I148 @T6G_MB_LIB.T6G(SCH_1):PAGE25
  CW24 P5E_CPU0_P3_RX_DN<12> @T6G_MB_LIB.T6G(SCH_1):P5E_CPU0_P3_RX_DN(12)   I148 @T6G_MB_LIB.T6G(SCH_1):PAGE25
  DC23 P5E_CPU0_P3_RX_DP<13> @T6G_MB_LIB.T6G(SCH_1):P5E_CPU0_P3_RX_DP(13)   I148 @T6G_MB_LIB.T6G(SCH_1):PAGE25
  DC24 P5E_CPU0_P3_RX_DN<13> @T6G_MB_LIB.T6G(SCH_1):P5E_CPU0_P3_RX_DN(13)   I148 @T6G_MB_LIB.T6G(SCH_1):PAGE25
  DA23 P5E_CPU0_P3_RX_DP<14> @T6G_MB_LIB.T6G(SCH_1):P5E_CPU0_P3_RX_DP(14)   I148 @T6G_MB_LIB.T6G(SCH_1):PAGE25
  DA24 P5E_CPU0_P3_RX_DN<14> @T6G_MB_LIB.T6G(SCH_1):P5E_CPU0_P3_RX_DN(14)   I148 @T6G_MB_LIB.T6G(SCH_1):PAGE25
  CU23 P5E_CPU0_P3_RX_DP<15> @T6G_MB_LIB.T6G(SCH_1):P5E_CPU0_P3_RX_DP(15)   I148 @T6G_MB_LIB.T6G(SCH_1):PAGE25
  CU24 P5E_CPU0_P3_RX_DN<15> @T6G_MB_LIB.T6G(SCH_1):P5E_CPU0_P3_RX_DN(15)   I148 @T6G_MB_LIB.T6G(SCH_1):PAGE25
  CD36 P5E_CPU0_P3_TX_DP<0> @T6G_MB_LIB.T6G(SCH_1):P5E_CPU0_P3_TX_DP(0)   I148 @T6G_MB_LIB.T6G(SCH_1):PAGE25
  CD35 P5E_CPU0_P3_TX_DN<0> @T6G_MB_LIB.T6G(SCH_1):P5E_CPU0_P3_TX_DN(0)   I148 @T6G_MB_LIB.T6G(SCH_1):PAGE25
  CF36 P5E_CPU0_P3_TX_DP<1> @T6G_MB_LIB.T6G(SCH_1):P5E_CPU0_P3_TX_DP(1)   I148 @T6G_MB_LIB.T6G(SCH_1):PAGE25
  CF35 P5E_CPU0_P3_TX_DN<1> @T6G_MB_LIB.T6G(SCH_1):P5E_CPU0_P3_TX_DN(1)   I148 @T6G_MB_LIB.T6G(SCH_1):PAGE25
  CH36 P5E_CPU0_P3_TX_DP<2> @T6G_MB_LIB.T6G(SCH_1):P5E_CPU0_P3_TX_DP(2)   I148 @T6G_MB_LIB.T6G(SCH_1):PAGE25
  CH35 P5E_CPU0_P3_TX_DN<2> @T6G_MB_LIB.T6G(SCH_1):P5E_CPU0_P3_TX_DN(2)   I148 @T6G_MB_LIB.T6G(SCH_1):PAGE25
  CC33 P5E_CPU0_P3_TX_DP<3> @T6G_MB_LIB.T6G(SCH_1):P5E_CPU0_P3_TX_DP(3)   I148 @T6G_MB_LIB.T6G(SCH_1):PAGE25
  CC32 P5E_CPU0_P3_TX_DN<3> @T6G_MB_LIB.T6G(SCH_1):P5E_CPU0_P3_TX_DN(3)   I148 @T6G_MB_LIB.T6G(SCH_1):PAGE25
  CJ33 P5E_CPU0_P3_TX_DP<4> @T6G_MB_LIB.T6G(SCH_1):P5E_CPU0_P3_TX_DP(4)   I148 @T6G_MB_LIB.T6G(SCH_1):PAGE25
  CJ32 P5E_CPU0_P3_TX_DN<4> @T6G_MB_LIB.T6G(SCH_1):P5E_CPU0_P3_TX_DN(4)   I148 @T6G_MB_LIB.T6G(SCH_1):PAGE25
  CG33 P5E_CPU0_P3_TX_DP<5> @T6G_MB_LIB.T6G(SCH_1):P5E_CPU0_P3_TX_DP(5)   I148 @T6G_MB_LIB.T6G(SCH_1):PAGE25
  CG32 P5E_CPU0_P3_TX_DN<5> @T6G_MB_LIB.T6G(SCH_1):P5E_CPU0_P3_TX_DN(5)   I148 @T6G_MB_LIB.T6G(SCH_1):PAGE25
  CE33 P5E_CPU0_P3_TX_DP<6> @T6G_MB_LIB.T6G(SCH_1):P5E_CPU0_P3_TX_DP(6)   I148 @T6G_MB_LIB.T6G(SCH_1):PAGE25
  CE32 P5E_CPU0_P3_TX_DN<6> @T6G_MB_LIB.T6G(SCH_1):P5E_CPU0_P3_TX_DN(6)   I148 @T6G_MB_LIB.T6G(SCH_1):PAGE25
  CC30 P5E_CPU0_P3_TX_DP<7> @T6G_MB_LIB.T6G(SCH_1):P5E_CPU0_P3_TX_DP(7)   I148 @T6G_MB_LIB.T6G(SCH_1):PAGE25
  CC29 P5E_CPU0_P3_TX_DN<7> @T6G_MB_LIB.T6G(SCH_1):P5E_CPU0_P3_TX_DN(7)   I148 @T6G_MB_LIB.T6G(SCH_1):PAGE25
  CG30 P5E_CPU0_P3_TX_DP<8> @T6G_MB_LIB.T6G(SCH_1):P5E_CPU0_P3_TX_DP(8)   I148 @T6G_MB_LIB.T6G(SCH_1):PAGE25
  CG29 P5E_CPU0_P3_TX_DN<8> @T6G_MB_LIB.T6G(SCH_1):P5E_CPU0_P3_TX_DN(8)   I148 @T6G_MB_LIB.T6G(SCH_1):PAGE25
  CE30 P5E_CPU0_P3_TX_DP<9> @T6G_MB_LIB.T6G(SCH_1):P5E_CPU0_P3_TX_DP(9)   I148 @T6G_MB_LIB.T6G(SCH_1):PAGE25
  CE29 P5E_CPU0_P3_TX_DN<9> @T6G_MB_LIB.T6G(SCH_1):P5E_CPU0_P3_TX_DN(9)   I148 @T6G_MB_LIB.T6G(SCH_1):PAGE25
  CC27 P5E_CPU0_P3_TX_DP<10> @T6G_MB_LIB.T6G(SCH_1):P5E_CPU0_P3_TX_DP(10)   I148 @T6G_MB_LIB.T6G(SCH_1):PAGE25
  CC26 P5E_CPU0_P3_TX_DN<10> @T6G_MB_LIB.T6G(SCH_1):P5E_CPU0_P3_TX_DN(10)   I148 @T6G_MB_LIB.T6G(SCH_1):PAGE25
  CG27 P5E_CPU0_P3_TX_DP<11> @T6G_MB_LIB.T6G(SCH_1):P5E_CPU0_P3_TX_DP(11)   I148 @T6G_MB_LIB.T6G(SCH_1):PAGE25
  CG26 P5E_CPU0_P3_TX_DN<11> @T6G_MB_LIB.T6G(SCH_1):P5E_CPU0_P3_TX_DN(11)   I148 @T6G_MB_LIB.T6G(SCH_1):PAGE25
  CE27 P5E_CPU0_P3_TX_DP<12> @T6G_MB_LIB.T6G(SCH_1):P5E_CPU0_P3_TX_DP(12)   I148 @T6G_MB_LIB.T6G(SCH_1):PAGE25
  CE26 P5E_CPU0_P3_TX_DN<12> @T6G_MB_LIB.T6G(SCH_1):P5E_CPU0_P3_TX_DN(12)   I148 @T6G_MB_LIB.T6G(SCH_1):PAGE25
  CC24 P5E_CPU0_P3_TX_DP<13> @T6G_MB_LIB.T6G(SCH_1):P5E_CPU0_P3_TX_DP(13)   I148 @T6G_MB_LIB.T6G(SCH_1):PAGE25
  CC23 P5E_CPU0_P3_TX_DN<13> @T6G_MB_LIB.T6G(SCH_1):P5E_CPU0_P3_TX_DN(13)   I148 @T6G_MB_LIB.T6G(SCH_1):PAGE25
  CG24 P5E_CPU0_P3_TX_DP<14> @T6G_MB_LIB.T6G(SCH_1):P5E_CPU0_P3_TX_DP(14)   I148 @T6G_MB_LIB.T6G(SCH_1):PAGE25
  CG23 P5E_CPU0_P3_TX_DN<14> @T6G_MB_LIB.T6G(SCH_1):P5E_CPU0_P3_TX_DN(14)   I148 @T6G_MB_LIB.T6G(SCH_1):PAGE25
  CE24 P5E_CPU0_P3_TX_DP<15> @T6G_MB_LIB.T6G(SCH_1):P5E_CPU0_P3_TX_DP(15)   I148 @T6G_MB_LIB.T6G(SCH_1):PAGE25
  CE23 P5E_CPU0_P3_TX_DN<15> @T6G_MB_LIB.T6G(SCH_1):P5E_CPU0_P3_TX_DN(15)   I148 @T6G_MB_LIB.T6G(SCH_1):PAGE25
  DG47 P3E_CPU0_P4_RX_DN<2> @T6G_MB_LIB.T6G(SCH_1):P3E_CPU0_P4_RX_DN(2)    I59 @T6G_MB_LIB.T6G(SCH_1):PAGE26
  DG44 P3E_CPU0_P4_RX_DN<3> @T6G_MB_LIB.T6G(SCH_1):P3E_CPU0_P4_RX_DN(3)    I59 @T6G_MB_LIB.T6G(SCH_1):PAGE26
  DG48 P3E_CPU0_P4_RX_DP<2> @T6G_MB_LIB.T6G(SCH_1):P3E_CPU0_P4_RX_DP(2)    I59 @T6G_MB_LIB.T6G(SCH_1):PAGE26
  DG45 P3E_CPU0_P4_RX_DP<3> @T6G_MB_LIB.T6G(SCH_1):P3E_CPU0_P4_RX_DP(3)    I59 @T6G_MB_LIB.T6G(SCH_1):PAGE26
  DE46 P3E_CPU0_P4_TX_DN<2> @T6G_MB_LIB.T6G(SCH_1):P3E_CPU0_P4_TX_DN(2)    I59 @T6G_MB_LIB.T6G(SCH_1):PAGE26
  DE43 P3E_CPU0_P4_TX_DN<3> @T6G_MB_LIB.T6G(SCH_1):P3E_CPU0_P4_TX_DN(3)    I59 @T6G_MB_LIB.T6G(SCH_1):PAGE26
  DE47 P3E_CPU0_P4_TX_DP<2> @T6G_MB_LIB.T6G(SCH_1):P3E_CPU0_P4_TX_DP(2)    I59 @T6G_MB_LIB.T6G(SCH_1):PAGE26
  DE44 P3E_CPU0_P4_TX_DP<3> @T6G_MB_LIB.T6G(SCH_1):P3E_CPU0_P4_TX_DP(3)    I59 @T6G_MB_LIB.T6G(SCH_1):PAGE26
   E44 P2E_CPU0_P5_RX_DN @T6G_MB_LIB.T6G(SCH_1):P2E_CPU0_P5_RX_DN    I59 @T6G_MB_LIB.T6G(SCH_1):PAGE26
   E41     NC     NC    I59 @T6G_MB_LIB.T6G(SCH_1):PAGE26
   E43 P2E_CPU0_P5_RX_DP @T6G_MB_LIB.T6G(SCH_1):P2E_CPU0_P5_RX_DP    I59 @T6G_MB_LIB.T6G(SCH_1):PAGE26
   E40     NC     NC    I59 @T6G_MB_LIB.T6G(SCH_1):PAGE26
   C45 P2E_CPU0_P5_TX_DN @T6G_MB_LIB.T6G(SCH_1):P2E_CPU0_P5_TX_DN    I59 @T6G_MB_LIB.T6G(SCH_1):PAGE26
   C42     NC     NC    I59 @T6G_MB_LIB.T6G(SCH_1):PAGE26
   C44 P2E_CPU0_P5_TX_DP @T6G_MB_LIB.T6G(SCH_1):P2E_CPU0_P5_TX_DP    I59 @T6G_MB_LIB.T6G(SCH_1):PAGE26
   C41     NC     NC    I59 @T6G_MB_LIB.T6G(SCH_1):PAGE26
  DE53 P3E_CPU0_P4_TX_DP<0> @T6G_MB_LIB.T6G(SCH_1):P3E_CPU0_P4_TX_DP(0)    I59 @T6G_MB_LIB.T6G(SCH_1):PAGE26
  DE50 P3E_CPU0_P4_TX_DP<1> @T6G_MB_LIB.T6G(SCH_1):P3E_CPU0_P4_TX_DP(1)    I59 @T6G_MB_LIB.T6G(SCH_1):PAGE26
  DE52 P3E_CPU0_P4_TX_DN<0> @T6G_MB_LIB.T6G(SCH_1):P3E_CPU0_P4_TX_DN(0)    I59 @T6G_MB_LIB.T6G(SCH_1):PAGE26
  DG54 P3E_CPU0_P4_RX_DP<0> @T6G_MB_LIB.T6G(SCH_1):P3E_CPU0_P4_RX_DP(0)    I59 @T6G_MB_LIB.T6G(SCH_1):PAGE26
  DE49 P3E_CPU0_P4_TX_DN<1> @T6G_MB_LIB.T6G(SCH_1):P3E_CPU0_P4_TX_DN(1)    I59 @T6G_MB_LIB.T6G(SCH_1):PAGE26
  DG51 P3E_CPU0_P4_RX_DP<1> @T6G_MB_LIB.T6G(SCH_1):P3E_CPU0_P4_RX_DP(1)    I59 @T6G_MB_LIB.T6G(SCH_1):PAGE26
  DG53 P3E_CPU0_P4_RX_DN<0> @T6G_MB_LIB.T6G(SCH_1):P3E_CPU0_P4_RX_DN(0)    I59 @T6G_MB_LIB.T6G(SCH_1):PAGE26
  DG50 P3E_CPU0_P4_RX_DN<1> @T6G_MB_LIB.T6G(SCH_1):P3E_CPU0_P4_RX_DN(1)    I59 @T6G_MB_LIB.T6G(SCH_1):PAGE26
   E50 WAFL_CPU1_TX1_CPU0_RX0_DN @T6G_MB_LIB.T6G(SCH_1):WAFL_CPU1_TX1_CPU0_RX0_DN    I59 @T6G_MB_LIB.T6G(SCH_1):PAGE26
   E49 WAFL_CPU1_TX1_CPU0_RX0_DP @T6G_MB_LIB.T6G(SCH_1):WAFL_CPU1_TX1_CPU0_RX0_DP    I59 @T6G_MB_LIB.T6G(SCH_1):PAGE26
   E47     NC     NC    I59 @T6G_MB_LIB.T6G(SCH_1):PAGE26
   E46     NC     NC    I59 @T6G_MB_LIB.T6G(SCH_1):PAGE26
   C51 WAFL_CPU0_TX0_CPU1_RX1_DN @T6G_MB_LIB.T6G(SCH_1):WAFL_CPU0_TX0_CPU1_RX1_DN    I59 @T6G_MB_LIB.T6G(SCH_1):PAGE26
   C50 WAFL_CPU0_TX0_CPU1_RX1_DP @T6G_MB_LIB.T6G(SCH_1):WAFL_CPU0_TX0_CPU1_RX1_DP    I59 @T6G_MB_LIB.T6G(SCH_1):PAGE26
   C48     NC     NC    I59 @T6G_MB_LIB.T6G(SCH_1):PAGE26
   C47     NC     NC    I59 @T6G_MB_LIB.T6G(SCH_1):PAGE26
   A68 APML_CPU0_ALERT_N @T6G_MB_LIB.T6G(SCH_1):APML_CPU0_ALERT_N   I227 @T6G_MB_LIB.T6G(SCH_1):PAGE27
   B66 PRSNT_CPU0_N @T6G_MB_LIB.T6G(SCH_1):PRSNT_CPU0_N   I227 @T6G_MB_LIB.T6G(SCH_1):PAGE27
   C16 JTAG_CPU0_DBREQ_N @T6G_MB_LIB.T6G(SCH_1):JTAG_CPU0_DBREQ_N   I227 @T6G_MB_LIB.T6G(SCH_1):PAGE27
   A69 CPU0_PROCHOT_N @T6G_MB_LIB.T6G(SCH_1):CPU0_PROCHOT_N   I227 @T6G_MB_LIB.T6G(SCH_1):PAGE27
  DJ55 CPU0_SA0 @T6G_MB_LIB.T6G(SCH_1):CPU0_SA0   I227 @T6G_MB_LIB.T6G(SCH_1):PAGE27
  DJ71 SMB_APML_CPU0_SCL @T6G_MB_LIB.T6G(SCH_1):SMB_APML_CPU0_SCL   I227 @T6G_MB_LIB.T6G(SCH_1):PAGE27
  DH71 SMB_APML_CPU0_SDA @T6G_MB_LIB.T6G(SCH_1):SMB_APML_CPU0_SDA   I227 @T6G_MB_LIB.T6G(SCH_1):PAGE27
   C17 JTAG_CPU0_TDI @T6G_MB_LIB.T6G(SCH_1):JTAG_CPU0_TDI   I227 @T6G_MB_LIB.T6G(SCH_1):PAGE27
   C18 JTAG_CPU0_R_TDO @T6G_MB_LIB.T6G(SCH_1):JTAG_CPU0_R_TDO   I227 @T6G_MB_LIB.T6G(SCH_1):PAGE27
   DJ9 CPU0_THERMTRIP_N @T6G_MB_LIB.T6G(SCH_1):CPU0_THERMTRIP_N   I227 @T6G_MB_LIB.T6G(SCH_1):PAGE27
   A16 JTAG_CPU0_TMS @T6G_MB_LIB.T6G(SCH_1):JTAG_CPU0_TMS   I227 @T6G_MB_LIB.T6G(SCH_1):PAGE27
   A17 JTAG_CPU0_TRST_N @T6G_MB_LIB.T6G(SCH_1):JTAG_CPU0_TRST_N   I227 @T6G_MB_LIB.T6G(SCH_1):PAGE27
   C66 CPU0_XTRIG_R2_L4 @T6G_MB_LIB.T6G(SCH_1):CPU0_XTRIG_R2_L4   I227 @T6G_MB_LIB.T6G(SCH_1):PAGE27
   C65 CPU0_XTRIG_R2_L5 @T6G_MB_LIB.T6G(SCH_1):CPU0_XTRIG_R2_L5   I227 @T6G_MB_LIB.T6G(SCH_1):PAGE27
   A66 CPU0_XTRIG_R2_L6 @T6G_MB_LIB.T6G(SCH_1):CPU0_XTRIG_R2_L6   I227 @T6G_MB_LIB.T6G(SCH_1):PAGE27
   A65 CPU0_XTRIG_R2_L7 @T6G_MB_LIB.T6G(SCH_1):CPU0_XTRIG_R2_L7   I227 @T6G_MB_LIB.T6G(SCH_1):PAGE27
  DJ56 CPU0_SA1 @T6G_MB_LIB.T6G(SCH_1):CPU0_SA1   I227 @T6G_MB_LIB.T6G(SCH_1):PAGE27
   C70 CPU0_CORETYPE0 @T6G_MB_LIB.T6G(SCH_1):CPU0_CORETYPE0   I227 @T6G_MB_LIB.T6G(SCH_1):PAGE27
   B69 CPU0_CORETYPE1 @T6G_MB_LIB.T6G(SCH_1):CPU0_CORETYPE1   I227 @T6G_MB_LIB.T6G(SCH_1):PAGE27
   C68 CPU0_SP5R2 @T6G_MB_LIB.T6G(SCH_1):CPU0_SP5R2   I227 @T6G_MB_LIB.T6G(SCH_1):PAGE27
  DH73 CPU0_SP5R3 @T6G_MB_LIB.T6G(SCH_1):CPU0_SP5R3   I227 @T6G_MB_LIB.T6G(SCH_1):PAGE27
  DH10 CPU0_SP5R4 @T6G_MB_LIB.T6G(SCH_1):CPU0_SP5R4   I227 @T6G_MB_LIB.T6G(SCH_1):PAGE27
   C22 FM_P0_PCC0_N @T6G_MB_LIB.T6G(SCH_1):FM_P0_PCC0_N   I227 @T6G_MB_LIB.T6G(SCH_1):PAGE27
  DG72 FM_P0_PCC1_N @T6G_MB_LIB.T6G(SCH_1):FM_P0_PCC1_N   I227 @T6G_MB_LIB.T6G(SCH_1):PAGE27
   C32 NC_CPU0_AZ_BITCLK @T6G_MB_LIB.T6G(SCH_1):NC_CPU0_AZ_BITCLK   I227 @T6G_MB_LIB.T6G(SCH_1):PAGE27
   D32 NC_CPU0_AZ_SYNC @T6G_MB_LIB.T6G(SCH_1):NC_CPU0_AZ_SYNC   I227 @T6G_MB_LIB.T6G(SCH_1):PAGE27
   A22 SVID_PVDDCR_CPU0_P0_SVD @T6G_MB_LIB.T6G(SCH_1):SVID_PVDDCR_CPU0_P0_SVD   I227 @T6G_MB_LIB.T6G(SCH_1):PAGE27
   B21 SVID_PVDDCR_CPU0_P0_SVTO @T6G_MB_LIB.T6G(SCH_1):SVID_PVDDCR_CPU0_P0_SVTO   I227 @T6G_MB_LIB.T6G(SCH_1):PAGE27
  DH72 SVID_PVDDCR_CPU1_P0_SVD @T6G_MB_LIB.T6G(SCH_1):SVID_PVDDCR_CPU1_P0_SVD   I227 @T6G_MB_LIB.T6G(SCH_1):PAGE27
   A23 SVID_PVDDCR_CPU0_P0_SVC @T6G_MB_LIB.T6G(SCH_1):SVID_PVDDCR_CPU0_P0_SVC   I227 @T6G_MB_LIB.T6G(SCH_1):PAGE27
  DG73 SVID_PVDDCR_CPU1_P0_SVTO @T6G_MB_LIB.T6G(SCH_1):SVID_PVDDCR_CPU1_P0_SVTO   I227 @T6G_MB_LIB.T6G(SCH_1):PAGE27
  DJ72 SVID_PVDDCR_CPU1_P0_SVC @T6G_MB_LIB.T6G(SCH_1):SVID_PVDDCR_CPU1_P0_SVC   I227 @T6G_MB_LIB.T6G(SCH_1):PAGE27
  DG35 UART_CPU0_UART0_RX @T6G_MB_LIB.T6G(SCH_1):UART_CPU0_UART0_RX   I227 @T6G_MB_LIB.T6G(SCH_1):PAGE27
  DF34 TP_UART_CPU0_UART0_RTS_N @T6G_MB_LIB.T6G(SCH_1):TP_UART_CPU0_UART0_RTS_N   I227 @T6G_MB_LIB.T6G(SCH_1):PAGE27
  DG34 TP_CPU0_UART0_INTR @T6G_MB_LIB.T6G(SCH_1):TP_CPU0_UART0_INTR   I227 @T6G_MB_LIB.T6G(SCH_1):PAGE27
  DJ34 UART_CPU0_UART0_R_TX @T6G_MB_LIB.T6G(SCH_1):UART_CPU0_UART0_R_TX   I227 @T6G_MB_LIB.T6G(SCH_1):PAGE27
  DJ33 FM_BIOS_USB_RECOVERY_R @T6G_MB_LIB.T6G(SCH_1):FM_BIOS_USB_RECOVERY_R   I227 @T6G_MB_LIB.T6G(SCH_1):PAGE27
   A33 NC_CPU0_AZ_SDIN2 @T6G_MB_LIB.T6G(SCH_1):NC_CPU0_AZ_SDIN2   I227 @T6G_MB_LIB.T6G(SCH_1):PAGE27
   A32 NC_CPU0_AZ_SDOUT @T6G_MB_LIB.T6G(SCH_1):NC_CPU0_AZ_SDOUT   I227 @T6G_MB_LIB.T6G(SCH_1):PAGE27
   A34 NC_CPU0_AZ_RST_N @T6G_MB_LIB.T6G(SCH_1):NC_CPU0_AZ_RST_N   I227 @T6G_MB_LIB.T6G(SCH_1):PAGE27
   C33 NC_CPU0_AZ_SDIN0 @T6G_MB_LIB.T6G(SCH_1):NC_CPU0_AZ_SDIN0   I227 @T6G_MB_LIB.T6G(SCH_1):PAGE27
   D33 NC_CPU0_AZ_SDIN1 @T6G_MB_LIB.T6G(SCH_1):NC_CPU0_AZ_SDIN1   I227 @T6G_MB_LIB.T6G(SCH_1):PAGE27
   C19 CPU0_SP5R1 @T6G_MB_LIB.T6G(SCH_1):CPU0_SP5R1   I227 @T6G_MB_LIB.T6G(SCH_1):PAGE27
   B17 JTAG_CPU0_TCK @T6G_MB_LIB.T6G(SCH_1):JTAG_CPU0_TCK   I227 @T6G_MB_LIB.T6G(SCH_1):PAGE27
   DH8 CPU0_RTC_LDO_SELECT @T6G_MB_LIB.T6G(SCH_1):CPU0_RTC_LDO_SELECT   I227 @T6G_MB_LIB.T6G(SCH_1):PAGE27
  DH33 UART_CPU0_SCM_UART1_RX @T6G_MB_LIB.T6G(SCH_1):UART_CPU0_SCM_UART1_RX   I227 @T6G_MB_LIB.T6G(SCH_1):PAGE27
  DJ32 UART_CPU0_SCM_UART1_R_TX @T6G_MB_LIB.T6G(SCH_1):UART_CPU0_SCM_UART1_R_TX   I227 @T6G_MB_LIB.T6G(SCH_1):PAGE27
    C3 VSENSE_VSS_SENSE_A_P0 @T6G_MB_LIB.T6G(SCH_1):VSENSE_VSS_SENSE_A_P0   I227 @T6G_MB_LIB.T6G(SCH_1):PAGE27
  BR54 VSENSE_VSS_SENSE_B_P0 @T6G_MB_LIB.T6G(SCH_1):VSENSE_VSS_SENSE_B_P0   I227 @T6G_MB_LIB.T6G(SCH_1):PAGE27
   DJ3 VSENSE_VSS_SENSE_C_P0 @T6G_MB_LIB.T6G(SCH_1):VSENSE_VSS_SENSE_C_P0   I227 @T6G_MB_LIB.T6G(SCH_1):PAGE27
   B73 VSENSE_PVDD18_S5_P0_DN @T6G_MB_LIB.T6G(SCH_1):VSENSE_PVDD18_S5_P0_DN   I227 @T6G_MB_LIB.T6G(SCH_1):PAGE27
  BR53 VSENSE_PVDDIO_P0_DP @T6G_MB_LIB.T6G(SCH_1):VSENSE_PVDDIO_P0_DP   I227 @T6G_MB_LIB.T6G(SCH_1):PAGE27
   DH3 VSENSE_PVDD11_S3_P0_DP @T6G_MB_LIB.T6G(SCH_1):VSENSE_PVDD11_S3_P0_DP   I227 @T6G_MB_LIB.T6G(SCH_1):PAGE27
   C74 VSENSE_PVDD18_S5_P0_DP @T6G_MB_LIB.T6G(SCH_1):VSENSE_PVDD18_S5_P0_DP   I227 @T6G_MB_LIB.T6G(SCH_1):PAGE27
  BP53 TP_VSENSE_PVDD33_S5_P0 @T6G_MB_LIB.T6G(SCH_1):TP_VSENSE_PVDD33_S5_P0   I227 @T6G_MB_LIB.T6G(SCH_1):PAGE27
    B3 VSENSE_PVDDCR_SOC_P0_DP @T6G_MB_LIB.T6G(SCH_1):VSENSE_PVDDCR_SOC_P0_DP   I227 @T6G_MB_LIB.T6G(SCH_1):PAGE27
   DG3 VSENSE_PVDDCR_CPU1_P0_DP @T6G_MB_LIB.T6G(SCH_1):VSENSE_PVDDCR_CPU1_P0_DP   I227 @T6G_MB_LIB.T6G(SCH_1):PAGE27
    C2 VSENSE_PVDDCR_CPU0_P0_DP @T6G_MB_LIB.T6G(SCH_1):VSENSE_PVDDCR_CPU0_P0_DP   I227 @T6G_MB_LIB.T6G(SCH_1):PAGE27
  AA23 TP_CPU0_TEST6_X3D4 @T6G_MB_LIB.T6G(SCH_1):TP_CPU0_TEST6_X3D4   I227 @T6G_MB_LIB.T6G(SCH_1):PAGE27
  CJ30 TP_CPU0_TEST6_CCD1 @T6G_MB_LIB.T6G(SCH_1):TP_CPU0_TEST6_CCD1   I227 @T6G_MB_LIB.T6G(SCH_1):PAGE27
  AA51 TP_CPU0_TEST5_CCD0 @T6G_MB_LIB.T6G(SCH_1):TP_CPU0_TEST5_CCD0   I227 @T6G_MB_LIB.T6G(SCH_1):PAGE27
  CJ53 TP_CPU0_TEST6_X3D5 @T6G_MB_LIB.T6G(SCH_1):TP_CPU0_TEST6_X3D5   I227 @T6G_MB_LIB.T6G(SCH_1):PAGE27
  CJ46 TP_CPU0_TEST6_CCD2 @T6G_MB_LIB.T6G(SCH_1):TP_CPU0_TEST6_CCD2   I227 @T6G_MB_LIB.T6G(SCH_1):PAGE27
  CJ27 TP_CPU0_TEST5_CCD1 @T6G_MB_LIB.T6G(SCH_1):TP_CPU0_TEST5_CCD1   I227 @T6G_MB_LIB.T6G(SCH_1):PAGE27
  AA50 TP_CPU0_TEST4_CCD0 @T6G_MB_LIB.T6G(SCH_1):TP_CPU0_TEST4_CCD0   I227 @T6G_MB_LIB.T6G(SCH_1):PAGE27
   Y46 TP_CPU0_TEST6_CCD3 @T6G_MB_LIB.T6G(SCH_1):TP_CPU0_TEST6_CCD3   I227 @T6G_MB_LIB.T6G(SCH_1):PAGE27
  CJ49 TP_CPU0_TEST5_CCD2 @T6G_MB_LIB.T6G(SCH_1):TP_CPU0_TEST5_CCD2   I227 @T6G_MB_LIB.T6G(SCH_1):PAGE27
  CJ28 TP_CPU0_TEST4_CCD1 @T6G_MB_LIB.T6G(SCH_1):TP_CPU0_TEST4_CCD1   I227 @T6G_MB_LIB.T6G(SCH_1):PAGE27
   Y30 TP_CPU0_TEST5_CCD3 @T6G_MB_LIB.T6G(SCH_1):TP_CPU0_TEST5_CCD3   I227 @T6G_MB_LIB.T6G(SCH_1):PAGE27
  AA25 TP_CPU0_TEST4_IOD @T6G_MB_LIB.T6G(SCH_1):TP_CPU0_TEST4_IOD   I227 @T6G_MB_LIB.T6G(SCH_1):PAGE27
  CJ48 TP_CPU0_TEST4_CCD2 @T6G_MB_LIB.T6G(SCH_1):TP_CPU0_TEST4_CCD2   I227 @T6G_MB_LIB.T6G(SCH_1):PAGE27
  AA24 TP_CPU0_TEST5_IOD @T6G_MB_LIB.T6G(SCH_1):TP_CPU0_TEST5_IOD   I227 @T6G_MB_LIB.T6G(SCH_1):PAGE27
  AA53 TP_CPU0_TEST5_CCD4 @T6G_MB_LIB.T6G(SCH_1):TP_CPU0_TEST5_CCD4   I227 @T6G_MB_LIB.T6G(SCH_1):PAGE27
  AA30 TP_CPU0_TEST4_CCD3 @T6G_MB_LIB.T6G(SCH_1):TP_CPU0_TEST4_CCD3   I227 @T6G_MB_LIB.T6G(SCH_1):PAGE27
  AA49 TP_CPU0_TEST6_IOD @T6G_MB_LIB.T6G(SCH_1):TP_CPU0_TEST6_IOD   I227 @T6G_MB_LIB.T6G(SCH_1):PAGE27
  CJ25 TP_CPU0_TEST5_CCD5 @T6G_MB_LIB.T6G(SCH_1):TP_CPU0_TEST5_CCD5   I227 @T6G_MB_LIB.T6G(SCH_1):PAGE27
  AA52 TP_CPU0_TEST4_CCD4 @T6G_MB_LIB.T6G(SCH_1):TP_CPU0_TEST4_CCD4   I227 @T6G_MB_LIB.T6G(SCH_1):PAGE27
  CJ51 TP_CPU0_TEST5_CCD6 @T6G_MB_LIB.T6G(SCH_1):TP_CPU0_TEST5_CCD6   I227 @T6G_MB_LIB.T6G(SCH_1):PAGE27
  CJ26 TP_CPU0_TEST4_CCD5 @T6G_MB_LIB.T6G(SCH_1):TP_CPU0_TEST4_CCD5   I227 @T6G_MB_LIB.T6G(SCH_1):PAGE27
  AA26 TP_CPU0_TEST5_CCD7 @T6G_MB_LIB.T6G(SCH_1):TP_CPU0_TEST5_CCD7   I227 @T6G_MB_LIB.T6G(SCH_1):PAGE27
  CJ50 TP_CPU0_TEST4_CCD6 @T6G_MB_LIB.T6G(SCH_1):TP_CPU0_TEST4_CCD6   I227 @T6G_MB_LIB.T6G(SCH_1):PAGE27
   B60 TP_CPU0_TEST47_CCD0 @T6G_MB_LIB.T6G(SCH_1):TP_CPU0_TEST47_CCD0   I227 @T6G_MB_LIB.T6G(SCH_1):PAGE27
   Y47 TP_CPU0_TEST5_CCD8 @T6G_MB_LIB.T6G(SCH_1):TP_CPU0_TEST5_CCD8   I227 @T6G_MB_LIB.T6G(SCH_1):PAGE27
   B61 TP_CPU0_TEST50_IOD @T6G_MB_LIB.T6G(SCH_1):TP_CPU0_TEST50_IOD   I227 @T6G_MB_LIB.T6G(SCH_1):PAGE27
  AA27 TP_CPU0_TEST4_CCD7 @T6G_MB_LIB.T6G(SCH_1):TP_CPU0_TEST4_CCD7   I227 @T6G_MB_LIB.T6G(SCH_1):PAGE27
  CJ24 TP_CPU0_TEST47_CCD1 @T6G_MB_LIB.T6G(SCH_1):TP_CPU0_TEST47_CCD1   I227 @T6G_MB_LIB.T6G(SCH_1):PAGE27
  CK29 TP_CPU0_TEST5_CCD9 @T6G_MB_LIB.T6G(SCH_1):TP_CPU0_TEST5_CCD9   I227 @T6G_MB_LIB.T6G(SCH_1):PAGE27
  AA48 TP_CPU0_TEST4_CCD8 @T6G_MB_LIB.T6G(SCH_1):TP_CPU0_TEST4_CCD8   I227 @T6G_MB_LIB.T6G(SCH_1):PAGE27
  CK46 TP_CPU0_TEST47_CCD2 @T6G_MB_LIB.T6G(SCH_1):TP_CPU0_TEST47_CCD2   I227 @T6G_MB_LIB.T6G(SCH_1):PAGE27
  CJ47 TP_CPU0_TEST4_CCD10 @T6G_MB_LIB.T6G(SCH_1):TP_CPU0_TEST4_CCD10   I227 @T6G_MB_LIB.T6G(SCH_1):PAGE27
  CK30 TP_CPU0_TEST4_CCD9 @T6G_MB_LIB.T6G(SCH_1):TP_CPU0_TEST4_CCD9   I227 @T6G_MB_LIB.T6G(SCH_1):PAGE27
  CK47 TP_CPU0_TEST5_CCD10 @T6G_MB_LIB.T6G(SCH_1):TP_CPU0_TEST5_CCD10   I227 @T6G_MB_LIB.T6G(SCH_1):PAGE27
  AA28 TP_CPU0_TEST4_CCD11 @T6G_MB_LIB.T6G(SCH_1):TP_CPU0_TEST4_CCD11   I227 @T6G_MB_LIB.T6G(SCH_1):PAGE27
   Y29 TP_CPU0_TEST5_CCD11 @T6G_MB_LIB.T6G(SCH_1):TP_CPU0_TEST5_CCD11   I227 @T6G_MB_LIB.T6G(SCH_1):PAGE27
  AA47 TP_CPU0_TEST6_X3D0 @T6G_MB_LIB.T6G(SCH_1):TP_CPU0_TEST6_X3D0   I227 @T6G_MB_LIB.T6G(SCH_1):PAGE27
   B58 TP_CPU0_TEST47_IOD0 @T6G_MB_LIB.T6G(SCH_1):TP_CPU0_TEST47_IOD0   I227 @T6G_MB_LIB.T6G(SCH_1):PAGE27
  CJ29 TP_CPU0_TEST6_X3D1 @T6G_MB_LIB.T6G(SCH_1):TP_CPU0_TEST6_X3D1   I227 @T6G_MB_LIB.T6G(SCH_1):PAGE27
    D7 TP_CPU0_TEST47_IOD1 @T6G_MB_LIB.T6G(SCH_1):TP_CPU0_TEST47_IOD1   I227 @T6G_MB_LIB.T6G(SCH_1):PAGE27
  AA29 TP_CPU0_TEST6_X3D2 @T6G_MB_LIB.T6G(SCH_1):TP_CPU0_TEST6_X3D2   I227 @T6G_MB_LIB.T6G(SCH_1):PAGE27
  CJ52 TP_CPU0_TEST6_X3D3 @T6G_MB_LIB.T6G(SCH_1):TP_CPU0_TEST6_X3D3   I227 @T6G_MB_LIB.T6G(SCH_1):PAGE27
  AA46 TP_CPU0_TEST6_CCD0 @T6G_MB_LIB.T6G(SCH_1):TP_CPU0_TEST6_CCD0   I227 @T6G_MB_LIB.T6G(SCH_1):PAGE27
   E32 TP_CPU0_TEST47_CCD3 @T6G_MB_LIB.T6G(SCH_1):TP_CPU0_TEST47_CCD3   I227 @T6G_MB_LIB.T6G(SCH_1):PAGE27
   W31 TP_CPU0_TEST41_IDO @T6G_MB_LIB.T6G(SCH_1):TP_CPU0_TEST41_IDO   I227 @T6G_MB_LIB.T6G(SCH_1):PAGE27
   C63 CPU0_BP0 @T6G_MB_LIB.T6G(SCH_1):CPU0_BP0   I227 @T6G_MB_LIB.T6G(SCH_1):PAGE27
   C62 CPU0_BP1 @T6G_MB_LIB.T6G(SCH_1):CPU0_BP1   I227 @T6G_MB_LIB.T6G(SCH_1):PAGE27
   A63 CPU0_BP2 @T6G_MB_LIB.T6G(SCH_1):CPU0_BP2   I227 @T6G_MB_LIB.T6G(SCH_1):PAGE27
   A62 CPU0_BP3 @T6G_MB_LIB.T6G(SCH_1):CPU0_BP3   I227 @T6G_MB_LIB.T6G(SCH_1):PAGE27
   D68 CPU0_CORETYPE2 @T6G_MB_LIB.T6G(SCH_1):CPU0_CORETYPE2   I227 @T6G_MB_LIB.T6G(SCH_1):PAGE27
   DJ8 CPU0_PWR_GOOD @T6G_MB_LIB.T6G(SCH_1):CPU0_PWR_GOOD   I188 @T6G_MB_LIB.T6G(SCH_1):PAGE28
  DG10 RST_CPU0_RSMRST_N @T6G_MB_LIB.T6G(SCH_1):RST_CPU0_RSMRST_N   I188 @T6G_MB_LIB.T6G(SCH_1):PAGE28
   DJ5 CPU0_SLP_S3_N @T6G_MB_LIB.T6G(SCH_1):CPU0_SLP_S3_N   I188 @T6G_MB_LIB.T6G(SCH_1):PAGE28
   DG4 CPU0_SLP_S5_N @T6G_MB_LIB.T6G(SCH_1):CPU0_SLP_S5_N   I188 @T6G_MB_LIB.T6G(SCH_1):PAGE28
   DH6 RST_CPU0_SYS_N @T6G_MB_LIB.T6G(SCH_1):RST_CPU0_SYS_N   I188 @T6G_MB_LIB.T6G(SCH_1):PAGE28
  DJ10 IRQ_WAKE_N @T6G_MB_LIB.T6G(SCH_1):IRQ_WAKE_N   I188 @T6G_MB_LIB.T6G(SCH_1):PAGE28
  DJ14 XTAL_CPU0_X32K_X1 @T6G_MB_LIB.T6G(SCH_1):XTAL_CPU0_X32K_X1   I188 @T6G_MB_LIB.T6G(SCH_1):PAGE28
  DJ13 XTAL_CPU0_X32K_X2 @T6G_MB_LIB.T6G(SCH_1):XTAL_CPU0_X32K_X2   I188 @T6G_MB_LIB.T6G(SCH_1):PAGE28
  DJ17 XTAL_CPU0_X48M_X1 @T6G_MB_LIB.T6G(SCH_1):XTAL_CPU0_X48M_X1   I188 @T6G_MB_LIB.T6G(SCH_1):PAGE28
  DJ16 XTAL_CPU0_X48M_X2 @T6G_MB_LIB.T6G(SCH_1):XTAL_CPU0_X48M_X2   I188 @T6G_MB_LIB.T6G(SCH_1):PAGE28
   DH7 CPU0_PWR_BTN_N @T6G_MB_LIB.T6G(SCH_1):CPU0_PWR_BTN_N   I188 @T6G_MB_LIB.T6G(SCH_1):PAGE28
   B64 CPU0_NV_SAVE_N @T6G_MB_LIB.T6G(SCH_1):CPU0_NV_SAVE_N   I188 @T6G_MB_LIB.T6G(SCH_1):PAGE28
   B63 CPU0_FORCE_SELFREFRESH @T6G_MB_LIB.T6G(SCH_1):CPU0_FORCE_SELFREFRESH   I188 @T6G_MB_LIB.T6G(SCH_1):PAGE28
   DH9 CLK_CPU0_RTCCLK @T6G_MB_LIB.T6G(SCH_1):CLK_CPU0_RTCCLK   I188 @T6G_MB_LIB.T6G(SCH_1):PAGE28
    C9 CLK_100M_CPU0_CLK05_R_DN @T6G_MB_LIB.T6G(SCH_1):CLK_100M_CPU0_CLK05_R_DN   I188 @T6G_MB_LIB.T6G(SCH_1):PAGE28
  DJ50     NC     NC   I188 @T6G_MB_LIB.T6G(SCH_1):PAGE28
   C12 CLK_100M_CPU0_CLK04_R_DN @T6G_MB_LIB.T6G(SCH_1):CLK_100M_CPU0_CLK04_R_DN   I188 @T6G_MB_LIB.T6G(SCH_1):PAGE28
  DJ47     NC     NC   I188 @T6G_MB_LIB.T6G(SCH_1):PAGE28
    B9 CLK_100M_CPU0_CLK05_R_DP @T6G_MB_LIB.T6G(SCH_1):CLK_100M_CPU0_CLK05_R_DP   I188 @T6G_MB_LIB.T6G(SCH_1):PAGE28
   A11 CLK_100M_CPU0_CLK03_R_DN @T6G_MB_LIB.T6G(SCH_1):CLK_100M_CPU0_CLK03_R_DN   I188 @T6G_MB_LIB.T6G(SCH_1):PAGE28
  DJ51     NC     NC   I188 @T6G_MB_LIB.T6G(SCH_1):PAGE28
  DJ54 CLK_100M_CPU0_CLK13_R_DN @T6G_MB_LIB.T6G(SCH_1):CLK_100M_CPU0_CLK13_R_DN   I188 @T6G_MB_LIB.T6G(SCH_1):PAGE28
   B12 CLK_100M_CPU0_CLK04_R_DP @T6G_MB_LIB.T6G(SCH_1):CLK_100M_CPU0_CLK04_R_DP   I188 @T6G_MB_LIB.T6G(SCH_1):PAGE28
    C6 CLK_100M_CPU0_CLK02_R_DN @T6G_MB_LIB.T6G(SCH_1):CLK_100M_CPU0_CLK02_R_DN   I188 @T6G_MB_LIB.T6G(SCH_1):PAGE28
  DJ48     NC     NC   I188 @T6G_MB_LIB.T6G(SCH_1):PAGE28
  DJ44 CLK_100M_CPU0_CLK12_R_DN @T6G_MB_LIB.T6G(SCH_1):CLK_100M_CPU0_CLK12_R_DN   I188 @T6G_MB_LIB.T6G(SCH_1):PAGE28
   A10 CLK_100M_CPU0_CLK03_R_DP @T6G_MB_LIB.T6G(SCH_1):CLK_100M_CPU0_CLK03_R_DP   I188 @T6G_MB_LIB.T6G(SCH_1):PAGE28
    A7 CLK_100M_CPU0_CLK01_R_DN @T6G_MB_LIB.T6G(SCH_1):CLK_100M_CPU0_CLK01_R_DN   I188 @T6G_MB_LIB.T6G(SCH_1):PAGE28
  DJ53 CLK_100M_CPU0_CLK13_R_DP @T6G_MB_LIB.T6G(SCH_1):CLK_100M_CPU0_CLK13_R_DP   I188 @T6G_MB_LIB.T6G(SCH_1):PAGE28
  DJ42 CLK_100M_CPU0_CLK11_R_DN @T6G_MB_LIB.T6G(SCH_1):CLK_100M_CPU0_CLK11_R_DN   I188 @T6G_MB_LIB.T6G(SCH_1):PAGE28
    B6 CLK_100M_CPU0_CLK02_R_DP @T6G_MB_LIB.T6G(SCH_1):CLK_100M_CPU0_CLK02_R_DP   I188 @T6G_MB_LIB.T6G(SCH_1):PAGE28
  DJ45 CLK_100M_CPU0_CLK12_R_DP @T6G_MB_LIB.T6G(SCH_1):CLK_100M_CPU0_CLK12_R_DP   I188 @T6G_MB_LIB.T6G(SCH_1):PAGE28
    A8 CLK_100M_CPU0_CLK01_R_DP @T6G_MB_LIB.T6G(SCH_1):CLK_100M_CPU0_CLK01_R_DP   I188 @T6G_MB_LIB.T6G(SCH_1):PAGE28
  DJ41 CLK_100M_CPU0_CLK11_R_DP @T6G_MB_LIB.T6G(SCH_1):CLK_100M_CPU0_CLK11_R_DP   I188 @T6G_MB_LIB.T6G(SCH_1):PAGE28
  DF36 FM_PASSWORD_CLEAR_R_N @T6G_MB_LIB.T6G(SCH_1):FM_PASSWORD_CLEAR_R_N   I188 @T6G_MB_LIB.T6G(SCH_1):PAGE28
  DE36 CPU0_SPD_HOST_CTRL_N @T6G_MB_LIB.T6G(SCH_1):CPU0_SPD_HOST_CTRL_N   I188 @T6G_MB_LIB.T6G(SCH_1):PAGE28
  DG36 RST_CPU0_PERST1_N @T6G_MB_LIB.T6G(SCH_1):RST_CPU0_PERST1_N   I188 @T6G_MB_LIB.T6G(SCH_1):PAGE28
   B15     NC     NC   I188 @T6G_MB_LIB.T6G(SCH_1):PAGE28
   B72 SMB_CPU0_2_R_SDA @T6G_MB_LIB.T6G(SCH_1):SMB_CPU0_2_R_SDA   I188 @T6G_MB_LIB.T6G(SCH_1):PAGE28
   D15     NC     NC   I188 @T6G_MB_LIB.T6G(SCH_1):PAGE28
    B4 SMB_CPU0_3_R_SDA @T6G_MB_LIB.T6G(SCH_1):SMB_CPU0_3_R_SDA   I188 @T6G_MB_LIB.T6G(SCH_1):PAGE28
   A13 FAB_REV_ID2 @T6G_MB_LIB.T6G(SCH_1):FAB_REV_ID2   I188 @T6G_MB_LIB.T6G(SCH_1):PAGE28
   A14 FAB_REV_ID0 @T6G_MB_LIB.T6G(SCH_1):FAB_REV_ID0   I188 @T6G_MB_LIB.T6G(SCH_1):PAGE28
   D18 RST_CPU0_PERST0_N @T6G_MB_LIB.T6G(SCH_1):RST_CPU0_PERST0_N   I188 @T6G_MB_LIB.T6G(SCH_1):PAGE28
  DH16 IRQ_SMI_ACTIVE_N @T6G_MB_LIB.T6G(SCH_1):IRQ_SMI_ACTIVE_N   I188 @T6G_MB_LIB.T6G(SCH_1):PAGE28
   B71 I3C_0_SPD_DDRAF_CPU0_R_SDA @T6G_MB_LIB.T6G(SCH_1):I3C_0_SPD_DDRAF_CPU0_R_SDA   I188 @T6G_MB_LIB.T6G(SCH_1):PAGE28
    C7 I3C_1_SPD_DDRGL_CPU0_R_SCL @T6G_MB_LIB.T6G(SCH_1):I3C_1_SPD_DDRGL_CPU0_R_SCL   I188 @T6G_MB_LIB.T6G(SCH_1):PAGE28
   C72 SMB_CPU0_2_R_SCL @T6G_MB_LIB.T6G(SCH_1):SMB_CPU0_2_R_SCL   I188 @T6G_MB_LIB.T6G(SCH_1):PAGE28
   A71 I3C_0_SPD_DDRAF_CPU0_R_SCL @T6G_MB_LIB.T6G(SCH_1):I3C_0_SPD_DDRAF_CPU0_R_SCL   I188 @T6G_MB_LIB.T6G(SCH_1):PAGE28
   B16     NC     NC   I188 @T6G_MB_LIB.T6G(SCH_1):PAGE28
  DH36 CPU0_PWR_GD_OUT @T6G_MB_LIB.T6G(SCH_1):CPU0_PWR_GD_OUT   I188 @T6G_MB_LIB.T6G(SCH_1):PAGE28
  DH15 IRQ_TPM_SPI_R_N @T6G_MB_LIB.T6G(SCH_1):IRQ_TPM_SPI_R_N   I188 @T6G_MB_LIB.T6G(SCH_1):PAGE28
    A5 I3C_1_SPD_DDRGL_CPU0_R_SDA @T6G_MB_LIB.T6G(SCH_1):I3C_1_SPD_DDRGL_CPU0_R_SDA   I188 @T6G_MB_LIB.T6G(SCH_1):PAGE28
    A4 SMB_CPU0_3_R_SCL @T6G_MB_LIB.T6G(SCH_1):SMB_CPU0_3_R_SCL   I188 @T6G_MB_LIB.T6G(SCH_1):PAGE28
  DG12 SMB_CPU0_4_R_SCL @T6G_MB_LIB.T6G(SCH_1):SMB_CPU0_4_R_SCL   I188 @T6G_MB_LIB.T6G(SCH_1):PAGE28
  DH12 SMB_CPU0_4_R_SDA @T6G_MB_LIB.T6G(SCH_1):SMB_CPU0_4_R_SDA   I188 @T6G_MB_LIB.T6G(SCH_1):PAGE28
  DJ21 SMB_CPU_5_R_SCL @T6G_MB_LIB.T6G(SCH_1):SMB_CPU_5_R_SCL   I188 @T6G_MB_LIB.T6G(SCH_1):PAGE28
  DJ20 SMB_CPU_5_R_SDA @T6G_MB_LIB.T6G(SCH_1):SMB_CPU_5_R_SDA   I188 @T6G_MB_LIB.T6G(SCH_1):PAGE28
  DJ11 CPU0_SMERR_N @T6G_MB_LIB.T6G(SCH_1):CPU0_SMERR_N   I188 @T6G_MB_LIB.T6G(SCH_1):PAGE28
   A19 CLK_100M_REF_OUT_DP @T6G_MB_LIB.T6G(SCH_1):CLK_100M_REF_OUT_DP   I188 @T6G_MB_LIB.T6G(SCH_1):PAGE28
   A20 CLK_100M_REF_OUT_DN @T6G_MB_LIB.T6G(SCH_1):CLK_100M_REF_OUT_DN   I188 @T6G_MB_LIB.T6G(SCH_1):PAGE28
   B67 RST_CPU0_RESETL_N @T6G_MB_LIB.T6G(SCH_1):RST_CPU0_RESETL_N   I188 @T6G_MB_LIB.T6G(SCH_1):PAGE28
  DH30 BOOT_RDY_R_H @T6G_MB_LIB.T6G(SCH_1):BOOT_RDY_R_H   I188 @T6G_MB_LIB.T6G(SCH_1):PAGE28
  DE30 BIOS_DEBUG_MODE @T6G_MB_LIB.T6G(SCH_1):BIOS_DEBUG_MODE   I188 @T6G_MB_LIB.T6G(SCH_1):PAGE28
  DF31 FM_BOARD_SKU_ID2 @T6G_MB_LIB.T6G(SCH_1):FM_BOARD_SKU_ID2   I188 @T6G_MB_LIB.T6G(SCH_1):PAGE28
  DG31 FM_BOARD_SKU_ID3 @T6G_MB_LIB.T6G(SCH_1):FM_BOARD_SKU_ID3   I188 @T6G_MB_LIB.T6G(SCH_1):PAGE28
  DG32 CPU0_ROM_TYPE_SELECT @T6G_MB_LIB.T6G(SCH_1):CPU0_ROM_TYPE_SELECT   I188 @T6G_MB_LIB.T6G(SCH_1):PAGE28
  DG11     NC     NC   I188 @T6G_MB_LIB.T6G(SCH_1):PAGE28
  DF33 FM_BOARD_SKU_ID0 @T6G_MB_LIB.T6G(SCH_1):FM_BOARD_SKU_ID0   I188 @T6G_MB_LIB.T6G(SCH_1):PAGE28
  DJ29 FM_BIOS_POST_CMPLT_R_N @T6G_MB_LIB.T6G(SCH_1):FM_BIOS_POST_CMPLT_R_N   I188 @T6G_MB_LIB.T6G(SCH_1):PAGE28
  DE32 FM_BOARD_SKU_ID1 @T6G_MB_LIB.T6G(SCH_1):FM_BOARD_SKU_ID1   I188 @T6G_MB_LIB.T6G(SCH_1):PAGE28
  DJ35 FM_INT_CPU0_HP_UBM_N @T6G_MB_LIB.T6G(SCH_1):FM_INT_CPU0_HP_UBM_N   I188 @T6G_MB_LIB.T6G(SCH_1):PAGE28
  DF40 FM_SMM_CRASHDUMP @T6G_MB_LIB.T6G(SCH_1):FM_SMM_CRASHDUMP   I188 @T6G_MB_LIB.T6G(SCH_1):PAGE28
  DE40 IRQ_BMC_SMI_N @T6G_MB_LIB.T6G(SCH_1):IRQ_BMC_SMI_N   I188 @T6G_MB_LIB.T6G(SCH_1):PAGE28
   D69 PWRGD_CPU0_PWROK @T6G_MB_LIB.T6G(SCH_1):PWRGD_CPU0_PWROK   I188 @T6G_MB_LIB.T6G(SCH_1):PAGE28
   C14 FAB_REV_ID1 @T6G_MB_LIB.T6G(SCH_1):FAB_REV_ID1   I188 @T6G_MB_LIB.T6G(SCH_1):PAGE28
   D14 SMB_CPU0_SEC_SDA @T6G_MB_LIB.T6G(SCH_1):SMB_CPU0_SEC_SDA   I188 @T6G_MB_LIB.T6G(SCH_1):PAGE28
   B14 SMB_CPU0_SEC_SCL @T6G_MB_LIB.T6G(SCH_1):SMB_CPU0_SEC_SCL   I188 @T6G_MB_LIB.T6G(SCH_1):PAGE28
  DJ31 CPU0_NMI_SYNC_FLOOD_N @T6G_MB_LIB.T6G(SCH_1):CPU0_NMI_SYNC_FLOOD_N   I188 @T6G_MB_LIB.T6G(SCH_1):PAGE28
   DH4 FM_BOARD_SKU_ID4 @T6G_MB_LIB.T6G(SCH_1):FM_BOARD_SKU_ID4   I188 @T6G_MB_LIB.T6G(SCH_1):PAGE28
   A25 USB2_CPU0_P0_DN @T6G_MB_LIB.T6G(SCH_1):USB2_CPU0_P0_DN   I287 @T6G_MB_LIB.T6G(SCH_1):PAGE29
   A26 USB2_CPU0_P0_DP @T6G_MB_LIB.T6G(SCH_1):USB2_CPU0_P0_DP   I287 @T6G_MB_LIB.T6G(SCH_1):PAGE29
   E26 USB3_CPU0_BMC_RX_HUB_C_DN @T6G_MB_LIB.T6G(SCH_1):USB3_CPU0_BMC_RX_HUB_C_DN   I287 @T6G_MB_LIB.T6G(SCH_1):PAGE29
   E27 USB3_CPU0_BMC_RX_HUB_C_DP @T6G_MB_LIB.T6G(SCH_1):USB3_CPU0_BMC_RX_HUB_C_DP   I287 @T6G_MB_LIB.T6G(SCH_1):PAGE29
   C26 USB3_CPU0_BMC_TX_DN @T6G_MB_LIB.T6G(SCH_1):USB3_CPU0_BMC_TX_DN   I287 @T6G_MB_LIB.T6G(SCH_1):PAGE29
   C25 USB3_CPU0_BMC_TX_DP @T6G_MB_LIB.T6G(SCH_1):USB3_CPU0_BMC_TX_DP   I287 @T6G_MB_LIB.T6G(SCH_1):PAGE29
   A29 USB2_CPU0_P1_DN @T6G_MB_LIB.T6G(SCH_1):USB2_CPU0_P1_DN   I287 @T6G_MB_LIB.T6G(SCH_1):PAGE29
   A28 USB2_CPU0_P1_DP @T6G_MB_LIB.T6G(SCH_1):USB2_CPU0_P1_DP   I287 @T6G_MB_LIB.T6G(SCH_1):PAGE29
   C28     NC     NC   I287 @T6G_MB_LIB.T6G(SCH_1):PAGE29
   C29     NC     NC   I287 @T6G_MB_LIB.T6G(SCH_1):PAGE29
   E29     NC     NC   I287 @T6G_MB_LIB.T6G(SCH_1):PAGE29
   E30     NC     NC   I287 @T6G_MB_LIB.T6G(SCH_1):PAGE29
  DH67 USB2_CPU0_P10_DN @T6G_MB_LIB.T6G(SCH_1):USB2_CPU0_P10_DN   I287 @T6G_MB_LIB.T6G(SCH_1):PAGE29
  DJ67 USB2_CPU0_P10_DP @T6G_MB_LIB.T6G(SCH_1):USB2_CPU0_P10_DP   I287 @T6G_MB_LIB.T6G(SCH_1):PAGE29
  DH65     NC     NC   I287 @T6G_MB_LIB.T6G(SCH_1):PAGE29
  DJ65     NC     NC   I287 @T6G_MB_LIB.T6G(SCH_1):PAGE29
  DJ69     NC     NC   I287 @T6G_MB_LIB.T6G(SCH_1):PAGE29
  DH69     NC     NC   I287 @T6G_MB_LIB.T6G(SCH_1):PAGE29
  DJ60 USB2_CPU0_P11_DN @T6G_MB_LIB.T6G(SCH_1):USB2_CPU0_P11_DN   I287 @T6G_MB_LIB.T6G(SCH_1):PAGE29
  DH60 USB2_CPU0_P11_DP @T6G_MB_LIB.T6G(SCH_1):USB2_CPU0_P11_DP   I287 @T6G_MB_LIB.T6G(SCH_1):PAGE29
  DH62     NC     NC   I287 @T6G_MB_LIB.T6G(SCH_1):PAGE29
  DJ62     NC     NC   I287 @T6G_MB_LIB.T6G(SCH_1):PAGE29
  DH58     NC     NC   I287 @T6G_MB_LIB.T6G(SCH_1):PAGE29
  DG58     NC     NC   I287 @T6G_MB_LIB.T6G(SCH_1):PAGE29
  DG40     NC     NC   I287 @T6G_MB_LIB.T6G(SCH_1):PAGE29
  DH40     NC     NC   I287 @T6G_MB_LIB.T6G(SCH_1):PAGE29
  DG28 CPU0_ESPI_CS0_N @T6G_MB_LIB.T6G(SCH_1):CPU0_ESPI_CS0_N   I287 @T6G_MB_LIB.T6G(SCH_1):PAGE29
   E23 SCM_USB_OC_BUF_N @T6G_MB_LIB.T6G(SCH_1):SCM_USB_OC_BUF_N   I287 @T6G_MB_LIB.T6G(SCH_1):PAGE29
  DF30 SPI_CPU0_R_CS0_N @T6G_MB_LIB.T6G(SCH_1):SPI_CPU0_R_CS0_N   I287 @T6G_MB_LIB.T6G(SCH_1):PAGE29
  DE24 ESPI_CPU0_R_D1 @T6G_MB_LIB.T6G(SCH_1):ESPI_CPU0_R_D1   I287 @T6G_MB_LIB.T6G(SCH_1):PAGE29
  DH24 ESPI_CPU0_R_D0 @T6G_MB_LIB.T6G(SCH_1):ESPI_CPU0_R_D0   I287 @T6G_MB_LIB.T6G(SCH_1):PAGE29
  DJ23 ESPI_CPU0_R_CS1_N @T6G_MB_LIB.T6G(SCH_1):ESPI_CPU0_R_CS1_N   I287 @T6G_MB_LIB.T6G(SCH_1):PAGE29
  DG25 ESPI_CPU0_R_D3 @T6G_MB_LIB.T6G(SCH_1):ESPI_CPU0_R_D3   I287 @T6G_MB_LIB.T6G(SCH_1):PAGE29
  DF25 ESPI_CPU0_R_D2 @T6G_MB_LIB.T6G(SCH_1):ESPI_CPU0_R_D2   I287 @T6G_MB_LIB.T6G(SCH_1):PAGE29
  DG29 SPI_CPU0_R_D3 @T6G_MB_LIB.T6G(SCH_1):SPI_CPU0_R_D3   I287 @T6G_MB_LIB.T6G(SCH_1):PAGE29
  DJ28 SPI_CPU0_R_D2 @T6G_MB_LIB.T6G(SCH_1):SPI_CPU0_R_D2   I287 @T6G_MB_LIB.T6G(SCH_1):PAGE29
  DG22 SPI_CPU0_R_D1 @T6G_MB_LIB.T6G(SCH_1):SPI_CPU0_R_D1   I287 @T6G_MB_LIB.T6G(SCH_1):PAGE29
  DF28 SPI_CPU0_R_D0 @T6G_MB_LIB.T6G(SCH_1):SPI_CPU0_R_D0   I287 @T6G_MB_LIB.T6G(SCH_1):PAGE29
  DH27 NC_CPU0_SPI_CS2_N @T6G_MB_LIB.T6G(SCH_1):NC_CPU0_SPI_CS2_N   I287 @T6G_MB_LIB.T6G(SCH_1):PAGE29
  DG26 SPI_CPU0_R_CS1_N @T6G_MB_LIB.T6G(SCH_1):SPI_CPU0_R_CS1_N   I287 @T6G_MB_LIB.T6G(SCH_1):PAGE29
   E24     NC     NC   I287 @T6G_MB_LIB.T6G(SCH_1):PAGE29
  DJ26 RST_CPU0_KBRST_R_N @T6G_MB_LIB.T6G(SCH_1):RST_CPU0_KBRST_R_N   I287 @T6G_MB_LIB.T6G(SCH_1):PAGE29
  DF24 ESPI_CPU0_R_ALERT_N @T6G_MB_LIB.T6G(SCH_1):ESPI_CPU0_R_ALERT_N   I287 @T6G_MB_LIB.T6G(SCH_1):PAGE29
  DJ27 SPI_CPU0_R_CLK @T6G_MB_LIB.T6G(SCH_1):SPI_CPU0_R_CLK   I287 @T6G_MB_LIB.T6G(SCH_1):PAGE29
  DJ25 SPI_CPU0_R_TPM_CS_N @T6G_MB_LIB.T6G(SCH_1):SPI_CPU0_R_TPM_CS_N   I287 @T6G_MB_LIB.T6G(SCH_1):PAGE29
  DJ22 CPU0_ESPI0_ALERT_N @T6G_MB_LIB.T6G(SCH_1):CPU0_ESPI0_ALERT_N   I287 @T6G_MB_LIB.T6G(SCH_1):PAGE29
  DF27 PD_ESPI_CPU0_CLK2 @T6G_MB_LIB.T6G(SCH_1):PD_ESPI_CPU0_CLK2   I287 @T6G_MB_LIB.T6G(SCH_1):PAGE29
  DG23 CLK_ESPI_CPU0_R_CLK1 @T6G_MB_LIB.T6G(SCH_1):CLK_ESPI_CPU0_R_CLK1   I287 @T6G_MB_LIB.T6G(SCH_1):PAGE29
  DE27 RST_ESPI_CPU0_R_RSTOUT_N @T6G_MB_LIB.T6G(SCH_1):RST_ESPI_CPU0_R_RSTOUT_N   I287 @T6G_MB_LIB.T6G(SCH_1):PAGE29
  BD62     NC     NC    I29 @T6G_MB_LIB.T6G(SCH_1):PAGE30
   D72     NC     NC    I29 @T6G_MB_LIB.T6G(SCH_1):PAGE30
   C54     NC     NC    I29 @T6G_MB_LIB.T6G(SCH_1):PAGE30
  BD65     NC     NC    I29 @T6G_MB_LIB.T6G(SCH_1):PAGE30
   E33     NC     NC    I29 @T6G_MB_LIB.T6G(SCH_1):PAGE30
    D4     NC     NC    I29 @T6G_MB_LIB.T6G(SCH_1):PAGE30
   A55     NC     NC    I29 @T6G_MB_LIB.T6G(SCH_1):PAGE30
  BD69     NC     NC    I29 @T6G_MB_LIB.T6G(SCH_1):PAGE30
   E36     NC     NC    I29 @T6G_MB_LIB.T6G(SCH_1):PAGE30
    D8     NC     NC    I29 @T6G_MB_LIB.T6G(SCH_1):PAGE30
   A56     NC     NC    I29 @T6G_MB_LIB.T6G(SCH_1):PAGE30
  BD72     NC     NC    I29 @T6G_MB_LIB.T6G(SCH_1):PAGE30
   BD4     NC     NC    I29 @T6G_MB_LIB.T6G(SCH_1):PAGE30
   D11     NC     NC    I29 @T6G_MB_LIB.T6G(SCH_1):PAGE30
   A57     NC     NC    I29 @T6G_MB_LIB.T6G(SCH_1):PAGE30
  DG17     NC     NC    I29 @T6G_MB_LIB.T6G(SCH_1):PAGE30
   D22     NC     NC    I29 @T6G_MB_LIB.T6G(SCH_1):PAGE30
   A59     NC     NC    I29 @T6G_MB_LIB.T6G(SCH_1):PAGE30
  DH17     NC     NC    I29 @T6G_MB_LIB.T6G(SCH_1):PAGE30
  BD11     NC     NC    I29 @T6G_MB_LIB.T6G(SCH_1):PAGE30
   D34     NC     NC    I29 @T6G_MB_LIB.T6G(SCH_1):PAGE30
   A31     NC     NC    I29 @T6G_MB_LIB.T6G(SCH_1):PAGE30
  DH21     NC     NC    I29 @T6G_MB_LIB.T6G(SCH_1):PAGE30
  BD14     NC     NC    I29 @T6G_MB_LIB.T6G(SCH_1):PAGE30
   B40     NC     NC    I29 @T6G_MB_LIB.T6G(SCH_1):PAGE30
   A35     NC     NC    I29 @T6G_MB_LIB.T6G(SCH_1):PAGE30
   DJ4     NC     NC    I29 @T6G_MB_LIB.T6G(SCH_1):PAGE30
  BD18     NC     NC    I29 @T6G_MB_LIB.T6G(SCH_1):PAGE30
   D58     NC     NC    I29 @T6G_MB_LIB.T6G(SCH_1):PAGE30
   C31     NC     NC    I29 @T6G_MB_LIB.T6G(SCH_1):PAGE30
   A41     NC     NC    I29 @T6G_MB_LIB.T6G(SCH_1):PAGE30
  BD21     NC     NC    I29 @T6G_MB_LIB.T6G(SCH_1):PAGE30
   D62     NC     NC    I29 @T6G_MB_LIB.T6G(SCH_1):PAGE30
   C34     NC     NC    I29 @T6G_MB_LIB.T6G(SCH_1):PAGE30
   A42     NC     NC    I29 @T6G_MB_LIB.T6G(SCH_1):PAGE30
   D65     NC     NC    I29 @T6G_MB_LIB.T6G(SCH_1):PAGE30
   C35     NC     NC    I29 @T6G_MB_LIB.T6G(SCH_1):PAGE30
   A45     NC     NC    I29 @T6G_MB_LIB.T6G(SCH_1):PAGE30
   C53     NC     NC    I29 @T6G_MB_LIB.T6G(SCH_1):PAGE30
   A48     NC     NC    I29 @T6G_MB_LIB.T6G(SCH_1):PAGE30
   A50     NC     NC    I29 @T6G_MB_LIB.T6G(SCH_1):PAGE30
   A51     NC     NC    I29 @T6G_MB_LIB.T6G(SCH_1):PAGE30
   A54     NC     NC    I29 @T6G_MB_LIB.T6G(SCH_1):PAGE30
  BD55     NC     NC    I29 @T6G_MB_LIB.T6G(SCH_1):PAGE30
  BD58     NC     NC    I29 @T6G_MB_LIB.T6G(SCH_1):PAGE30
   D36     NC     NC    I29 @T6G_MB_LIB.T6G(SCH_1):PAGE30
   BD7     NC     NC    I29 @T6G_MB_LIB.T6G(SCH_1):PAGE30
   A60     NC     NC    I29 @T6G_MB_LIB.T6G(SCH_1):PAGE30
  DJ57     NC     NC    I29 @T6G_MB_LIB.T6G(SCH_1):PAGE30
  DH14     NC     NC    I29 @T6G_MB_LIB.T6G(SCH_1):PAGE30
  DH13     NC     NC    I29 @T6G_MB_LIB.T6G(SCH_1):PAGE30
  DG42     NC     NC    I29 @T6G_MB_LIB.T6G(SCH_1):PAGE30
  DF41     NC     NC    I29 @T6G_MB_LIB.T6G(SCH_1):PAGE30
   D23     NC     NC    I29 @T6G_MB_LIB.T6G(SCH_1):PAGE30
   C59     NC     NC    I29 @T6G_MB_LIB.T6G(SCH_1):PAGE30
   C58     NC     NC    I29 @T6G_MB_LIB.T6G(SCH_1):PAGE30
   C23     NC     NC    I29 @T6G_MB_LIB.T6G(SCH_1):PAGE30
   B36     NC     NC    I29 @T6G_MB_LIB.T6G(SCH_1):PAGE30
   W47 PVDDCR_CPU0_P0 @T6G_MB_LIB.T6G(SCH_1):PVDDCR_CPU0_P0    I42 @T6G_MB_LIB.T6G(SCH_1):PAGE30
   W46 PVDDCR_CPU0_P0 @T6G_MB_LIB.T6G(SCH_1):PVDDCR_CPU0_P0    I42 @T6G_MB_LIB.T6G(SCH_1):PAGE30
   W44 PVDDCR_CPU0_P0 @T6G_MB_LIB.T6G(SCH_1):PVDDCR_CPU0_P0    I42 @T6G_MB_LIB.T6G(SCH_1):PAGE30
   W43 PVDDCR_CPU0_P0 @T6G_MB_LIB.T6G(SCH_1):PVDDCR_CPU0_P0    I42 @T6G_MB_LIB.T6G(SCH_1):PAGE30
   W33 PVDDCR_CPU0_P0 @T6G_MB_LIB.T6G(SCH_1):PVDDCR_CPU0_P0    I42 @T6G_MB_LIB.T6G(SCH_1):PAGE30
   W32 PVDDCR_CPU0_P0 @T6G_MB_LIB.T6G(SCH_1):PVDDCR_CPU0_P0    I42 @T6G_MB_LIB.T6G(SCH_1):PAGE30
   W30 PVDDCR_CPU0_P0 @T6G_MB_LIB.T6G(SCH_1):PVDDCR_CPU0_P0    I42 @T6G_MB_LIB.T6G(SCH_1):PAGE30
   W29 PVDDCR_CPU0_P0 @T6G_MB_LIB.T6G(SCH_1):PVDDCR_CPU0_P0    I42 @T6G_MB_LIB.T6G(SCH_1):PAGE30
   U41 PVDDCR_CPU0_P0 @T6G_MB_LIB.T6G(SCH_1):PVDDCR_CPU0_P0    I42 @T6G_MB_LIB.T6G(SCH_1):PAGE30
   U40 PVDDCR_CPU0_P0 @T6G_MB_LIB.T6G(SCH_1):PVDDCR_CPU0_P0    I42 @T6G_MB_LIB.T6G(SCH_1):PAGE30
   U36 PVDDCR_CPU0_P0 @T6G_MB_LIB.T6G(SCH_1):PVDDCR_CPU0_P0    I42 @T6G_MB_LIB.T6G(SCH_1):PAGE30
   U35 PVDDCR_CPU0_P0 @T6G_MB_LIB.T6G(SCH_1):PVDDCR_CPU0_P0    I42 @T6G_MB_LIB.T6G(SCH_1):PAGE30
   T53 PVDDCR_CPU0_P0 @T6G_MB_LIB.T6G(SCH_1):PVDDCR_CPU0_P0    I42 @T6G_MB_LIB.T6G(SCH_1):PAGE30
   T52 PVDDCR_CPU0_P0 @T6G_MB_LIB.T6G(SCH_1):PVDDCR_CPU0_P0    I42 @T6G_MB_LIB.T6G(SCH_1):PAGE30
   T50 PVDDCR_CPU0_P0 @T6G_MB_LIB.T6G(SCH_1):PVDDCR_CPU0_P0    I42 @T6G_MB_LIB.T6G(SCH_1):PAGE30
   T49 PVDDCR_CPU0_P0 @T6G_MB_LIB.T6G(SCH_1):PVDDCR_CPU0_P0    I42 @T6G_MB_LIB.T6G(SCH_1):PAGE30
   T47 PVDDCR_CPU0_P0 @T6G_MB_LIB.T6G(SCH_1):PVDDCR_CPU0_P0    I42 @T6G_MB_LIB.T6G(SCH_1):PAGE30
   T46 PVDDCR_CPU0_P0 @T6G_MB_LIB.T6G(SCH_1):PVDDCR_CPU0_P0    I42 @T6G_MB_LIB.T6G(SCH_1):PAGE30
   T44 PVDDCR_CPU0_P0 @T6G_MB_LIB.T6G(SCH_1):PVDDCR_CPU0_P0    I42 @T6G_MB_LIB.T6G(SCH_1):PAGE30
   T43 PVDDCR_CPU0_P0 @T6G_MB_LIB.T6G(SCH_1):PVDDCR_CPU0_P0    I42 @T6G_MB_LIB.T6G(SCH_1):PAGE30
   T33 PVDDCR_CPU0_P0 @T6G_MB_LIB.T6G(SCH_1):PVDDCR_CPU0_P0    I42 @T6G_MB_LIB.T6G(SCH_1):PAGE30
   T32 PVDDCR_CPU0_P0 @T6G_MB_LIB.T6G(SCH_1):PVDDCR_CPU0_P0    I42 @T6G_MB_LIB.T6G(SCH_1):PAGE30
   T30 PVDDCR_CPU0_P0 @T6G_MB_LIB.T6G(SCH_1):PVDDCR_CPU0_P0    I42 @T6G_MB_LIB.T6G(SCH_1):PAGE30
   T29 PVDDCR_CPU0_P0 @T6G_MB_LIB.T6G(SCH_1):PVDDCR_CPU0_P0    I42 @T6G_MB_LIB.T6G(SCH_1):PAGE30
   T27 PVDDCR_CPU0_P0 @T6G_MB_LIB.T6G(SCH_1):PVDDCR_CPU0_P0    I42 @T6G_MB_LIB.T6G(SCH_1):PAGE30
   T26 PVDDCR_CPU0_P0 @T6G_MB_LIB.T6G(SCH_1):PVDDCR_CPU0_P0    I42 @T6G_MB_LIB.T6G(SCH_1):PAGE30
   T24 PVDDCR_CPU0_P0 @T6G_MB_LIB.T6G(SCH_1):PVDDCR_CPU0_P0    I42 @T6G_MB_LIB.T6G(SCH_1):PAGE30
   T23 PVDDCR_CPU0_P0 @T6G_MB_LIB.T6G(SCH_1):PVDDCR_CPU0_P0    I42 @T6G_MB_LIB.T6G(SCH_1):PAGE30
   N41 PVDDCR_CPU0_P0 @T6G_MB_LIB.T6G(SCH_1):PVDDCR_CPU0_P0    I42 @T6G_MB_LIB.T6G(SCH_1):PAGE30
   N40 PVDDCR_CPU0_P0 @T6G_MB_LIB.T6G(SCH_1):PVDDCR_CPU0_P0    I42 @T6G_MB_LIB.T6G(SCH_1):PAGE30
   N36 PVDDCR_CPU0_P0 @T6G_MB_LIB.T6G(SCH_1):PVDDCR_CPU0_P0    I42 @T6G_MB_LIB.T6G(SCH_1):PAGE30
   N35 PVDDCR_CPU0_P0 @T6G_MB_LIB.T6G(SCH_1):PVDDCR_CPU0_P0    I42 @T6G_MB_LIB.T6G(SCH_1):PAGE30
   M53 PVDDCR_CPU0_P0 @T6G_MB_LIB.T6G(SCH_1):PVDDCR_CPU0_P0    I42 @T6G_MB_LIB.T6G(SCH_1):PAGE30
   M52 PVDDCR_CPU0_P0 @T6G_MB_LIB.T6G(SCH_1):PVDDCR_CPU0_P0    I42 @T6G_MB_LIB.T6G(SCH_1):PAGE30
   M50 PVDDCR_CPU0_P0 @T6G_MB_LIB.T6G(SCH_1):PVDDCR_CPU0_P0    I42 @T6G_MB_LIB.T6G(SCH_1):PAGE30
   M49 PVDDCR_CPU0_P0 @T6G_MB_LIB.T6G(SCH_1):PVDDCR_CPU0_P0    I42 @T6G_MB_LIB.T6G(SCH_1):PAGE30
   M47 PVDDCR_CPU0_P0 @T6G_MB_LIB.T6G(SCH_1):PVDDCR_CPU0_P0    I42 @T6G_MB_LIB.T6G(SCH_1):PAGE30
   M46 PVDDCR_CPU0_P0 @T6G_MB_LIB.T6G(SCH_1):PVDDCR_CPU0_P0    I42 @T6G_MB_LIB.T6G(SCH_1):PAGE30
   M44 PVDDCR_CPU0_P0 @T6G_MB_LIB.T6G(SCH_1):PVDDCR_CPU0_P0    I42 @T6G_MB_LIB.T6G(SCH_1):PAGE30
   M43 PVDDCR_CPU0_P0 @T6G_MB_LIB.T6G(SCH_1):PVDDCR_CPU0_P0    I42 @T6G_MB_LIB.T6G(SCH_1):PAGE30
   M33 PVDDCR_CPU0_P0 @T6G_MB_LIB.T6G(SCH_1):PVDDCR_CPU0_P0    I42 @T6G_MB_LIB.T6G(SCH_1):PAGE30
   M32 PVDDCR_CPU0_P0 @T6G_MB_LIB.T6G(SCH_1):PVDDCR_CPU0_P0    I42 @T6G_MB_LIB.T6G(SCH_1):PAGE30
   M30 PVDDCR_CPU0_P0 @T6G_MB_LIB.T6G(SCH_1):PVDDCR_CPU0_P0    I42 @T6G_MB_LIB.T6G(SCH_1):PAGE30
   M29 PVDDCR_CPU0_P0 @T6G_MB_LIB.T6G(SCH_1):PVDDCR_CPU0_P0    I42 @T6G_MB_LIB.T6G(SCH_1):PAGE30
   M27 PVDDCR_CPU0_P0 @T6G_MB_LIB.T6G(SCH_1):PVDDCR_CPU0_P0    I42 @T6G_MB_LIB.T6G(SCH_1):PAGE30
   M26 PVDDCR_CPU0_P0 @T6G_MB_LIB.T6G(SCH_1):PVDDCR_CPU0_P0    I42 @T6G_MB_LIB.T6G(SCH_1):PAGE30
   M24 PVDDCR_CPU0_P0 @T6G_MB_LIB.T6G(SCH_1):PVDDCR_CPU0_P0    I42 @T6G_MB_LIB.T6G(SCH_1):PAGE30
   M23 PVDDCR_CPU0_P0 @T6G_MB_LIB.T6G(SCH_1):PVDDCR_CPU0_P0    I42 @T6G_MB_LIB.T6G(SCH_1):PAGE30
   J41 PVDDCR_CPU0_P0 @T6G_MB_LIB.T6G(SCH_1):PVDDCR_CPU0_P0    I42 @T6G_MB_LIB.T6G(SCH_1):PAGE30
   J40 PVDDCR_CPU0_P0 @T6G_MB_LIB.T6G(SCH_1):PVDDCR_CPU0_P0    I42 @T6G_MB_LIB.T6G(SCH_1):PAGE30
   J36 PVDDCR_CPU0_P0 @T6G_MB_LIB.T6G(SCH_1):PVDDCR_CPU0_P0    I42 @T6G_MB_LIB.T6G(SCH_1):PAGE30
   J35 PVDDCR_CPU0_P0 @T6G_MB_LIB.T6G(SCH_1):PVDDCR_CPU0_P0    I42 @T6G_MB_LIB.T6G(SCH_1):PAGE30
   H53 PVDDCR_CPU0_P0 @T6G_MB_LIB.T6G(SCH_1):PVDDCR_CPU0_P0    I42 @T6G_MB_LIB.T6G(SCH_1):PAGE30
   H52 PVDDCR_CPU0_P0 @T6G_MB_LIB.T6G(SCH_1):PVDDCR_CPU0_P0    I42 @T6G_MB_LIB.T6G(SCH_1):PAGE30
   H50 PVDDCR_CPU0_P0 @T6G_MB_LIB.T6G(SCH_1):PVDDCR_CPU0_P0    I42 @T6G_MB_LIB.T6G(SCH_1):PAGE30
   H49 PVDDCR_CPU0_P0 @T6G_MB_LIB.T6G(SCH_1):PVDDCR_CPU0_P0    I42 @T6G_MB_LIB.T6G(SCH_1):PAGE30
   H47 PVDDCR_CPU0_P0 @T6G_MB_LIB.T6G(SCH_1):PVDDCR_CPU0_P0    I42 @T6G_MB_LIB.T6G(SCH_1):PAGE30
   H46 PVDDCR_CPU0_P0 @T6G_MB_LIB.T6G(SCH_1):PVDDCR_CPU0_P0    I42 @T6G_MB_LIB.T6G(SCH_1):PAGE30
   H44 PVDDCR_CPU0_P0 @T6G_MB_LIB.T6G(SCH_1):PVDDCR_CPU0_P0    I42 @T6G_MB_LIB.T6G(SCH_1):PAGE30
   H43 PVDDCR_CPU0_P0 @T6G_MB_LIB.T6G(SCH_1):PVDDCR_CPU0_P0    I42 @T6G_MB_LIB.T6G(SCH_1):PAGE30
   H33 PVDDCR_CPU0_P0 @T6G_MB_LIB.T6G(SCH_1):PVDDCR_CPU0_P0    I42 @T6G_MB_LIB.T6G(SCH_1):PAGE30
   H32 PVDDCR_CPU0_P0 @T6G_MB_LIB.T6G(SCH_1):PVDDCR_CPU0_P0    I42 @T6G_MB_LIB.T6G(SCH_1):PAGE30
   H30 PVDDCR_CPU0_P0 @T6G_MB_LIB.T6G(SCH_1):PVDDCR_CPU0_P0    I42 @T6G_MB_LIB.T6G(SCH_1):PAGE30
   H29 PVDDCR_CPU0_P0 @T6G_MB_LIB.T6G(SCH_1):PVDDCR_CPU0_P0    I42 @T6G_MB_LIB.T6G(SCH_1):PAGE30
   H27 PVDDCR_CPU0_P0 @T6G_MB_LIB.T6G(SCH_1):PVDDCR_CPU0_P0    I42 @T6G_MB_LIB.T6G(SCH_1):PAGE30
   H26 PVDDCR_CPU0_P0 @T6G_MB_LIB.T6G(SCH_1):PVDDCR_CPU0_P0    I42 @T6G_MB_LIB.T6G(SCH_1):PAGE30
   H24 PVDDCR_CPU0_P0 @T6G_MB_LIB.T6G(SCH_1):PVDDCR_CPU0_P0    I42 @T6G_MB_LIB.T6G(SCH_1):PAGE30
   H23 PVDDCR_CPU0_P0 @T6G_MB_LIB.T6G(SCH_1):PVDDCR_CPU0_P0    I42 @T6G_MB_LIB.T6G(SCH_1):PAGE30
   G41 PVDDCR_CPU0_P0 @T6G_MB_LIB.T6G(SCH_1):PVDDCR_CPU0_P0    I42 @T6G_MB_LIB.T6G(SCH_1):PAGE30
   G40 PVDDCR_CPU0_P0 @T6G_MB_LIB.T6G(SCH_1):PVDDCR_CPU0_P0    I42 @T6G_MB_LIB.T6G(SCH_1):PAGE30
   G36 PVDDCR_CPU0_P0 @T6G_MB_LIB.T6G(SCH_1):PVDDCR_CPU0_P0    I42 @T6G_MB_LIB.T6G(SCH_1):PAGE30
   G35 PVDDCR_CPU0_P0 @T6G_MB_LIB.T6G(SCH_1):PVDDCR_CPU0_P0    I42 @T6G_MB_LIB.T6G(SCH_1):PAGE30
   F54 PVDDCR_CPU0_P0 @T6G_MB_LIB.T6G(SCH_1):PVDDCR_CPU0_P0    I42 @T6G_MB_LIB.T6G(SCH_1):PAGE30
   F51 PVDDCR_CPU0_P0 @T6G_MB_LIB.T6G(SCH_1):PVDDCR_CPU0_P0    I42 @T6G_MB_LIB.T6G(SCH_1):PAGE30
   F48 PVDDCR_CPU0_P0 @T6G_MB_LIB.T6G(SCH_1):PVDDCR_CPU0_P0    I42 @T6G_MB_LIB.T6G(SCH_1):PAGE30
   F45 PVDDCR_CPU0_P0 @T6G_MB_LIB.T6G(SCH_1):PVDDCR_CPU0_P0    I42 @T6G_MB_LIB.T6G(SCH_1):PAGE30
   F42 PVDDCR_CPU0_P0 @T6G_MB_LIB.T6G(SCH_1):PVDDCR_CPU0_P0    I42 @T6G_MB_LIB.T6G(SCH_1):PAGE30
   F34 PVDDCR_CPU0_P0 @T6G_MB_LIB.T6G(SCH_1):PVDDCR_CPU0_P0    I42 @T6G_MB_LIB.T6G(SCH_1):PAGE30
   F31 PVDDCR_CPU0_P0 @T6G_MB_LIB.T6G(SCH_1):PVDDCR_CPU0_P0    I42 @T6G_MB_LIB.T6G(SCH_1):PAGE30
   F28 PVDDCR_CPU0_P0 @T6G_MB_LIB.T6G(SCH_1):PVDDCR_CPU0_P0    I42 @T6G_MB_LIB.T6G(SCH_1):PAGE30
   F25 PVDDCR_CPU0_P0 @T6G_MB_LIB.T6G(SCH_1):PVDDCR_CPU0_P0    I42 @T6G_MB_LIB.T6G(SCH_1):PAGE30
   F22 PVDDCR_CPU0_P0 @T6G_MB_LIB.T6G(SCH_1):PVDDCR_CPU0_P0    I42 @T6G_MB_LIB.T6G(SCH_1):PAGE30
   E54 PVDDCR_CPU0_P0 @T6G_MB_LIB.T6G(SCH_1):PVDDCR_CPU0_P0    I42 @T6G_MB_LIB.T6G(SCH_1):PAGE30
   E51 PVDDCR_CPU0_P0 @T6G_MB_LIB.T6G(SCH_1):PVDDCR_CPU0_P0    I42 @T6G_MB_LIB.T6G(SCH_1):PAGE30
   E48 PVDDCR_CPU0_P0 @T6G_MB_LIB.T6G(SCH_1):PVDDCR_CPU0_P0    I42 @T6G_MB_LIB.T6G(SCH_1):PAGE30
   E45 PVDDCR_CPU0_P0 @T6G_MB_LIB.T6G(SCH_1):PVDDCR_CPU0_P0    I42 @T6G_MB_LIB.T6G(SCH_1):PAGE30
   E42 PVDDCR_CPU0_P0 @T6G_MB_LIB.T6G(SCH_1):PVDDCR_CPU0_P0    I42 @T6G_MB_LIB.T6G(SCH_1):PAGE30
   E35 PVDDCR_CPU0_P0 @T6G_MB_LIB.T6G(SCH_1):PVDDCR_CPU0_P0    I42 @T6G_MB_LIB.T6G(SCH_1):PAGE30
   E34 PVDDCR_CPU0_P0 @T6G_MB_LIB.T6G(SCH_1):PVDDCR_CPU0_P0    I42 @T6G_MB_LIB.T6G(SCH_1):PAGE30
   E31 PVDDCR_CPU0_P0 @T6G_MB_LIB.T6G(SCH_1):PVDDCR_CPU0_P0    I42 @T6G_MB_LIB.T6G(SCH_1):PAGE30
   E28 PVDDCR_CPU0_P0 @T6G_MB_LIB.T6G(SCH_1):PVDDCR_CPU0_P0    I42 @T6G_MB_LIB.T6G(SCH_1):PAGE30
   E25 PVDDCR_CPU0_P0 @T6G_MB_LIB.T6G(SCH_1):PVDDCR_CPU0_P0    I42 @T6G_MB_LIB.T6G(SCH_1):PAGE30
   E22 PVDDCR_CPU0_P0 @T6G_MB_LIB.T6G(SCH_1):PVDDCR_CPU0_P0    I42 @T6G_MB_LIB.T6G(SCH_1):PAGE30
   D56 PVDDCR_CPU0_P0 @T6G_MB_LIB.T6G(SCH_1):PVDDCR_CPU0_P0    I42 @T6G_MB_LIB.T6G(SCH_1):PAGE30
   D55 PVDDCR_CPU0_P0 @T6G_MB_LIB.T6G(SCH_1):PVDDCR_CPU0_P0    I42 @T6G_MB_LIB.T6G(SCH_1):PAGE30
   C20 PVDDCR_CPU0_P0 @T6G_MB_LIB.T6G(SCH_1):PVDDCR_CPU0_P0    I42 @T6G_MB_LIB.T6G(SCH_1):PAGE30
   B57 PVDDCR_CPU0_P0 @T6G_MB_LIB.T6G(SCH_1):PVDDCR_CPU0_P0    I42 @T6G_MB_LIB.T6G(SCH_1):PAGE30
   B56 PVDDCR_CPU0_P0 @T6G_MB_LIB.T6G(SCH_1):PVDDCR_CPU0_P0    I42 @T6G_MB_LIB.T6G(SCH_1):PAGE30
   B54 PVDDCR_CPU0_P0 @T6G_MB_LIB.T6G(SCH_1):PVDDCR_CPU0_P0    I42 @T6G_MB_LIB.T6G(SCH_1):PAGE30
   B53 PVDDCR_CPU0_P0 @T6G_MB_LIB.T6G(SCH_1):PVDDCR_CPU0_P0    I42 @T6G_MB_LIB.T6G(SCH_1):PAGE30
   B51 PVDDCR_CPU0_P0 @T6G_MB_LIB.T6G(SCH_1):PVDDCR_CPU0_P0    I42 @T6G_MB_LIB.T6G(SCH_1):PAGE30
   B50 PVDDCR_CPU0_P0 @T6G_MB_LIB.T6G(SCH_1):PVDDCR_CPU0_P0    I42 @T6G_MB_LIB.T6G(SCH_1):PAGE30
   B48 PVDDCR_CPU0_P0 @T6G_MB_LIB.T6G(SCH_1):PVDDCR_CPU0_P0    I42 @T6G_MB_LIB.T6G(SCH_1):PAGE30
   B47 PVDDCR_CPU0_P0 @T6G_MB_LIB.T6G(SCH_1):PVDDCR_CPU0_P0    I42 @T6G_MB_LIB.T6G(SCH_1):PAGE30
   B45 PVDDCR_CPU0_P0 @T6G_MB_LIB.T6G(SCH_1):PVDDCR_CPU0_P0    I42 @T6G_MB_LIB.T6G(SCH_1):PAGE30
   B44 PVDDCR_CPU0_P0 @T6G_MB_LIB.T6G(SCH_1):PVDDCR_CPU0_P0    I42 @T6G_MB_LIB.T6G(SCH_1):PAGE30
   B42 PVDDCR_CPU0_P0 @T6G_MB_LIB.T6G(SCH_1):PVDDCR_CPU0_P0    I42 @T6G_MB_LIB.T6G(SCH_1):PAGE30
   B41 PVDDCR_CPU0_P0 @T6G_MB_LIB.T6G(SCH_1):PVDDCR_CPU0_P0    I42 @T6G_MB_LIB.T6G(SCH_1):PAGE30
   B35 PVDDCR_CPU0_P0 @T6G_MB_LIB.T6G(SCH_1):PVDDCR_CPU0_P0    I42 @T6G_MB_LIB.T6G(SCH_1):PAGE30
   B34 PVDDCR_CPU0_P0 @T6G_MB_LIB.T6G(SCH_1):PVDDCR_CPU0_P0    I42 @T6G_MB_LIB.T6G(SCH_1):PAGE30
   B32 PVDDCR_CPU0_P0 @T6G_MB_LIB.T6G(SCH_1):PVDDCR_CPU0_P0    I42 @T6G_MB_LIB.T6G(SCH_1):PAGE30
   B31 PVDDCR_CPU0_P0 @T6G_MB_LIB.T6G(SCH_1):PVDDCR_CPU0_P0    I42 @T6G_MB_LIB.T6G(SCH_1):PAGE30
   B29 PVDDCR_CPU0_P0 @T6G_MB_LIB.T6G(SCH_1):PVDDCR_CPU0_P0    I42 @T6G_MB_LIB.T6G(SCH_1):PAGE30
   B28 PVDDCR_CPU0_P0 @T6G_MB_LIB.T6G(SCH_1):PVDDCR_CPU0_P0    I42 @T6G_MB_LIB.T6G(SCH_1):PAGE30
   B26 PVDDCR_CPU0_P0 @T6G_MB_LIB.T6G(SCH_1):PVDDCR_CPU0_P0    I42 @T6G_MB_LIB.T6G(SCH_1):PAGE30
   B25 PVDDCR_CPU0_P0 @T6G_MB_LIB.T6G(SCH_1):PVDDCR_CPU0_P0    I42 @T6G_MB_LIB.T6G(SCH_1):PAGE30
   B23 PVDDCR_CPU0_P0 @T6G_MB_LIB.T6G(SCH_1):PVDDCR_CPU0_P0    I42 @T6G_MB_LIB.T6G(SCH_1):PAGE30
   B22 PVDDCR_CPU0_P0 @T6G_MB_LIB.T6G(SCH_1):PVDDCR_CPU0_P0    I42 @T6G_MB_LIB.T6G(SCH_1):PAGE30
   B20 PVDDCR_CPU0_P0 @T6G_MB_LIB.T6G(SCH_1):PVDDCR_CPU0_P0    I42 @T6G_MB_LIB.T6G(SCH_1):PAGE30
   B19 PVDDCR_CPU0_P0 @T6G_MB_LIB.T6G(SCH_1):PVDDCR_CPU0_P0    I42 @T6G_MB_LIB.T6G(SCH_1):PAGE30
  AT47 PVDDCR_CPU0_P0 @T6G_MB_LIB.T6G(SCH_1):PVDDCR_CPU0_P0    I42 @T6G_MB_LIB.T6G(SCH_1):PAGE30
  AT45 PVDDCR_CPU0_P0 @T6G_MB_LIB.T6G(SCH_1):PVDDCR_CPU0_P0    I42 @T6G_MB_LIB.T6G(SCH_1):PAGE30
  AT43 PVDDCR_CPU0_P0 @T6G_MB_LIB.T6G(SCH_1):PVDDCR_CPU0_P0    I42 @T6G_MB_LIB.T6G(SCH_1):PAGE30
  AT41 PVDDCR_CPU0_P0 @T6G_MB_LIB.T6G(SCH_1):PVDDCR_CPU0_P0    I42 @T6G_MB_LIB.T6G(SCH_1):PAGE30
  AT39 PVDDCR_CPU0_P0 @T6G_MB_LIB.T6G(SCH_1):PVDDCR_CPU0_P0    I42 @T6G_MB_LIB.T6G(SCH_1):PAGE30
  AT36 PVDDCR_CPU0_P0 @T6G_MB_LIB.T6G(SCH_1):PVDDCR_CPU0_P0    I42 @T6G_MB_LIB.T6G(SCH_1):PAGE30
  AT34 PVDDCR_CPU0_P0 @T6G_MB_LIB.T6G(SCH_1):PVDDCR_CPU0_P0    I42 @T6G_MB_LIB.T6G(SCH_1):PAGE30
  AT32 PVDDCR_CPU0_P0 @T6G_MB_LIB.T6G(SCH_1):PVDDCR_CPU0_P0    I42 @T6G_MB_LIB.T6G(SCH_1):PAGE30
  AT30 PVDDCR_CPU0_P0 @T6G_MB_LIB.T6G(SCH_1):PVDDCR_CPU0_P0    I42 @T6G_MB_LIB.T6G(SCH_1):PAGE30
  AT28 PVDDCR_CPU0_P0 @T6G_MB_LIB.T6G(SCH_1):PVDDCR_CPU0_P0    I42 @T6G_MB_LIB.T6G(SCH_1):PAGE30
  AT26 PVDDCR_CPU0_P0 @T6G_MB_LIB.T6G(SCH_1):PVDDCR_CPU0_P0    I42 @T6G_MB_LIB.T6G(SCH_1):PAGE30
  AT24 PVDDCR_CPU0_P0 @T6G_MB_LIB.T6G(SCH_1):PVDDCR_CPU0_P0    I42 @T6G_MB_LIB.T6G(SCH_1):PAGE30
  AR50 PVDDCR_CPU0_P0 @T6G_MB_LIB.T6G(SCH_1):PVDDCR_CPU0_P0    I42 @T6G_MB_LIB.T6G(SCH_1):PAGE30
  AR48 PVDDCR_CPU0_P0 @T6G_MB_LIB.T6G(SCH_1):PVDDCR_CPU0_P0    I42 @T6G_MB_LIB.T6G(SCH_1):PAGE30
  AR46 PVDDCR_CPU0_P0 @T6G_MB_LIB.T6G(SCH_1):PVDDCR_CPU0_P0    I42 @T6G_MB_LIB.T6G(SCH_1):PAGE30
  AR44 PVDDCR_CPU0_P0 @T6G_MB_LIB.T6G(SCH_1):PVDDCR_CPU0_P0    I42 @T6G_MB_LIB.T6G(SCH_1):PAGE30
  AR42 PVDDCR_CPU0_P0 @T6G_MB_LIB.T6G(SCH_1):PVDDCR_CPU0_P0    I42 @T6G_MB_LIB.T6G(SCH_1):PAGE30
  AR40 PVDDCR_CPU0_P0 @T6G_MB_LIB.T6G(SCH_1):PVDDCR_CPU0_P0    I42 @T6G_MB_LIB.T6G(SCH_1):PAGE30
  AR35 PVDDCR_CPU0_P0 @T6G_MB_LIB.T6G(SCH_1):PVDDCR_CPU0_P0    I42 @T6G_MB_LIB.T6G(SCH_1):PAGE30
  AR33 PVDDCR_CPU0_P0 @T6G_MB_LIB.T6G(SCH_1):PVDDCR_CPU0_P0    I42 @T6G_MB_LIB.T6G(SCH_1):PAGE30
  AR31 PVDDCR_CPU0_P0 @T6G_MB_LIB.T6G(SCH_1):PVDDCR_CPU0_P0    I42 @T6G_MB_LIB.T6G(SCH_1):PAGE30
  AR29 PVDDCR_CPU0_P0 @T6G_MB_LIB.T6G(SCH_1):PVDDCR_CPU0_P0    I42 @T6G_MB_LIB.T6G(SCH_1):PAGE30
  AR27 PVDDCR_CPU0_P0 @T6G_MB_LIB.T6G(SCH_1):PVDDCR_CPU0_P0    I42 @T6G_MB_LIB.T6G(SCH_1):PAGE30
  AR25 PVDDCR_CPU0_P0 @T6G_MB_LIB.T6G(SCH_1):PVDDCR_CPU0_P0    I42 @T6G_MB_LIB.T6G(SCH_1):PAGE30
  AR23 PVDDCR_CPU0_P0 @T6G_MB_LIB.T6G(SCH_1):PVDDCR_CPU0_P0    I42 @T6G_MB_LIB.T6G(SCH_1):PAGE30
  AP53 PVDDCR_CPU0_P0 @T6G_MB_LIB.T6G(SCH_1):PVDDCR_CPU0_P0    I42 @T6G_MB_LIB.T6G(SCH_1):PAGE30
  AP52 PVDDCR_CPU0_P0 @T6G_MB_LIB.T6G(SCH_1):PVDDCR_CPU0_P0    I42 @T6G_MB_LIB.T6G(SCH_1):PAGE30
  AP50 PVDDCR_CPU0_P0 @T6G_MB_LIB.T6G(SCH_1):PVDDCR_CPU0_P0    I42 @T6G_MB_LIB.T6G(SCH_1):PAGE30
  AP49 PVDDCR_CPU0_P0 @T6G_MB_LIB.T6G(SCH_1):PVDDCR_CPU0_P0    I42 @T6G_MB_LIB.T6G(SCH_1):PAGE30
  AP47 PVDDCR_CPU0_P0 @T6G_MB_LIB.T6G(SCH_1):PVDDCR_CPU0_P0    I42 @T6G_MB_LIB.T6G(SCH_1):PAGE30
  AP46 PVDDCR_CPU0_P0 @T6G_MB_LIB.T6G(SCH_1):PVDDCR_CPU0_P0    I42 @T6G_MB_LIB.T6G(SCH_1):PAGE30
  AP44 PVDDCR_CPU0_P0 @T6G_MB_LIB.T6G(SCH_1):PVDDCR_CPU0_P0    I42 @T6G_MB_LIB.T6G(SCH_1):PAGE30
  AP43 PVDDCR_CPU0_P0 @T6G_MB_LIB.T6G(SCH_1):PVDDCR_CPU0_P0    I42 @T6G_MB_LIB.T6G(SCH_1):PAGE30
  AP33 PVDDCR_CPU0_P0 @T6G_MB_LIB.T6G(SCH_1):PVDDCR_CPU0_P0    I42 @T6G_MB_LIB.T6G(SCH_1):PAGE30
  AP32 PVDDCR_CPU0_P0 @T6G_MB_LIB.T6G(SCH_1):PVDDCR_CPU0_P0    I42 @T6G_MB_LIB.T6G(SCH_1):PAGE30
  AP30 PVDDCR_CPU0_P0 @T6G_MB_LIB.T6G(SCH_1):PVDDCR_CPU0_P0    I42 @T6G_MB_LIB.T6G(SCH_1):PAGE30
  AP29 PVDDCR_CPU0_P0 @T6G_MB_LIB.T6G(SCH_1):PVDDCR_CPU0_P0    I42 @T6G_MB_LIB.T6G(SCH_1):PAGE30
  AP27 PVDDCR_CPU0_P0 @T6G_MB_LIB.T6G(SCH_1):PVDDCR_CPU0_P0    I42 @T6G_MB_LIB.T6G(SCH_1):PAGE30
  AP26 PVDDCR_CPU0_P0 @T6G_MB_LIB.T6G(SCH_1):PVDDCR_CPU0_P0    I42 @T6G_MB_LIB.T6G(SCH_1):PAGE30
  AP24 PVDDCR_CPU0_P0 @T6G_MB_LIB.T6G(SCH_1):PVDDCR_CPU0_P0    I42 @T6G_MB_LIB.T6G(SCH_1):PAGE30
  AP23 PVDDCR_CPU0_P0 @T6G_MB_LIB.T6G(SCH_1):PVDDCR_CPU0_P0    I42 @T6G_MB_LIB.T6G(SCH_1):PAGE30
  AL41 PVDDCR_CPU0_P0 @T6G_MB_LIB.T6G(SCH_1):PVDDCR_CPU0_P0    I42 @T6G_MB_LIB.T6G(SCH_1):PAGE30
  AL40 PVDDCR_CPU0_P0 @T6G_MB_LIB.T6G(SCH_1):PVDDCR_CPU0_P0    I42 @T6G_MB_LIB.T6G(SCH_1):PAGE30
  AL36 PVDDCR_CPU0_P0 @T6G_MB_LIB.T6G(SCH_1):PVDDCR_CPU0_P0    I42 @T6G_MB_LIB.T6G(SCH_1):PAGE30
  AL35 PVDDCR_CPU0_P0 @T6G_MB_LIB.T6G(SCH_1):PVDDCR_CPU0_P0    I42 @T6G_MB_LIB.T6G(SCH_1):PAGE30
  AK53 PVDDCR_CPU0_P0 @T6G_MB_LIB.T6G(SCH_1):PVDDCR_CPU0_P0    I42 @T6G_MB_LIB.T6G(SCH_1):PAGE30
  AK52 PVDDCR_CPU0_P0 @T6G_MB_LIB.T6G(SCH_1):PVDDCR_CPU0_P0    I42 @T6G_MB_LIB.T6G(SCH_1):PAGE30
  AK50 PVDDCR_CPU0_P0 @T6G_MB_LIB.T6G(SCH_1):PVDDCR_CPU0_P0    I42 @T6G_MB_LIB.T6G(SCH_1):PAGE30
  AK49 PVDDCR_CPU0_P0 @T6G_MB_LIB.T6G(SCH_1):PVDDCR_CPU0_P0    I42 @T6G_MB_LIB.T6G(SCH_1):PAGE30
  AK47 PVDDCR_CPU0_P0 @T6G_MB_LIB.T6G(SCH_1):PVDDCR_CPU0_P0    I42 @T6G_MB_LIB.T6G(SCH_1):PAGE30
  AK46 PVDDCR_CPU0_P0 @T6G_MB_LIB.T6G(SCH_1):PVDDCR_CPU0_P0    I42 @T6G_MB_LIB.T6G(SCH_1):PAGE30
  AK44 PVDDCR_CPU0_P0 @T6G_MB_LIB.T6G(SCH_1):PVDDCR_CPU0_P0    I42 @T6G_MB_LIB.T6G(SCH_1):PAGE30
  AK43 PVDDCR_CPU0_P0 @T6G_MB_LIB.T6G(SCH_1):PVDDCR_CPU0_P0    I42 @T6G_MB_LIB.T6G(SCH_1):PAGE30
  AK33 PVDDCR_CPU0_P0 @T6G_MB_LIB.T6G(SCH_1):PVDDCR_CPU0_P0    I42 @T6G_MB_LIB.T6G(SCH_1):PAGE30
  AK32 PVDDCR_CPU0_P0 @T6G_MB_LIB.T6G(SCH_1):PVDDCR_CPU0_P0    I42 @T6G_MB_LIB.T6G(SCH_1):PAGE30
  AK30 PVDDCR_CPU0_P0 @T6G_MB_LIB.T6G(SCH_1):PVDDCR_CPU0_P0    I42 @T6G_MB_LIB.T6G(SCH_1):PAGE30
  AK29 PVDDCR_CPU0_P0 @T6G_MB_LIB.T6G(SCH_1):PVDDCR_CPU0_P0    I42 @T6G_MB_LIB.T6G(SCH_1):PAGE30
  AK27 PVDDCR_CPU0_P0 @T6G_MB_LIB.T6G(SCH_1):PVDDCR_CPU0_P0    I42 @T6G_MB_LIB.T6G(SCH_1):PAGE30
  AK26 PVDDCR_CPU0_P0 @T6G_MB_LIB.T6G(SCH_1):PVDDCR_CPU0_P0    I42 @T6G_MB_LIB.T6G(SCH_1):PAGE30
  AK24 PVDDCR_CPU0_P0 @T6G_MB_LIB.T6G(SCH_1):PVDDCR_CPU0_P0    I42 @T6G_MB_LIB.T6G(SCH_1):PAGE30
  AK23 PVDDCR_CPU0_P0 @T6G_MB_LIB.T6G(SCH_1):PVDDCR_CPU0_P0    I42 @T6G_MB_LIB.T6G(SCH_1):PAGE30
  AG41 PVDDCR_CPU0_P0 @T6G_MB_LIB.T6G(SCH_1):PVDDCR_CPU0_P0    I42 @T6G_MB_LIB.T6G(SCH_1):PAGE30
  AG40 PVDDCR_CPU0_P0 @T6G_MB_LIB.T6G(SCH_1):PVDDCR_CPU0_P0    I42 @T6G_MB_LIB.T6G(SCH_1):PAGE30
  AG36 PVDDCR_CPU0_P0 @T6G_MB_LIB.T6G(SCH_1):PVDDCR_CPU0_P0    I42 @T6G_MB_LIB.T6G(SCH_1):PAGE30
  AG35 PVDDCR_CPU0_P0 @T6G_MB_LIB.T6G(SCH_1):PVDDCR_CPU0_P0    I42 @T6G_MB_LIB.T6G(SCH_1):PAGE30
  AF53 PVDDCR_CPU0_P0 @T6G_MB_LIB.T6G(SCH_1):PVDDCR_CPU0_P0    I42 @T6G_MB_LIB.T6G(SCH_1):PAGE30
  AF52 PVDDCR_CPU0_P0 @T6G_MB_LIB.T6G(SCH_1):PVDDCR_CPU0_P0    I42 @T6G_MB_LIB.T6G(SCH_1):PAGE30
  AF50 PVDDCR_CPU0_P0 @T6G_MB_LIB.T6G(SCH_1):PVDDCR_CPU0_P0    I42 @T6G_MB_LIB.T6G(SCH_1):PAGE30
  AF49 PVDDCR_CPU0_P0 @T6G_MB_LIB.T6G(SCH_1):PVDDCR_CPU0_P0    I42 @T6G_MB_LIB.T6G(SCH_1):PAGE30
  AF47 PVDDCR_CPU0_P0 @T6G_MB_LIB.T6G(SCH_1):PVDDCR_CPU0_P0    I42 @T6G_MB_LIB.T6G(SCH_1):PAGE30
  AF46 PVDDCR_CPU0_P0 @T6G_MB_LIB.T6G(SCH_1):PVDDCR_CPU0_P0    I42 @T6G_MB_LIB.T6G(SCH_1):PAGE30
  AF44 PVDDCR_CPU0_P0 @T6G_MB_LIB.T6G(SCH_1):PVDDCR_CPU0_P0    I42 @T6G_MB_LIB.T6G(SCH_1):PAGE30
  AF43 PVDDCR_CPU0_P0 @T6G_MB_LIB.T6G(SCH_1):PVDDCR_CPU0_P0    I42 @T6G_MB_LIB.T6G(SCH_1):PAGE30
  AF33 PVDDCR_CPU0_P0 @T6G_MB_LIB.T6G(SCH_1):PVDDCR_CPU0_P0    I42 @T6G_MB_LIB.T6G(SCH_1):PAGE30
  AF32 PVDDCR_CPU0_P0 @T6G_MB_LIB.T6G(SCH_1):PVDDCR_CPU0_P0    I42 @T6G_MB_LIB.T6G(SCH_1):PAGE30
  AF30 PVDDCR_CPU0_P0 @T6G_MB_LIB.T6G(SCH_1):PVDDCR_CPU0_P0    I42 @T6G_MB_LIB.T6G(SCH_1):PAGE30
  AF29 PVDDCR_CPU0_P0 @T6G_MB_LIB.T6G(SCH_1):PVDDCR_CPU0_P0    I42 @T6G_MB_LIB.T6G(SCH_1):PAGE30
  AF27 PVDDCR_CPU0_P0 @T6G_MB_LIB.T6G(SCH_1):PVDDCR_CPU0_P0    I42 @T6G_MB_LIB.T6G(SCH_1):PAGE30
  AF26 PVDDCR_CPU0_P0 @T6G_MB_LIB.T6G(SCH_1):PVDDCR_CPU0_P0    I42 @T6G_MB_LIB.T6G(SCH_1):PAGE30
  AF24 PVDDCR_CPU0_P0 @T6G_MB_LIB.T6G(SCH_1):PVDDCR_CPU0_P0    I42 @T6G_MB_LIB.T6G(SCH_1):PAGE30
  AF23 PVDDCR_CPU0_P0 @T6G_MB_LIB.T6G(SCH_1):PVDDCR_CPU0_P0    I42 @T6G_MB_LIB.T6G(SCH_1):PAGE30
  AC41 PVDDCR_CPU0_P0 @T6G_MB_LIB.T6G(SCH_1):PVDDCR_CPU0_P0    I42 @T6G_MB_LIB.T6G(SCH_1):PAGE30
  AC40 PVDDCR_CPU0_P0 @T6G_MB_LIB.T6G(SCH_1):PVDDCR_CPU0_P0    I42 @T6G_MB_LIB.T6G(SCH_1):PAGE30
  AC36 PVDDCR_CPU0_P0 @T6G_MB_LIB.T6G(SCH_1):PVDDCR_CPU0_P0    I42 @T6G_MB_LIB.T6G(SCH_1):PAGE30
  AC35 PVDDCR_CPU0_P0 @T6G_MB_LIB.T6G(SCH_1):PVDDCR_CPU0_P0    I42 @T6G_MB_LIB.T6G(SCH_1):PAGE30
  AB53 PVDDCR_CPU0_P0 @T6G_MB_LIB.T6G(SCH_1):PVDDCR_CPU0_P0    I42 @T6G_MB_LIB.T6G(SCH_1):PAGE30
  AB52 PVDDCR_CPU0_P0 @T6G_MB_LIB.T6G(SCH_1):PVDDCR_CPU0_P0    I42 @T6G_MB_LIB.T6G(SCH_1):PAGE30
  AB50 PVDDCR_CPU0_P0 @T6G_MB_LIB.T6G(SCH_1):PVDDCR_CPU0_P0    I42 @T6G_MB_LIB.T6G(SCH_1):PAGE30
  AB49 PVDDCR_CPU0_P0 @T6G_MB_LIB.T6G(SCH_1):PVDDCR_CPU0_P0    I42 @T6G_MB_LIB.T6G(SCH_1):PAGE30
  AB47 PVDDCR_CPU0_P0 @T6G_MB_LIB.T6G(SCH_1):PVDDCR_CPU0_P0    I42 @T6G_MB_LIB.T6G(SCH_1):PAGE30
  AB46 PVDDCR_CPU0_P0 @T6G_MB_LIB.T6G(SCH_1):PVDDCR_CPU0_P0    I42 @T6G_MB_LIB.T6G(SCH_1):PAGE30
  AB44 PVDDCR_CPU0_P0 @T6G_MB_LIB.T6G(SCH_1):PVDDCR_CPU0_P0    I42 @T6G_MB_LIB.T6G(SCH_1):PAGE30
  AB43 PVDDCR_CPU0_P0 @T6G_MB_LIB.T6G(SCH_1):PVDDCR_CPU0_P0    I42 @T6G_MB_LIB.T6G(SCH_1):PAGE30
  AB33 PVDDCR_CPU0_P0 @T6G_MB_LIB.T6G(SCH_1):PVDDCR_CPU0_P0    I42 @T6G_MB_LIB.T6G(SCH_1):PAGE30
  AB32 PVDDCR_CPU0_P0 @T6G_MB_LIB.T6G(SCH_1):PVDDCR_CPU0_P0    I42 @T6G_MB_LIB.T6G(SCH_1):PAGE30
  AB30 PVDDCR_CPU0_P0 @T6G_MB_LIB.T6G(SCH_1):PVDDCR_CPU0_P0    I42 @T6G_MB_LIB.T6G(SCH_1):PAGE30
  AB29 PVDDCR_CPU0_P0 @T6G_MB_LIB.T6G(SCH_1):PVDDCR_CPU0_P0    I42 @T6G_MB_LIB.T6G(SCH_1):PAGE30
  AB27 PVDDCR_CPU0_P0 @T6G_MB_LIB.T6G(SCH_1):PVDDCR_CPU0_P0    I42 @T6G_MB_LIB.T6G(SCH_1):PAGE30
  AB26 PVDDCR_CPU0_P0 @T6G_MB_LIB.T6G(SCH_1):PVDDCR_CPU0_P0    I42 @T6G_MB_LIB.T6G(SCH_1):PAGE30
  AB24 PVDDCR_CPU0_P0 @T6G_MB_LIB.T6G(SCH_1):PVDDCR_CPU0_P0    I42 @T6G_MB_LIB.T6G(SCH_1):PAGE30
  AB23 PVDDCR_CPU0_P0 @T6G_MB_LIB.T6G(SCH_1):PVDDCR_CPU0_P0    I42 @T6G_MB_LIB.T6G(SCH_1):PAGE30
   Y41 PVDDCR_CPU0_P0 @T6G_MB_LIB.T6G(SCH_1):PVDDCR_CPU0_P0    I42 @T6G_MB_LIB.T6G(SCH_1):PAGE30
   Y40 PVDDCR_CPU0_P0 @T6G_MB_LIB.T6G(SCH_1):PVDDCR_CPU0_P0    I42 @T6G_MB_LIB.T6G(SCH_1):PAGE30
   Y36 PVDDCR_CPU0_P0 @T6G_MB_LIB.T6G(SCH_1):PVDDCR_CPU0_P0    I42 @T6G_MB_LIB.T6G(SCH_1):PAGE30
   Y35 PVDDCR_CPU0_P0 @T6G_MB_LIB.T6G(SCH_1):PVDDCR_CPU0_P0    I42 @T6G_MB_LIB.T6G(SCH_1):PAGE30
  AU42 PVDDCR_CPU0_P0 @T6G_MB_LIB.T6G(SCH_1):PVDDCR_CPU0_P0    I42 @T6G_MB_LIB.T6G(SCH_1):PAGE30
  AU46 PVDDCR_CPU0_P0 @T6G_MB_LIB.T6G(SCH_1):PVDDCR_CPU0_P0    I42 @T6G_MB_LIB.T6G(SCH_1):PAGE30
  AT49 PVDDCR_CPU0_P0 @T6G_MB_LIB.T6G(SCH_1):PVDDCR_CPU0_P0    I42 @T6G_MB_LIB.T6G(SCH_1):PAGE30
  AU29 PVDDCR_CPU0_P0 @T6G_MB_LIB.T6G(SCH_1):PVDDCR_CPU0_P0    I42 @T6G_MB_LIB.T6G(SCH_1):PAGE30
  AU44 PVDDCR_CPU0_P0 @T6G_MB_LIB.T6G(SCH_1):PVDDCR_CPU0_P0    I42 @T6G_MB_LIB.T6G(SCH_1):PAGE30
  AU48 PVDDCR_CPU0_P0 @T6G_MB_LIB.T6G(SCH_1):PVDDCR_CPU0_P0    I42 @T6G_MB_LIB.T6G(SCH_1):PAGE30
  AU25 PVDDCR_CPU0_P0 @T6G_MB_LIB.T6G(SCH_1):PVDDCR_CPU0_P0    I42 @T6G_MB_LIB.T6G(SCH_1):PAGE30
  AU33 PVDDCR_CPU0_P0 @T6G_MB_LIB.T6G(SCH_1):PVDDCR_CPU0_P0    I42 @T6G_MB_LIB.T6G(SCH_1):PAGE30
  BN31 PVDDCR_CPU1_P0 @T6G_MB_LIB.T6G(SCH_1):PVDDCR_CPU1_P0    I45 @T6G_MB_LIB.T6G(SCH_1):PAGE30
  BN42 PVDDCR_CPU1_P0 @T6G_MB_LIB.T6G(SCH_1):PVDDCR_CPU1_P0    I45 @T6G_MB_LIB.T6G(SCH_1):PAGE30
  BN50 PVDDCR_CPU1_P0 @T6G_MB_LIB.T6G(SCH_1):PVDDCR_CPU1_P0    I45 @T6G_MB_LIB.T6G(SCH_1):PAGE30
  BP26 PVDDCR_CPU1_P0 @T6G_MB_LIB.T6G(SCH_1):PVDDCR_CPU1_P0    I45 @T6G_MB_LIB.T6G(SCH_1):PAGE30
  BP30 PVDDCR_CPU1_P0 @T6G_MB_LIB.T6G(SCH_1):PVDDCR_CPU1_P0    I45 @T6G_MB_LIB.T6G(SCH_1):PAGE30
  BP34 PVDDCR_CPU1_P0 @T6G_MB_LIB.T6G(SCH_1):PVDDCR_CPU1_P0    I45 @T6G_MB_LIB.T6G(SCH_1):PAGE30
  BP36 PVDDCR_CPU1_P0 @T6G_MB_LIB.T6G(SCH_1):PVDDCR_CPU1_P0    I45 @T6G_MB_LIB.T6G(SCH_1):PAGE30
  BP39 PVDDCR_CPU1_P0 @T6G_MB_LIB.T6G(SCH_1):PVDDCR_CPU1_P0    I45 @T6G_MB_LIB.T6G(SCH_1):PAGE30
  BP41 PVDDCR_CPU1_P0 @T6G_MB_LIB.T6G(SCH_1):PVDDCR_CPU1_P0    I45 @T6G_MB_LIB.T6G(SCH_1):PAGE30
  BP43 PVDDCR_CPU1_P0 @T6G_MB_LIB.T6G(SCH_1):PVDDCR_CPU1_P0    I45 @T6G_MB_LIB.T6G(SCH_1):PAGE30
  BP45 PVDDCR_CPU1_P0 @T6G_MB_LIB.T6G(SCH_1):PVDDCR_CPU1_P0    I45 @T6G_MB_LIB.T6G(SCH_1):PAGE30
  BP47 PVDDCR_CPU1_P0 @T6G_MB_LIB.T6G(SCH_1):PVDDCR_CPU1_P0    I45 @T6G_MB_LIB.T6G(SCH_1):PAGE30
  BP49 PVDDCR_CPU1_P0 @T6G_MB_LIB.T6G(SCH_1):PVDDCR_CPU1_P0    I45 @T6G_MB_LIB.T6G(SCH_1):PAGE30
  BR23 PVDDCR_CPU1_P0 @T6G_MB_LIB.T6G(SCH_1):PVDDCR_CPU1_P0    I45 @T6G_MB_LIB.T6G(SCH_1):PAGE30
  BR25 PVDDCR_CPU1_P0 @T6G_MB_LIB.T6G(SCH_1):PVDDCR_CPU1_P0    I45 @T6G_MB_LIB.T6G(SCH_1):PAGE30
  BR27 PVDDCR_CPU1_P0 @T6G_MB_LIB.T6G(SCH_1):PVDDCR_CPU1_P0    I45 @T6G_MB_LIB.T6G(SCH_1):PAGE30
  BR29 PVDDCR_CPU1_P0 @T6G_MB_LIB.T6G(SCH_1):PVDDCR_CPU1_P0    I45 @T6G_MB_LIB.T6G(SCH_1):PAGE30
  BR31 PVDDCR_CPU1_P0 @T6G_MB_LIB.T6G(SCH_1):PVDDCR_CPU1_P0    I45 @T6G_MB_LIB.T6G(SCH_1):PAGE30
  BR33 PVDDCR_CPU1_P0 @T6G_MB_LIB.T6G(SCH_1):PVDDCR_CPU1_P0    I45 @T6G_MB_LIB.T6G(SCH_1):PAGE30
  BR35 PVDDCR_CPU1_P0 @T6G_MB_LIB.T6G(SCH_1):PVDDCR_CPU1_P0    I45 @T6G_MB_LIB.T6G(SCH_1):PAGE30
  BR40 PVDDCR_CPU1_P0 @T6G_MB_LIB.T6G(SCH_1):PVDDCR_CPU1_P0    I45 @T6G_MB_LIB.T6G(SCH_1):PAGE30
  BR42 PVDDCR_CPU1_P0 @T6G_MB_LIB.T6G(SCH_1):PVDDCR_CPU1_P0    I45 @T6G_MB_LIB.T6G(SCH_1):PAGE30
  BR44 PVDDCR_CPU1_P0 @T6G_MB_LIB.T6G(SCH_1):PVDDCR_CPU1_P0    I45 @T6G_MB_LIB.T6G(SCH_1):PAGE30
  BR46 PVDDCR_CPU1_P0 @T6G_MB_LIB.T6G(SCH_1):PVDDCR_CPU1_P0    I45 @T6G_MB_LIB.T6G(SCH_1):PAGE30
  BR48 PVDDCR_CPU1_P0 @T6G_MB_LIB.T6G(SCH_1):PVDDCR_CPU1_P0    I45 @T6G_MB_LIB.T6G(SCH_1):PAGE30
  BR50 PVDDCR_CPU1_P0 @T6G_MB_LIB.T6G(SCH_1):PVDDCR_CPU1_P0    I45 @T6G_MB_LIB.T6G(SCH_1):PAGE30
  BR52 PVDDCR_CPU1_P0 @T6G_MB_LIB.T6G(SCH_1):PVDDCR_CPU1_P0    I45 @T6G_MB_LIB.T6G(SCH_1):PAGE30
  BT23 PVDDCR_CPU1_P0 @T6G_MB_LIB.T6G(SCH_1):PVDDCR_CPU1_P0    I45 @T6G_MB_LIB.T6G(SCH_1):PAGE30
  BT24 PVDDCR_CPU1_P0 @T6G_MB_LIB.T6G(SCH_1):PVDDCR_CPU1_P0    I45 @T6G_MB_LIB.T6G(SCH_1):PAGE30
  BT26 PVDDCR_CPU1_P0 @T6G_MB_LIB.T6G(SCH_1):PVDDCR_CPU1_P0    I45 @T6G_MB_LIB.T6G(SCH_1):PAGE30
  BT27 PVDDCR_CPU1_P0 @T6G_MB_LIB.T6G(SCH_1):PVDDCR_CPU1_P0    I45 @T6G_MB_LIB.T6G(SCH_1):PAGE30
  BT29 PVDDCR_CPU1_P0 @T6G_MB_LIB.T6G(SCH_1):PVDDCR_CPU1_P0    I45 @T6G_MB_LIB.T6G(SCH_1):PAGE30
  BT30 PVDDCR_CPU1_P0 @T6G_MB_LIB.T6G(SCH_1):PVDDCR_CPU1_P0    I45 @T6G_MB_LIB.T6G(SCH_1):PAGE30
  BT32 PVDDCR_CPU1_P0 @T6G_MB_LIB.T6G(SCH_1):PVDDCR_CPU1_P0    I45 @T6G_MB_LIB.T6G(SCH_1):PAGE30
  BT33 PVDDCR_CPU1_P0 @T6G_MB_LIB.T6G(SCH_1):PVDDCR_CPU1_P0    I45 @T6G_MB_LIB.T6G(SCH_1):PAGE30
  BT43 PVDDCR_CPU1_P0 @T6G_MB_LIB.T6G(SCH_1):PVDDCR_CPU1_P0    I45 @T6G_MB_LIB.T6G(SCH_1):PAGE30
  BT44 PVDDCR_CPU1_P0 @T6G_MB_LIB.T6G(SCH_1):PVDDCR_CPU1_P0    I45 @T6G_MB_LIB.T6G(SCH_1):PAGE30
  BT46 PVDDCR_CPU1_P0 @T6G_MB_LIB.T6G(SCH_1):PVDDCR_CPU1_P0    I45 @T6G_MB_LIB.T6G(SCH_1):PAGE30
  BT47 PVDDCR_CPU1_P0 @T6G_MB_LIB.T6G(SCH_1):PVDDCR_CPU1_P0    I45 @T6G_MB_LIB.T6G(SCH_1):PAGE30
  BT49 PVDDCR_CPU1_P0 @T6G_MB_LIB.T6G(SCH_1):PVDDCR_CPU1_P0    I45 @T6G_MB_LIB.T6G(SCH_1):PAGE30
  BT50 PVDDCR_CPU1_P0 @T6G_MB_LIB.T6G(SCH_1):PVDDCR_CPU1_P0    I45 @T6G_MB_LIB.T6G(SCH_1):PAGE30
  BT52 PVDDCR_CPU1_P0 @T6G_MB_LIB.T6G(SCH_1):PVDDCR_CPU1_P0    I45 @T6G_MB_LIB.T6G(SCH_1):PAGE30
  BT53 PVDDCR_CPU1_P0 @T6G_MB_LIB.T6G(SCH_1):PVDDCR_CPU1_P0    I45 @T6G_MB_LIB.T6G(SCH_1):PAGE30
  BW35 PVDDCR_CPU1_P0 @T6G_MB_LIB.T6G(SCH_1):PVDDCR_CPU1_P0    I45 @T6G_MB_LIB.T6G(SCH_1):PAGE30
  BW36 PVDDCR_CPU1_P0 @T6G_MB_LIB.T6G(SCH_1):PVDDCR_CPU1_P0    I45 @T6G_MB_LIB.T6G(SCH_1):PAGE30
  BW40 PVDDCR_CPU1_P0 @T6G_MB_LIB.T6G(SCH_1):PVDDCR_CPU1_P0    I45 @T6G_MB_LIB.T6G(SCH_1):PAGE30
  BW41 PVDDCR_CPU1_P0 @T6G_MB_LIB.T6G(SCH_1):PVDDCR_CPU1_P0    I45 @T6G_MB_LIB.T6G(SCH_1):PAGE30
  BY23 PVDDCR_CPU1_P0 @T6G_MB_LIB.T6G(SCH_1):PVDDCR_CPU1_P0    I45 @T6G_MB_LIB.T6G(SCH_1):PAGE30
  BY24 PVDDCR_CPU1_P0 @T6G_MB_LIB.T6G(SCH_1):PVDDCR_CPU1_P0    I45 @T6G_MB_LIB.T6G(SCH_1):PAGE30
  BY26 PVDDCR_CPU1_P0 @T6G_MB_LIB.T6G(SCH_1):PVDDCR_CPU1_P0    I45 @T6G_MB_LIB.T6G(SCH_1):PAGE30
  BY27 PVDDCR_CPU1_P0 @T6G_MB_LIB.T6G(SCH_1):PVDDCR_CPU1_P0    I45 @T6G_MB_LIB.T6G(SCH_1):PAGE30
  BY29 PVDDCR_CPU1_P0 @T6G_MB_LIB.T6G(SCH_1):PVDDCR_CPU1_P0    I45 @T6G_MB_LIB.T6G(SCH_1):PAGE30
  BY30 PVDDCR_CPU1_P0 @T6G_MB_LIB.T6G(SCH_1):PVDDCR_CPU1_P0    I45 @T6G_MB_LIB.T6G(SCH_1):PAGE30
  BY32 PVDDCR_CPU1_P0 @T6G_MB_LIB.T6G(SCH_1):PVDDCR_CPU1_P0    I45 @T6G_MB_LIB.T6G(SCH_1):PAGE30
  BY33 PVDDCR_CPU1_P0 @T6G_MB_LIB.T6G(SCH_1):PVDDCR_CPU1_P0    I45 @T6G_MB_LIB.T6G(SCH_1):PAGE30
  BY43 PVDDCR_CPU1_P0 @T6G_MB_LIB.T6G(SCH_1):PVDDCR_CPU1_P0    I45 @T6G_MB_LIB.T6G(SCH_1):PAGE30
  BY44 PVDDCR_CPU1_P0 @T6G_MB_LIB.T6G(SCH_1):PVDDCR_CPU1_P0    I45 @T6G_MB_LIB.T6G(SCH_1):PAGE30
  BY46 PVDDCR_CPU1_P0 @T6G_MB_LIB.T6G(SCH_1):PVDDCR_CPU1_P0    I45 @T6G_MB_LIB.T6G(SCH_1):PAGE30
  BY47 PVDDCR_CPU1_P0 @T6G_MB_LIB.T6G(SCH_1):PVDDCR_CPU1_P0    I45 @T6G_MB_LIB.T6G(SCH_1):PAGE30
  BY49 PVDDCR_CPU1_P0 @T6G_MB_LIB.T6G(SCH_1):PVDDCR_CPU1_P0    I45 @T6G_MB_LIB.T6G(SCH_1):PAGE30
  BY50 PVDDCR_CPU1_P0 @T6G_MB_LIB.T6G(SCH_1):PVDDCR_CPU1_P0    I45 @T6G_MB_LIB.T6G(SCH_1):PAGE30
  BY52 PVDDCR_CPU1_P0 @T6G_MB_LIB.T6G(SCH_1):PVDDCR_CPU1_P0    I45 @T6G_MB_LIB.T6G(SCH_1):PAGE30
  BY53 PVDDCR_CPU1_P0 @T6G_MB_LIB.T6G(SCH_1):PVDDCR_CPU1_P0    I45 @T6G_MB_LIB.T6G(SCH_1):PAGE30
  CC35 PVDDCR_CPU1_P0 @T6G_MB_LIB.T6G(SCH_1):PVDDCR_CPU1_P0    I45 @T6G_MB_LIB.T6G(SCH_1):PAGE30
  CC36 PVDDCR_CPU1_P0 @T6G_MB_LIB.T6G(SCH_1):PVDDCR_CPU1_P0    I45 @T6G_MB_LIB.T6G(SCH_1):PAGE30
  CC40 PVDDCR_CPU1_P0 @T6G_MB_LIB.T6G(SCH_1):PVDDCR_CPU1_P0    I45 @T6G_MB_LIB.T6G(SCH_1):PAGE30
  CC41 PVDDCR_CPU1_P0 @T6G_MB_LIB.T6G(SCH_1):PVDDCR_CPU1_P0    I45 @T6G_MB_LIB.T6G(SCH_1):PAGE30
  CD23 PVDDCR_CPU1_P0 @T6G_MB_LIB.T6G(SCH_1):PVDDCR_CPU1_P0    I45 @T6G_MB_LIB.T6G(SCH_1):PAGE30
  CD24 PVDDCR_CPU1_P0 @T6G_MB_LIB.T6G(SCH_1):PVDDCR_CPU1_P0    I45 @T6G_MB_LIB.T6G(SCH_1):PAGE30
  CD26 PVDDCR_CPU1_P0 @T6G_MB_LIB.T6G(SCH_1):PVDDCR_CPU1_P0    I45 @T6G_MB_LIB.T6G(SCH_1):PAGE30
  CD27 PVDDCR_CPU1_P0 @T6G_MB_LIB.T6G(SCH_1):PVDDCR_CPU1_P0    I45 @T6G_MB_LIB.T6G(SCH_1):PAGE30
  CD29 PVDDCR_CPU1_P0 @T6G_MB_LIB.T6G(SCH_1):PVDDCR_CPU1_P0    I45 @T6G_MB_LIB.T6G(SCH_1):PAGE30
  CD30 PVDDCR_CPU1_P0 @T6G_MB_LIB.T6G(SCH_1):PVDDCR_CPU1_P0    I45 @T6G_MB_LIB.T6G(SCH_1):PAGE30
  CD32 PVDDCR_CPU1_P0 @T6G_MB_LIB.T6G(SCH_1):PVDDCR_CPU1_P0    I45 @T6G_MB_LIB.T6G(SCH_1):PAGE30
  CD33 PVDDCR_CPU1_P0 @T6G_MB_LIB.T6G(SCH_1):PVDDCR_CPU1_P0    I45 @T6G_MB_LIB.T6G(SCH_1):PAGE30
  CD43 PVDDCR_CPU1_P0 @T6G_MB_LIB.T6G(SCH_1):PVDDCR_CPU1_P0    I45 @T6G_MB_LIB.T6G(SCH_1):PAGE30
  CD44 PVDDCR_CPU1_P0 @T6G_MB_LIB.T6G(SCH_1):PVDDCR_CPU1_P0    I45 @T6G_MB_LIB.T6G(SCH_1):PAGE30
  CD46 PVDDCR_CPU1_P0 @T6G_MB_LIB.T6G(SCH_1):PVDDCR_CPU1_P0    I45 @T6G_MB_LIB.T6G(SCH_1):PAGE30
  CD47 PVDDCR_CPU1_P0 @T6G_MB_LIB.T6G(SCH_1):PVDDCR_CPU1_P0    I45 @T6G_MB_LIB.T6G(SCH_1):PAGE30
  CD49 PVDDCR_CPU1_P0 @T6G_MB_LIB.T6G(SCH_1):PVDDCR_CPU1_P0    I45 @T6G_MB_LIB.T6G(SCH_1):PAGE30
  CD50 PVDDCR_CPU1_P0 @T6G_MB_LIB.T6G(SCH_1):PVDDCR_CPU1_P0    I45 @T6G_MB_LIB.T6G(SCH_1):PAGE30
  CD52 PVDDCR_CPU1_P0 @T6G_MB_LIB.T6G(SCH_1):PVDDCR_CPU1_P0    I45 @T6G_MB_LIB.T6G(SCH_1):PAGE30
  CD53 PVDDCR_CPU1_P0 @T6G_MB_LIB.T6G(SCH_1):PVDDCR_CPU1_P0    I45 @T6G_MB_LIB.T6G(SCH_1):PAGE30
  CG35 PVDDCR_CPU1_P0 @T6G_MB_LIB.T6G(SCH_1):PVDDCR_CPU1_P0    I45 @T6G_MB_LIB.T6G(SCH_1):PAGE30
  CG36 PVDDCR_CPU1_P0 @T6G_MB_LIB.T6G(SCH_1):PVDDCR_CPU1_P0    I45 @T6G_MB_LIB.T6G(SCH_1):PAGE30
  CG40 PVDDCR_CPU1_P0 @T6G_MB_LIB.T6G(SCH_1):PVDDCR_CPU1_P0    I45 @T6G_MB_LIB.T6G(SCH_1):PAGE30
  CG41 PVDDCR_CPU1_P0 @T6G_MB_LIB.T6G(SCH_1):PVDDCR_CPU1_P0    I45 @T6G_MB_LIB.T6G(SCH_1):PAGE30
  CH23 PVDDCR_CPU1_P0 @T6G_MB_LIB.T6G(SCH_1):PVDDCR_CPU1_P0    I45 @T6G_MB_LIB.T6G(SCH_1):PAGE30
  CH24 PVDDCR_CPU1_P0 @T6G_MB_LIB.T6G(SCH_1):PVDDCR_CPU1_P0    I45 @T6G_MB_LIB.T6G(SCH_1):PAGE30
  CH26 PVDDCR_CPU1_P0 @T6G_MB_LIB.T6G(SCH_1):PVDDCR_CPU1_P0    I45 @T6G_MB_LIB.T6G(SCH_1):PAGE30
  CH27 PVDDCR_CPU1_P0 @T6G_MB_LIB.T6G(SCH_1):PVDDCR_CPU1_P0    I45 @T6G_MB_LIB.T6G(SCH_1):PAGE30
  CH29 PVDDCR_CPU1_P0 @T6G_MB_LIB.T6G(SCH_1):PVDDCR_CPU1_P0    I45 @T6G_MB_LIB.T6G(SCH_1):PAGE30
  CH30 PVDDCR_CPU1_P0 @T6G_MB_LIB.T6G(SCH_1):PVDDCR_CPU1_P0    I45 @T6G_MB_LIB.T6G(SCH_1):PAGE30
  CH32 PVDDCR_CPU1_P0 @T6G_MB_LIB.T6G(SCH_1):PVDDCR_CPU1_P0    I45 @T6G_MB_LIB.T6G(SCH_1):PAGE30
  CH33 PVDDCR_CPU1_P0 @T6G_MB_LIB.T6G(SCH_1):PVDDCR_CPU1_P0    I45 @T6G_MB_LIB.T6G(SCH_1):PAGE30
  CH43 PVDDCR_CPU1_P0 @T6G_MB_LIB.T6G(SCH_1):PVDDCR_CPU1_P0    I45 @T6G_MB_LIB.T6G(SCH_1):PAGE30
  CH44 PVDDCR_CPU1_P0 @T6G_MB_LIB.T6G(SCH_1):PVDDCR_CPU1_P0    I45 @T6G_MB_LIB.T6G(SCH_1):PAGE30
  CH46 PVDDCR_CPU1_P0 @T6G_MB_LIB.T6G(SCH_1):PVDDCR_CPU1_P0    I45 @T6G_MB_LIB.T6G(SCH_1):PAGE30
  CH47 PVDDCR_CPU1_P0 @T6G_MB_LIB.T6G(SCH_1):PVDDCR_CPU1_P0    I45 @T6G_MB_LIB.T6G(SCH_1):PAGE30
  CH49 PVDDCR_CPU1_P0 @T6G_MB_LIB.T6G(SCH_1):PVDDCR_CPU1_P0    I45 @T6G_MB_LIB.T6G(SCH_1):PAGE30
  CH50 PVDDCR_CPU1_P0 @T6G_MB_LIB.T6G(SCH_1):PVDDCR_CPU1_P0    I45 @T6G_MB_LIB.T6G(SCH_1):PAGE30
  CH52 PVDDCR_CPU1_P0 @T6G_MB_LIB.T6G(SCH_1):PVDDCR_CPU1_P0    I45 @T6G_MB_LIB.T6G(SCH_1):PAGE30
  CH53 PVDDCR_CPU1_P0 @T6G_MB_LIB.T6G(SCH_1):PVDDCR_CPU1_P0    I45 @T6G_MB_LIB.T6G(SCH_1):PAGE30
  CK35 PVDDCR_CPU1_P0 @T6G_MB_LIB.T6G(SCH_1):PVDDCR_CPU1_P0    I45 @T6G_MB_LIB.T6G(SCH_1):PAGE30
  CK36 PVDDCR_CPU1_P0 @T6G_MB_LIB.T6G(SCH_1):PVDDCR_CPU1_P0    I45 @T6G_MB_LIB.T6G(SCH_1):PAGE30
  CK40 PVDDCR_CPU1_P0 @T6G_MB_LIB.T6G(SCH_1):PVDDCR_CPU1_P0    I45 @T6G_MB_LIB.T6G(SCH_1):PAGE30
  CK41 PVDDCR_CPU1_P0 @T6G_MB_LIB.T6G(SCH_1):PVDDCR_CPU1_P0    I45 @T6G_MB_LIB.T6G(SCH_1):PAGE30
  CL29 PVDDCR_CPU1_P0 @T6G_MB_LIB.T6G(SCH_1):PVDDCR_CPU1_P0    I45 @T6G_MB_LIB.T6G(SCH_1):PAGE30
  CL30 PVDDCR_CPU1_P0 @T6G_MB_LIB.T6G(SCH_1):PVDDCR_CPU1_P0    I45 @T6G_MB_LIB.T6G(SCH_1):PAGE30
  CL32 PVDDCR_CPU1_P0 @T6G_MB_LIB.T6G(SCH_1):PVDDCR_CPU1_P0    I45 @T6G_MB_LIB.T6G(SCH_1):PAGE30
  CL33 PVDDCR_CPU1_P0 @T6G_MB_LIB.T6G(SCH_1):PVDDCR_CPU1_P0    I45 @T6G_MB_LIB.T6G(SCH_1):PAGE30
  CL43 PVDDCR_CPU1_P0 @T6G_MB_LIB.T6G(SCH_1):PVDDCR_CPU1_P0    I45 @T6G_MB_LIB.T6G(SCH_1):PAGE30
  CL44 PVDDCR_CPU1_P0 @T6G_MB_LIB.T6G(SCH_1):PVDDCR_CPU1_P0    I45 @T6G_MB_LIB.T6G(SCH_1):PAGE30
  CL46 PVDDCR_CPU1_P0 @T6G_MB_LIB.T6G(SCH_1):PVDDCR_CPU1_P0    I45 @T6G_MB_LIB.T6G(SCH_1):PAGE30
  CL47 PVDDCR_CPU1_P0 @T6G_MB_LIB.T6G(SCH_1):PVDDCR_CPU1_P0    I45 @T6G_MB_LIB.T6G(SCH_1):PAGE30
  CN35 PVDDCR_CPU1_P0 @T6G_MB_LIB.T6G(SCH_1):PVDDCR_CPU1_P0    I45 @T6G_MB_LIB.T6G(SCH_1):PAGE30
  CN36 PVDDCR_CPU1_P0 @T6G_MB_LIB.T6G(SCH_1):PVDDCR_CPU1_P0    I45 @T6G_MB_LIB.T6G(SCH_1):PAGE30
  CN40 PVDDCR_CPU1_P0 @T6G_MB_LIB.T6G(SCH_1):PVDDCR_CPU1_P0    I45 @T6G_MB_LIB.T6G(SCH_1):PAGE30
  CN41 PVDDCR_CPU1_P0 @T6G_MB_LIB.T6G(SCH_1):PVDDCR_CPU1_P0    I45 @T6G_MB_LIB.T6G(SCH_1):PAGE30
  CP23 PVDDCR_CPU1_P0 @T6G_MB_LIB.T6G(SCH_1):PVDDCR_CPU1_P0    I45 @T6G_MB_LIB.T6G(SCH_1):PAGE30
  CP24 PVDDCR_CPU1_P0 @T6G_MB_LIB.T6G(SCH_1):PVDDCR_CPU1_P0    I45 @T6G_MB_LIB.T6G(SCH_1):PAGE30
  CP26 PVDDCR_CPU1_P0 @T6G_MB_LIB.T6G(SCH_1):PVDDCR_CPU1_P0    I45 @T6G_MB_LIB.T6G(SCH_1):PAGE30
  CP27 PVDDCR_CPU1_P0 @T6G_MB_LIB.T6G(SCH_1):PVDDCR_CPU1_P0    I45 @T6G_MB_LIB.T6G(SCH_1):PAGE30
  CP29 PVDDCR_CPU1_P0 @T6G_MB_LIB.T6G(SCH_1):PVDDCR_CPU1_P0    I45 @T6G_MB_LIB.T6G(SCH_1):PAGE30
  CP30 PVDDCR_CPU1_P0 @T6G_MB_LIB.T6G(SCH_1):PVDDCR_CPU1_P0    I45 @T6G_MB_LIB.T6G(SCH_1):PAGE30
  CP32 PVDDCR_CPU1_P0 @T6G_MB_LIB.T6G(SCH_1):PVDDCR_CPU1_P0    I45 @T6G_MB_LIB.T6G(SCH_1):PAGE30
  CP33 PVDDCR_CPU1_P0 @T6G_MB_LIB.T6G(SCH_1):PVDDCR_CPU1_P0    I45 @T6G_MB_LIB.T6G(SCH_1):PAGE30
  CP43 PVDDCR_CPU1_P0 @T6G_MB_LIB.T6G(SCH_1):PVDDCR_CPU1_P0    I45 @T6G_MB_LIB.T6G(SCH_1):PAGE30
  CP44 PVDDCR_CPU1_P0 @T6G_MB_LIB.T6G(SCH_1):PVDDCR_CPU1_P0    I45 @T6G_MB_LIB.T6G(SCH_1):PAGE30
  CP46 PVDDCR_CPU1_P0 @T6G_MB_LIB.T6G(SCH_1):PVDDCR_CPU1_P0    I45 @T6G_MB_LIB.T6G(SCH_1):PAGE30
  CP47 PVDDCR_CPU1_P0 @T6G_MB_LIB.T6G(SCH_1):PVDDCR_CPU1_P0    I45 @T6G_MB_LIB.T6G(SCH_1):PAGE30
  CP49 PVDDCR_CPU1_P0 @T6G_MB_LIB.T6G(SCH_1):PVDDCR_CPU1_P0    I45 @T6G_MB_LIB.T6G(SCH_1):PAGE30
  CP50 PVDDCR_CPU1_P0 @T6G_MB_LIB.T6G(SCH_1):PVDDCR_CPU1_P0    I45 @T6G_MB_LIB.T6G(SCH_1):PAGE30
  CP52 PVDDCR_CPU1_P0 @T6G_MB_LIB.T6G(SCH_1):PVDDCR_CPU1_P0    I45 @T6G_MB_LIB.T6G(SCH_1):PAGE30
  CP53 PVDDCR_CPU1_P0 @T6G_MB_LIB.T6G(SCH_1):PVDDCR_CPU1_P0    I45 @T6G_MB_LIB.T6G(SCH_1):PAGE30
  CU35 PVDDCR_CPU1_P0 @T6G_MB_LIB.T6G(SCH_1):PVDDCR_CPU1_P0    I45 @T6G_MB_LIB.T6G(SCH_1):PAGE30
  CU36 PVDDCR_CPU1_P0 @T6G_MB_LIB.T6G(SCH_1):PVDDCR_CPU1_P0    I45 @T6G_MB_LIB.T6G(SCH_1):PAGE30
  CU40 PVDDCR_CPU1_P0 @T6G_MB_LIB.T6G(SCH_1):PVDDCR_CPU1_P0    I45 @T6G_MB_LIB.T6G(SCH_1):PAGE30
  CU41 PVDDCR_CPU1_P0 @T6G_MB_LIB.T6G(SCH_1):PVDDCR_CPU1_P0    I45 @T6G_MB_LIB.T6G(SCH_1):PAGE30
  CV23 PVDDCR_CPU1_P0 @T6G_MB_LIB.T6G(SCH_1):PVDDCR_CPU1_P0    I45 @T6G_MB_LIB.T6G(SCH_1):PAGE30
  CV24 PVDDCR_CPU1_P0 @T6G_MB_LIB.T6G(SCH_1):PVDDCR_CPU1_P0    I45 @T6G_MB_LIB.T6G(SCH_1):PAGE30
  CV26 PVDDCR_CPU1_P0 @T6G_MB_LIB.T6G(SCH_1):PVDDCR_CPU1_P0    I45 @T6G_MB_LIB.T6G(SCH_1):PAGE30
  CV27 PVDDCR_CPU1_P0 @T6G_MB_LIB.T6G(SCH_1):PVDDCR_CPU1_P0    I45 @T6G_MB_LIB.T6G(SCH_1):PAGE30
  CV29 PVDDCR_CPU1_P0 @T6G_MB_LIB.T6G(SCH_1):PVDDCR_CPU1_P0    I45 @T6G_MB_LIB.T6G(SCH_1):PAGE30
  CV30 PVDDCR_CPU1_P0 @T6G_MB_LIB.T6G(SCH_1):PVDDCR_CPU1_P0    I45 @T6G_MB_LIB.T6G(SCH_1):PAGE30
  CV32 PVDDCR_CPU1_P0 @T6G_MB_LIB.T6G(SCH_1):PVDDCR_CPU1_P0    I45 @T6G_MB_LIB.T6G(SCH_1):PAGE30
  CV33 PVDDCR_CPU1_P0 @T6G_MB_LIB.T6G(SCH_1):PVDDCR_CPU1_P0    I45 @T6G_MB_LIB.T6G(SCH_1):PAGE30
  CV43 PVDDCR_CPU1_P0 @T6G_MB_LIB.T6G(SCH_1):PVDDCR_CPU1_P0    I45 @T6G_MB_LIB.T6G(SCH_1):PAGE30
  CV44 PVDDCR_CPU1_P0 @T6G_MB_LIB.T6G(SCH_1):PVDDCR_CPU1_P0    I45 @T6G_MB_LIB.T6G(SCH_1):PAGE30
  CV46 PVDDCR_CPU1_P0 @T6G_MB_LIB.T6G(SCH_1):PVDDCR_CPU1_P0    I45 @T6G_MB_LIB.T6G(SCH_1):PAGE30
  CV47 PVDDCR_CPU1_P0 @T6G_MB_LIB.T6G(SCH_1):PVDDCR_CPU1_P0    I45 @T6G_MB_LIB.T6G(SCH_1):PAGE30
  CV49 PVDDCR_CPU1_P0 @T6G_MB_LIB.T6G(SCH_1):PVDDCR_CPU1_P0    I45 @T6G_MB_LIB.T6G(SCH_1):PAGE30
  CV50 PVDDCR_CPU1_P0 @T6G_MB_LIB.T6G(SCH_1):PVDDCR_CPU1_P0    I45 @T6G_MB_LIB.T6G(SCH_1):PAGE30
  CV52 PVDDCR_CPU1_P0 @T6G_MB_LIB.T6G(SCH_1):PVDDCR_CPU1_P0    I45 @T6G_MB_LIB.T6G(SCH_1):PAGE30
  CV53 PVDDCR_CPU1_P0 @T6G_MB_LIB.T6G(SCH_1):PVDDCR_CPU1_P0    I45 @T6G_MB_LIB.T6G(SCH_1):PAGE30
  DA35 PVDDCR_CPU1_P0 @T6G_MB_LIB.T6G(SCH_1):PVDDCR_CPU1_P0    I45 @T6G_MB_LIB.T6G(SCH_1):PAGE30
  DA36 PVDDCR_CPU1_P0 @T6G_MB_LIB.T6G(SCH_1):PVDDCR_CPU1_P0    I45 @T6G_MB_LIB.T6G(SCH_1):PAGE30
  DA40 PVDDCR_CPU1_P0 @T6G_MB_LIB.T6G(SCH_1):PVDDCR_CPU1_P0    I45 @T6G_MB_LIB.T6G(SCH_1):PAGE30
  DA41 PVDDCR_CPU1_P0 @T6G_MB_LIB.T6G(SCH_1):PVDDCR_CPU1_P0    I45 @T6G_MB_LIB.T6G(SCH_1):PAGE30
  DB23 PVDDCR_CPU1_P0 @T6G_MB_LIB.T6G(SCH_1):PVDDCR_CPU1_P0    I45 @T6G_MB_LIB.T6G(SCH_1):PAGE30
  DB24 PVDDCR_CPU1_P0 @T6G_MB_LIB.T6G(SCH_1):PVDDCR_CPU1_P0    I45 @T6G_MB_LIB.T6G(SCH_1):PAGE30
  DB26 PVDDCR_CPU1_P0 @T6G_MB_LIB.T6G(SCH_1):PVDDCR_CPU1_P0    I45 @T6G_MB_LIB.T6G(SCH_1):PAGE30
  DB27 PVDDCR_CPU1_P0 @T6G_MB_LIB.T6G(SCH_1):PVDDCR_CPU1_P0    I45 @T6G_MB_LIB.T6G(SCH_1):PAGE30
  DB29 PVDDCR_CPU1_P0 @T6G_MB_LIB.T6G(SCH_1):PVDDCR_CPU1_P0    I45 @T6G_MB_LIB.T6G(SCH_1):PAGE30
  DB30 PVDDCR_CPU1_P0 @T6G_MB_LIB.T6G(SCH_1):PVDDCR_CPU1_P0    I45 @T6G_MB_LIB.T6G(SCH_1):PAGE30
  DB32 PVDDCR_CPU1_P0 @T6G_MB_LIB.T6G(SCH_1):PVDDCR_CPU1_P0    I45 @T6G_MB_LIB.T6G(SCH_1):PAGE30
  DB33 PVDDCR_CPU1_P0 @T6G_MB_LIB.T6G(SCH_1):PVDDCR_CPU1_P0    I45 @T6G_MB_LIB.T6G(SCH_1):PAGE30
  DB43 PVDDCR_CPU1_P0 @T6G_MB_LIB.T6G(SCH_1):PVDDCR_CPU1_P0    I45 @T6G_MB_LIB.T6G(SCH_1):PAGE30
  DB44 PVDDCR_CPU1_P0 @T6G_MB_LIB.T6G(SCH_1):PVDDCR_CPU1_P0    I45 @T6G_MB_LIB.T6G(SCH_1):PAGE30
  DB46 PVDDCR_CPU1_P0 @T6G_MB_LIB.T6G(SCH_1):PVDDCR_CPU1_P0    I45 @T6G_MB_LIB.T6G(SCH_1):PAGE30
  DB47 PVDDCR_CPU1_P0 @T6G_MB_LIB.T6G(SCH_1):PVDDCR_CPU1_P0    I45 @T6G_MB_LIB.T6G(SCH_1):PAGE30
  DB49 PVDDCR_CPU1_P0 @T6G_MB_LIB.T6G(SCH_1):PVDDCR_CPU1_P0    I45 @T6G_MB_LIB.T6G(SCH_1):PAGE30
  DB50 PVDDCR_CPU1_P0 @T6G_MB_LIB.T6G(SCH_1):PVDDCR_CPU1_P0    I45 @T6G_MB_LIB.T6G(SCH_1):PAGE30
  DB52 PVDDCR_CPU1_P0 @T6G_MB_LIB.T6G(SCH_1):PVDDCR_CPU1_P0    I45 @T6G_MB_LIB.T6G(SCH_1):PAGE30
  DB53 PVDDCR_CPU1_P0 @T6G_MB_LIB.T6G(SCH_1):PVDDCR_CPU1_P0    I45 @T6G_MB_LIB.T6G(SCH_1):PAGE30
  DC35 PVDDCR_CPU1_P0 @T6G_MB_LIB.T6G(SCH_1):PVDDCR_CPU1_P0    I45 @T6G_MB_LIB.T6G(SCH_1):PAGE30
  DC36 PVDDCR_CPU1_P0 @T6G_MB_LIB.T6G(SCH_1):PVDDCR_CPU1_P0    I45 @T6G_MB_LIB.T6G(SCH_1):PAGE30
  DC40 PVDDCR_CPU1_P0 @T6G_MB_LIB.T6G(SCH_1):PVDDCR_CPU1_P0    I45 @T6G_MB_LIB.T6G(SCH_1):PAGE30
  DC41 PVDDCR_CPU1_P0 @T6G_MB_LIB.T6G(SCH_1):PVDDCR_CPU1_P0    I45 @T6G_MB_LIB.T6G(SCH_1):PAGE30
  DD22 PVDDCR_CPU1_P0 @T6G_MB_LIB.T6G(SCH_1):PVDDCR_CPU1_P0    I45 @T6G_MB_LIB.T6G(SCH_1):PAGE30
  DD25 PVDDCR_CPU1_P0 @T6G_MB_LIB.T6G(SCH_1):PVDDCR_CPU1_P0    I45 @T6G_MB_LIB.T6G(SCH_1):PAGE30
  DD28 PVDDCR_CPU1_P0 @T6G_MB_LIB.T6G(SCH_1):PVDDCR_CPU1_P0    I45 @T6G_MB_LIB.T6G(SCH_1):PAGE30
  DD31 PVDDCR_CPU1_P0 @T6G_MB_LIB.T6G(SCH_1):PVDDCR_CPU1_P0    I45 @T6G_MB_LIB.T6G(SCH_1):PAGE30
  DD34 PVDDCR_CPU1_P0 @T6G_MB_LIB.T6G(SCH_1):PVDDCR_CPU1_P0    I45 @T6G_MB_LIB.T6G(SCH_1):PAGE30
  DD42 PVDDCR_CPU1_P0 @T6G_MB_LIB.T6G(SCH_1):PVDDCR_CPU1_P0    I45 @T6G_MB_LIB.T6G(SCH_1):PAGE30
  DD45 PVDDCR_CPU1_P0 @T6G_MB_LIB.T6G(SCH_1):PVDDCR_CPU1_P0    I45 @T6G_MB_LIB.T6G(SCH_1):PAGE30
  DD48 PVDDCR_CPU1_P0 @T6G_MB_LIB.T6G(SCH_1):PVDDCR_CPU1_P0    I45 @T6G_MB_LIB.T6G(SCH_1):PAGE30
  DD51 PVDDCR_CPU1_P0 @T6G_MB_LIB.T6G(SCH_1):PVDDCR_CPU1_P0    I45 @T6G_MB_LIB.T6G(SCH_1):PAGE30
  DD54 PVDDCR_CPU1_P0 @T6G_MB_LIB.T6G(SCH_1):PVDDCR_CPU1_P0    I45 @T6G_MB_LIB.T6G(SCH_1):PAGE30
  DE22 PVDDCR_CPU1_P0 @T6G_MB_LIB.T6G(SCH_1):PVDDCR_CPU1_P0    I45 @T6G_MB_LIB.T6G(SCH_1):PAGE30
  DE25 PVDDCR_CPU1_P0 @T6G_MB_LIB.T6G(SCH_1):PVDDCR_CPU1_P0    I45 @T6G_MB_LIB.T6G(SCH_1):PAGE30
  DE28 PVDDCR_CPU1_P0 @T6G_MB_LIB.T6G(SCH_1):PVDDCR_CPU1_P0    I45 @T6G_MB_LIB.T6G(SCH_1):PAGE30
  DE31 PVDDCR_CPU1_P0 @T6G_MB_LIB.T6G(SCH_1):PVDDCR_CPU1_P0    I45 @T6G_MB_LIB.T6G(SCH_1):PAGE30
  DE34 PVDDCR_CPU1_P0 @T6G_MB_LIB.T6G(SCH_1):PVDDCR_CPU1_P0    I45 @T6G_MB_LIB.T6G(SCH_1):PAGE30
  DE35 PVDDCR_CPU1_P0 @T6G_MB_LIB.T6G(SCH_1):PVDDCR_CPU1_P0    I45 @T6G_MB_LIB.T6G(SCH_1):PAGE30
  DE41 PVDDCR_CPU1_P0 @T6G_MB_LIB.T6G(SCH_1):PVDDCR_CPU1_P0    I45 @T6G_MB_LIB.T6G(SCH_1):PAGE30
  DE42 PVDDCR_CPU1_P0 @T6G_MB_LIB.T6G(SCH_1):PVDDCR_CPU1_P0    I45 @T6G_MB_LIB.T6G(SCH_1):PAGE30
  DE45 PVDDCR_CPU1_P0 @T6G_MB_LIB.T6G(SCH_1):PVDDCR_CPU1_P0    I45 @T6G_MB_LIB.T6G(SCH_1):PAGE30
  DE48 PVDDCR_CPU1_P0 @T6G_MB_LIB.T6G(SCH_1):PVDDCR_CPU1_P0    I45 @T6G_MB_LIB.T6G(SCH_1):PAGE30
  DE51 PVDDCR_CPU1_P0 @T6G_MB_LIB.T6G(SCH_1):PVDDCR_CPU1_P0    I45 @T6G_MB_LIB.T6G(SCH_1):PAGE30
  DE54 PVDDCR_CPU1_P0 @T6G_MB_LIB.T6G(SCH_1):PVDDCR_CPU1_P0    I45 @T6G_MB_LIB.T6G(SCH_1):PAGE30
  DG19 PVDDCR_CPU1_P0 @T6G_MB_LIB.T6G(SCH_1):PVDDCR_CPU1_P0    I45 @T6G_MB_LIB.T6G(SCH_1):PAGE30
  DG57 PVDDCR_CPU1_P0 @T6G_MB_LIB.T6G(SCH_1):PVDDCR_CPU1_P0    I45 @T6G_MB_LIB.T6G(SCH_1):PAGE30
  DH19 PVDDCR_CPU1_P0 @T6G_MB_LIB.T6G(SCH_1):PVDDCR_CPU1_P0    I45 @T6G_MB_LIB.T6G(SCH_1):PAGE30
  DH20 PVDDCR_CPU1_P0 @T6G_MB_LIB.T6G(SCH_1):PVDDCR_CPU1_P0    I45 @T6G_MB_LIB.T6G(SCH_1):PAGE30
  DH22 PVDDCR_CPU1_P0 @T6G_MB_LIB.T6G(SCH_1):PVDDCR_CPU1_P0    I45 @T6G_MB_LIB.T6G(SCH_1):PAGE30
  DH23 PVDDCR_CPU1_P0 @T6G_MB_LIB.T6G(SCH_1):PVDDCR_CPU1_P0    I45 @T6G_MB_LIB.T6G(SCH_1):PAGE30
  DH25 PVDDCR_CPU1_P0 @T6G_MB_LIB.T6G(SCH_1):PVDDCR_CPU1_P0    I45 @T6G_MB_LIB.T6G(SCH_1):PAGE30
  DH26 PVDDCR_CPU1_P0 @T6G_MB_LIB.T6G(SCH_1):PVDDCR_CPU1_P0    I45 @T6G_MB_LIB.T6G(SCH_1):PAGE30
  DH28 PVDDCR_CPU1_P0 @T6G_MB_LIB.T6G(SCH_1):PVDDCR_CPU1_P0    I45 @T6G_MB_LIB.T6G(SCH_1):PAGE30
  DH29 PVDDCR_CPU1_P0 @T6G_MB_LIB.T6G(SCH_1):PVDDCR_CPU1_P0    I45 @T6G_MB_LIB.T6G(SCH_1):PAGE30
  DH31 PVDDCR_CPU1_P0 @T6G_MB_LIB.T6G(SCH_1):PVDDCR_CPU1_P0    I45 @T6G_MB_LIB.T6G(SCH_1):PAGE30
  DH32 PVDDCR_CPU1_P0 @T6G_MB_LIB.T6G(SCH_1):PVDDCR_CPU1_P0    I45 @T6G_MB_LIB.T6G(SCH_1):PAGE30
  DH34 PVDDCR_CPU1_P0 @T6G_MB_LIB.T6G(SCH_1):PVDDCR_CPU1_P0    I45 @T6G_MB_LIB.T6G(SCH_1):PAGE30
  DH35 PVDDCR_CPU1_P0 @T6G_MB_LIB.T6G(SCH_1):PVDDCR_CPU1_P0    I45 @T6G_MB_LIB.T6G(SCH_1):PAGE30
  DH41 PVDDCR_CPU1_P0 @T6G_MB_LIB.T6G(SCH_1):PVDDCR_CPU1_P0    I45 @T6G_MB_LIB.T6G(SCH_1):PAGE30
  DH42 PVDDCR_CPU1_P0 @T6G_MB_LIB.T6G(SCH_1):PVDDCR_CPU1_P0    I45 @T6G_MB_LIB.T6G(SCH_1):PAGE30
  DH44 PVDDCR_CPU1_P0 @T6G_MB_LIB.T6G(SCH_1):PVDDCR_CPU1_P0    I45 @T6G_MB_LIB.T6G(SCH_1):PAGE30
  DH53 PVDDCR_CPU1_P0 @T6G_MB_LIB.T6G(SCH_1):PVDDCR_CPU1_P0    I45 @T6G_MB_LIB.T6G(SCH_1):PAGE30
  DH54 PVDDCR_CPU1_P0 @T6G_MB_LIB.T6G(SCH_1):PVDDCR_CPU1_P0    I45 @T6G_MB_LIB.T6G(SCH_1):PAGE30
  DH56 PVDDCR_CPU1_P0 @T6G_MB_LIB.T6G(SCH_1):PVDDCR_CPU1_P0    I45 @T6G_MB_LIB.T6G(SCH_1):PAGE30
  DH57 PVDDCR_CPU1_P0 @T6G_MB_LIB.T6G(SCH_1):PVDDCR_CPU1_P0    I45 @T6G_MB_LIB.T6G(SCH_1):PAGE30
  DH45 PVDDCR_CPU1_P0 @T6G_MB_LIB.T6G(SCH_1):PVDDCR_CPU1_P0    I45 @T6G_MB_LIB.T6G(SCH_1):PAGE30
  DH47 PVDDCR_CPU1_P0 @T6G_MB_LIB.T6G(SCH_1):PVDDCR_CPU1_P0    I45 @T6G_MB_LIB.T6G(SCH_1):PAGE30
  DH48 PVDDCR_CPU1_P0 @T6G_MB_LIB.T6G(SCH_1):PVDDCR_CPU1_P0    I45 @T6G_MB_LIB.T6G(SCH_1):PAGE30
  DH50 PVDDCR_CPU1_P0 @T6G_MB_LIB.T6G(SCH_1):PVDDCR_CPU1_P0    I45 @T6G_MB_LIB.T6G(SCH_1):PAGE30
  DH51 PVDDCR_CPU1_P0 @T6G_MB_LIB.T6G(SCH_1):PVDDCR_CPU1_P0    I45 @T6G_MB_LIB.T6G(SCH_1):PAGE30
  BP24 PVDDCR_CPU1_P0 @T6G_MB_LIB.T6G(SCH_1):PVDDCR_CPU1_P0    I45 @T6G_MB_LIB.T6G(SCH_1):PAGE30
  BP28 PVDDCR_CPU1_P0 @T6G_MB_LIB.T6G(SCH_1):PVDDCR_CPU1_P0    I45 @T6G_MB_LIB.T6G(SCH_1):PAGE30
  BP32 PVDDCR_CPU1_P0 @T6G_MB_LIB.T6G(SCH_1):PVDDCR_CPU1_P0    I45 @T6G_MB_LIB.T6G(SCH_1):PAGE30
  BN27 PVDDCR_CPU1_P0 @T6G_MB_LIB.T6G(SCH_1):PVDDCR_CPU1_P0    I45 @T6G_MB_LIB.T6G(SCH_1):PAGE30
  BN35 PVDDCR_CPU1_P0 @T6G_MB_LIB.T6G(SCH_1):PVDDCR_CPU1_P0    I45 @T6G_MB_LIB.T6G(SCH_1):PAGE30
  BN46 PVDDCR_CPU1_P0 @T6G_MB_LIB.T6G(SCH_1):PVDDCR_CPU1_P0    I45 @T6G_MB_LIB.T6G(SCH_1):PAGE30
    B5 PVDDCR_SOC_P0 @T6G_MB_LIB.T6G(SCH_1):PVDDCR_SOC_P0    I50 @T6G_MB_LIB.T6G(SCH_1):PAGE30
    C4 PVDDCR_SOC_P0 @T6G_MB_LIB.T6G(SCH_1):PVDDCR_SOC_P0    I50 @T6G_MB_LIB.T6G(SCH_1):PAGE30
    E4 PVDDCR_SOC_P0 @T6G_MB_LIB.T6G(SCH_1):PVDDCR_SOC_P0    I50 @T6G_MB_LIB.T6G(SCH_1):PAGE30
   E11 PVDDCR_SOC_P0 @T6G_MB_LIB.T6G(SCH_1):PVDDCR_SOC_P0    I50 @T6G_MB_LIB.T6G(SCH_1):PAGE30
    H5 PVDDCR_SOC_P0 @T6G_MB_LIB.T6G(SCH_1):PVDDCR_SOC_P0    I50 @T6G_MB_LIB.T6G(SCH_1):PAGE30
   H12 PVDDCR_SOC_P0 @T6G_MB_LIB.T6G(SCH_1):PVDDCR_SOC_P0    I50 @T6G_MB_LIB.T6G(SCH_1):PAGE30
   H19 PVDDCR_SOC_P0 @T6G_MB_LIB.T6G(SCH_1):PVDDCR_SOC_P0    I50 @T6G_MB_LIB.T6G(SCH_1):PAGE30
   K22 PVDDCR_SOC_P0 @T6G_MB_LIB.T6G(SCH_1):PVDDCR_SOC_P0    I50 @T6G_MB_LIB.T6G(SCH_1):PAGE30
    L4 PVDDCR_SOC_P0 @T6G_MB_LIB.T6G(SCH_1):PVDDCR_SOC_P0    I50 @T6G_MB_LIB.T6G(SCH_1):PAGE30
   L11 PVDDCR_SOC_P0 @T6G_MB_LIB.T6G(SCH_1):PVDDCR_SOC_P0    I50 @T6G_MB_LIB.T6G(SCH_1):PAGE30
   L18 PVDDCR_SOC_P0 @T6G_MB_LIB.T6G(SCH_1):PVDDCR_SOC_P0    I50 @T6G_MB_LIB.T6G(SCH_1):PAGE30
    P5 PVDDCR_SOC_P0 @T6G_MB_LIB.T6G(SCH_1):PVDDCR_SOC_P0    I50 @T6G_MB_LIB.T6G(SCH_1):PAGE30
   P12 PVDDCR_SOC_P0 @T6G_MB_LIB.T6G(SCH_1):PVDDCR_SOC_P0    I50 @T6G_MB_LIB.T6G(SCH_1):PAGE30
   P19 PVDDCR_SOC_P0 @T6G_MB_LIB.T6G(SCH_1):PVDDCR_SOC_P0    I50 @T6G_MB_LIB.T6G(SCH_1):PAGE30
   P22 PVDDCR_SOC_P0 @T6G_MB_LIB.T6G(SCH_1):PVDDCR_SOC_P0    I50 @T6G_MB_LIB.T6G(SCH_1):PAGE30
    U4 PVDDCR_SOC_P0 @T6G_MB_LIB.T6G(SCH_1):PVDDCR_SOC_P0    I50 @T6G_MB_LIB.T6G(SCH_1):PAGE30
   U11 PVDDCR_SOC_P0 @T6G_MB_LIB.T6G(SCH_1):PVDDCR_SOC_P0    I50 @T6G_MB_LIB.T6G(SCH_1):PAGE30
   U18 PVDDCR_SOC_P0 @T6G_MB_LIB.T6G(SCH_1):PVDDCR_SOC_P0    I50 @T6G_MB_LIB.T6G(SCH_1):PAGE30
   V22 PVDDCR_SOC_P0 @T6G_MB_LIB.T6G(SCH_1):PVDDCR_SOC_P0    I50 @T6G_MB_LIB.T6G(SCH_1):PAGE30
    Y5 PVDDCR_SOC_P0 @T6G_MB_LIB.T6G(SCH_1):PVDDCR_SOC_P0    I50 @T6G_MB_LIB.T6G(SCH_1):PAGE30
   Y12 PVDDCR_SOC_P0 @T6G_MB_LIB.T6G(SCH_1):PVDDCR_SOC_P0    I50 @T6G_MB_LIB.T6G(SCH_1):PAGE30
   Y19 PVDDCR_SOC_P0 @T6G_MB_LIB.T6G(SCH_1):PVDDCR_SOC_P0    I50 @T6G_MB_LIB.T6G(SCH_1):PAGE30
  AA22 PVDDCR_SOC_P0 @T6G_MB_LIB.T6G(SCH_1):PVDDCR_SOC_P0    I50 @T6G_MB_LIB.T6G(SCH_1):PAGE30
   AC4 PVDDCR_SOC_P0 @T6G_MB_LIB.T6G(SCH_1):PVDDCR_SOC_P0    I50 @T6G_MB_LIB.T6G(SCH_1):PAGE30
  AC11 PVDDCR_SOC_P0 @T6G_MB_LIB.T6G(SCH_1):PVDDCR_SOC_P0    I50 @T6G_MB_LIB.T6G(SCH_1):PAGE30
  AC18 PVDDCR_SOC_P0 @T6G_MB_LIB.T6G(SCH_1):PVDDCR_SOC_P0    I50 @T6G_MB_LIB.T6G(SCH_1):PAGE30
  AD22 PVDDCR_SOC_P0 @T6G_MB_LIB.T6G(SCH_1):PVDDCR_SOC_P0    I50 @T6G_MB_LIB.T6G(SCH_1):PAGE30
   AF5 PVDDCR_SOC_P0 @T6G_MB_LIB.T6G(SCH_1):PVDDCR_SOC_P0    I50 @T6G_MB_LIB.T6G(SCH_1):PAGE30
  AF12 PVDDCR_SOC_P0 @T6G_MB_LIB.T6G(SCH_1):PVDDCR_SOC_P0    I50 @T6G_MB_LIB.T6G(SCH_1):PAGE30
  AF19 PVDDCR_SOC_P0 @T6G_MB_LIB.T6G(SCH_1):PVDDCR_SOC_P0    I50 @T6G_MB_LIB.T6G(SCH_1):PAGE30
  AH22 PVDDCR_SOC_P0 @T6G_MB_LIB.T6G(SCH_1):PVDDCR_SOC_P0    I50 @T6G_MB_LIB.T6G(SCH_1):PAGE30
   AJ4 PVDDCR_SOC_P0 @T6G_MB_LIB.T6G(SCH_1):PVDDCR_SOC_P0    I50 @T6G_MB_LIB.T6G(SCH_1):PAGE30
  AJ11 PVDDCR_SOC_P0 @T6G_MB_LIB.T6G(SCH_1):PVDDCR_SOC_P0    I50 @T6G_MB_LIB.T6G(SCH_1):PAGE30
  AJ18 PVDDCR_SOC_P0 @T6G_MB_LIB.T6G(SCH_1):PVDDCR_SOC_P0    I50 @T6G_MB_LIB.T6G(SCH_1):PAGE30
   AM5 PVDDCR_SOC_P0 @T6G_MB_LIB.T6G(SCH_1):PVDDCR_SOC_P0    I50 @T6G_MB_LIB.T6G(SCH_1):PAGE30
  AM12 PVDDCR_SOC_P0 @T6G_MB_LIB.T6G(SCH_1):PVDDCR_SOC_P0    I50 @T6G_MB_LIB.T6G(SCH_1):PAGE30
  AM19 PVDDCR_SOC_P0 @T6G_MB_LIB.T6G(SCH_1):PVDDCR_SOC_P0    I50 @T6G_MB_LIB.T6G(SCH_1):PAGE30
  AM22 PVDDCR_SOC_P0 @T6G_MB_LIB.T6G(SCH_1):PVDDCR_SOC_P0    I50 @T6G_MB_LIB.T6G(SCH_1):PAGE30
   AR4 PVDDCR_SOC_P0 @T6G_MB_LIB.T6G(SCH_1):PVDDCR_SOC_P0    I50 @T6G_MB_LIB.T6G(SCH_1):PAGE30
  AR11 PVDDCR_SOC_P0 @T6G_MB_LIB.T6G(SCH_1):PVDDCR_SOC_P0    I50 @T6G_MB_LIB.T6G(SCH_1):PAGE30
  AR18 PVDDCR_SOC_P0 @T6G_MB_LIB.T6G(SCH_1):PVDDCR_SOC_P0    I50 @T6G_MB_LIB.T6G(SCH_1):PAGE30
  AT22 PVDDCR_SOC_P0 @T6G_MB_LIB.T6G(SCH_1):PVDDCR_SOC_P0    I50 @T6G_MB_LIB.T6G(SCH_1):PAGE30
  AU23 PVDDCR_SOC_P0 @T6G_MB_LIB.T6G(SCH_1):PVDDCR_SOC_P0    I50 @T6G_MB_LIB.T6G(SCH_1):PAGE30
  AU27 PVDDCR_SOC_P0 @T6G_MB_LIB.T6G(SCH_1):PVDDCR_SOC_P0    I50 @T6G_MB_LIB.T6G(SCH_1):PAGE30
  AU31 PVDDCR_SOC_P0 @T6G_MB_LIB.T6G(SCH_1):PVDDCR_SOC_P0    I50 @T6G_MB_LIB.T6G(SCH_1):PAGE30
  AU35 PVDDCR_SOC_P0 @T6G_MB_LIB.T6G(SCH_1):PVDDCR_SOC_P0    I50 @T6G_MB_LIB.T6G(SCH_1):PAGE30
  AU40 PVDDCR_SOC_P0 @T6G_MB_LIB.T6G(SCH_1):PVDDCR_SOC_P0    I50 @T6G_MB_LIB.T6G(SCH_1):PAGE30
   AV5 PVDDCR_SOC_P0 @T6G_MB_LIB.T6G(SCH_1):PVDDCR_SOC_P0    I50 @T6G_MB_LIB.T6G(SCH_1):PAGE30
  AV12 PVDDCR_SOC_P0 @T6G_MB_LIB.T6G(SCH_1):PVDDCR_SOC_P0    I50 @T6G_MB_LIB.T6G(SCH_1):PAGE30
  AV19 PVDDCR_SOC_P0 @T6G_MB_LIB.T6G(SCH_1):PVDDCR_SOC_P0    I50 @T6G_MB_LIB.T6G(SCH_1):PAGE30
  AV22 PVDDCR_SOC_P0 @T6G_MB_LIB.T6G(SCH_1):PVDDCR_SOC_P0    I50 @T6G_MB_LIB.T6G(SCH_1):PAGE30
  AV24 PVDDCR_SOC_P0 @T6G_MB_LIB.T6G(SCH_1):PVDDCR_SOC_P0    I50 @T6G_MB_LIB.T6G(SCH_1):PAGE30
  AV26 PVDDCR_SOC_P0 @T6G_MB_LIB.T6G(SCH_1):PVDDCR_SOC_P0    I50 @T6G_MB_LIB.T6G(SCH_1):PAGE30
  AV28 PVDDCR_SOC_P0 @T6G_MB_LIB.T6G(SCH_1):PVDDCR_SOC_P0    I50 @T6G_MB_LIB.T6G(SCH_1):PAGE30
  AV30 PVDDCR_SOC_P0 @T6G_MB_LIB.T6G(SCH_1):PVDDCR_SOC_P0    I50 @T6G_MB_LIB.T6G(SCH_1):PAGE30
  AV32 PVDDCR_SOC_P0 @T6G_MB_LIB.T6G(SCH_1):PVDDCR_SOC_P0    I50 @T6G_MB_LIB.T6G(SCH_1):PAGE30
  AV34 PVDDCR_SOC_P0 @T6G_MB_LIB.T6G(SCH_1):PVDDCR_SOC_P0    I50 @T6G_MB_LIB.T6G(SCH_1):PAGE30
  AV36 PVDDCR_SOC_P0 @T6G_MB_LIB.T6G(SCH_1):PVDDCR_SOC_P0    I50 @T6G_MB_LIB.T6G(SCH_1):PAGE30
  AV39 PVDDCR_SOC_P0 @T6G_MB_LIB.T6G(SCH_1):PVDDCR_SOC_P0    I50 @T6G_MB_LIB.T6G(SCH_1):PAGE30
  AV41 PVDDCR_SOC_P0 @T6G_MB_LIB.T6G(SCH_1):PVDDCR_SOC_P0    I50 @T6G_MB_LIB.T6G(SCH_1):PAGE30
  AV43 PVDDCR_SOC_P0 @T6G_MB_LIB.T6G(SCH_1):PVDDCR_SOC_P0    I50 @T6G_MB_LIB.T6G(SCH_1):PAGE30
  AV45 PVDDCR_SOC_P0 @T6G_MB_LIB.T6G(SCH_1):PVDDCR_SOC_P0    I50 @T6G_MB_LIB.T6G(SCH_1):PAGE30
  AV47 PVDDCR_SOC_P0 @T6G_MB_LIB.T6G(SCH_1):PVDDCR_SOC_P0    I50 @T6G_MB_LIB.T6G(SCH_1):PAGE30
  AW23 PVDDCR_SOC_P0 @T6G_MB_LIB.T6G(SCH_1):PVDDCR_SOC_P0    I50 @T6G_MB_LIB.T6G(SCH_1):PAGE30
  AW25 PVDDCR_SOC_P0 @T6G_MB_LIB.T6G(SCH_1):PVDDCR_SOC_P0    I50 @T6G_MB_LIB.T6G(SCH_1):PAGE30
  AW27 PVDDCR_SOC_P0 @T6G_MB_LIB.T6G(SCH_1):PVDDCR_SOC_P0    I50 @T6G_MB_LIB.T6G(SCH_1):PAGE30
  AW48 PVDDCR_SOC_P0 @T6G_MB_LIB.T6G(SCH_1):PVDDCR_SOC_P0    I50 @T6G_MB_LIB.T6G(SCH_1):PAGE30
  AY22 PVDDCR_SOC_P0 @T6G_MB_LIB.T6G(SCH_1):PVDDCR_SOC_P0    I50 @T6G_MB_LIB.T6G(SCH_1):PAGE30
  AY24 PVDDCR_SOC_P0 @T6G_MB_LIB.T6G(SCH_1):PVDDCR_SOC_P0    I50 @T6G_MB_LIB.T6G(SCH_1):PAGE30
  AY26 PVDDCR_SOC_P0 @T6G_MB_LIB.T6G(SCH_1):PVDDCR_SOC_P0    I50 @T6G_MB_LIB.T6G(SCH_1):PAGE30
  AY28 PVDDCR_SOC_P0 @T6G_MB_LIB.T6G(SCH_1):PVDDCR_SOC_P0    I50 @T6G_MB_LIB.T6G(SCH_1):PAGE30
  AY49 PVDDCR_SOC_P0 @T6G_MB_LIB.T6G(SCH_1):PVDDCR_SOC_P0    I50 @T6G_MB_LIB.T6G(SCH_1):PAGE30
   BA4 PVDDCR_SOC_P0 @T6G_MB_LIB.T6G(SCH_1):PVDDCR_SOC_P0    I50 @T6G_MB_LIB.T6G(SCH_1):PAGE30
  BA11 PVDDCR_SOC_P0 @T6G_MB_LIB.T6G(SCH_1):PVDDCR_SOC_P0    I50 @T6G_MB_LIB.T6G(SCH_1):PAGE30
  BA18 PVDDCR_SOC_P0 @T6G_MB_LIB.T6G(SCH_1):PVDDCR_SOC_P0    I50 @T6G_MB_LIB.T6G(SCH_1):PAGE30
  BA23 PVDDCR_SOC_P0 @T6G_MB_LIB.T6G(SCH_1):PVDDCR_SOC_P0    I50 @T6G_MB_LIB.T6G(SCH_1):PAGE30
  BA25 PVDDCR_SOC_P0 @T6G_MB_LIB.T6G(SCH_1):PVDDCR_SOC_P0    I50 @T6G_MB_LIB.T6G(SCH_1):PAGE30
  BA27 PVDDCR_SOC_P0 @T6G_MB_LIB.T6G(SCH_1):PVDDCR_SOC_P0    I50 @T6G_MB_LIB.T6G(SCH_1):PAGE30
  BA48 PVDDCR_SOC_P0 @T6G_MB_LIB.T6G(SCH_1):PVDDCR_SOC_P0    I50 @T6G_MB_LIB.T6G(SCH_1):PAGE30
  BB22 PVDDCR_SOC_P0 @T6G_MB_LIB.T6G(SCH_1):PVDDCR_SOC_P0    I50 @T6G_MB_LIB.T6G(SCH_1):PAGE30
  BB24 PVDDCR_SOC_P0 @T6G_MB_LIB.T6G(SCH_1):PVDDCR_SOC_P0    I50 @T6G_MB_LIB.T6G(SCH_1):PAGE30
  BB26 PVDDCR_SOC_P0 @T6G_MB_LIB.T6G(SCH_1):PVDDCR_SOC_P0    I50 @T6G_MB_LIB.T6G(SCH_1):PAGE30
  BB28 PVDDCR_SOC_P0 @T6G_MB_LIB.T6G(SCH_1):PVDDCR_SOC_P0    I50 @T6G_MB_LIB.T6G(SCH_1):PAGE30
  BB49 PVDDCR_SOC_P0 @T6G_MB_LIB.T6G(SCH_1):PVDDCR_SOC_P0    I50 @T6G_MB_LIB.T6G(SCH_1):PAGE30
  BC23 PVDDCR_SOC_P0 @T6G_MB_LIB.T6G(SCH_1):PVDDCR_SOC_P0    I50 @T6G_MB_LIB.T6G(SCH_1):PAGE30
  BC25 PVDDCR_SOC_P0 @T6G_MB_LIB.T6G(SCH_1):PVDDCR_SOC_P0    I50 @T6G_MB_LIB.T6G(SCH_1):PAGE30
  BC27 PVDDCR_SOC_P0 @T6G_MB_LIB.T6G(SCH_1):PVDDCR_SOC_P0    I50 @T6G_MB_LIB.T6G(SCH_1):PAGE30
  BC48 PVDDCR_SOC_P0 @T6G_MB_LIB.T6G(SCH_1):PVDDCR_SOC_P0    I50 @T6G_MB_LIB.T6G(SCH_1):PAGE30
   BD5 PVDDCR_SOC_P0 @T6G_MB_LIB.T6G(SCH_1):PVDDCR_SOC_P0    I50 @T6G_MB_LIB.T6G(SCH_1):PAGE30
  BD12 PVDDCR_SOC_P0 @T6G_MB_LIB.T6G(SCH_1):PVDDCR_SOC_P0    I50 @T6G_MB_LIB.T6G(SCH_1):PAGE30
  BD19 PVDDCR_SOC_P0 @T6G_MB_LIB.T6G(SCH_1):PVDDCR_SOC_P0    I50 @T6G_MB_LIB.T6G(SCH_1):PAGE30
  BD22 PVDDCR_SOC_P0 @T6G_MB_LIB.T6G(SCH_1):PVDDCR_SOC_P0    I50 @T6G_MB_LIB.T6G(SCH_1):PAGE30
  BD24 PVDDCR_SOC_P0 @T6G_MB_LIB.T6G(SCH_1):PVDDCR_SOC_P0    I50 @T6G_MB_LIB.T6G(SCH_1):PAGE30
  BD26 PVDDCR_SOC_P0 @T6G_MB_LIB.T6G(SCH_1):PVDDCR_SOC_P0    I50 @T6G_MB_LIB.T6G(SCH_1):PAGE30
  BD28 PVDDCR_SOC_P0 @T6G_MB_LIB.T6G(SCH_1):PVDDCR_SOC_P0    I50 @T6G_MB_LIB.T6G(SCH_1):PAGE30
  BD48 PVDDCR_SOC_P0 @T6G_MB_LIB.T6G(SCH_1):PVDDCR_SOC_P0    I50 @T6G_MB_LIB.T6G(SCH_1):PAGE30
  BF23 PVDDCR_SOC_P0 @T6G_MB_LIB.T6G(SCH_1):PVDDCR_SOC_P0    I50 @T6G_MB_LIB.T6G(SCH_1):PAGE30
  BF25 PVDDCR_SOC_P0 @T6G_MB_LIB.T6G(SCH_1):PVDDCR_SOC_P0    I50 @T6G_MB_LIB.T6G(SCH_1):PAGE30
  BF27 PVDDCR_SOC_P0 @T6G_MB_LIB.T6G(SCH_1):PVDDCR_SOC_P0    I50 @T6G_MB_LIB.T6G(SCH_1):PAGE30
  BF48 PVDDCR_SOC_P0 @T6G_MB_LIB.T6G(SCH_1):PVDDCR_SOC_P0    I50 @T6G_MB_LIB.T6G(SCH_1):PAGE30
   BM5 PVDDCR_SOC_P0 @T6G_MB_LIB.T6G(SCH_1):PVDDCR_SOC_P0    I50 @T6G_MB_LIB.T6G(SCH_1):PAGE30
  BJ48 PVDDCR_SOC_P0 @T6G_MB_LIB.T6G(SCH_1):PVDDCR_SOC_P0    I50 @T6G_MB_LIB.T6G(SCH_1):PAGE30
  BJ11 PVDDCR_SOC_P0 @T6G_MB_LIB.T6G(SCH_1):PVDDCR_SOC_P0    I50 @T6G_MB_LIB.T6G(SCH_1):PAGE30
   BJ4 PVDDCR_SOC_P0 @T6G_MB_LIB.T6G(SCH_1):PVDDCR_SOC_P0    I50 @T6G_MB_LIB.T6G(SCH_1):PAGE30
  BH48 PVDDCR_SOC_P0 @T6G_MB_LIB.T6G(SCH_1):PVDDCR_SOC_P0    I50 @T6G_MB_LIB.T6G(SCH_1):PAGE30
  BH25 PVDDCR_SOC_P0 @T6G_MB_LIB.T6G(SCH_1):PVDDCR_SOC_P0    I50 @T6G_MB_LIB.T6G(SCH_1):PAGE30
  BH23 PVDDCR_SOC_P0 @T6G_MB_LIB.T6G(SCH_1):PVDDCR_SOC_P0    I50 @T6G_MB_LIB.T6G(SCH_1):PAGE30
  BG48 PVDDCR_SOC_P0 @T6G_MB_LIB.T6G(SCH_1):PVDDCR_SOC_P0    I50 @T6G_MB_LIB.T6G(SCH_1):PAGE30
  BG28 PVDDCR_SOC_P0 @T6G_MB_LIB.T6G(SCH_1):PVDDCR_SOC_P0    I50 @T6G_MB_LIB.T6G(SCH_1):PAGE30
  BG26 PVDDCR_SOC_P0 @T6G_MB_LIB.T6G(SCH_1):PVDDCR_SOC_P0    I50 @T6G_MB_LIB.T6G(SCH_1):PAGE30
  BG24 PVDDCR_SOC_P0 @T6G_MB_LIB.T6G(SCH_1):PVDDCR_SOC_P0    I50 @T6G_MB_LIB.T6G(SCH_1):PAGE30
  BG22 PVDDCR_SOC_P0 @T6G_MB_LIB.T6G(SCH_1):PVDDCR_SOC_P0    I50 @T6G_MB_LIB.T6G(SCH_1):PAGE30
   H57 PVDDIO_P0 @T6G_MB_LIB.T6G(SCH_1):PVDDIO_P0    I28 @T6G_MB_LIB.T6G(SCH_1):PAGE30
   H64 PVDDIO_P0 @T6G_MB_LIB.T6G(SCH_1):PVDDIO_P0    I28 @T6G_MB_LIB.T6G(SCH_1):PAGE30
   H71 PVDDIO_P0 @T6G_MB_LIB.T6G(SCH_1):PVDDIO_P0    I28 @T6G_MB_LIB.T6G(SCH_1):PAGE30
   K54 PVDDIO_P0 @T6G_MB_LIB.T6G(SCH_1):PVDDIO_P0    I28 @T6G_MB_LIB.T6G(SCH_1):PAGE30
   L58 PVDDIO_P0 @T6G_MB_LIB.T6G(SCH_1):PVDDIO_P0    I28 @T6G_MB_LIB.T6G(SCH_1):PAGE30
   L65 PVDDIO_P0 @T6G_MB_LIB.T6G(SCH_1):PVDDIO_P0    I28 @T6G_MB_LIB.T6G(SCH_1):PAGE30
   L72 PVDDIO_P0 @T6G_MB_LIB.T6G(SCH_1):PVDDIO_P0    I28 @T6G_MB_LIB.T6G(SCH_1):PAGE30
   P54 PVDDIO_P0 @T6G_MB_LIB.T6G(SCH_1):PVDDIO_P0    I28 @T6G_MB_LIB.T6G(SCH_1):PAGE30
   P57 PVDDIO_P0 @T6G_MB_LIB.T6G(SCH_1):PVDDIO_P0    I28 @T6G_MB_LIB.T6G(SCH_1):PAGE30
   P64 PVDDIO_P0 @T6G_MB_LIB.T6G(SCH_1):PVDDIO_P0    I28 @T6G_MB_LIB.T6G(SCH_1):PAGE30
   P71 PVDDIO_P0 @T6G_MB_LIB.T6G(SCH_1):PVDDIO_P0    I28 @T6G_MB_LIB.T6G(SCH_1):PAGE30
   U58 PVDDIO_P0 @T6G_MB_LIB.T6G(SCH_1):PVDDIO_P0    I28 @T6G_MB_LIB.T6G(SCH_1):PAGE30
   U65 PVDDIO_P0 @T6G_MB_LIB.T6G(SCH_1):PVDDIO_P0    I28 @T6G_MB_LIB.T6G(SCH_1):PAGE30
   U72 PVDDIO_P0 @T6G_MB_LIB.T6G(SCH_1):PVDDIO_P0    I28 @T6G_MB_LIB.T6G(SCH_1):PAGE30
   V54 PVDDIO_P0 @T6G_MB_LIB.T6G(SCH_1):PVDDIO_P0    I28 @T6G_MB_LIB.T6G(SCH_1):PAGE30
   Y57 PVDDIO_P0 @T6G_MB_LIB.T6G(SCH_1):PVDDIO_P0    I28 @T6G_MB_LIB.T6G(SCH_1):PAGE30
   Y64 PVDDIO_P0 @T6G_MB_LIB.T6G(SCH_1):PVDDIO_P0    I28 @T6G_MB_LIB.T6G(SCH_1):PAGE30
   Y71 PVDDIO_P0 @T6G_MB_LIB.T6G(SCH_1):PVDDIO_P0    I28 @T6G_MB_LIB.T6G(SCH_1):PAGE30
  AA54 PVDDIO_P0 @T6G_MB_LIB.T6G(SCH_1):PVDDIO_P0    I28 @T6G_MB_LIB.T6G(SCH_1):PAGE30
  AC58 PVDDIO_P0 @T6G_MB_LIB.T6G(SCH_1):PVDDIO_P0    I28 @T6G_MB_LIB.T6G(SCH_1):PAGE30
  AC65 PVDDIO_P0 @T6G_MB_LIB.T6G(SCH_1):PVDDIO_P0    I28 @T6G_MB_LIB.T6G(SCH_1):PAGE30
  AC72 PVDDIO_P0 @T6G_MB_LIB.T6G(SCH_1):PVDDIO_P0    I28 @T6G_MB_LIB.T6G(SCH_1):PAGE30
  AD54 PVDDIO_P0 @T6G_MB_LIB.T6G(SCH_1):PVDDIO_P0    I28 @T6G_MB_LIB.T6G(SCH_1):PAGE30
  AF57 PVDDIO_P0 @T6G_MB_LIB.T6G(SCH_1):PVDDIO_P0    I28 @T6G_MB_LIB.T6G(SCH_1):PAGE30
  AF64 PVDDIO_P0 @T6G_MB_LIB.T6G(SCH_1):PVDDIO_P0    I28 @T6G_MB_LIB.T6G(SCH_1):PAGE30
  AF71 PVDDIO_P0 @T6G_MB_LIB.T6G(SCH_1):PVDDIO_P0    I28 @T6G_MB_LIB.T6G(SCH_1):PAGE30
  AH54 PVDDIO_P0 @T6G_MB_LIB.T6G(SCH_1):PVDDIO_P0    I28 @T6G_MB_LIB.T6G(SCH_1):PAGE30
  AJ58 PVDDIO_P0 @T6G_MB_LIB.T6G(SCH_1):PVDDIO_P0    I28 @T6G_MB_LIB.T6G(SCH_1):PAGE30
  AJ65 PVDDIO_P0 @T6G_MB_LIB.T6G(SCH_1):PVDDIO_P0    I28 @T6G_MB_LIB.T6G(SCH_1):PAGE30
  AJ72 PVDDIO_P0 @T6G_MB_LIB.T6G(SCH_1):PVDDIO_P0    I28 @T6G_MB_LIB.T6G(SCH_1):PAGE30
  AM54 PVDDIO_P0 @T6G_MB_LIB.T6G(SCH_1):PVDDIO_P0    I28 @T6G_MB_LIB.T6G(SCH_1):PAGE30
  AM57 PVDDIO_P0 @T6G_MB_LIB.T6G(SCH_1):PVDDIO_P0    I28 @T6G_MB_LIB.T6G(SCH_1):PAGE30
  AM64 PVDDIO_P0 @T6G_MB_LIB.T6G(SCH_1):PVDDIO_P0    I28 @T6G_MB_LIB.T6G(SCH_1):PAGE30
  AM71 PVDDIO_P0 @T6G_MB_LIB.T6G(SCH_1):PVDDIO_P0    I28 @T6G_MB_LIB.T6G(SCH_1):PAGE30
  AR58 PVDDIO_P0 @T6G_MB_LIB.T6G(SCH_1):PVDDIO_P0    I28 @T6G_MB_LIB.T6G(SCH_1):PAGE30
  AR65 PVDDIO_P0 @T6G_MB_LIB.T6G(SCH_1):PVDDIO_P0    I28 @T6G_MB_LIB.T6G(SCH_1):PAGE30
  AR72 PVDDIO_P0 @T6G_MB_LIB.T6G(SCH_1):PVDDIO_P0    I28 @T6G_MB_LIB.T6G(SCH_1):PAGE30
  AV57 PVDDIO_P0 @T6G_MB_LIB.T6G(SCH_1):PVDDIO_P0    I28 @T6G_MB_LIB.T6G(SCH_1):PAGE30
  AV64 PVDDIO_P0 @T6G_MB_LIB.T6G(SCH_1):PVDDIO_P0    I28 @T6G_MB_LIB.T6G(SCH_1):PAGE30
  AV71 PVDDIO_P0 @T6G_MB_LIB.T6G(SCH_1):PVDDIO_P0    I28 @T6G_MB_LIB.T6G(SCH_1):PAGE30
  BA58 PVDDIO_P0 @T6G_MB_LIB.T6G(SCH_1):PVDDIO_P0    I28 @T6G_MB_LIB.T6G(SCH_1):PAGE30
  BA65 PVDDIO_P0 @T6G_MB_LIB.T6G(SCH_1):PVDDIO_P0    I28 @T6G_MB_LIB.T6G(SCH_1):PAGE30
  BA72 PVDDIO_P0 @T6G_MB_LIB.T6G(SCH_1):PVDDIO_P0    I28 @T6G_MB_LIB.T6G(SCH_1):PAGE30
  BD50 PVDDIO_P0 @T6G_MB_LIB.T6G(SCH_1):PVDDIO_P0    I28 @T6G_MB_LIB.T6G(SCH_1):PAGE30
  BD52 PVDDIO_P0 @T6G_MB_LIB.T6G(SCH_1):PVDDIO_P0    I28 @T6G_MB_LIB.T6G(SCH_1):PAGE30
  BD54 PVDDIO_P0 @T6G_MB_LIB.T6G(SCH_1):PVDDIO_P0    I28 @T6G_MB_LIB.T6G(SCH_1):PAGE30
  BF51 PVDDIO_P0 @T6G_MB_LIB.T6G(SCH_1):PVDDIO_P0    I28 @T6G_MB_LIB.T6G(SCH_1):PAGE30
  BF53 PVDDIO_P0 @T6G_MB_LIB.T6G(SCH_1):PVDDIO_P0    I28 @T6G_MB_LIB.T6G(SCH_1):PAGE30
  BF57 PVDDIO_P0 @T6G_MB_LIB.T6G(SCH_1):PVDDIO_P0    I28 @T6G_MB_LIB.T6G(SCH_1):PAGE30
  BF64 PVDDIO_P0 @T6G_MB_LIB.T6G(SCH_1):PVDDIO_P0    I28 @T6G_MB_LIB.T6G(SCH_1):PAGE30
  BF71 PVDDIO_P0 @T6G_MB_LIB.T6G(SCH_1):PVDDIO_P0    I28 @T6G_MB_LIB.T6G(SCH_1):PAGE30
  BG50 PVDDIO_P0 @T6G_MB_LIB.T6G(SCH_1):PVDDIO_P0    I28 @T6G_MB_LIB.T6G(SCH_1):PAGE30
  BG52 PVDDIO_P0 @T6G_MB_LIB.T6G(SCH_1):PVDDIO_P0    I28 @T6G_MB_LIB.T6G(SCH_1):PAGE30
  BG54 PVDDIO_P0 @T6G_MB_LIB.T6G(SCH_1):PVDDIO_P0    I28 @T6G_MB_LIB.T6G(SCH_1):PAGE30
  BH51 PVDDIO_P0 @T6G_MB_LIB.T6G(SCH_1):PVDDIO_P0    I28 @T6G_MB_LIB.T6G(SCH_1):PAGE30
  BH53 PVDDIO_P0 @T6G_MB_LIB.T6G(SCH_1):PVDDIO_P0    I28 @T6G_MB_LIB.T6G(SCH_1):PAGE30
  BJ50 PVDDIO_P0 @T6G_MB_LIB.T6G(SCH_1):PVDDIO_P0    I28 @T6G_MB_LIB.T6G(SCH_1):PAGE30
  BJ52 PVDDIO_P0 @T6G_MB_LIB.T6G(SCH_1):PVDDIO_P0    I28 @T6G_MB_LIB.T6G(SCH_1):PAGE30
  BJ54 PVDDIO_P0 @T6G_MB_LIB.T6G(SCH_1):PVDDIO_P0    I28 @T6G_MB_LIB.T6G(SCH_1):PAGE30
  BJ58 PVDDIO_P0 @T6G_MB_LIB.T6G(SCH_1):PVDDIO_P0    I28 @T6G_MB_LIB.T6G(SCH_1):PAGE30
  BJ65 PVDDIO_P0 @T6G_MB_LIB.T6G(SCH_1):PVDDIO_P0    I28 @T6G_MB_LIB.T6G(SCH_1):PAGE30
  BJ72 PVDDIO_P0 @T6G_MB_LIB.T6G(SCH_1):PVDDIO_P0    I28 @T6G_MB_LIB.T6G(SCH_1):PAGE30
  BK51 PVDDIO_P0 @T6G_MB_LIB.T6G(SCH_1):PVDDIO_P0    I28 @T6G_MB_LIB.T6G(SCH_1):PAGE30
  BK53 PVDDIO_P0 @T6G_MB_LIB.T6G(SCH_1):PVDDIO_P0    I28 @T6G_MB_LIB.T6G(SCH_1):PAGE30
  BL50 PVDDIO_P0 @T6G_MB_LIB.T6G(SCH_1):PVDDIO_P0    I28 @T6G_MB_LIB.T6G(SCH_1):PAGE30
  BL52 PVDDIO_P0 @T6G_MB_LIB.T6G(SCH_1):PVDDIO_P0    I28 @T6G_MB_LIB.T6G(SCH_1):PAGE30
  BL54 PVDDIO_P0 @T6G_MB_LIB.T6G(SCH_1):PVDDIO_P0    I28 @T6G_MB_LIB.T6G(SCH_1):PAGE30
  BM51 PVDDIO_P0 @T6G_MB_LIB.T6G(SCH_1):PVDDIO_P0    I28 @T6G_MB_LIB.T6G(SCH_1):PAGE30
  BM53 PVDDIO_P0 @T6G_MB_LIB.T6G(SCH_1):PVDDIO_P0    I28 @T6G_MB_LIB.T6G(SCH_1):PAGE30
  BM57 PVDDIO_P0 @T6G_MB_LIB.T6G(SCH_1):PVDDIO_P0    I28 @T6G_MB_LIB.T6G(SCH_1):PAGE30
  BM64 PVDDIO_P0 @T6G_MB_LIB.T6G(SCH_1):PVDDIO_P0    I28 @T6G_MB_LIB.T6G(SCH_1):PAGE30
  BM71 PVDDIO_P0 @T6G_MB_LIB.T6G(SCH_1):PVDDIO_P0    I28 @T6G_MB_LIB.T6G(SCH_1):PAGE30
  BN54 PVDDIO_P0 @T6G_MB_LIB.T6G(SCH_1):PVDDIO_P0    I28 @T6G_MB_LIB.T6G(SCH_1):PAGE30
  BR58 PVDDIO_P0 @T6G_MB_LIB.T6G(SCH_1):PVDDIO_P0    I28 @T6G_MB_LIB.T6G(SCH_1):PAGE30
  BR65 PVDDIO_P0 @T6G_MB_LIB.T6G(SCH_1):PVDDIO_P0    I28 @T6G_MB_LIB.T6G(SCH_1):PAGE30
  BR72 PVDDIO_P0 @T6G_MB_LIB.T6G(SCH_1):PVDDIO_P0    I28 @T6G_MB_LIB.T6G(SCH_1):PAGE30
  BV54 PVDDIO_P0 @T6G_MB_LIB.T6G(SCH_1):PVDDIO_P0    I28 @T6G_MB_LIB.T6G(SCH_1):PAGE30
  BV57 PVDDIO_P0 @T6G_MB_LIB.T6G(SCH_1):PVDDIO_P0    I28 @T6G_MB_LIB.T6G(SCH_1):PAGE30
  BV64 PVDDIO_P0 @T6G_MB_LIB.T6G(SCH_1):PVDDIO_P0    I28 @T6G_MB_LIB.T6G(SCH_1):PAGE30
  BV71 PVDDIO_P0 @T6G_MB_LIB.T6G(SCH_1):PVDDIO_P0    I28 @T6G_MB_LIB.T6G(SCH_1):PAGE30
  CA58 PVDDIO_P0 @T6G_MB_LIB.T6G(SCH_1):PVDDIO_P0    I28 @T6G_MB_LIB.T6G(SCH_1):PAGE30
  CA65 PVDDIO_P0 @T6G_MB_LIB.T6G(SCH_1):PVDDIO_P0    I28 @T6G_MB_LIB.T6G(SCH_1):PAGE30
  CA72 PVDDIO_P0 @T6G_MB_LIB.T6G(SCH_1):PVDDIO_P0    I28 @T6G_MB_LIB.T6G(SCH_1):PAGE30
  CB54 PVDDIO_P0 @T6G_MB_LIB.T6G(SCH_1):PVDDIO_P0    I28 @T6G_MB_LIB.T6G(SCH_1):PAGE30
  CD57 PVDDIO_P0 @T6G_MB_LIB.T6G(SCH_1):PVDDIO_P0    I28 @T6G_MB_LIB.T6G(SCH_1):PAGE30
  CD64 PVDDIO_P0 @T6G_MB_LIB.T6G(SCH_1):PVDDIO_P0    I28 @T6G_MB_LIB.T6G(SCH_1):PAGE30
  CD71 PVDDIO_P0 @T6G_MB_LIB.T6G(SCH_1):PVDDIO_P0    I28 @T6G_MB_LIB.T6G(SCH_1):PAGE30
  CF54 PVDDIO_P0 @T6G_MB_LIB.T6G(SCH_1):PVDDIO_P0    I28 @T6G_MB_LIB.T6G(SCH_1):PAGE30
  CG58 PVDDIO_P0 @T6G_MB_LIB.T6G(SCH_1):PVDDIO_P0    I28 @T6G_MB_LIB.T6G(SCH_1):PAGE30
  CG65 PVDDIO_P0 @T6G_MB_LIB.T6G(SCH_1):PVDDIO_P0    I28 @T6G_MB_LIB.T6G(SCH_1):PAGE30
  CG72 PVDDIO_P0 @T6G_MB_LIB.T6G(SCH_1):PVDDIO_P0    I28 @T6G_MB_LIB.T6G(SCH_1):PAGE30
  CJ54 PVDDIO_P0 @T6G_MB_LIB.T6G(SCH_1):PVDDIO_P0    I28 @T6G_MB_LIB.T6G(SCH_1):PAGE30
  CK57 PVDDIO_P0 @T6G_MB_LIB.T6G(SCH_1):PVDDIO_P0    I28 @T6G_MB_LIB.T6G(SCH_1):PAGE30
  CK64 PVDDIO_P0 @T6G_MB_LIB.T6G(SCH_1):PVDDIO_P0    I28 @T6G_MB_LIB.T6G(SCH_1):PAGE30
  CK71 PVDDIO_P0 @T6G_MB_LIB.T6G(SCH_1):PVDDIO_P0    I28 @T6G_MB_LIB.T6G(SCH_1):PAGE30
  CM54 PVDDIO_P0 @T6G_MB_LIB.T6G(SCH_1):PVDDIO_P0    I28 @T6G_MB_LIB.T6G(SCH_1):PAGE30
  CN58 PVDDIO_P0 @T6G_MB_LIB.T6G(SCH_1):PVDDIO_P0    I28 @T6G_MB_LIB.T6G(SCH_1):PAGE30
  CN65 PVDDIO_P0 @T6G_MB_LIB.T6G(SCH_1):PVDDIO_P0    I28 @T6G_MB_LIB.T6G(SCH_1):PAGE30
  CN72 PVDDIO_P0 @T6G_MB_LIB.T6G(SCH_1):PVDDIO_P0    I28 @T6G_MB_LIB.T6G(SCH_1):PAGE30
  CT54 PVDDIO_P0 @T6G_MB_LIB.T6G(SCH_1):PVDDIO_P0    I28 @T6G_MB_LIB.T6G(SCH_1):PAGE30
  CT57 PVDDIO_P0 @T6G_MB_LIB.T6G(SCH_1):PVDDIO_P0    I28 @T6G_MB_LIB.T6G(SCH_1):PAGE30
  BJ18 PVDD11_S3_P0 @T6G_MB_LIB.T6G(SCH_1):PVDD11_S3_P0    I28 @T6G_MB_LIB.T6G(SCH_1):PAGE30
  BJ23 PVDD11_S3_P0 @T6G_MB_LIB.T6G(SCH_1):PVDD11_S3_P0    I28 @T6G_MB_LIB.T6G(SCH_1):PAGE30
  BJ25 PVDD11_S3_P0 @T6G_MB_LIB.T6G(SCH_1):PVDD11_S3_P0    I28 @T6G_MB_LIB.T6G(SCH_1):PAGE30
  BJ27 PVDD11_S3_P0 @T6G_MB_LIB.T6G(SCH_1):PVDD11_S3_P0    I28 @T6G_MB_LIB.T6G(SCH_1):PAGE30
  BK22 PVDD11_S3_P0 @T6G_MB_LIB.T6G(SCH_1):PVDD11_S3_P0    I28 @T6G_MB_LIB.T6G(SCH_1):PAGE30
  BK24 PVDD11_S3_P0 @T6G_MB_LIB.T6G(SCH_1):PVDD11_S3_P0    I28 @T6G_MB_LIB.T6G(SCH_1):PAGE30
  BK26 PVDD11_S3_P0 @T6G_MB_LIB.T6G(SCH_1):PVDD11_S3_P0    I28 @T6G_MB_LIB.T6G(SCH_1):PAGE30
  BK28 PVDD11_S3_P0 @T6G_MB_LIB.T6G(SCH_1):PVDD11_S3_P0    I28 @T6G_MB_LIB.T6G(SCH_1):PAGE30
  BK49 PVDD11_S3_P0 @T6G_MB_LIB.T6G(SCH_1):PVDD11_S3_P0    I28 @T6G_MB_LIB.T6G(SCH_1):PAGE30
  BL23 PVDD11_S3_P0 @T6G_MB_LIB.T6G(SCH_1):PVDD11_S3_P0    I28 @T6G_MB_LIB.T6G(SCH_1):PAGE30
  BL25 PVDD11_S3_P0 @T6G_MB_LIB.T6G(SCH_1):PVDD11_S3_P0    I28 @T6G_MB_LIB.T6G(SCH_1):PAGE30
  BL27 PVDD11_S3_P0 @T6G_MB_LIB.T6G(SCH_1):PVDD11_S3_P0    I28 @T6G_MB_LIB.T6G(SCH_1):PAGE30
  BL48 PVDD11_S3_P0 @T6G_MB_LIB.T6G(SCH_1):PVDD11_S3_P0    I28 @T6G_MB_LIB.T6G(SCH_1):PAGE30
  BM12 PVDD11_S3_P0 @T6G_MB_LIB.T6G(SCH_1):PVDD11_S3_P0    I28 @T6G_MB_LIB.T6G(SCH_1):PAGE30
  BM19 PVDD11_S3_P0 @T6G_MB_LIB.T6G(SCH_1):PVDD11_S3_P0    I28 @T6G_MB_LIB.T6G(SCH_1):PAGE30
  BM22 PVDD11_S3_P0 @T6G_MB_LIB.T6G(SCH_1):PVDD11_S3_P0    I28 @T6G_MB_LIB.T6G(SCH_1):PAGE30
  BM24 PVDD11_S3_P0 @T6G_MB_LIB.T6G(SCH_1):PVDD11_S3_P0    I28 @T6G_MB_LIB.T6G(SCH_1):PAGE30
  BM26 PVDD11_S3_P0 @T6G_MB_LIB.T6G(SCH_1):PVDD11_S3_P0    I28 @T6G_MB_LIB.T6G(SCH_1):PAGE30
  BM28 PVDD11_S3_P0 @T6G_MB_LIB.T6G(SCH_1):PVDD11_S3_P0    I28 @T6G_MB_LIB.T6G(SCH_1):PAGE30
  BM30 PVDD11_S3_P0 @T6G_MB_LIB.T6G(SCH_1):PVDD11_S3_P0    I28 @T6G_MB_LIB.T6G(SCH_1):PAGE30
  BM32 PVDD11_S3_P0 @T6G_MB_LIB.T6G(SCH_1):PVDD11_S3_P0    I28 @T6G_MB_LIB.T6G(SCH_1):PAGE30
  BM34 PVDD11_S3_P0 @T6G_MB_LIB.T6G(SCH_1):PVDD11_S3_P0    I28 @T6G_MB_LIB.T6G(SCH_1):PAGE30
  BM36 PVDD11_S3_P0 @T6G_MB_LIB.T6G(SCH_1):PVDD11_S3_P0    I28 @T6G_MB_LIB.T6G(SCH_1):PAGE30
  BM39 PVDD11_S3_P0 @T6G_MB_LIB.T6G(SCH_1):PVDD11_S3_P0    I28 @T6G_MB_LIB.T6G(SCH_1):PAGE30
  BM41 PVDD11_S3_P0 @T6G_MB_LIB.T6G(SCH_1):PVDD11_S3_P0    I28 @T6G_MB_LIB.T6G(SCH_1):PAGE30
  BM43 PVDD11_S3_P0 @T6G_MB_LIB.T6G(SCH_1):PVDD11_S3_P0    I28 @T6G_MB_LIB.T6G(SCH_1):PAGE30
  BM45 PVDD11_S3_P0 @T6G_MB_LIB.T6G(SCH_1):PVDD11_S3_P0    I28 @T6G_MB_LIB.T6G(SCH_1):PAGE30
  BM47 PVDD11_S3_P0 @T6G_MB_LIB.T6G(SCH_1):PVDD11_S3_P0    I28 @T6G_MB_LIB.T6G(SCH_1):PAGE30
  BM49 PVDD11_S3_P0 @T6G_MB_LIB.T6G(SCH_1):PVDD11_S3_P0    I28 @T6G_MB_LIB.T6G(SCH_1):PAGE30
  BN25 PVDD11_S3_P0 @T6G_MB_LIB.T6G(SCH_1):PVDD11_S3_P0    I28 @T6G_MB_LIB.T6G(SCH_1):PAGE30
  BN29 PVDD11_S3_P0 @T6G_MB_LIB.T6G(SCH_1):PVDD11_S3_P0    I28 @T6G_MB_LIB.T6G(SCH_1):PAGE30
  BN33 PVDD11_S3_P0 @T6G_MB_LIB.T6G(SCH_1):PVDD11_S3_P0    I28 @T6G_MB_LIB.T6G(SCH_1):PAGE30
  BN40 PVDD11_S3_P0 @T6G_MB_LIB.T6G(SCH_1):PVDD11_S3_P0    I28 @T6G_MB_LIB.T6G(SCH_1):PAGE30
  BN44 PVDD11_S3_P0 @T6G_MB_LIB.T6G(SCH_1):PVDD11_S3_P0    I28 @T6G_MB_LIB.T6G(SCH_1):PAGE30
  BN48 PVDD11_S3_P0 @T6G_MB_LIB.T6G(SCH_1):PVDD11_S3_P0    I28 @T6G_MB_LIB.T6G(SCH_1):PAGE30
  BP22 PVDD11_S3_P0 @T6G_MB_LIB.T6G(SCH_1):PVDD11_S3_P0    I28 @T6G_MB_LIB.T6G(SCH_1):PAGE30
   BR4 PVDD11_S3_P0 @T6G_MB_LIB.T6G(SCH_1):PVDD11_S3_P0    I28 @T6G_MB_LIB.T6G(SCH_1):PAGE30
  BR11 PVDD11_S3_P0 @T6G_MB_LIB.T6G(SCH_1):PVDD11_S3_P0    I28 @T6G_MB_LIB.T6G(SCH_1):PAGE30
  BR18 PVDD11_S3_P0 @T6G_MB_LIB.T6G(SCH_1):PVDD11_S3_P0    I28 @T6G_MB_LIB.T6G(SCH_1):PAGE30
   BV5 PVDD11_S3_P0 @T6G_MB_LIB.T6G(SCH_1):PVDD11_S3_P0    I28 @T6G_MB_LIB.T6G(SCH_1):PAGE30
  BV12 PVDD11_S3_P0 @T6G_MB_LIB.T6G(SCH_1):PVDD11_S3_P0    I28 @T6G_MB_LIB.T6G(SCH_1):PAGE30
  BV19 PVDD11_S3_P0 @T6G_MB_LIB.T6G(SCH_1):PVDD11_S3_P0    I28 @T6G_MB_LIB.T6G(SCH_1):PAGE30
  BV22 PVDD11_S3_P0 @T6G_MB_LIB.T6G(SCH_1):PVDD11_S3_P0    I28 @T6G_MB_LIB.T6G(SCH_1):PAGE30
   CA4 PVDD11_S3_P0 @T6G_MB_LIB.T6G(SCH_1):PVDD11_S3_P0    I28 @T6G_MB_LIB.T6G(SCH_1):PAGE30
  CA11 PVDD11_S3_P0 @T6G_MB_LIB.T6G(SCH_1):PVDD11_S3_P0    I28 @T6G_MB_LIB.T6G(SCH_1):PAGE30
  CA18 PVDD11_S3_P0 @T6G_MB_LIB.T6G(SCH_1):PVDD11_S3_P0    I28 @T6G_MB_LIB.T6G(SCH_1):PAGE30
  CB22 PVDD11_S3_P0 @T6G_MB_LIB.T6G(SCH_1):PVDD11_S3_P0    I28 @T6G_MB_LIB.T6G(SCH_1):PAGE30
   CD5 PVDD11_S3_P0 @T6G_MB_LIB.T6G(SCH_1):PVDD11_S3_P0    I28 @T6G_MB_LIB.T6G(SCH_1):PAGE30
  CD12 PVDD11_S3_P0 @T6G_MB_LIB.T6G(SCH_1):PVDD11_S3_P0    I28 @T6G_MB_LIB.T6G(SCH_1):PAGE30
  CD19 PVDD11_S3_P0 @T6G_MB_LIB.T6G(SCH_1):PVDD11_S3_P0    I28 @T6G_MB_LIB.T6G(SCH_1):PAGE30
  CF22 PVDD11_S3_P0 @T6G_MB_LIB.T6G(SCH_1):PVDD11_S3_P0    I28 @T6G_MB_LIB.T6G(SCH_1):PAGE30
   CG4 PVDD11_S3_P0 @T6G_MB_LIB.T6G(SCH_1):PVDD11_S3_P0    I28 @T6G_MB_LIB.T6G(SCH_1):PAGE30
  CG11 PVDD11_S3_P0 @T6G_MB_LIB.T6G(SCH_1):PVDD11_S3_P0    I28 @T6G_MB_LIB.T6G(SCH_1):PAGE30
  CG18 PVDD11_S3_P0 @T6G_MB_LIB.T6G(SCH_1):PVDD11_S3_P0    I28 @T6G_MB_LIB.T6G(SCH_1):PAGE30
  CJ22 PVDD11_S3_P0 @T6G_MB_LIB.T6G(SCH_1):PVDD11_S3_P0    I28 @T6G_MB_LIB.T6G(SCH_1):PAGE30
   CK5 PVDD11_S3_P0 @T6G_MB_LIB.T6G(SCH_1):PVDD11_S3_P0    I28 @T6G_MB_LIB.T6G(SCH_1):PAGE30
  CK12 PVDD11_S3_P0 @T6G_MB_LIB.T6G(SCH_1):PVDD11_S3_P0    I28 @T6G_MB_LIB.T6G(SCH_1):PAGE30
  CK19 PVDD11_S3_P0 @T6G_MB_LIB.T6G(SCH_1):PVDD11_S3_P0    I28 @T6G_MB_LIB.T6G(SCH_1):PAGE30
  CM22 PVDD11_S3_P0 @T6G_MB_LIB.T6G(SCH_1):PVDD11_S3_P0    I28 @T6G_MB_LIB.T6G(SCH_1):PAGE30
   CN4 PVDD11_S3_P0 @T6G_MB_LIB.T6G(SCH_1):PVDD11_S3_P0    I28 @T6G_MB_LIB.T6G(SCH_1):PAGE30
  CN11 PVDD11_S3_P0 @T6G_MB_LIB.T6G(SCH_1):PVDD11_S3_P0    I28 @T6G_MB_LIB.T6G(SCH_1):PAGE30
  CN18 PVDD11_S3_P0 @T6G_MB_LIB.T6G(SCH_1):PVDD11_S3_P0    I28 @T6G_MB_LIB.T6G(SCH_1):PAGE30
   CT5 PVDD11_S3_P0 @T6G_MB_LIB.T6G(SCH_1):PVDD11_S3_P0    I28 @T6G_MB_LIB.T6G(SCH_1):PAGE30
  AU54 PVDD18_S5_P0 @T6G_MB_LIB.T6G(SCH_1):PVDD18_S5_P0    I28 @T6G_MB_LIB.T6G(SCH_1):PAGE30
  AR52 PVDD18_S5_P0 @T6G_MB_LIB.T6G(SCH_1):PVDD18_S5_P0    I28 @T6G_MB_LIB.T6G(SCH_1):PAGE30
  AR54 PVDD18_S5_P0 @T6G_MB_LIB.T6G(SCH_1):PVDD18_S5_P0    I28 @T6G_MB_LIB.T6G(SCH_1):PAGE30
  AT51 PVDD18_S5_P0 @T6G_MB_LIB.T6G(SCH_1):PVDD18_S5_P0    I28 @T6G_MB_LIB.T6G(SCH_1):PAGE30
  AT53 PVDD18_S5_P0 @T6G_MB_LIB.T6G(SCH_1):PVDD18_S5_P0    I28 @T6G_MB_LIB.T6G(SCH_1):PAGE30
  AU50 PVDD18_S5_P0 @T6G_MB_LIB.T6G(SCH_1):PVDD18_S5_P0    I28 @T6G_MB_LIB.T6G(SCH_1):PAGE30
  AU52 PVDD18_S5_P0 @T6G_MB_LIB.T6G(SCH_1):PVDD18_S5_P0    I28 @T6G_MB_LIB.T6G(SCH_1):PAGE30
  AV49 PVDD18_S5_P0 @T6G_MB_LIB.T6G(SCH_1):PVDD18_S5_P0    I28 @T6G_MB_LIB.T6G(SCH_1):PAGE30
  AV51 PVDD18_S5_P0 @T6G_MB_LIB.T6G(SCH_1):PVDD18_S5_P0    I28 @T6G_MB_LIB.T6G(SCH_1):PAGE30
  AV53 PVDD18_S5_P0 @T6G_MB_LIB.T6G(SCH_1):PVDD18_S5_P0    I28 @T6G_MB_LIB.T6G(SCH_1):PAGE30
  AW50 PVDD18_S5_P0 @T6G_MB_LIB.T6G(SCH_1):PVDD18_S5_P0    I28 @T6G_MB_LIB.T6G(SCH_1):PAGE30
  BC52 PVDD18_S5_P0 @T6G_MB_LIB.T6G(SCH_1):PVDD18_S5_P0    I28 @T6G_MB_LIB.T6G(SCH_1):PAGE30
  BC54 PVDD18_S5_P0 @T6G_MB_LIB.T6G(SCH_1):PVDD18_S5_P0    I28 @T6G_MB_LIB.T6G(SCH_1):PAGE30
  AW52 PVDD18_S5_P0 @T6G_MB_LIB.T6G(SCH_1):PVDD18_S5_P0    I28 @T6G_MB_LIB.T6G(SCH_1):PAGE30
  AW54 PVDD18_S5_P0 @T6G_MB_LIB.T6G(SCH_1):PVDD18_S5_P0    I28 @T6G_MB_LIB.T6G(SCH_1):PAGE30
  AY51 PVDD18_S5_P0 @T6G_MB_LIB.T6G(SCH_1):PVDD18_S5_P0    I28 @T6G_MB_LIB.T6G(SCH_1):PAGE30
  AY53 PVDD18_S5_P0 @T6G_MB_LIB.T6G(SCH_1):PVDD18_S5_P0    I28 @T6G_MB_LIB.T6G(SCH_1):PAGE30
  BA50 PVDD18_S5_P0 @T6G_MB_LIB.T6G(SCH_1):PVDD18_S5_P0    I28 @T6G_MB_LIB.T6G(SCH_1):PAGE30
  BA52 PVDD18_S5_P0 @T6G_MB_LIB.T6G(SCH_1):PVDD18_S5_P0    I28 @T6G_MB_LIB.T6G(SCH_1):PAGE30
  BA54 PVDD18_S5_P0 @T6G_MB_LIB.T6G(SCH_1):PVDD18_S5_P0    I28 @T6G_MB_LIB.T6G(SCH_1):PAGE30
  BB51 PVDD18_S5_P0 @T6G_MB_LIB.T6G(SCH_1):PVDD18_S5_P0    I28 @T6G_MB_LIB.T6G(SCH_1):PAGE30
  BB53 PVDD18_S5_P0 @T6G_MB_LIB.T6G(SCH_1):PVDD18_S5_P0    I28 @T6G_MB_LIB.T6G(SCH_1):PAGE30
  CT12 PVDD11_S3_P0 @T6G_MB_LIB.T6G(SCH_1):PVDD11_S3_P0    I28 @T6G_MB_LIB.T6G(SCH_1):PAGE30
  BN52 PVDD_33_S5 @T6G_MB_LIB.T6G(SCH_1):PVDD_33_S5    I28 @T6G_MB_LIB.T6G(SCH_1):PAGE30
  BP51 PVDD_33_S5 @T6G_MB_LIB.T6G(SCH_1):PVDD_33_S5    I28 @T6G_MB_LIB.T6G(SCH_1):PAGE30
  BH27 PVDD18_S5_P0 @T6G_MB_LIB.T6G(SCH_1):PVDD18_S5_P0    I28 @T6G_MB_LIB.T6G(SCH_1):PAGE30
  BN23 P1V5_BAT @T6G_MB_LIB.T6G(SCH_1):P1V5_BAT    I28 @T6G_MB_LIB.T6G(SCH_1):PAGE30
  DG71 PVDDIO_P0 @T6G_MB_LIB.T6G(SCH_1):PVDDIO_P0    I28 @T6G_MB_LIB.T6G(SCH_1):PAGE30
  DG64 PVDDIO_P0 @T6G_MB_LIB.T6G(SCH_1):PVDDIO_P0    I28 @T6G_MB_LIB.T6G(SCH_1):PAGE30
  DE72 PVDDIO_P0 @T6G_MB_LIB.T6G(SCH_1):PVDDIO_P0    I28 @T6G_MB_LIB.T6G(SCH_1):PAGE30
  DE65 PVDDIO_P0 @T6G_MB_LIB.T6G(SCH_1):PVDDIO_P0    I28 @T6G_MB_LIB.T6G(SCH_1):PAGE30
  DE58 PVDDIO_P0 @T6G_MB_LIB.T6G(SCH_1):PVDDIO_P0    I28 @T6G_MB_LIB.T6G(SCH_1):PAGE30
  DB71 PVDDIO_P0 @T6G_MB_LIB.T6G(SCH_1):PVDDIO_P0    I28 @T6G_MB_LIB.T6G(SCH_1):PAGE30
  DB64 PVDDIO_P0 @T6G_MB_LIB.T6G(SCH_1):PVDDIO_P0    I28 @T6G_MB_LIB.T6G(SCH_1):PAGE30
  DB57 PVDDIO_P0 @T6G_MB_LIB.T6G(SCH_1):PVDDIO_P0    I28 @T6G_MB_LIB.T6G(SCH_1):PAGE30
  CY54 PVDDIO_P0 @T6G_MB_LIB.T6G(SCH_1):PVDDIO_P0    I28 @T6G_MB_LIB.T6G(SCH_1):PAGE30
  CW72 PVDDIO_P0 @T6G_MB_LIB.T6G(SCH_1):PVDDIO_P0    I28 @T6G_MB_LIB.T6G(SCH_1):PAGE30
  CW65 PVDDIO_P0 @T6G_MB_LIB.T6G(SCH_1):PVDDIO_P0    I28 @T6G_MB_LIB.T6G(SCH_1):PAGE30
  CW58 PVDDIO_P0 @T6G_MB_LIB.T6G(SCH_1):PVDDIO_P0    I28 @T6G_MB_LIB.T6G(SCH_1):PAGE30
  CT71 PVDDIO_P0 @T6G_MB_LIB.T6G(SCH_1):PVDDIO_P0    I28 @T6G_MB_LIB.T6G(SCH_1):PAGE30
  CT64 PVDDIO_P0 @T6G_MB_LIB.T6G(SCH_1):PVDDIO_P0    I28 @T6G_MB_LIB.T6G(SCH_1):PAGE30
   DG5 PVDD11_S3_P0 @T6G_MB_LIB.T6G(SCH_1):PVDD11_S3_P0    I28 @T6G_MB_LIB.T6G(SCH_1):PAGE30
  DE18 PVDD11_S3_P0 @T6G_MB_LIB.T6G(SCH_1):PVDD11_S3_P0    I28 @T6G_MB_LIB.T6G(SCH_1):PAGE30
  DE11 PVDD11_S3_P0 @T6G_MB_LIB.T6G(SCH_1):PVDD11_S3_P0    I28 @T6G_MB_LIB.T6G(SCH_1):PAGE30
   DE4 PVDD11_S3_P0 @T6G_MB_LIB.T6G(SCH_1):PVDD11_S3_P0    I28 @T6G_MB_LIB.T6G(SCH_1):PAGE30
  DB19 PVDD11_S3_P0 @T6G_MB_LIB.T6G(SCH_1):PVDD11_S3_P0    I28 @T6G_MB_LIB.T6G(SCH_1):PAGE30
  DB12 PVDD11_S3_P0 @T6G_MB_LIB.T6G(SCH_1):PVDD11_S3_P0    I28 @T6G_MB_LIB.T6G(SCH_1):PAGE30
   DB5 PVDD11_S3_P0 @T6G_MB_LIB.T6G(SCH_1):PVDD11_S3_P0    I28 @T6G_MB_LIB.T6G(SCH_1):PAGE30
  CY22 PVDD11_S3_P0 @T6G_MB_LIB.T6G(SCH_1):PVDD11_S3_P0    I28 @T6G_MB_LIB.T6G(SCH_1):PAGE30
  CW18 PVDD11_S3_P0 @T6G_MB_LIB.T6G(SCH_1):PVDD11_S3_P0    I28 @T6G_MB_LIB.T6G(SCH_1):PAGE30
  CW11 PVDD11_S3_P0 @T6G_MB_LIB.T6G(SCH_1):PVDD11_S3_P0    I28 @T6G_MB_LIB.T6G(SCH_1):PAGE30
   CW4 PVDD11_S3_P0 @T6G_MB_LIB.T6G(SCH_1):PVDD11_S3_P0    I28 @T6G_MB_LIB.T6G(SCH_1):PAGE30
  CT22 PVDD11_S3_P0 @T6G_MB_LIB.T6G(SCH_1):PVDD11_S3_P0    I28 @T6G_MB_LIB.T6G(SCH_1):PAGE30
  CT19 PVDD11_S3_P0 @T6G_MB_LIB.T6G(SCH_1):PVDD11_S3_P0    I28 @T6G_MB_LIB.T6G(SCH_1):PAGE30
   H37    GND @T6G_MB_LIB.T6G(SCH_1):GND    I19 @T6G_MB_LIB.T6G(SCH_1):PAGE31
   H39    GND @T6G_MB_LIB.T6G(SCH_1):GND    I19 @T6G_MB_LIB.T6G(SCH_1):PAGE31
   H42    GND @T6G_MB_LIB.T6G(SCH_1):GND    I19 @T6G_MB_LIB.T6G(SCH_1):PAGE31
   H45    GND @T6G_MB_LIB.T6G(SCH_1):GND    I19 @T6G_MB_LIB.T6G(SCH_1):PAGE31
   H48    GND @T6G_MB_LIB.T6G(SCH_1):GND    I19 @T6G_MB_LIB.T6G(SCH_1):PAGE31
   H51    GND @T6G_MB_LIB.T6G(SCH_1):GND    I19 @T6G_MB_LIB.T6G(SCH_1):PAGE31
   H54    GND @T6G_MB_LIB.T6G(SCH_1):GND    I19 @T6G_MB_LIB.T6G(SCH_1):PAGE31
   H59    GND @T6G_MB_LIB.T6G(SCH_1):GND    I19 @T6G_MB_LIB.T6G(SCH_1):PAGE31
   H61    GND @T6G_MB_LIB.T6G(SCH_1):GND    I19 @T6G_MB_LIB.T6G(SCH_1):PAGE31
   H66    GND @T6G_MB_LIB.T6G(SCH_1):GND    I19 @T6G_MB_LIB.T6G(SCH_1):PAGE31
   H68    GND @T6G_MB_LIB.T6G(SCH_1):GND    I19 @T6G_MB_LIB.T6G(SCH_1):PAGE31
   H73    GND @T6G_MB_LIB.T6G(SCH_1):GND    I19 @T6G_MB_LIB.T6G(SCH_1):PAGE31
    J1    GND @T6G_MB_LIB.T6G(SCH_1):GND    I19 @T6G_MB_LIB.T6G(SCH_1):PAGE31
    J4    GND @T6G_MB_LIB.T6G(SCH_1):GND    I19 @T6G_MB_LIB.T6G(SCH_1):PAGE31
    J6    GND @T6G_MB_LIB.T6G(SCH_1):GND    I19 @T6G_MB_LIB.T6G(SCH_1):PAGE31
    J8    GND @T6G_MB_LIB.T6G(SCH_1):GND    I19 @T6G_MB_LIB.T6G(SCH_1):PAGE31
   J11    GND @T6G_MB_LIB.T6G(SCH_1):GND    I19 @T6G_MB_LIB.T6G(SCH_1):PAGE31
   J13    GND @T6G_MB_LIB.T6G(SCH_1):GND    I19 @T6G_MB_LIB.T6G(SCH_1):PAGE31
    A3    GND @T6G_MB_LIB.T6G(SCH_1):GND    I19 @T6G_MB_LIB.T6G(SCH_1):PAGE31
    A9    GND @T6G_MB_LIB.T6G(SCH_1):GND    I19 @T6G_MB_LIB.T6G(SCH_1):PAGE31
   A15    GND @T6G_MB_LIB.T6G(SCH_1):GND    I19 @T6G_MB_LIB.T6G(SCH_1):PAGE31
   A21    GND @T6G_MB_LIB.T6G(SCH_1):GND    I19 @T6G_MB_LIB.T6G(SCH_1):PAGE31
   A27    GND @T6G_MB_LIB.T6G(SCH_1):GND    I19 @T6G_MB_LIB.T6G(SCH_1):PAGE31
   A43    GND @T6G_MB_LIB.T6G(SCH_1):GND    I19 @T6G_MB_LIB.T6G(SCH_1):PAGE31
   A44    GND @T6G_MB_LIB.T6G(SCH_1):GND    I19 @T6G_MB_LIB.T6G(SCH_1):PAGE31
   A47    GND @T6G_MB_LIB.T6G(SCH_1):GND    I19 @T6G_MB_LIB.T6G(SCH_1):PAGE31
   A49    GND @T6G_MB_LIB.T6G(SCH_1):GND    I19 @T6G_MB_LIB.T6G(SCH_1):PAGE31
   A53    GND @T6G_MB_LIB.T6G(SCH_1):GND    I19 @T6G_MB_LIB.T6G(SCH_1):PAGE31
   A61    GND @T6G_MB_LIB.T6G(SCH_1):GND    I19 @T6G_MB_LIB.T6G(SCH_1):PAGE31
   A67    GND @T6G_MB_LIB.T6G(SCH_1):GND    I19 @T6G_MB_LIB.T6G(SCH_1):PAGE31
   A72    GND @T6G_MB_LIB.T6G(SCH_1):GND    I19 @T6G_MB_LIB.T6G(SCH_1):PAGE31
   A73    GND @T6G_MB_LIB.T6G(SCH_1):GND    I19 @T6G_MB_LIB.T6G(SCH_1):PAGE31
    B7    GND @T6G_MB_LIB.T6G(SCH_1):GND    I19 @T6G_MB_LIB.T6G(SCH_1):PAGE31
    B8    GND @T6G_MB_LIB.T6G(SCH_1):GND    I19 @T6G_MB_LIB.T6G(SCH_1):PAGE31
   B10    GND @T6G_MB_LIB.T6G(SCH_1):GND    I19 @T6G_MB_LIB.T6G(SCH_1):PAGE31
   B11    GND @T6G_MB_LIB.T6G(SCH_1):GND    I19 @T6G_MB_LIB.T6G(SCH_1):PAGE31
   B13    GND @T6G_MB_LIB.T6G(SCH_1):GND    I19 @T6G_MB_LIB.T6G(SCH_1):PAGE31
   B18    GND @T6G_MB_LIB.T6G(SCH_1):GND    I19 @T6G_MB_LIB.T6G(SCH_1):PAGE31
   B24    GND @T6G_MB_LIB.T6G(SCH_1):GND    I19 @T6G_MB_LIB.T6G(SCH_1):PAGE31
   B27    GND @T6G_MB_LIB.T6G(SCH_1):GND    I19 @T6G_MB_LIB.T6G(SCH_1):PAGE31
   B30    GND @T6G_MB_LIB.T6G(SCH_1):GND    I19 @T6G_MB_LIB.T6G(SCH_1):PAGE31
   B33    GND @T6G_MB_LIB.T6G(SCH_1):GND    I19 @T6G_MB_LIB.T6G(SCH_1):PAGE31
   B37    GND @T6G_MB_LIB.T6G(SCH_1):GND    I19 @T6G_MB_LIB.T6G(SCH_1):PAGE31
   B39    GND @T6G_MB_LIB.T6G(SCH_1):GND    I19 @T6G_MB_LIB.T6G(SCH_1):PAGE31
   B43    GND @T6G_MB_LIB.T6G(SCH_1):GND    I19 @T6G_MB_LIB.T6G(SCH_1):PAGE31
   B46    GND @T6G_MB_LIB.T6G(SCH_1):GND    I19 @T6G_MB_LIB.T6G(SCH_1):PAGE31
   B49    GND @T6G_MB_LIB.T6G(SCH_1):GND    I19 @T6G_MB_LIB.T6G(SCH_1):PAGE31
   B52    GND @T6G_MB_LIB.T6G(SCH_1):GND    I19 @T6G_MB_LIB.T6G(SCH_1):PAGE31
   B55    GND @T6G_MB_LIB.T6G(SCH_1):GND    I19 @T6G_MB_LIB.T6G(SCH_1):PAGE31
   B59    GND @T6G_MB_LIB.T6G(SCH_1):GND    I19 @T6G_MB_LIB.T6G(SCH_1):PAGE31
   B62    GND @T6G_MB_LIB.T6G(SCH_1):GND    I19 @T6G_MB_LIB.T6G(SCH_1):PAGE31
   B65    GND @T6G_MB_LIB.T6G(SCH_1):GND    I19 @T6G_MB_LIB.T6G(SCH_1):PAGE31
   B68    GND @T6G_MB_LIB.T6G(SCH_1):GND    I19 @T6G_MB_LIB.T6G(SCH_1):PAGE31
   B70    GND @T6G_MB_LIB.T6G(SCH_1):GND    I19 @T6G_MB_LIB.T6G(SCH_1):PAGE31
    C1    GND @T6G_MB_LIB.T6G(SCH_1):GND    I19 @T6G_MB_LIB.T6G(SCH_1):PAGE31
    C5    GND @T6G_MB_LIB.T6G(SCH_1):GND    I19 @T6G_MB_LIB.T6G(SCH_1):PAGE31
    C8    GND @T6G_MB_LIB.T6G(SCH_1):GND    I19 @T6G_MB_LIB.T6G(SCH_1):PAGE31
   C10    GND @T6G_MB_LIB.T6G(SCH_1):GND    I19 @T6G_MB_LIB.T6G(SCH_1):PAGE31
   C11    GND @T6G_MB_LIB.T6G(SCH_1):GND    I19 @T6G_MB_LIB.T6G(SCH_1):PAGE31
   C13    GND @T6G_MB_LIB.T6G(SCH_1):GND    I19 @T6G_MB_LIB.T6G(SCH_1):PAGE31
   C15    GND @T6G_MB_LIB.T6G(SCH_1):GND    I19 @T6G_MB_LIB.T6G(SCH_1):PAGE31
   C21    GND @T6G_MB_LIB.T6G(SCH_1):GND    I19 @T6G_MB_LIB.T6G(SCH_1):PAGE31
   C24    GND @T6G_MB_LIB.T6G(SCH_1):GND    I19 @T6G_MB_LIB.T6G(SCH_1):PAGE31
   C27    GND @T6G_MB_LIB.T6G(SCH_1):GND    I19 @T6G_MB_LIB.T6G(SCH_1):PAGE31
   C30    GND @T6G_MB_LIB.T6G(SCH_1):GND    I19 @T6G_MB_LIB.T6G(SCH_1):PAGE31
   C36    GND @T6G_MB_LIB.T6G(SCH_1):GND    I19 @T6G_MB_LIB.T6G(SCH_1):PAGE31
   C40    GND @T6G_MB_LIB.T6G(SCH_1):GND    I19 @T6G_MB_LIB.T6G(SCH_1):PAGE31
   C43    GND @T6G_MB_LIB.T6G(SCH_1):GND    I19 @T6G_MB_LIB.T6G(SCH_1):PAGE31
   C46    GND @T6G_MB_LIB.T6G(SCH_1):GND    I19 @T6G_MB_LIB.T6G(SCH_1):PAGE31
   C49    GND @T6G_MB_LIB.T6G(SCH_1):GND    I19 @T6G_MB_LIB.T6G(SCH_1):PAGE31
   C52    GND @T6G_MB_LIB.T6G(SCH_1):GND    I19 @T6G_MB_LIB.T6G(SCH_1):PAGE31
   C55    GND @T6G_MB_LIB.T6G(SCH_1):GND    I19 @T6G_MB_LIB.T6G(SCH_1):PAGE31
   C56    GND @T6G_MB_LIB.T6G(SCH_1):GND    I19 @T6G_MB_LIB.T6G(SCH_1):PAGE31
   C57    GND @T6G_MB_LIB.T6G(SCH_1):GND    I19 @T6G_MB_LIB.T6G(SCH_1):PAGE31
   C61    GND @T6G_MB_LIB.T6G(SCH_1):GND    I19 @T6G_MB_LIB.T6G(SCH_1):PAGE31
   C64    GND @T6G_MB_LIB.T6G(SCH_1):GND    I19 @T6G_MB_LIB.T6G(SCH_1):PAGE31
   C67    GND @T6G_MB_LIB.T6G(SCH_1):GND    I19 @T6G_MB_LIB.T6G(SCH_1):PAGE31
   C69    GND @T6G_MB_LIB.T6G(SCH_1):GND    I19 @T6G_MB_LIB.T6G(SCH_1):PAGE31
   C71    GND @T6G_MB_LIB.T6G(SCH_1):GND    I19 @T6G_MB_LIB.T6G(SCH_1):PAGE31
   C73    GND @T6G_MB_LIB.T6G(SCH_1):GND    I19 @T6G_MB_LIB.T6G(SCH_1):PAGE31
   C75    GND @T6G_MB_LIB.T6G(SCH_1):GND    I19 @T6G_MB_LIB.T6G(SCH_1):PAGE31
    D2    GND @T6G_MB_LIB.T6G(SCH_1):GND    I19 @T6G_MB_LIB.T6G(SCH_1):PAGE31
    D3    GND @T6G_MB_LIB.T6G(SCH_1):GND    I19 @T6G_MB_LIB.T6G(SCH_1):PAGE31
    D5    GND @T6G_MB_LIB.T6G(SCH_1):GND    I19 @T6G_MB_LIB.T6G(SCH_1):PAGE31
    D6    GND @T6G_MB_LIB.T6G(SCH_1):GND    I19 @T6G_MB_LIB.T6G(SCH_1):PAGE31
    D9    GND @T6G_MB_LIB.T6G(SCH_1):GND    I19 @T6G_MB_LIB.T6G(SCH_1):PAGE31
   D10    GND @T6G_MB_LIB.T6G(SCH_1):GND    I19 @T6G_MB_LIB.T6G(SCH_1):PAGE31
   D12    GND @T6G_MB_LIB.T6G(SCH_1):GND    I19 @T6G_MB_LIB.T6G(SCH_1):PAGE31
   D13    GND @T6G_MB_LIB.T6G(SCH_1):GND    I19 @T6G_MB_LIB.T6G(SCH_1):PAGE31
   D16    GND @T6G_MB_LIB.T6G(SCH_1):GND    I19 @T6G_MB_LIB.T6G(SCH_1):PAGE31
   D17    GND @T6G_MB_LIB.T6G(SCH_1):GND    I19 @T6G_MB_LIB.T6G(SCH_1):PAGE31
   D19    GND @T6G_MB_LIB.T6G(SCH_1):GND    I19 @T6G_MB_LIB.T6G(SCH_1):PAGE31
   D20    GND @T6G_MB_LIB.T6G(SCH_1):GND    I19 @T6G_MB_LIB.T6G(SCH_1):PAGE31
   D21    GND @T6G_MB_LIB.T6G(SCH_1):GND    I19 @T6G_MB_LIB.T6G(SCH_1):PAGE31
   D24    GND @T6G_MB_LIB.T6G(SCH_1):GND    I19 @T6G_MB_LIB.T6G(SCH_1):PAGE31
   D25    GND @T6G_MB_LIB.T6G(SCH_1):GND    I19 @T6G_MB_LIB.T6G(SCH_1):PAGE31
   D26    GND @T6G_MB_LIB.T6G(SCH_1):GND    I19 @T6G_MB_LIB.T6G(SCH_1):PAGE31
   D27    GND @T6G_MB_LIB.T6G(SCH_1):GND    I19 @T6G_MB_LIB.T6G(SCH_1):PAGE31
   D28    GND @T6G_MB_LIB.T6G(SCH_1):GND    I19 @T6G_MB_LIB.T6G(SCH_1):PAGE31
   D29    GND @T6G_MB_LIB.T6G(SCH_1):GND    I19 @T6G_MB_LIB.T6G(SCH_1):PAGE31
   D30    GND @T6G_MB_LIB.T6G(SCH_1):GND    I19 @T6G_MB_LIB.T6G(SCH_1):PAGE31
   D31    GND @T6G_MB_LIB.T6G(SCH_1):GND    I19 @T6G_MB_LIB.T6G(SCH_1):PAGE31
   D35    GND @T6G_MB_LIB.T6G(SCH_1):GND    I19 @T6G_MB_LIB.T6G(SCH_1):PAGE31
   D37    GND @T6G_MB_LIB.T6G(SCH_1):GND    I19 @T6G_MB_LIB.T6G(SCH_1):PAGE31
   D39    GND @T6G_MB_LIB.T6G(SCH_1):GND    I19 @T6G_MB_LIB.T6G(SCH_1):PAGE31
   D40    GND @T6G_MB_LIB.T6G(SCH_1):GND    I19 @T6G_MB_LIB.T6G(SCH_1):PAGE31
   D41    GND @T6G_MB_LIB.T6G(SCH_1):GND    I19 @T6G_MB_LIB.T6G(SCH_1):PAGE31
   D42    GND @T6G_MB_LIB.T6G(SCH_1):GND    I19 @T6G_MB_LIB.T6G(SCH_1):PAGE31
   D43    GND @T6G_MB_LIB.T6G(SCH_1):GND    I19 @T6G_MB_LIB.T6G(SCH_1):PAGE31
   D44    GND @T6G_MB_LIB.T6G(SCH_1):GND    I19 @T6G_MB_LIB.T6G(SCH_1):PAGE31
   D45    GND @T6G_MB_LIB.T6G(SCH_1):GND    I19 @T6G_MB_LIB.T6G(SCH_1):PAGE31
   D46    GND @T6G_MB_LIB.T6G(SCH_1):GND    I19 @T6G_MB_LIB.T6G(SCH_1):PAGE31
   D47    GND @T6G_MB_LIB.T6G(SCH_1):GND    I19 @T6G_MB_LIB.T6G(SCH_1):PAGE31
   D48    GND @T6G_MB_LIB.T6G(SCH_1):GND    I19 @T6G_MB_LIB.T6G(SCH_1):PAGE31
   D49    GND @T6G_MB_LIB.T6G(SCH_1):GND    I19 @T6G_MB_LIB.T6G(SCH_1):PAGE31
   D50    GND @T6G_MB_LIB.T6G(SCH_1):GND    I19 @T6G_MB_LIB.T6G(SCH_1):PAGE31
   D51    GND @T6G_MB_LIB.T6G(SCH_1):GND    I19 @T6G_MB_LIB.T6G(SCH_1):PAGE31
   D52    GND @T6G_MB_LIB.T6G(SCH_1):GND    I19 @T6G_MB_LIB.T6G(SCH_1):PAGE31
   D53    GND @T6G_MB_LIB.T6G(SCH_1):GND    I19 @T6G_MB_LIB.T6G(SCH_1):PAGE31
   D54    GND @T6G_MB_LIB.T6G(SCH_1):GND    I19 @T6G_MB_LIB.T6G(SCH_1):PAGE31
   D57    GND @T6G_MB_LIB.T6G(SCH_1):GND    I19 @T6G_MB_LIB.T6G(SCH_1):PAGE31
   D59    GND @T6G_MB_LIB.T6G(SCH_1):GND    I19 @T6G_MB_LIB.T6G(SCH_1):PAGE31
   D60    GND @T6G_MB_LIB.T6G(SCH_1):GND    I19 @T6G_MB_LIB.T6G(SCH_1):PAGE31
   D61    GND @T6G_MB_LIB.T6G(SCH_1):GND    I19 @T6G_MB_LIB.T6G(SCH_1):PAGE31
   D63    GND @T6G_MB_LIB.T6G(SCH_1):GND    I19 @T6G_MB_LIB.T6G(SCH_1):PAGE31
   D64    GND @T6G_MB_LIB.T6G(SCH_1):GND    I19 @T6G_MB_LIB.T6G(SCH_1):PAGE31
   D66    GND @T6G_MB_LIB.T6G(SCH_1):GND    I19 @T6G_MB_LIB.T6G(SCH_1):PAGE31
   D67    GND @T6G_MB_LIB.T6G(SCH_1):GND    I19 @T6G_MB_LIB.T6G(SCH_1):PAGE31
   D70    GND @T6G_MB_LIB.T6G(SCH_1):GND    I19 @T6G_MB_LIB.T6G(SCH_1):PAGE31
   D71    GND @T6G_MB_LIB.T6G(SCH_1):GND    I19 @T6G_MB_LIB.T6G(SCH_1):PAGE31
   D73    GND @T6G_MB_LIB.T6G(SCH_1):GND    I19 @T6G_MB_LIB.T6G(SCH_1):PAGE31
   D74    GND @T6G_MB_LIB.T6G(SCH_1):GND    I19 @T6G_MB_LIB.T6G(SCH_1):PAGE31
    E1    GND @T6G_MB_LIB.T6G(SCH_1):GND    I19 @T6G_MB_LIB.T6G(SCH_1):PAGE31
    E3    GND @T6G_MB_LIB.T6G(SCH_1):GND    I19 @T6G_MB_LIB.T6G(SCH_1):PAGE31
    E6    GND @T6G_MB_LIB.T6G(SCH_1):GND    I19 @T6G_MB_LIB.T6G(SCH_1):PAGE31
    E7    GND @T6G_MB_LIB.T6G(SCH_1):GND    I19 @T6G_MB_LIB.T6G(SCH_1):PAGE31
    E8    GND @T6G_MB_LIB.T6G(SCH_1):GND    I19 @T6G_MB_LIB.T6G(SCH_1):PAGE31
   E10    GND @T6G_MB_LIB.T6G(SCH_1):GND    I19 @T6G_MB_LIB.T6G(SCH_1):PAGE31
   E13    GND @T6G_MB_LIB.T6G(SCH_1):GND    I19 @T6G_MB_LIB.T6G(SCH_1):PAGE31
   E14    GND @T6G_MB_LIB.T6G(SCH_1):GND    I19 @T6G_MB_LIB.T6G(SCH_1):PAGE31
   E15    GND @T6G_MB_LIB.T6G(SCH_1):GND    I19 @T6G_MB_LIB.T6G(SCH_1):PAGE31
   E17    GND @T6G_MB_LIB.T6G(SCH_1):GND    I19 @T6G_MB_LIB.T6G(SCH_1):PAGE31
   E18    GND @T6G_MB_LIB.T6G(SCH_1):GND    I19 @T6G_MB_LIB.T6G(SCH_1):PAGE31
   E20    GND @T6G_MB_LIB.T6G(SCH_1):GND    I19 @T6G_MB_LIB.T6G(SCH_1):PAGE31
   E21    GND @T6G_MB_LIB.T6G(SCH_1):GND    I19 @T6G_MB_LIB.T6G(SCH_1):PAGE31
   E52    GND @T6G_MB_LIB.T6G(SCH_1):GND    I19 @T6G_MB_LIB.T6G(SCH_1):PAGE31
   E53    GND @T6G_MB_LIB.T6G(SCH_1):GND    I19 @T6G_MB_LIB.T6G(SCH_1):PAGE31
   E55    GND @T6G_MB_LIB.T6G(SCH_1):GND    I19 @T6G_MB_LIB.T6G(SCH_1):PAGE31
   E56    GND @T6G_MB_LIB.T6G(SCH_1):GND    I19 @T6G_MB_LIB.T6G(SCH_1):PAGE31
   E58    GND @T6G_MB_LIB.T6G(SCH_1):GND    I19 @T6G_MB_LIB.T6G(SCH_1):PAGE31
   E59    GND @T6G_MB_LIB.T6G(SCH_1):GND    I19 @T6G_MB_LIB.T6G(SCH_1):PAGE31
   E61    GND @T6G_MB_LIB.T6G(SCH_1):GND    I19 @T6G_MB_LIB.T6G(SCH_1):PAGE31
   E62    GND @T6G_MB_LIB.T6G(SCH_1):GND    I19 @T6G_MB_LIB.T6G(SCH_1):PAGE31
   E63    GND @T6G_MB_LIB.T6G(SCH_1):GND    I19 @T6G_MB_LIB.T6G(SCH_1):PAGE31
   E65    GND @T6G_MB_LIB.T6G(SCH_1):GND    I19 @T6G_MB_LIB.T6G(SCH_1):PAGE31
   E66    GND @T6G_MB_LIB.T6G(SCH_1):GND    I19 @T6G_MB_LIB.T6G(SCH_1):PAGE31
   E68    GND @T6G_MB_LIB.T6G(SCH_1):GND    I19 @T6G_MB_LIB.T6G(SCH_1):PAGE31
   E69    GND @T6G_MB_LIB.T6G(SCH_1):GND    I19 @T6G_MB_LIB.T6G(SCH_1):PAGE31
   E70    GND @T6G_MB_LIB.T6G(SCH_1):GND    I19 @T6G_MB_LIB.T6G(SCH_1):PAGE31
   E72    GND @T6G_MB_LIB.T6G(SCH_1):GND    I19 @T6G_MB_LIB.T6G(SCH_1):PAGE31
   E73    GND @T6G_MB_LIB.T6G(SCH_1):GND    I19 @T6G_MB_LIB.T6G(SCH_1):PAGE31
   E75    GND @T6G_MB_LIB.T6G(SCH_1):GND    I19 @T6G_MB_LIB.T6G(SCH_1):PAGE31
    F3    GND @T6G_MB_LIB.T6G(SCH_1):GND    I19 @T6G_MB_LIB.T6G(SCH_1):PAGE31
    F5    GND @T6G_MB_LIB.T6G(SCH_1):GND    I19 @T6G_MB_LIB.T6G(SCH_1):PAGE31
    F8    GND @T6G_MB_LIB.T6G(SCH_1):GND    I19 @T6G_MB_LIB.T6G(SCH_1):PAGE31
   F10    GND @T6G_MB_LIB.T6G(SCH_1):GND    I19 @T6G_MB_LIB.T6G(SCH_1):PAGE31
   F12    GND @T6G_MB_LIB.T6G(SCH_1):GND    I19 @T6G_MB_LIB.T6G(SCH_1):PAGE31
   F15    GND @T6G_MB_LIB.T6G(SCH_1):GND    I19 @T6G_MB_LIB.T6G(SCH_1):PAGE31
   F17    GND @T6G_MB_LIB.T6G(SCH_1):GND    I19 @T6G_MB_LIB.T6G(SCH_1):PAGE31
   F19    GND @T6G_MB_LIB.T6G(SCH_1):GND    I19 @T6G_MB_LIB.T6G(SCH_1):PAGE31
   F23    GND @T6G_MB_LIB.T6G(SCH_1):GND    I19 @T6G_MB_LIB.T6G(SCH_1):PAGE31
   F24    GND @T6G_MB_LIB.T6G(SCH_1):GND    I19 @T6G_MB_LIB.T6G(SCH_1):PAGE31
   F26    GND @T6G_MB_LIB.T6G(SCH_1):GND    I19 @T6G_MB_LIB.T6G(SCH_1):PAGE31
   F27    GND @T6G_MB_LIB.T6G(SCH_1):GND    I19 @T6G_MB_LIB.T6G(SCH_1):PAGE31
   F29    GND @T6G_MB_LIB.T6G(SCH_1):GND    I19 @T6G_MB_LIB.T6G(SCH_1):PAGE31
   F30    GND @T6G_MB_LIB.T6G(SCH_1):GND    I19 @T6G_MB_LIB.T6G(SCH_1):PAGE31
   F32    GND @T6G_MB_LIB.T6G(SCH_1):GND    I19 @T6G_MB_LIB.T6G(SCH_1):PAGE31
   F33    GND @T6G_MB_LIB.T6G(SCH_1):GND    I19 @T6G_MB_LIB.T6G(SCH_1):PAGE31
   F35    GND @T6G_MB_LIB.T6G(SCH_1):GND    I19 @T6G_MB_LIB.T6G(SCH_1):PAGE31
   F36    GND @T6G_MB_LIB.T6G(SCH_1):GND    I19 @T6G_MB_LIB.T6G(SCH_1):PAGE31
   F37    GND @T6G_MB_LIB.T6G(SCH_1):GND    I19 @T6G_MB_LIB.T6G(SCH_1):PAGE31
   F39    GND @T6G_MB_LIB.T6G(SCH_1):GND    I19 @T6G_MB_LIB.T6G(SCH_1):PAGE31
   F40    GND @T6G_MB_LIB.T6G(SCH_1):GND    I19 @T6G_MB_LIB.T6G(SCH_1):PAGE31
   F41    GND @T6G_MB_LIB.T6G(SCH_1):GND    I19 @T6G_MB_LIB.T6G(SCH_1):PAGE31
   F43    GND @T6G_MB_LIB.T6G(SCH_1):GND    I19 @T6G_MB_LIB.T6G(SCH_1):PAGE31
   F44    GND @T6G_MB_LIB.T6G(SCH_1):GND    I19 @T6G_MB_LIB.T6G(SCH_1):PAGE31
   F46    GND @T6G_MB_LIB.T6G(SCH_1):GND    I19 @T6G_MB_LIB.T6G(SCH_1):PAGE31
   F47    GND @T6G_MB_LIB.T6G(SCH_1):GND    I19 @T6G_MB_LIB.T6G(SCH_1):PAGE31
   F49    GND @T6G_MB_LIB.T6G(SCH_1):GND    I19 @T6G_MB_LIB.T6G(SCH_1):PAGE31
   F50    GND @T6G_MB_LIB.T6G(SCH_1):GND    I19 @T6G_MB_LIB.T6G(SCH_1):PAGE31
   F52    GND @T6G_MB_LIB.T6G(SCH_1):GND    I19 @T6G_MB_LIB.T6G(SCH_1):PAGE31
   F53    GND @T6G_MB_LIB.T6G(SCH_1):GND    I19 @T6G_MB_LIB.T6G(SCH_1):PAGE31
   F57    GND @T6G_MB_LIB.T6G(SCH_1):GND    I19 @T6G_MB_LIB.T6G(SCH_1):PAGE31
   F59    GND @T6G_MB_LIB.T6G(SCH_1):GND    I19 @T6G_MB_LIB.T6G(SCH_1):PAGE31
   F61    GND @T6G_MB_LIB.T6G(SCH_1):GND    I19 @T6G_MB_LIB.T6G(SCH_1):PAGE31
   F64    GND @T6G_MB_LIB.T6G(SCH_1):GND    I19 @T6G_MB_LIB.T6G(SCH_1):PAGE31
   F66    GND @T6G_MB_LIB.T6G(SCH_1):GND    I19 @T6G_MB_LIB.T6G(SCH_1):PAGE31
   F68    GND @T6G_MB_LIB.T6G(SCH_1):GND    I19 @T6G_MB_LIB.T6G(SCH_1):PAGE31
   F71    GND @T6G_MB_LIB.T6G(SCH_1):GND    I19 @T6G_MB_LIB.T6G(SCH_1):PAGE31
   F73    GND @T6G_MB_LIB.T6G(SCH_1):GND    I19 @T6G_MB_LIB.T6G(SCH_1):PAGE31
    G1    GND @T6G_MB_LIB.T6G(SCH_1):GND    I19 @T6G_MB_LIB.T6G(SCH_1):PAGE31
    G4    GND @T6G_MB_LIB.T6G(SCH_1):GND    I19 @T6G_MB_LIB.T6G(SCH_1):PAGE31
    G6    GND @T6G_MB_LIB.T6G(SCH_1):GND    I19 @T6G_MB_LIB.T6G(SCH_1):PAGE31
    G8    GND @T6G_MB_LIB.T6G(SCH_1):GND    I19 @T6G_MB_LIB.T6G(SCH_1):PAGE31
   G11    GND @T6G_MB_LIB.T6G(SCH_1):GND    I19 @T6G_MB_LIB.T6G(SCH_1):PAGE31
   G13    GND @T6G_MB_LIB.T6G(SCH_1):GND    I19 @T6G_MB_LIB.T6G(SCH_1):PAGE31
   G15    GND @T6G_MB_LIB.T6G(SCH_1):GND    I19 @T6G_MB_LIB.T6G(SCH_1):PAGE31
   G18    GND @T6G_MB_LIB.T6G(SCH_1):GND    I19 @T6G_MB_LIB.T6G(SCH_1):PAGE31
   G20    GND @T6G_MB_LIB.T6G(SCH_1):GND    I19 @T6G_MB_LIB.T6G(SCH_1):PAGE31
   G22    GND @T6G_MB_LIB.T6G(SCH_1):GND    I19 @T6G_MB_LIB.T6G(SCH_1):PAGE31
   G25    GND @T6G_MB_LIB.T6G(SCH_1):GND    I19 @T6G_MB_LIB.T6G(SCH_1):PAGE31
   G28    GND @T6G_MB_LIB.T6G(SCH_1):GND    I19 @T6G_MB_LIB.T6G(SCH_1):PAGE31
   G31    GND @T6G_MB_LIB.T6G(SCH_1):GND    I19 @T6G_MB_LIB.T6G(SCH_1):PAGE31
   G34    GND @T6G_MB_LIB.T6G(SCH_1):GND    I19 @T6G_MB_LIB.T6G(SCH_1):PAGE31
   G42    GND @T6G_MB_LIB.T6G(SCH_1):GND    I19 @T6G_MB_LIB.T6G(SCH_1):PAGE31
   G45    GND @T6G_MB_LIB.T6G(SCH_1):GND    I19 @T6G_MB_LIB.T6G(SCH_1):PAGE31
   G48    GND @T6G_MB_LIB.T6G(SCH_1):GND    I19 @T6G_MB_LIB.T6G(SCH_1):PAGE31
   G51    GND @T6G_MB_LIB.T6G(SCH_1):GND    I19 @T6G_MB_LIB.T6G(SCH_1):PAGE31
   G54    GND @T6G_MB_LIB.T6G(SCH_1):GND    I19 @T6G_MB_LIB.T6G(SCH_1):PAGE31
   G56    GND @T6G_MB_LIB.T6G(SCH_1):GND    I19 @T6G_MB_LIB.T6G(SCH_1):PAGE31
   G58    GND @T6G_MB_LIB.T6G(SCH_1):GND    I19 @T6G_MB_LIB.T6G(SCH_1):PAGE31
   G61    GND @T6G_MB_LIB.T6G(SCH_1):GND    I19 @T6G_MB_LIB.T6G(SCH_1):PAGE31
   G63    GND @T6G_MB_LIB.T6G(SCH_1):GND    I19 @T6G_MB_LIB.T6G(SCH_1):PAGE31
   G65    GND @T6G_MB_LIB.T6G(SCH_1):GND    I19 @T6G_MB_LIB.T6G(SCH_1):PAGE31
   G68    GND @T6G_MB_LIB.T6G(SCH_1):GND    I19 @T6G_MB_LIB.T6G(SCH_1):PAGE31
   G70    GND @T6G_MB_LIB.T6G(SCH_1):GND    I19 @T6G_MB_LIB.T6G(SCH_1):PAGE31
   G72    GND @T6G_MB_LIB.T6G(SCH_1):GND    I19 @T6G_MB_LIB.T6G(SCH_1):PAGE31
   G75    GND @T6G_MB_LIB.T6G(SCH_1):GND    I19 @T6G_MB_LIB.T6G(SCH_1):PAGE31
    H3    GND @T6G_MB_LIB.T6G(SCH_1):GND    I19 @T6G_MB_LIB.T6G(SCH_1):PAGE31
    H8    GND @T6G_MB_LIB.T6G(SCH_1):GND    I19 @T6G_MB_LIB.T6G(SCH_1):PAGE31
   H10    GND @T6G_MB_LIB.T6G(SCH_1):GND    I19 @T6G_MB_LIB.T6G(SCH_1):PAGE31
   H15    GND @T6G_MB_LIB.T6G(SCH_1):GND    I19 @T6G_MB_LIB.T6G(SCH_1):PAGE31
   H17    GND @T6G_MB_LIB.T6G(SCH_1):GND    I19 @T6G_MB_LIB.T6G(SCH_1):PAGE31
   H22    GND @T6G_MB_LIB.T6G(SCH_1):GND    I19 @T6G_MB_LIB.T6G(SCH_1):PAGE31
   H25    GND @T6G_MB_LIB.T6G(SCH_1):GND    I19 @T6G_MB_LIB.T6G(SCH_1):PAGE31
   H28    GND @T6G_MB_LIB.T6G(SCH_1):GND    I19 @T6G_MB_LIB.T6G(SCH_1):PAGE31
   H31    GND @T6G_MB_LIB.T6G(SCH_1):GND    I19 @T6G_MB_LIB.T6G(SCH_1):PAGE31
   H34    GND @T6G_MB_LIB.T6G(SCH_1):GND    I19 @T6G_MB_LIB.T6G(SCH_1):PAGE31
   R48    GND @T6G_MB_LIB.T6G(SCH_1):GND    I20 @T6G_MB_LIB.T6G(SCH_1):PAGE31
   R51    GND @T6G_MB_LIB.T6G(SCH_1):GND    I20 @T6G_MB_LIB.T6G(SCH_1):PAGE31
   R54    GND @T6G_MB_LIB.T6G(SCH_1):GND    I20 @T6G_MB_LIB.T6G(SCH_1):PAGE31
   R56    GND @T6G_MB_LIB.T6G(SCH_1):GND    I20 @T6G_MB_LIB.T6G(SCH_1):PAGE31
   R58    GND @T6G_MB_LIB.T6G(SCH_1):GND    I20 @T6G_MB_LIB.T6G(SCH_1):PAGE31
   R61    GND @T6G_MB_LIB.T6G(SCH_1):GND    I20 @T6G_MB_LIB.T6G(SCH_1):PAGE31
   R63    GND @T6G_MB_LIB.T6G(SCH_1):GND    I20 @T6G_MB_LIB.T6G(SCH_1):PAGE31
   R65    GND @T6G_MB_LIB.T6G(SCH_1):GND    I20 @T6G_MB_LIB.T6G(SCH_1):PAGE31
   R68    GND @T6G_MB_LIB.T6G(SCH_1):GND    I20 @T6G_MB_LIB.T6G(SCH_1):PAGE31
   R70    GND @T6G_MB_LIB.T6G(SCH_1):GND    I20 @T6G_MB_LIB.T6G(SCH_1):PAGE31
   R72    GND @T6G_MB_LIB.T6G(SCH_1):GND    I20 @T6G_MB_LIB.T6G(SCH_1):PAGE31
   R75    GND @T6G_MB_LIB.T6G(SCH_1):GND    I20 @T6G_MB_LIB.T6G(SCH_1):PAGE31
    T3    GND @T6G_MB_LIB.T6G(SCH_1):GND    I20 @T6G_MB_LIB.T6G(SCH_1):PAGE31
    T5    GND @T6G_MB_LIB.T6G(SCH_1):GND    I20 @T6G_MB_LIB.T6G(SCH_1):PAGE31
    T8    GND @T6G_MB_LIB.T6G(SCH_1):GND    I20 @T6G_MB_LIB.T6G(SCH_1):PAGE31
   T10    GND @T6G_MB_LIB.T6G(SCH_1):GND    I20 @T6G_MB_LIB.T6G(SCH_1):PAGE31
   T12    GND @T6G_MB_LIB.T6G(SCH_1):GND    I20 @T6G_MB_LIB.T6G(SCH_1):PAGE31
   T15    GND @T6G_MB_LIB.T6G(SCH_1):GND    I20 @T6G_MB_LIB.T6G(SCH_1):PAGE31
   T17    GND @T6G_MB_LIB.T6G(SCH_1):GND    I20 @T6G_MB_LIB.T6G(SCH_1):PAGE31
   T19    GND @T6G_MB_LIB.T6G(SCH_1):GND    I20 @T6G_MB_LIB.T6G(SCH_1):PAGE31
   T22    GND @T6G_MB_LIB.T6G(SCH_1):GND    I20 @T6G_MB_LIB.T6G(SCH_1):PAGE31
   T25    GND @T6G_MB_LIB.T6G(SCH_1):GND    I20 @T6G_MB_LIB.T6G(SCH_1):PAGE31
   T28    GND @T6G_MB_LIB.T6G(SCH_1):GND    I20 @T6G_MB_LIB.T6G(SCH_1):PAGE31
   T31    GND @T6G_MB_LIB.T6G(SCH_1):GND    I20 @T6G_MB_LIB.T6G(SCH_1):PAGE31
   T34    GND @T6G_MB_LIB.T6G(SCH_1):GND    I20 @T6G_MB_LIB.T6G(SCH_1):PAGE31
   T37    GND @T6G_MB_LIB.T6G(SCH_1):GND    I20 @T6G_MB_LIB.T6G(SCH_1):PAGE31
   T39    GND @T6G_MB_LIB.T6G(SCH_1):GND    I20 @T6G_MB_LIB.T6G(SCH_1):PAGE31
   T42    GND @T6G_MB_LIB.T6G(SCH_1):GND    I20 @T6G_MB_LIB.T6G(SCH_1):PAGE31
   T45    GND @T6G_MB_LIB.T6G(SCH_1):GND    I20 @T6G_MB_LIB.T6G(SCH_1):PAGE31
   T48    GND @T6G_MB_LIB.T6G(SCH_1):GND    I20 @T6G_MB_LIB.T6G(SCH_1):PAGE31
   T51    GND @T6G_MB_LIB.T6G(SCH_1):GND    I20 @T6G_MB_LIB.T6G(SCH_1):PAGE31
   T54    GND @T6G_MB_LIB.T6G(SCH_1):GND    I20 @T6G_MB_LIB.T6G(SCH_1):PAGE31
   T57    GND @T6G_MB_LIB.T6G(SCH_1):GND    I20 @T6G_MB_LIB.T6G(SCH_1):PAGE31
   T59    GND @T6G_MB_LIB.T6G(SCH_1):GND    I20 @T6G_MB_LIB.T6G(SCH_1):PAGE31
   T61    GND @T6G_MB_LIB.T6G(SCH_1):GND    I20 @T6G_MB_LIB.T6G(SCH_1):PAGE31
   T64    GND @T6G_MB_LIB.T6G(SCH_1):GND    I20 @T6G_MB_LIB.T6G(SCH_1):PAGE31
   J15    GND @T6G_MB_LIB.T6G(SCH_1):GND    I20 @T6G_MB_LIB.T6G(SCH_1):PAGE31
   J18    GND @T6G_MB_LIB.T6G(SCH_1):GND    I20 @T6G_MB_LIB.T6G(SCH_1):PAGE31
   J20    GND @T6G_MB_LIB.T6G(SCH_1):GND    I20 @T6G_MB_LIB.T6G(SCH_1):PAGE31
   J22    GND @T6G_MB_LIB.T6G(SCH_1):GND    I20 @T6G_MB_LIB.T6G(SCH_1):PAGE31
   J25    GND @T6G_MB_LIB.T6G(SCH_1):GND    I20 @T6G_MB_LIB.T6G(SCH_1):PAGE31
   J28    GND @T6G_MB_LIB.T6G(SCH_1):GND    I20 @T6G_MB_LIB.T6G(SCH_1):PAGE31
   J31    GND @T6G_MB_LIB.T6G(SCH_1):GND    I20 @T6G_MB_LIB.T6G(SCH_1):PAGE31
   J34    GND @T6G_MB_LIB.T6G(SCH_1):GND    I20 @T6G_MB_LIB.T6G(SCH_1):PAGE31
   J42    GND @T6G_MB_LIB.T6G(SCH_1):GND    I20 @T6G_MB_LIB.T6G(SCH_1):PAGE31
   J45    GND @T6G_MB_LIB.T6G(SCH_1):GND    I20 @T6G_MB_LIB.T6G(SCH_1):PAGE31
   J48    GND @T6G_MB_LIB.T6G(SCH_1):GND    I20 @T6G_MB_LIB.T6G(SCH_1):PAGE31
   J51    GND @T6G_MB_LIB.T6G(SCH_1):GND    I20 @T6G_MB_LIB.T6G(SCH_1):PAGE31
   J54    GND @T6G_MB_LIB.T6G(SCH_1):GND    I20 @T6G_MB_LIB.T6G(SCH_1):PAGE31
   J56    GND @T6G_MB_LIB.T6G(SCH_1):GND    I20 @T6G_MB_LIB.T6G(SCH_1):PAGE31
   J58    GND @T6G_MB_LIB.T6G(SCH_1):GND    I20 @T6G_MB_LIB.T6G(SCH_1):PAGE31
   J61    GND @T6G_MB_LIB.T6G(SCH_1):GND    I20 @T6G_MB_LIB.T6G(SCH_1):PAGE31
   J63    GND @T6G_MB_LIB.T6G(SCH_1):GND    I20 @T6G_MB_LIB.T6G(SCH_1):PAGE31
   J65    GND @T6G_MB_LIB.T6G(SCH_1):GND    I20 @T6G_MB_LIB.T6G(SCH_1):PAGE31
   J68    GND @T6G_MB_LIB.T6G(SCH_1):GND    I20 @T6G_MB_LIB.T6G(SCH_1):PAGE31
   J70    GND @T6G_MB_LIB.T6G(SCH_1):GND    I20 @T6G_MB_LIB.T6G(SCH_1):PAGE31
   J72    GND @T6G_MB_LIB.T6G(SCH_1):GND    I20 @T6G_MB_LIB.T6G(SCH_1):PAGE31
   J75    GND @T6G_MB_LIB.T6G(SCH_1):GND    I20 @T6G_MB_LIB.T6G(SCH_1):PAGE31
    K3    GND @T6G_MB_LIB.T6G(SCH_1):GND    I20 @T6G_MB_LIB.T6G(SCH_1):PAGE31
    K5    GND @T6G_MB_LIB.T6G(SCH_1):GND    I20 @T6G_MB_LIB.T6G(SCH_1):PAGE31
    K8    GND @T6G_MB_LIB.T6G(SCH_1):GND    I20 @T6G_MB_LIB.T6G(SCH_1):PAGE31
   K10    GND @T6G_MB_LIB.T6G(SCH_1):GND    I20 @T6G_MB_LIB.T6G(SCH_1):PAGE31
   K12    GND @T6G_MB_LIB.T6G(SCH_1):GND    I20 @T6G_MB_LIB.T6G(SCH_1):PAGE31
   K15    GND @T6G_MB_LIB.T6G(SCH_1):GND    I20 @T6G_MB_LIB.T6G(SCH_1):PAGE31
   K17    GND @T6G_MB_LIB.T6G(SCH_1):GND    I20 @T6G_MB_LIB.T6G(SCH_1):PAGE31
   K19    GND @T6G_MB_LIB.T6G(SCH_1):GND    I20 @T6G_MB_LIB.T6G(SCH_1):PAGE31
   K24    GND @T6G_MB_LIB.T6G(SCH_1):GND    I20 @T6G_MB_LIB.T6G(SCH_1):PAGE31
   K25    GND @T6G_MB_LIB.T6G(SCH_1):GND    I20 @T6G_MB_LIB.T6G(SCH_1):PAGE31
   K26    GND @T6G_MB_LIB.T6G(SCH_1):GND    I20 @T6G_MB_LIB.T6G(SCH_1):PAGE31
   K27    GND @T6G_MB_LIB.T6G(SCH_1):GND    I20 @T6G_MB_LIB.T6G(SCH_1):PAGE31
   K28    GND @T6G_MB_LIB.T6G(SCH_1):GND    I20 @T6G_MB_LIB.T6G(SCH_1):PAGE31
   K29    GND @T6G_MB_LIB.T6G(SCH_1):GND    I20 @T6G_MB_LIB.T6G(SCH_1):PAGE31
   K30    GND @T6G_MB_LIB.T6G(SCH_1):GND    I20 @T6G_MB_LIB.T6G(SCH_1):PAGE31
   K31    GND @T6G_MB_LIB.T6G(SCH_1):GND    I20 @T6G_MB_LIB.T6G(SCH_1):PAGE31
   K32    GND @T6G_MB_LIB.T6G(SCH_1):GND    I20 @T6G_MB_LIB.T6G(SCH_1):PAGE31
   K33    GND @T6G_MB_LIB.T6G(SCH_1):GND    I20 @T6G_MB_LIB.T6G(SCH_1):PAGE31
   K34    GND @T6G_MB_LIB.T6G(SCH_1):GND    I20 @T6G_MB_LIB.T6G(SCH_1):PAGE31
   K37    GND @T6G_MB_LIB.T6G(SCH_1):GND    I20 @T6G_MB_LIB.T6G(SCH_1):PAGE31
   K39    GND @T6G_MB_LIB.T6G(SCH_1):GND    I20 @T6G_MB_LIB.T6G(SCH_1):PAGE31
   K42    GND @T6G_MB_LIB.T6G(SCH_1):GND    I20 @T6G_MB_LIB.T6G(SCH_1):PAGE31
   K43    GND @T6G_MB_LIB.T6G(SCH_1):GND    I20 @T6G_MB_LIB.T6G(SCH_1):PAGE31
   K44    GND @T6G_MB_LIB.T6G(SCH_1):GND    I20 @T6G_MB_LIB.T6G(SCH_1):PAGE31
   K45    GND @T6G_MB_LIB.T6G(SCH_1):GND    I20 @T6G_MB_LIB.T6G(SCH_1):PAGE31
   K46    GND @T6G_MB_LIB.T6G(SCH_1):GND    I20 @T6G_MB_LIB.T6G(SCH_1):PAGE31
   K47    GND @T6G_MB_LIB.T6G(SCH_1):GND    I20 @T6G_MB_LIB.T6G(SCH_1):PAGE31
   K48    GND @T6G_MB_LIB.T6G(SCH_1):GND    I20 @T6G_MB_LIB.T6G(SCH_1):PAGE31
   K49    GND @T6G_MB_LIB.T6G(SCH_1):GND    I20 @T6G_MB_LIB.T6G(SCH_1):PAGE31
   K50    GND @T6G_MB_LIB.T6G(SCH_1):GND    I20 @T6G_MB_LIB.T6G(SCH_1):PAGE31
   K51    GND @T6G_MB_LIB.T6G(SCH_1):GND    I20 @T6G_MB_LIB.T6G(SCH_1):PAGE31
   K52    GND @T6G_MB_LIB.T6G(SCH_1):GND    I20 @T6G_MB_LIB.T6G(SCH_1):PAGE31
   K53    GND @T6G_MB_LIB.T6G(SCH_1):GND    I20 @T6G_MB_LIB.T6G(SCH_1):PAGE31
   K57    GND @T6G_MB_LIB.T6G(SCH_1):GND    I20 @T6G_MB_LIB.T6G(SCH_1):PAGE31
   K61    GND @T6G_MB_LIB.T6G(SCH_1):GND    I20 @T6G_MB_LIB.T6G(SCH_1):PAGE31
   K64    GND @T6G_MB_LIB.T6G(SCH_1):GND    I20 @T6G_MB_LIB.T6G(SCH_1):PAGE31
   K66    GND @T6G_MB_LIB.T6G(SCH_1):GND    I20 @T6G_MB_LIB.T6G(SCH_1):PAGE31
   K68    GND @T6G_MB_LIB.T6G(SCH_1):GND    I20 @T6G_MB_LIB.T6G(SCH_1):PAGE31
   K71    GND @T6G_MB_LIB.T6G(SCH_1):GND    I20 @T6G_MB_LIB.T6G(SCH_1):PAGE31
   K73    GND @T6G_MB_LIB.T6G(SCH_1):GND    I20 @T6G_MB_LIB.T6G(SCH_1):PAGE31
    L1    GND @T6G_MB_LIB.T6G(SCH_1):GND    I20 @T6G_MB_LIB.T6G(SCH_1):PAGE31
    L6    GND @T6G_MB_LIB.T6G(SCH_1):GND    I20 @T6G_MB_LIB.T6G(SCH_1):PAGE31
    L8    GND @T6G_MB_LIB.T6G(SCH_1):GND    I20 @T6G_MB_LIB.T6G(SCH_1):PAGE31
   L13    GND @T6G_MB_LIB.T6G(SCH_1):GND    I20 @T6G_MB_LIB.T6G(SCH_1):PAGE31
   L15    GND @T6G_MB_LIB.T6G(SCH_1):GND    I20 @T6G_MB_LIB.T6G(SCH_1):PAGE31
   L20    GND @T6G_MB_LIB.T6G(SCH_1):GND    I20 @T6G_MB_LIB.T6G(SCH_1):PAGE31
   L22    GND @T6G_MB_LIB.T6G(SCH_1):GND    I20 @T6G_MB_LIB.T6G(SCH_1):PAGE31
   L25    GND @T6G_MB_LIB.T6G(SCH_1):GND    I20 @T6G_MB_LIB.T6G(SCH_1):PAGE31
   L28    GND @T6G_MB_LIB.T6G(SCH_1):GND    I20 @T6G_MB_LIB.T6G(SCH_1):PAGE31
   L31    GND @T6G_MB_LIB.T6G(SCH_1):GND    I20 @T6G_MB_LIB.T6G(SCH_1):PAGE31
   L34    GND @T6G_MB_LIB.T6G(SCH_1):GND    I20 @T6G_MB_LIB.T6G(SCH_1):PAGE31
   L35    GND @T6G_MB_LIB.T6G(SCH_1):GND    I20 @T6G_MB_LIB.T6G(SCH_1):PAGE31
   L36    GND @T6G_MB_LIB.T6G(SCH_1):GND    I20 @T6G_MB_LIB.T6G(SCH_1):PAGE31
   L40    GND @T6G_MB_LIB.T6G(SCH_1):GND    I20 @T6G_MB_LIB.T6G(SCH_1):PAGE31
   L41    GND @T6G_MB_LIB.T6G(SCH_1):GND    I20 @T6G_MB_LIB.T6G(SCH_1):PAGE31
   L42    GND @T6G_MB_LIB.T6G(SCH_1):GND    I20 @T6G_MB_LIB.T6G(SCH_1):PAGE31
   L45    GND @T6G_MB_LIB.T6G(SCH_1):GND    I20 @T6G_MB_LIB.T6G(SCH_1):PAGE31
   L48    GND @T6G_MB_LIB.T6G(SCH_1):GND    I20 @T6G_MB_LIB.T6G(SCH_1):PAGE31
   L51    GND @T6G_MB_LIB.T6G(SCH_1):GND    I20 @T6G_MB_LIB.T6G(SCH_1):PAGE31
   L54    GND @T6G_MB_LIB.T6G(SCH_1):GND    I20 @T6G_MB_LIB.T6G(SCH_1):PAGE31
   L56    GND @T6G_MB_LIB.T6G(SCH_1):GND    I20 @T6G_MB_LIB.T6G(SCH_1):PAGE31
   L61    GND @T6G_MB_LIB.T6G(SCH_1):GND    I20 @T6G_MB_LIB.T6G(SCH_1):PAGE31
   L63    GND @T6G_MB_LIB.T6G(SCH_1):GND    I20 @T6G_MB_LIB.T6G(SCH_1):PAGE31
   L68    GND @T6G_MB_LIB.T6G(SCH_1):GND    I20 @T6G_MB_LIB.T6G(SCH_1):PAGE31
   L70    GND @T6G_MB_LIB.T6G(SCH_1):GND    I20 @T6G_MB_LIB.T6G(SCH_1):PAGE31
   L75    GND @T6G_MB_LIB.T6G(SCH_1):GND    I20 @T6G_MB_LIB.T6G(SCH_1):PAGE31
    M3    GND @T6G_MB_LIB.T6G(SCH_1):GND    I20 @T6G_MB_LIB.T6G(SCH_1):PAGE31
    M5    GND @T6G_MB_LIB.T6G(SCH_1):GND    I20 @T6G_MB_LIB.T6G(SCH_1):PAGE31
    M8    GND @T6G_MB_LIB.T6G(SCH_1):GND    I20 @T6G_MB_LIB.T6G(SCH_1):PAGE31
   M10    GND @T6G_MB_LIB.T6G(SCH_1):GND    I20 @T6G_MB_LIB.T6G(SCH_1):PAGE31
   M12    GND @T6G_MB_LIB.T6G(SCH_1):GND    I20 @T6G_MB_LIB.T6G(SCH_1):PAGE31
   M15    GND @T6G_MB_LIB.T6G(SCH_1):GND    I20 @T6G_MB_LIB.T6G(SCH_1):PAGE31
   M17    GND @T6G_MB_LIB.T6G(SCH_1):GND    I20 @T6G_MB_LIB.T6G(SCH_1):PAGE31
   M19    GND @T6G_MB_LIB.T6G(SCH_1):GND    I20 @T6G_MB_LIB.T6G(SCH_1):PAGE31
   M22    GND @T6G_MB_LIB.T6G(SCH_1):GND    I20 @T6G_MB_LIB.T6G(SCH_1):PAGE31
   M25    GND @T6G_MB_LIB.T6G(SCH_1):GND    I20 @T6G_MB_LIB.T6G(SCH_1):PAGE31
   M28    GND @T6G_MB_LIB.T6G(SCH_1):GND    I20 @T6G_MB_LIB.T6G(SCH_1):PAGE31
   M31    GND @T6G_MB_LIB.T6G(SCH_1):GND    I20 @T6G_MB_LIB.T6G(SCH_1):PAGE31
   M34    GND @T6G_MB_LIB.T6G(SCH_1):GND    I20 @T6G_MB_LIB.T6G(SCH_1):PAGE31
   M37    GND @T6G_MB_LIB.T6G(SCH_1):GND    I20 @T6G_MB_LIB.T6G(SCH_1):PAGE31
   M39    GND @T6G_MB_LIB.T6G(SCH_1):GND    I20 @T6G_MB_LIB.T6G(SCH_1):PAGE31
   M42    GND @T6G_MB_LIB.T6G(SCH_1):GND    I20 @T6G_MB_LIB.T6G(SCH_1):PAGE31
   M45    GND @T6G_MB_LIB.T6G(SCH_1):GND    I20 @T6G_MB_LIB.T6G(SCH_1):PAGE31
   M48    GND @T6G_MB_LIB.T6G(SCH_1):GND    I20 @T6G_MB_LIB.T6G(SCH_1):PAGE31
   M51    GND @T6G_MB_LIB.T6G(SCH_1):GND    I20 @T6G_MB_LIB.T6G(SCH_1):PAGE31
   M54    GND @T6G_MB_LIB.T6G(SCH_1):GND    I20 @T6G_MB_LIB.T6G(SCH_1):PAGE31
   M57    GND @T6G_MB_LIB.T6G(SCH_1):GND    I20 @T6G_MB_LIB.T6G(SCH_1):PAGE31
   M59    GND @T6G_MB_LIB.T6G(SCH_1):GND    I20 @T6G_MB_LIB.T6G(SCH_1):PAGE31
   M61    GND @T6G_MB_LIB.T6G(SCH_1):GND    I20 @T6G_MB_LIB.T6G(SCH_1):PAGE31
   M64    GND @T6G_MB_LIB.T6G(SCH_1):GND    I20 @T6G_MB_LIB.T6G(SCH_1):PAGE31
   M66    GND @T6G_MB_LIB.T6G(SCH_1):GND    I20 @T6G_MB_LIB.T6G(SCH_1):PAGE31
   M68    GND @T6G_MB_LIB.T6G(SCH_1):GND    I20 @T6G_MB_LIB.T6G(SCH_1):PAGE31
   M71    GND @T6G_MB_LIB.T6G(SCH_1):GND    I20 @T6G_MB_LIB.T6G(SCH_1):PAGE31
   M73    GND @T6G_MB_LIB.T6G(SCH_1):GND    I20 @T6G_MB_LIB.T6G(SCH_1):PAGE31
    N1    GND @T6G_MB_LIB.T6G(SCH_1):GND    I20 @T6G_MB_LIB.T6G(SCH_1):PAGE31
    N4    GND @T6G_MB_LIB.T6G(SCH_1):GND    I20 @T6G_MB_LIB.T6G(SCH_1):PAGE31
    N6    GND @T6G_MB_LIB.T6G(SCH_1):GND    I20 @T6G_MB_LIB.T6G(SCH_1):PAGE31
    N8    GND @T6G_MB_LIB.T6G(SCH_1):GND    I20 @T6G_MB_LIB.T6G(SCH_1):PAGE31
   N11    GND @T6G_MB_LIB.T6G(SCH_1):GND    I20 @T6G_MB_LIB.T6G(SCH_1):PAGE31
   N13    GND @T6G_MB_LIB.T6G(SCH_1):GND    I20 @T6G_MB_LIB.T6G(SCH_1):PAGE31
   N15    GND @T6G_MB_LIB.T6G(SCH_1):GND    I20 @T6G_MB_LIB.T6G(SCH_1):PAGE31
   N18    GND @T6G_MB_LIB.T6G(SCH_1):GND    I20 @T6G_MB_LIB.T6G(SCH_1):PAGE31
   N20    GND @T6G_MB_LIB.T6G(SCH_1):GND    I20 @T6G_MB_LIB.T6G(SCH_1):PAGE31
   N22    GND @T6G_MB_LIB.T6G(SCH_1):GND    I20 @T6G_MB_LIB.T6G(SCH_1):PAGE31
   N25    GND @T6G_MB_LIB.T6G(SCH_1):GND    I20 @T6G_MB_LIB.T6G(SCH_1):PAGE31
   N28    GND @T6G_MB_LIB.T6G(SCH_1):GND    I20 @T6G_MB_LIB.T6G(SCH_1):PAGE31
   N31    GND @T6G_MB_LIB.T6G(SCH_1):GND    I20 @T6G_MB_LIB.T6G(SCH_1):PAGE31
   N34    GND @T6G_MB_LIB.T6G(SCH_1):GND    I20 @T6G_MB_LIB.T6G(SCH_1):PAGE31
   N42    GND @T6G_MB_LIB.T6G(SCH_1):GND    I20 @T6G_MB_LIB.T6G(SCH_1):PAGE31
   N45    GND @T6G_MB_LIB.T6G(SCH_1):GND    I20 @T6G_MB_LIB.T6G(SCH_1):PAGE31
   N48    GND @T6G_MB_LIB.T6G(SCH_1):GND    I20 @T6G_MB_LIB.T6G(SCH_1):PAGE31
   N51    GND @T6G_MB_LIB.T6G(SCH_1):GND    I20 @T6G_MB_LIB.T6G(SCH_1):PAGE31
   N54    GND @T6G_MB_LIB.T6G(SCH_1):GND    I20 @T6G_MB_LIB.T6G(SCH_1):PAGE31
   N56    GND @T6G_MB_LIB.T6G(SCH_1):GND    I20 @T6G_MB_LIB.T6G(SCH_1):PAGE31
   N58    GND @T6G_MB_LIB.T6G(SCH_1):GND    I20 @T6G_MB_LIB.T6G(SCH_1):PAGE31
   N61    GND @T6G_MB_LIB.T6G(SCH_1):GND    I20 @T6G_MB_LIB.T6G(SCH_1):PAGE31
   N63    GND @T6G_MB_LIB.T6G(SCH_1):GND    I20 @T6G_MB_LIB.T6G(SCH_1):PAGE31
   N65    GND @T6G_MB_LIB.T6G(SCH_1):GND    I20 @T6G_MB_LIB.T6G(SCH_1):PAGE31
   N68    GND @T6G_MB_LIB.T6G(SCH_1):GND    I20 @T6G_MB_LIB.T6G(SCH_1):PAGE31
   N70    GND @T6G_MB_LIB.T6G(SCH_1):GND    I20 @T6G_MB_LIB.T6G(SCH_1):PAGE31
   N72    GND @T6G_MB_LIB.T6G(SCH_1):GND    I20 @T6G_MB_LIB.T6G(SCH_1):PAGE31
   N75    GND @T6G_MB_LIB.T6G(SCH_1):GND    I20 @T6G_MB_LIB.T6G(SCH_1):PAGE31
    P3    GND @T6G_MB_LIB.T6G(SCH_1):GND    I20 @T6G_MB_LIB.T6G(SCH_1):PAGE31
    P8    GND @T6G_MB_LIB.T6G(SCH_1):GND    I20 @T6G_MB_LIB.T6G(SCH_1):PAGE31
   P10    GND @T6G_MB_LIB.T6G(SCH_1):GND    I20 @T6G_MB_LIB.T6G(SCH_1):PAGE31
   P15    GND @T6G_MB_LIB.T6G(SCH_1):GND    I20 @T6G_MB_LIB.T6G(SCH_1):PAGE31
   P17    GND @T6G_MB_LIB.T6G(SCH_1):GND    I20 @T6G_MB_LIB.T6G(SCH_1):PAGE31
   P23    GND @T6G_MB_LIB.T6G(SCH_1):GND    I20 @T6G_MB_LIB.T6G(SCH_1):PAGE31
   P24    GND @T6G_MB_LIB.T6G(SCH_1):GND    I20 @T6G_MB_LIB.T6G(SCH_1):PAGE31
   P26    GND @T6G_MB_LIB.T6G(SCH_1):GND    I20 @T6G_MB_LIB.T6G(SCH_1):PAGE31
   P27    GND @T6G_MB_LIB.T6G(SCH_1):GND    I20 @T6G_MB_LIB.T6G(SCH_1):PAGE31
   P28    GND @T6G_MB_LIB.T6G(SCH_1):GND    I20 @T6G_MB_LIB.T6G(SCH_1):PAGE31
   P29    GND @T6G_MB_LIB.T6G(SCH_1):GND    I20 @T6G_MB_LIB.T6G(SCH_1):PAGE31
   P30    GND @T6G_MB_LIB.T6G(SCH_1):GND    I20 @T6G_MB_LIB.T6G(SCH_1):PAGE31
   P31    GND @T6G_MB_LIB.T6G(SCH_1):GND    I20 @T6G_MB_LIB.T6G(SCH_1):PAGE31
   P32    GND @T6G_MB_LIB.T6G(SCH_1):GND    I20 @T6G_MB_LIB.T6G(SCH_1):PAGE31
   P33    GND @T6G_MB_LIB.T6G(SCH_1):GND    I20 @T6G_MB_LIB.T6G(SCH_1):PAGE31
   P34    GND @T6G_MB_LIB.T6G(SCH_1):GND    I20 @T6G_MB_LIB.T6G(SCH_1):PAGE31
   P37    GND @T6G_MB_LIB.T6G(SCH_1):GND    I20 @T6G_MB_LIB.T6G(SCH_1):PAGE31
   P39    GND @T6G_MB_LIB.T6G(SCH_1):GND    I20 @T6G_MB_LIB.T6G(SCH_1):PAGE31
   P42    GND @T6G_MB_LIB.T6G(SCH_1):GND    I20 @T6G_MB_LIB.T6G(SCH_1):PAGE31
   P43    GND @T6G_MB_LIB.T6G(SCH_1):GND    I20 @T6G_MB_LIB.T6G(SCH_1):PAGE31
   P44    GND @T6G_MB_LIB.T6G(SCH_1):GND    I20 @T6G_MB_LIB.T6G(SCH_1):PAGE31
   P45    GND @T6G_MB_LIB.T6G(SCH_1):GND    I20 @T6G_MB_LIB.T6G(SCH_1):PAGE31
   P46    GND @T6G_MB_LIB.T6G(SCH_1):GND    I20 @T6G_MB_LIB.T6G(SCH_1):PAGE31
   P47    GND @T6G_MB_LIB.T6G(SCH_1):GND    I20 @T6G_MB_LIB.T6G(SCH_1):PAGE31
   P48    GND @T6G_MB_LIB.T6G(SCH_1):GND    I20 @T6G_MB_LIB.T6G(SCH_1):PAGE31
   P49    GND @T6G_MB_LIB.T6G(SCH_1):GND    I20 @T6G_MB_LIB.T6G(SCH_1):PAGE31
   P50    GND @T6G_MB_LIB.T6G(SCH_1):GND    I20 @T6G_MB_LIB.T6G(SCH_1):PAGE31
   P51    GND @T6G_MB_LIB.T6G(SCH_1):GND    I20 @T6G_MB_LIB.T6G(SCH_1):PAGE31
   P52    GND @T6G_MB_LIB.T6G(SCH_1):GND    I20 @T6G_MB_LIB.T6G(SCH_1):PAGE31
   P53    GND @T6G_MB_LIB.T6G(SCH_1):GND    I20 @T6G_MB_LIB.T6G(SCH_1):PAGE31
   P59    GND @T6G_MB_LIB.T6G(SCH_1):GND    I20 @T6G_MB_LIB.T6G(SCH_1):PAGE31
   P61    GND @T6G_MB_LIB.T6G(SCH_1):GND    I20 @T6G_MB_LIB.T6G(SCH_1):PAGE31
   P66    GND @T6G_MB_LIB.T6G(SCH_1):GND    I20 @T6G_MB_LIB.T6G(SCH_1):PAGE31
   P73    GND @T6G_MB_LIB.T6G(SCH_1):GND    I20 @T6G_MB_LIB.T6G(SCH_1):PAGE31
    R1    GND @T6G_MB_LIB.T6G(SCH_1):GND    I20 @T6G_MB_LIB.T6G(SCH_1):PAGE31
    R4    GND @T6G_MB_LIB.T6G(SCH_1):GND    I20 @T6G_MB_LIB.T6G(SCH_1):PAGE31
    R6    GND @T6G_MB_LIB.T6G(SCH_1):GND    I20 @T6G_MB_LIB.T6G(SCH_1):PAGE31
    R8    GND @T6G_MB_LIB.T6G(SCH_1):GND    I20 @T6G_MB_LIB.T6G(SCH_1):PAGE31
   R11    GND @T6G_MB_LIB.T6G(SCH_1):GND    I20 @T6G_MB_LIB.T6G(SCH_1):PAGE31
   R13    GND @T6G_MB_LIB.T6G(SCH_1):GND    I20 @T6G_MB_LIB.T6G(SCH_1):PAGE31
   R15    GND @T6G_MB_LIB.T6G(SCH_1):GND    I20 @T6G_MB_LIB.T6G(SCH_1):PAGE31
   R18    GND @T6G_MB_LIB.T6G(SCH_1):GND    I20 @T6G_MB_LIB.T6G(SCH_1):PAGE31
   R20    GND @T6G_MB_LIB.T6G(SCH_1):GND    I20 @T6G_MB_LIB.T6G(SCH_1):PAGE31
   R22    GND @T6G_MB_LIB.T6G(SCH_1):GND    I20 @T6G_MB_LIB.T6G(SCH_1):PAGE31
   R25    GND @T6G_MB_LIB.T6G(SCH_1):GND    I20 @T6G_MB_LIB.T6G(SCH_1):PAGE31
   R28    GND @T6G_MB_LIB.T6G(SCH_1):GND    I20 @T6G_MB_LIB.T6G(SCH_1):PAGE31
   R31    GND @T6G_MB_LIB.T6G(SCH_1):GND    I20 @T6G_MB_LIB.T6G(SCH_1):PAGE31
   R34    GND @T6G_MB_LIB.T6G(SCH_1):GND    I20 @T6G_MB_LIB.T6G(SCH_1):PAGE31
   R35    GND @T6G_MB_LIB.T6G(SCH_1):GND    I20 @T6G_MB_LIB.T6G(SCH_1):PAGE31
   R36    GND @T6G_MB_LIB.T6G(SCH_1):GND    I20 @T6G_MB_LIB.T6G(SCH_1):PAGE31
   R40    GND @T6G_MB_LIB.T6G(SCH_1):GND    I20 @T6G_MB_LIB.T6G(SCH_1):PAGE31
   R41    GND @T6G_MB_LIB.T6G(SCH_1):GND    I20 @T6G_MB_LIB.T6G(SCH_1):PAGE31
   R42    GND @T6G_MB_LIB.T6G(SCH_1):GND    I20 @T6G_MB_LIB.T6G(SCH_1):PAGE31
   R45    GND @T6G_MB_LIB.T6G(SCH_1):GND    I20 @T6G_MB_LIB.T6G(SCH_1):PAGE31
  AB68    GND @T6G_MB_LIB.T6G(SCH_1):GND    I21 @T6G_MB_LIB.T6G(SCH_1):PAGE31
  AB71    GND @T6G_MB_LIB.T6G(SCH_1):GND    I21 @T6G_MB_LIB.T6G(SCH_1):PAGE31
  AB73    GND @T6G_MB_LIB.T6G(SCH_1):GND    I21 @T6G_MB_LIB.T6G(SCH_1):PAGE31
   AC1    GND @T6G_MB_LIB.T6G(SCH_1):GND    I21 @T6G_MB_LIB.T6G(SCH_1):PAGE31
   AC6    GND @T6G_MB_LIB.T6G(SCH_1):GND    I21 @T6G_MB_LIB.T6G(SCH_1):PAGE31
   AC8    GND @T6G_MB_LIB.T6G(SCH_1):GND    I21 @T6G_MB_LIB.T6G(SCH_1):PAGE31
  AC13    GND @T6G_MB_LIB.T6G(SCH_1):GND    I21 @T6G_MB_LIB.T6G(SCH_1):PAGE31
  AC15    GND @T6G_MB_LIB.T6G(SCH_1):GND    I21 @T6G_MB_LIB.T6G(SCH_1):PAGE31
  AC20    GND @T6G_MB_LIB.T6G(SCH_1):GND    I21 @T6G_MB_LIB.T6G(SCH_1):PAGE31
  AC22    GND @T6G_MB_LIB.T6G(SCH_1):GND    I21 @T6G_MB_LIB.T6G(SCH_1):PAGE31
  AC25    GND @T6G_MB_LIB.T6G(SCH_1):GND    I21 @T6G_MB_LIB.T6G(SCH_1):PAGE31
  AC28    GND @T6G_MB_LIB.T6G(SCH_1):GND    I21 @T6G_MB_LIB.T6G(SCH_1):PAGE31
  AC31    GND @T6G_MB_LIB.T6G(SCH_1):GND    I21 @T6G_MB_LIB.T6G(SCH_1):PAGE31
  AC34    GND @T6G_MB_LIB.T6G(SCH_1):GND    I21 @T6G_MB_LIB.T6G(SCH_1):PAGE31
  AC42    GND @T6G_MB_LIB.T6G(SCH_1):GND    I21 @T6G_MB_LIB.T6G(SCH_1):PAGE31
  AC45    GND @T6G_MB_LIB.T6G(SCH_1):GND    I21 @T6G_MB_LIB.T6G(SCH_1):PAGE31
  AC48    GND @T6G_MB_LIB.T6G(SCH_1):GND    I21 @T6G_MB_LIB.T6G(SCH_1):PAGE31
  AC51    GND @T6G_MB_LIB.T6G(SCH_1):GND    I21 @T6G_MB_LIB.T6G(SCH_1):PAGE31
  AC54    GND @T6G_MB_LIB.T6G(SCH_1):GND    I21 @T6G_MB_LIB.T6G(SCH_1):PAGE31
  AC56    GND @T6G_MB_LIB.T6G(SCH_1):GND    I21 @T6G_MB_LIB.T6G(SCH_1):PAGE31
  AC61    GND @T6G_MB_LIB.T6G(SCH_1):GND    I21 @T6G_MB_LIB.T6G(SCH_1):PAGE31
  AC63    GND @T6G_MB_LIB.T6G(SCH_1):GND    I21 @T6G_MB_LIB.T6G(SCH_1):PAGE31
  AC68    GND @T6G_MB_LIB.T6G(SCH_1):GND    I21 @T6G_MB_LIB.T6G(SCH_1):PAGE31
  AC70    GND @T6G_MB_LIB.T6G(SCH_1):GND    I21 @T6G_MB_LIB.T6G(SCH_1):PAGE31
  AC75    GND @T6G_MB_LIB.T6G(SCH_1):GND    I21 @T6G_MB_LIB.T6G(SCH_1):PAGE31
   AD3    GND @T6G_MB_LIB.T6G(SCH_1):GND    I21 @T6G_MB_LIB.T6G(SCH_1):PAGE31
   AD5    GND @T6G_MB_LIB.T6G(SCH_1):GND    I21 @T6G_MB_LIB.T6G(SCH_1):PAGE31
   AD8    GND @T6G_MB_LIB.T6G(SCH_1):GND    I21 @T6G_MB_LIB.T6G(SCH_1):PAGE31
  AD10    GND @T6G_MB_LIB.T6G(SCH_1):GND    I21 @T6G_MB_LIB.T6G(SCH_1):PAGE31
  AD12    GND @T6G_MB_LIB.T6G(SCH_1):GND    I21 @T6G_MB_LIB.T6G(SCH_1):PAGE31
  AD15    GND @T6G_MB_LIB.T6G(SCH_1):GND    I21 @T6G_MB_LIB.T6G(SCH_1):PAGE31
  AD17    GND @T6G_MB_LIB.T6G(SCH_1):GND    I21 @T6G_MB_LIB.T6G(SCH_1):PAGE31
  AD19    GND @T6G_MB_LIB.T6G(SCH_1):GND    I21 @T6G_MB_LIB.T6G(SCH_1):PAGE31
  AD23    GND @T6G_MB_LIB.T6G(SCH_1):GND    I21 @T6G_MB_LIB.T6G(SCH_1):PAGE31
  AD24    GND @T6G_MB_LIB.T6G(SCH_1):GND    I21 @T6G_MB_LIB.T6G(SCH_1):PAGE31
  AD25    GND @T6G_MB_LIB.T6G(SCH_1):GND    I21 @T6G_MB_LIB.T6G(SCH_1):PAGE31
  AD26    GND @T6G_MB_LIB.T6G(SCH_1):GND    I21 @T6G_MB_LIB.T6G(SCH_1):PAGE31
  AD27    GND @T6G_MB_LIB.T6G(SCH_1):GND    I21 @T6G_MB_LIB.T6G(SCH_1):PAGE31
  AD28    GND @T6G_MB_LIB.T6G(SCH_1):GND    I21 @T6G_MB_LIB.T6G(SCH_1):PAGE31
  AD29    GND @T6G_MB_LIB.T6G(SCH_1):GND    I21 @T6G_MB_LIB.T6G(SCH_1):PAGE31
  AD30    GND @T6G_MB_LIB.T6G(SCH_1):GND    I21 @T6G_MB_LIB.T6G(SCH_1):PAGE31
  AD32    GND @T6G_MB_LIB.T6G(SCH_1):GND    I21 @T6G_MB_LIB.T6G(SCH_1):PAGE31
  AD33    GND @T6G_MB_LIB.T6G(SCH_1):GND    I21 @T6G_MB_LIB.T6G(SCH_1):PAGE31
  AD34    GND @T6G_MB_LIB.T6G(SCH_1):GND    I21 @T6G_MB_LIB.T6G(SCH_1):PAGE31
  AD37    GND @T6G_MB_LIB.T6G(SCH_1):GND    I21 @T6G_MB_LIB.T6G(SCH_1):PAGE31
  AD39    GND @T6G_MB_LIB.T6G(SCH_1):GND    I21 @T6G_MB_LIB.T6G(SCH_1):PAGE31
  AD42    GND @T6G_MB_LIB.T6G(SCH_1):GND    I21 @T6G_MB_LIB.T6G(SCH_1):PAGE31
  AD43    GND @T6G_MB_LIB.T6G(SCH_1):GND    I21 @T6G_MB_LIB.T6G(SCH_1):PAGE31
  AD44    GND @T6G_MB_LIB.T6G(SCH_1):GND    I21 @T6G_MB_LIB.T6G(SCH_1):PAGE31
  AD45    GND @T6G_MB_LIB.T6G(SCH_1):GND    I21 @T6G_MB_LIB.T6G(SCH_1):PAGE31
  AD46    GND @T6G_MB_LIB.T6G(SCH_1):GND    I21 @T6G_MB_LIB.T6G(SCH_1):PAGE31
  AD47    GND @T6G_MB_LIB.T6G(SCH_1):GND    I21 @T6G_MB_LIB.T6G(SCH_1):PAGE31
  AD48    GND @T6G_MB_LIB.T6G(SCH_1):GND    I21 @T6G_MB_LIB.T6G(SCH_1):PAGE31
   T66    GND @T6G_MB_LIB.T6G(SCH_1):GND    I21 @T6G_MB_LIB.T6G(SCH_1):PAGE31
   T68    GND @T6G_MB_LIB.T6G(SCH_1):GND    I21 @T6G_MB_LIB.T6G(SCH_1):PAGE31
   T71    GND @T6G_MB_LIB.T6G(SCH_1):GND    I21 @T6G_MB_LIB.T6G(SCH_1):PAGE31
   T73    GND @T6G_MB_LIB.T6G(SCH_1):GND    I21 @T6G_MB_LIB.T6G(SCH_1):PAGE31
    U1    GND @T6G_MB_LIB.T6G(SCH_1):GND    I21 @T6G_MB_LIB.T6G(SCH_1):PAGE31
    U6    GND @T6G_MB_LIB.T6G(SCH_1):GND    I21 @T6G_MB_LIB.T6G(SCH_1):PAGE31
    U8    GND @T6G_MB_LIB.T6G(SCH_1):GND    I21 @T6G_MB_LIB.T6G(SCH_1):PAGE31
   U13    GND @T6G_MB_LIB.T6G(SCH_1):GND    I21 @T6G_MB_LIB.T6G(SCH_1):PAGE31
   U15    GND @T6G_MB_LIB.T6G(SCH_1):GND    I21 @T6G_MB_LIB.T6G(SCH_1):PAGE31
   U20    GND @T6G_MB_LIB.T6G(SCH_1):GND    I21 @T6G_MB_LIB.T6G(SCH_1):PAGE31
   U22    GND @T6G_MB_LIB.T6G(SCH_1):GND    I21 @T6G_MB_LIB.T6G(SCH_1):PAGE31
   U25    GND @T6G_MB_LIB.T6G(SCH_1):GND    I21 @T6G_MB_LIB.T6G(SCH_1):PAGE31
   U28    GND @T6G_MB_LIB.T6G(SCH_1):GND    I21 @T6G_MB_LIB.T6G(SCH_1):PAGE31
   U31    GND @T6G_MB_LIB.T6G(SCH_1):GND    I21 @T6G_MB_LIB.T6G(SCH_1):PAGE31
   U34    GND @T6G_MB_LIB.T6G(SCH_1):GND    I21 @T6G_MB_LIB.T6G(SCH_1):PAGE31
   U42    GND @T6G_MB_LIB.T6G(SCH_1):GND    I21 @T6G_MB_LIB.T6G(SCH_1):PAGE31
   U45    GND @T6G_MB_LIB.T6G(SCH_1):GND    I21 @T6G_MB_LIB.T6G(SCH_1):PAGE31
   U48    GND @T6G_MB_LIB.T6G(SCH_1):GND    I21 @T6G_MB_LIB.T6G(SCH_1):PAGE31
   U51    GND @T6G_MB_LIB.T6G(SCH_1):GND    I21 @T6G_MB_LIB.T6G(SCH_1):PAGE31
   U54    GND @T6G_MB_LIB.T6G(SCH_1):GND    I21 @T6G_MB_LIB.T6G(SCH_1):PAGE31
   U56    GND @T6G_MB_LIB.T6G(SCH_1):GND    I21 @T6G_MB_LIB.T6G(SCH_1):PAGE31
   U61    GND @T6G_MB_LIB.T6G(SCH_1):GND    I21 @T6G_MB_LIB.T6G(SCH_1):PAGE31
   U63    GND @T6G_MB_LIB.T6G(SCH_1):GND    I21 @T6G_MB_LIB.T6G(SCH_1):PAGE31
   U68    GND @T6G_MB_LIB.T6G(SCH_1):GND    I21 @T6G_MB_LIB.T6G(SCH_1):PAGE31
   U70    GND @T6G_MB_LIB.T6G(SCH_1):GND    I21 @T6G_MB_LIB.T6G(SCH_1):PAGE31
   U75    GND @T6G_MB_LIB.T6G(SCH_1):GND    I21 @T6G_MB_LIB.T6G(SCH_1):PAGE31
    V3    GND @T6G_MB_LIB.T6G(SCH_1):GND    I21 @T6G_MB_LIB.T6G(SCH_1):PAGE31
    V5    GND @T6G_MB_LIB.T6G(SCH_1):GND    I21 @T6G_MB_LIB.T6G(SCH_1):PAGE31
    V8    GND @T6G_MB_LIB.T6G(SCH_1):GND    I21 @T6G_MB_LIB.T6G(SCH_1):PAGE31
   V10    GND @T6G_MB_LIB.T6G(SCH_1):GND    I21 @T6G_MB_LIB.T6G(SCH_1):PAGE31
   V12    GND @T6G_MB_LIB.T6G(SCH_1):GND    I21 @T6G_MB_LIB.T6G(SCH_1):PAGE31
   V15    GND @T6G_MB_LIB.T6G(SCH_1):GND    I21 @T6G_MB_LIB.T6G(SCH_1):PAGE31
   V17    GND @T6G_MB_LIB.T6G(SCH_1):GND    I21 @T6G_MB_LIB.T6G(SCH_1):PAGE31
   V19    GND @T6G_MB_LIB.T6G(SCH_1):GND    I21 @T6G_MB_LIB.T6G(SCH_1):PAGE31
   V23    GND @T6G_MB_LIB.T6G(SCH_1):GND    I21 @T6G_MB_LIB.T6G(SCH_1):PAGE31
   V24    GND @T6G_MB_LIB.T6G(SCH_1):GND    I21 @T6G_MB_LIB.T6G(SCH_1):PAGE31
   V25    GND @T6G_MB_LIB.T6G(SCH_1):GND    I21 @T6G_MB_LIB.T6G(SCH_1):PAGE31
   V26    GND @T6G_MB_LIB.T6G(SCH_1):GND    I21 @T6G_MB_LIB.T6G(SCH_1):PAGE31
   V28    GND @T6G_MB_LIB.T6G(SCH_1):GND    I21 @T6G_MB_LIB.T6G(SCH_1):PAGE31
   V29    GND @T6G_MB_LIB.T6G(SCH_1):GND    I21 @T6G_MB_LIB.T6G(SCH_1):PAGE31
   V30    GND @T6G_MB_LIB.T6G(SCH_1):GND    I21 @T6G_MB_LIB.T6G(SCH_1):PAGE31
   V31    GND @T6G_MB_LIB.T6G(SCH_1):GND    I21 @T6G_MB_LIB.T6G(SCH_1):PAGE31
   V32    GND @T6G_MB_LIB.T6G(SCH_1):GND    I21 @T6G_MB_LIB.T6G(SCH_1):PAGE31
   V33    GND @T6G_MB_LIB.T6G(SCH_1):GND    I21 @T6G_MB_LIB.T6G(SCH_1):PAGE31
   V34    GND @T6G_MB_LIB.T6G(SCH_1):GND    I21 @T6G_MB_LIB.T6G(SCH_1):PAGE31
   V37    GND @T6G_MB_LIB.T6G(SCH_1):GND    I21 @T6G_MB_LIB.T6G(SCH_1):PAGE31
   V39    GND @T6G_MB_LIB.T6G(SCH_1):GND    I21 @T6G_MB_LIB.T6G(SCH_1):PAGE31
   V42    GND @T6G_MB_LIB.T6G(SCH_1):GND    I21 @T6G_MB_LIB.T6G(SCH_1):PAGE31
   V43    GND @T6G_MB_LIB.T6G(SCH_1):GND    I21 @T6G_MB_LIB.T6G(SCH_1):PAGE31
   V44    GND @T6G_MB_LIB.T6G(SCH_1):GND    I21 @T6G_MB_LIB.T6G(SCH_1):PAGE31
   V45    GND @T6G_MB_LIB.T6G(SCH_1):GND    I21 @T6G_MB_LIB.T6G(SCH_1):PAGE31
   V46    GND @T6G_MB_LIB.T6G(SCH_1):GND    I21 @T6G_MB_LIB.T6G(SCH_1):PAGE31
   V47    GND @T6G_MB_LIB.T6G(SCH_1):GND    I21 @T6G_MB_LIB.T6G(SCH_1):PAGE31
   V48    GND @T6G_MB_LIB.T6G(SCH_1):GND    I21 @T6G_MB_LIB.T6G(SCH_1):PAGE31
   V49    GND @T6G_MB_LIB.T6G(SCH_1):GND    I21 @T6G_MB_LIB.T6G(SCH_1):PAGE31
   V50    GND @T6G_MB_LIB.T6G(SCH_1):GND    I21 @T6G_MB_LIB.T6G(SCH_1):PAGE31
   V51    GND @T6G_MB_LIB.T6G(SCH_1):GND    I21 @T6G_MB_LIB.T6G(SCH_1):PAGE31
   V52    GND @T6G_MB_LIB.T6G(SCH_1):GND    I21 @T6G_MB_LIB.T6G(SCH_1):PAGE31
   V53    GND @T6G_MB_LIB.T6G(SCH_1):GND    I21 @T6G_MB_LIB.T6G(SCH_1):PAGE31
   V57    GND @T6G_MB_LIB.T6G(SCH_1):GND    I21 @T6G_MB_LIB.T6G(SCH_1):PAGE31
   V59    GND @T6G_MB_LIB.T6G(SCH_1):GND    I21 @T6G_MB_LIB.T6G(SCH_1):PAGE31
   V61    GND @T6G_MB_LIB.T6G(SCH_1):GND    I21 @T6G_MB_LIB.T6G(SCH_1):PAGE31
   V64    GND @T6G_MB_LIB.T6G(SCH_1):GND    I21 @T6G_MB_LIB.T6G(SCH_1):PAGE31
   V66    GND @T6G_MB_LIB.T6G(SCH_1):GND    I21 @T6G_MB_LIB.T6G(SCH_1):PAGE31
   V71    GND @T6G_MB_LIB.T6G(SCH_1):GND    I21 @T6G_MB_LIB.T6G(SCH_1):PAGE31
   V73    GND @T6G_MB_LIB.T6G(SCH_1):GND    I21 @T6G_MB_LIB.T6G(SCH_1):PAGE31
    W1    GND @T6G_MB_LIB.T6G(SCH_1):GND    I21 @T6G_MB_LIB.T6G(SCH_1):PAGE31
    W4    GND @T6G_MB_LIB.T6G(SCH_1):GND    I21 @T6G_MB_LIB.T6G(SCH_1):PAGE31
    W6    GND @T6G_MB_LIB.T6G(SCH_1):GND    I21 @T6G_MB_LIB.T6G(SCH_1):PAGE31
    W8    GND @T6G_MB_LIB.T6G(SCH_1):GND    I21 @T6G_MB_LIB.T6G(SCH_1):PAGE31
   W11    GND @T6G_MB_LIB.T6G(SCH_1):GND    I21 @T6G_MB_LIB.T6G(SCH_1):PAGE31
   W13    GND @T6G_MB_LIB.T6G(SCH_1):GND    I21 @T6G_MB_LIB.T6G(SCH_1):PAGE31
   W15    GND @T6G_MB_LIB.T6G(SCH_1):GND    I21 @T6G_MB_LIB.T6G(SCH_1):PAGE31
   W18    GND @T6G_MB_LIB.T6G(SCH_1):GND    I21 @T6G_MB_LIB.T6G(SCH_1):PAGE31
   W20    GND @T6G_MB_LIB.T6G(SCH_1):GND    I21 @T6G_MB_LIB.T6G(SCH_1):PAGE31
   W22    GND @T6G_MB_LIB.T6G(SCH_1):GND    I21 @T6G_MB_LIB.T6G(SCH_1):PAGE31
   W25    GND @T6G_MB_LIB.T6G(SCH_1):GND    I21 @T6G_MB_LIB.T6G(SCH_1):PAGE31
   W28    GND @T6G_MB_LIB.T6G(SCH_1):GND    I21 @T6G_MB_LIB.T6G(SCH_1):PAGE31
   W34    GND @T6G_MB_LIB.T6G(SCH_1):GND    I21 @T6G_MB_LIB.T6G(SCH_1):PAGE31
   W35    GND @T6G_MB_LIB.T6G(SCH_1):GND    I21 @T6G_MB_LIB.T6G(SCH_1):PAGE31
   W36    GND @T6G_MB_LIB.T6G(SCH_1):GND    I21 @T6G_MB_LIB.T6G(SCH_1):PAGE31
   W40    GND @T6G_MB_LIB.T6G(SCH_1):GND    I21 @T6G_MB_LIB.T6G(SCH_1):PAGE31
   W41    GND @T6G_MB_LIB.T6G(SCH_1):GND    I21 @T6G_MB_LIB.T6G(SCH_1):PAGE31
   W42    GND @T6G_MB_LIB.T6G(SCH_1):GND    I21 @T6G_MB_LIB.T6G(SCH_1):PAGE31
   W45    GND @T6G_MB_LIB.T6G(SCH_1):GND    I21 @T6G_MB_LIB.T6G(SCH_1):PAGE31
   W48    GND @T6G_MB_LIB.T6G(SCH_1):GND    I21 @T6G_MB_LIB.T6G(SCH_1):PAGE31
   W51    GND @T6G_MB_LIB.T6G(SCH_1):GND    I21 @T6G_MB_LIB.T6G(SCH_1):PAGE31
   W54    GND @T6G_MB_LIB.T6G(SCH_1):GND    I21 @T6G_MB_LIB.T6G(SCH_1):PAGE31
   W56    GND @T6G_MB_LIB.T6G(SCH_1):GND    I21 @T6G_MB_LIB.T6G(SCH_1):PAGE31
   W58    GND @T6G_MB_LIB.T6G(SCH_1):GND    I21 @T6G_MB_LIB.T6G(SCH_1):PAGE31
   W61    GND @T6G_MB_LIB.T6G(SCH_1):GND    I21 @T6G_MB_LIB.T6G(SCH_1):PAGE31
   W63    GND @T6G_MB_LIB.T6G(SCH_1):GND    I21 @T6G_MB_LIB.T6G(SCH_1):PAGE31
   W65    GND @T6G_MB_LIB.T6G(SCH_1):GND    I21 @T6G_MB_LIB.T6G(SCH_1):PAGE31
   W68    GND @T6G_MB_LIB.T6G(SCH_1):GND    I21 @T6G_MB_LIB.T6G(SCH_1):PAGE31
   W70    GND @T6G_MB_LIB.T6G(SCH_1):GND    I21 @T6G_MB_LIB.T6G(SCH_1):PAGE31
   W72    GND @T6G_MB_LIB.T6G(SCH_1):GND    I21 @T6G_MB_LIB.T6G(SCH_1):PAGE31
   W75    GND @T6G_MB_LIB.T6G(SCH_1):GND    I21 @T6G_MB_LIB.T6G(SCH_1):PAGE31
    Y3    GND @T6G_MB_LIB.T6G(SCH_1):GND    I21 @T6G_MB_LIB.T6G(SCH_1):PAGE31
    Y8    GND @T6G_MB_LIB.T6G(SCH_1):GND    I21 @T6G_MB_LIB.T6G(SCH_1):PAGE31
   Y10    GND @T6G_MB_LIB.T6G(SCH_1):GND    I21 @T6G_MB_LIB.T6G(SCH_1):PAGE31
   Y15    GND @T6G_MB_LIB.T6G(SCH_1):GND    I21 @T6G_MB_LIB.T6G(SCH_1):PAGE31
   Y17    GND @T6G_MB_LIB.T6G(SCH_1):GND    I21 @T6G_MB_LIB.T6G(SCH_1):PAGE31
   Y22    GND @T6G_MB_LIB.T6G(SCH_1):GND    I21 @T6G_MB_LIB.T6G(SCH_1):PAGE31
   Y23    GND @T6G_MB_LIB.T6G(SCH_1):GND    I21 @T6G_MB_LIB.T6G(SCH_1):PAGE31
   Y24    GND @T6G_MB_LIB.T6G(SCH_1):GND    I21 @T6G_MB_LIB.T6G(SCH_1):PAGE31
   Y25    GND @T6G_MB_LIB.T6G(SCH_1):GND    I21 @T6G_MB_LIB.T6G(SCH_1):PAGE31
   Y26    GND @T6G_MB_LIB.T6G(SCH_1):GND    I21 @T6G_MB_LIB.T6G(SCH_1):PAGE31
   Y27    GND @T6G_MB_LIB.T6G(SCH_1):GND    I21 @T6G_MB_LIB.T6G(SCH_1):PAGE31
   Y28    GND @T6G_MB_LIB.T6G(SCH_1):GND    I21 @T6G_MB_LIB.T6G(SCH_1):PAGE31
   Y31    GND @T6G_MB_LIB.T6G(SCH_1):GND    I21 @T6G_MB_LIB.T6G(SCH_1):PAGE31
   Y32    GND @T6G_MB_LIB.T6G(SCH_1):GND    I21 @T6G_MB_LIB.T6G(SCH_1):PAGE31
   Y33    GND @T6G_MB_LIB.T6G(SCH_1):GND    I21 @T6G_MB_LIB.T6G(SCH_1):PAGE31
   Y34    GND @T6G_MB_LIB.T6G(SCH_1):GND    I21 @T6G_MB_LIB.T6G(SCH_1):PAGE31
   Y37    GND @T6G_MB_LIB.T6G(SCH_1):GND    I21 @T6G_MB_LIB.T6G(SCH_1):PAGE31
   Y39    GND @T6G_MB_LIB.T6G(SCH_1):GND    I21 @T6G_MB_LIB.T6G(SCH_1):PAGE31
   Y42    GND @T6G_MB_LIB.T6G(SCH_1):GND    I21 @T6G_MB_LIB.T6G(SCH_1):PAGE31
   Y43    GND @T6G_MB_LIB.T6G(SCH_1):GND    I21 @T6G_MB_LIB.T6G(SCH_1):PAGE31
   Y44    GND @T6G_MB_LIB.T6G(SCH_1):GND    I21 @T6G_MB_LIB.T6G(SCH_1):PAGE31
   Y45    GND @T6G_MB_LIB.T6G(SCH_1):GND    I21 @T6G_MB_LIB.T6G(SCH_1):PAGE31
   Y48    GND @T6G_MB_LIB.T6G(SCH_1):GND    I21 @T6G_MB_LIB.T6G(SCH_1):PAGE31
   Y49    GND @T6G_MB_LIB.T6G(SCH_1):GND    I21 @T6G_MB_LIB.T6G(SCH_1):PAGE31
   Y50    GND @T6G_MB_LIB.T6G(SCH_1):GND    I21 @T6G_MB_LIB.T6G(SCH_1):PAGE31
   Y51    GND @T6G_MB_LIB.T6G(SCH_1):GND    I21 @T6G_MB_LIB.T6G(SCH_1):PAGE31
   Y52    GND @T6G_MB_LIB.T6G(SCH_1):GND    I21 @T6G_MB_LIB.T6G(SCH_1):PAGE31
   Y53    GND @T6G_MB_LIB.T6G(SCH_1):GND    I21 @T6G_MB_LIB.T6G(SCH_1):PAGE31
   Y54    GND @T6G_MB_LIB.T6G(SCH_1):GND    I21 @T6G_MB_LIB.T6G(SCH_1):PAGE31
   Y59    GND @T6G_MB_LIB.T6G(SCH_1):GND    I21 @T6G_MB_LIB.T6G(SCH_1):PAGE31
   Y61    GND @T6G_MB_LIB.T6G(SCH_1):GND    I21 @T6G_MB_LIB.T6G(SCH_1):PAGE31
   Y66    GND @T6G_MB_LIB.T6G(SCH_1):GND    I21 @T6G_MB_LIB.T6G(SCH_1):PAGE31
   Y68    GND @T6G_MB_LIB.T6G(SCH_1):GND    I21 @T6G_MB_LIB.T6G(SCH_1):PAGE31
   Y73    GND @T6G_MB_LIB.T6G(SCH_1):GND    I21 @T6G_MB_LIB.T6G(SCH_1):PAGE31
   AA1    GND @T6G_MB_LIB.T6G(SCH_1):GND    I21 @T6G_MB_LIB.T6G(SCH_1):PAGE31
   AA4    GND @T6G_MB_LIB.T6G(SCH_1):GND    I21 @T6G_MB_LIB.T6G(SCH_1):PAGE31
   AA6    GND @T6G_MB_LIB.T6G(SCH_1):GND    I21 @T6G_MB_LIB.T6G(SCH_1):PAGE31
   AA8    GND @T6G_MB_LIB.T6G(SCH_1):GND    I21 @T6G_MB_LIB.T6G(SCH_1):PAGE31
  AA11    GND @T6G_MB_LIB.T6G(SCH_1):GND    I21 @T6G_MB_LIB.T6G(SCH_1):PAGE31
  AA13    GND @T6G_MB_LIB.T6G(SCH_1):GND    I21 @T6G_MB_LIB.T6G(SCH_1):PAGE31
  AA15    GND @T6G_MB_LIB.T6G(SCH_1):GND    I21 @T6G_MB_LIB.T6G(SCH_1):PAGE31
  AA18    GND @T6G_MB_LIB.T6G(SCH_1):GND    I21 @T6G_MB_LIB.T6G(SCH_1):PAGE31
  AA20    GND @T6G_MB_LIB.T6G(SCH_1):GND    I21 @T6G_MB_LIB.T6G(SCH_1):PAGE31
  AA31    GND @T6G_MB_LIB.T6G(SCH_1):GND    I21 @T6G_MB_LIB.T6G(SCH_1):PAGE31
  AA34    GND @T6G_MB_LIB.T6G(SCH_1):GND    I21 @T6G_MB_LIB.T6G(SCH_1):PAGE31
  AA35    GND @T6G_MB_LIB.T6G(SCH_1):GND    I21 @T6G_MB_LIB.T6G(SCH_1):PAGE31
  AA36    GND @T6G_MB_LIB.T6G(SCH_1):GND    I21 @T6G_MB_LIB.T6G(SCH_1):PAGE31
  AA40    GND @T6G_MB_LIB.T6G(SCH_1):GND    I21 @T6G_MB_LIB.T6G(SCH_1):PAGE31
  AA41    GND @T6G_MB_LIB.T6G(SCH_1):GND    I21 @T6G_MB_LIB.T6G(SCH_1):PAGE31
  AA45    GND @T6G_MB_LIB.T6G(SCH_1):GND    I21 @T6G_MB_LIB.T6G(SCH_1):PAGE31
  AA56    GND @T6G_MB_LIB.T6G(SCH_1):GND    I21 @T6G_MB_LIB.T6G(SCH_1):PAGE31
  AA58    GND @T6G_MB_LIB.T6G(SCH_1):GND    I21 @T6G_MB_LIB.T6G(SCH_1):PAGE31
  AA61    GND @T6G_MB_LIB.T6G(SCH_1):GND    I21 @T6G_MB_LIB.T6G(SCH_1):PAGE31
  AA63    GND @T6G_MB_LIB.T6G(SCH_1):GND    I21 @T6G_MB_LIB.T6G(SCH_1):PAGE31
  AA65    GND @T6G_MB_LIB.T6G(SCH_1):GND    I21 @T6G_MB_LIB.T6G(SCH_1):PAGE31
  AA68    GND @T6G_MB_LIB.T6G(SCH_1):GND    I21 @T6G_MB_LIB.T6G(SCH_1):PAGE31
  AA70    GND @T6G_MB_LIB.T6G(SCH_1):GND    I21 @T6G_MB_LIB.T6G(SCH_1):PAGE31
  AA75    GND @T6G_MB_LIB.T6G(SCH_1):GND    I21 @T6G_MB_LIB.T6G(SCH_1):PAGE31
   AB3    GND @T6G_MB_LIB.T6G(SCH_1):GND    I21 @T6G_MB_LIB.T6G(SCH_1):PAGE31
   AB5    GND @T6G_MB_LIB.T6G(SCH_1):GND    I21 @T6G_MB_LIB.T6G(SCH_1):PAGE31
   AB8    GND @T6G_MB_LIB.T6G(SCH_1):GND    I21 @T6G_MB_LIB.T6G(SCH_1):PAGE31
  AB10    GND @T6G_MB_LIB.T6G(SCH_1):GND    I21 @T6G_MB_LIB.T6G(SCH_1):PAGE31
  AB12    GND @T6G_MB_LIB.T6G(SCH_1):GND    I21 @T6G_MB_LIB.T6G(SCH_1):PAGE31
  AB15    GND @T6G_MB_LIB.T6G(SCH_1):GND    I21 @T6G_MB_LIB.T6G(SCH_1):PAGE31
  AB17    GND @T6G_MB_LIB.T6G(SCH_1):GND    I21 @T6G_MB_LIB.T6G(SCH_1):PAGE31
  AB19    GND @T6G_MB_LIB.T6G(SCH_1):GND    I21 @T6G_MB_LIB.T6G(SCH_1):PAGE31
  AB22    GND @T6G_MB_LIB.T6G(SCH_1):GND    I21 @T6G_MB_LIB.T6G(SCH_1):PAGE31
  AB25    GND @T6G_MB_LIB.T6G(SCH_1):GND    I21 @T6G_MB_LIB.T6G(SCH_1):PAGE31
  AB28    GND @T6G_MB_LIB.T6G(SCH_1):GND    I21 @T6G_MB_LIB.T6G(SCH_1):PAGE31
  AB31    GND @T6G_MB_LIB.T6G(SCH_1):GND    I21 @T6G_MB_LIB.T6G(SCH_1):PAGE31
  AB34    GND @T6G_MB_LIB.T6G(SCH_1):GND    I21 @T6G_MB_LIB.T6G(SCH_1):PAGE31
  AB37    GND @T6G_MB_LIB.T6G(SCH_1):GND    I21 @T6G_MB_LIB.T6G(SCH_1):PAGE31
  AB39    GND @T6G_MB_LIB.T6G(SCH_1):GND    I21 @T6G_MB_LIB.T6G(SCH_1):PAGE31
  AB42    GND @T6G_MB_LIB.T6G(SCH_1):GND    I21 @T6G_MB_LIB.T6G(SCH_1):PAGE31
  AB45    GND @T6G_MB_LIB.T6G(SCH_1):GND    I21 @T6G_MB_LIB.T6G(SCH_1):PAGE31
  AB48    GND @T6G_MB_LIB.T6G(SCH_1):GND    I21 @T6G_MB_LIB.T6G(SCH_1):PAGE31
  AB51    GND @T6G_MB_LIB.T6G(SCH_1):GND    I21 @T6G_MB_LIB.T6G(SCH_1):PAGE31
  AB54    GND @T6G_MB_LIB.T6G(SCH_1):GND    I21 @T6G_MB_LIB.T6G(SCH_1):PAGE31
  AB57    GND @T6G_MB_LIB.T6G(SCH_1):GND    I21 @T6G_MB_LIB.T6G(SCH_1):PAGE31
  AB59    GND @T6G_MB_LIB.T6G(SCH_1):GND    I21 @T6G_MB_LIB.T6G(SCH_1):PAGE31
  AB61    GND @T6G_MB_LIB.T6G(SCH_1):GND    I21 @T6G_MB_LIB.T6G(SCH_1):PAGE31
  AB64    GND @T6G_MB_LIB.T6G(SCH_1):GND    I21 @T6G_MB_LIB.T6G(SCH_1):PAGE31
  AB66    GND @T6G_MB_LIB.T6G(SCH_1):GND    I21 @T6G_MB_LIB.T6G(SCH_1):PAGE31
  AK10    GND @T6G_MB_LIB.T6G(SCH_1):GND    I22 @T6G_MB_LIB.T6G(SCH_1):PAGE31
  AK12    GND @T6G_MB_LIB.T6G(SCH_1):GND    I22 @T6G_MB_LIB.T6G(SCH_1):PAGE31
  AK15    GND @T6G_MB_LIB.T6G(SCH_1):GND    I22 @T6G_MB_LIB.T6G(SCH_1):PAGE31
  AK17    GND @T6G_MB_LIB.T6G(SCH_1):GND    I22 @T6G_MB_LIB.T6G(SCH_1):PAGE31
  AK19    GND @T6G_MB_LIB.T6G(SCH_1):GND    I22 @T6G_MB_LIB.T6G(SCH_1):PAGE31
  AK22    GND @T6G_MB_LIB.T6G(SCH_1):GND    I22 @T6G_MB_LIB.T6G(SCH_1):PAGE31
  AK25    GND @T6G_MB_LIB.T6G(SCH_1):GND    I22 @T6G_MB_LIB.T6G(SCH_1):PAGE31
  AK28    GND @T6G_MB_LIB.T6G(SCH_1):GND    I22 @T6G_MB_LIB.T6G(SCH_1):PAGE31
  AK31    GND @T6G_MB_LIB.T6G(SCH_1):GND    I22 @T6G_MB_LIB.T6G(SCH_1):PAGE31
  AK34    GND @T6G_MB_LIB.T6G(SCH_1):GND    I22 @T6G_MB_LIB.T6G(SCH_1):PAGE31
  AK37    GND @T6G_MB_LIB.T6G(SCH_1):GND    I22 @T6G_MB_LIB.T6G(SCH_1):PAGE31
  AK39    GND @T6G_MB_LIB.T6G(SCH_1):GND    I22 @T6G_MB_LIB.T6G(SCH_1):PAGE31
  AK42    GND @T6G_MB_LIB.T6G(SCH_1):GND    I22 @T6G_MB_LIB.T6G(SCH_1):PAGE31
  AK45    GND @T6G_MB_LIB.T6G(SCH_1):GND    I22 @T6G_MB_LIB.T6G(SCH_1):PAGE31
  AK48    GND @T6G_MB_LIB.T6G(SCH_1):GND    I22 @T6G_MB_LIB.T6G(SCH_1):PAGE31
  AK51    GND @T6G_MB_LIB.T6G(SCH_1):GND    I22 @T6G_MB_LIB.T6G(SCH_1):PAGE31
  AK54    GND @T6G_MB_LIB.T6G(SCH_1):GND    I22 @T6G_MB_LIB.T6G(SCH_1):PAGE31
  AK57    GND @T6G_MB_LIB.T6G(SCH_1):GND    I22 @T6G_MB_LIB.T6G(SCH_1):PAGE31
  AK59    GND @T6G_MB_LIB.T6G(SCH_1):GND    I22 @T6G_MB_LIB.T6G(SCH_1):PAGE31
  AK61    GND @T6G_MB_LIB.T6G(SCH_1):GND    I22 @T6G_MB_LIB.T6G(SCH_1):PAGE31
  AK64    GND @T6G_MB_LIB.T6G(SCH_1):GND    I22 @T6G_MB_LIB.T6G(SCH_1):PAGE31
  AK66    GND @T6G_MB_LIB.T6G(SCH_1):GND    I22 @T6G_MB_LIB.T6G(SCH_1):PAGE31
  AK68    GND @T6G_MB_LIB.T6G(SCH_1):GND    I22 @T6G_MB_LIB.T6G(SCH_1):PAGE31
  AK71    GND @T6G_MB_LIB.T6G(SCH_1):GND    I22 @T6G_MB_LIB.T6G(SCH_1):PAGE31
  AK73    GND @T6G_MB_LIB.T6G(SCH_1):GND    I22 @T6G_MB_LIB.T6G(SCH_1):PAGE31
   AL1    GND @T6G_MB_LIB.T6G(SCH_1):GND    I22 @T6G_MB_LIB.T6G(SCH_1):PAGE31
   AL4    GND @T6G_MB_LIB.T6G(SCH_1):GND    I22 @T6G_MB_LIB.T6G(SCH_1):PAGE31
   AL6    GND @T6G_MB_LIB.T6G(SCH_1):GND    I22 @T6G_MB_LIB.T6G(SCH_1):PAGE31
   AL8    GND @T6G_MB_LIB.T6G(SCH_1):GND    I22 @T6G_MB_LIB.T6G(SCH_1):PAGE31
  AL11    GND @T6G_MB_LIB.T6G(SCH_1):GND    I22 @T6G_MB_LIB.T6G(SCH_1):PAGE31
  AL13    GND @T6G_MB_LIB.T6G(SCH_1):GND    I22 @T6G_MB_LIB.T6G(SCH_1):PAGE31
  AL15    GND @T6G_MB_LIB.T6G(SCH_1):GND    I22 @T6G_MB_LIB.T6G(SCH_1):PAGE31
  AL18    GND @T6G_MB_LIB.T6G(SCH_1):GND    I22 @T6G_MB_LIB.T6G(SCH_1):PAGE31
  AL20    GND @T6G_MB_LIB.T6G(SCH_1):GND    I22 @T6G_MB_LIB.T6G(SCH_1):PAGE31
  AL22    GND @T6G_MB_LIB.T6G(SCH_1):GND    I22 @T6G_MB_LIB.T6G(SCH_1):PAGE31
  AL25    GND @T6G_MB_LIB.T6G(SCH_1):GND    I22 @T6G_MB_LIB.T6G(SCH_1):PAGE31
  AL28    GND @T6G_MB_LIB.T6G(SCH_1):GND    I22 @T6G_MB_LIB.T6G(SCH_1):PAGE31
  AL31    GND @T6G_MB_LIB.T6G(SCH_1):GND    I22 @T6G_MB_LIB.T6G(SCH_1):PAGE31
  AL34    GND @T6G_MB_LIB.T6G(SCH_1):GND    I22 @T6G_MB_LIB.T6G(SCH_1):PAGE31
  AL42    GND @T6G_MB_LIB.T6G(SCH_1):GND    I22 @T6G_MB_LIB.T6G(SCH_1):PAGE31
  AL45    GND @T6G_MB_LIB.T6G(SCH_1):GND    I22 @T6G_MB_LIB.T6G(SCH_1):PAGE31
  AL48    GND @T6G_MB_LIB.T6G(SCH_1):GND    I22 @T6G_MB_LIB.T6G(SCH_1):PAGE31
  AL51    GND @T6G_MB_LIB.T6G(SCH_1):GND    I22 @T6G_MB_LIB.T6G(SCH_1):PAGE31
  AL54    GND @T6G_MB_LIB.T6G(SCH_1):GND    I22 @T6G_MB_LIB.T6G(SCH_1):PAGE31
  AL56    GND @T6G_MB_LIB.T6G(SCH_1):GND    I22 @T6G_MB_LIB.T6G(SCH_1):PAGE31
  AL58    GND @T6G_MB_LIB.T6G(SCH_1):GND    I22 @T6G_MB_LIB.T6G(SCH_1):PAGE31
  AL61    GND @T6G_MB_LIB.T6G(SCH_1):GND    I22 @T6G_MB_LIB.T6G(SCH_1):PAGE31
  AL63    GND @T6G_MB_LIB.T6G(SCH_1):GND    I22 @T6G_MB_LIB.T6G(SCH_1):PAGE31
  AL65    GND @T6G_MB_LIB.T6G(SCH_1):GND    I22 @T6G_MB_LIB.T6G(SCH_1):PAGE31
  AL68    GND @T6G_MB_LIB.T6G(SCH_1):GND    I22 @T6G_MB_LIB.T6G(SCH_1):PAGE31
  AL70    GND @T6G_MB_LIB.T6G(SCH_1):GND    I22 @T6G_MB_LIB.T6G(SCH_1):PAGE31
  AL72    GND @T6G_MB_LIB.T6G(SCH_1):GND    I22 @T6G_MB_LIB.T6G(SCH_1):PAGE31
  AL75    GND @T6G_MB_LIB.T6G(SCH_1):GND    I22 @T6G_MB_LIB.T6G(SCH_1):PAGE31
   AM3    GND @T6G_MB_LIB.T6G(SCH_1):GND    I22 @T6G_MB_LIB.T6G(SCH_1):PAGE31
   AM8    GND @T6G_MB_LIB.T6G(SCH_1):GND    I22 @T6G_MB_LIB.T6G(SCH_1):PAGE31
  AM10    GND @T6G_MB_LIB.T6G(SCH_1):GND    I22 @T6G_MB_LIB.T6G(SCH_1):PAGE31
  AM15    GND @T6G_MB_LIB.T6G(SCH_1):GND    I22 @T6G_MB_LIB.T6G(SCH_1):PAGE31
  AM17    GND @T6G_MB_LIB.T6G(SCH_1):GND    I22 @T6G_MB_LIB.T6G(SCH_1):PAGE31
  AM23    GND @T6G_MB_LIB.T6G(SCH_1):GND    I22 @T6G_MB_LIB.T6G(SCH_1):PAGE31
  AM24    GND @T6G_MB_LIB.T6G(SCH_1):GND    I22 @T6G_MB_LIB.T6G(SCH_1):PAGE31
  AM25    GND @T6G_MB_LIB.T6G(SCH_1):GND    I22 @T6G_MB_LIB.T6G(SCH_1):PAGE31
  AM26    GND @T6G_MB_LIB.T6G(SCH_1):GND    I22 @T6G_MB_LIB.T6G(SCH_1):PAGE31
  AM27    GND @T6G_MB_LIB.T6G(SCH_1):GND    I22 @T6G_MB_LIB.T6G(SCH_1):PAGE31
  AM28    GND @T6G_MB_LIB.T6G(SCH_1):GND    I22 @T6G_MB_LIB.T6G(SCH_1):PAGE31
  AM29    GND @T6G_MB_LIB.T6G(SCH_1):GND    I22 @T6G_MB_LIB.T6G(SCH_1):PAGE31
  AM30    GND @T6G_MB_LIB.T6G(SCH_1):GND    I22 @T6G_MB_LIB.T6G(SCH_1):PAGE31
  AM31    GND @T6G_MB_LIB.T6G(SCH_1):GND    I22 @T6G_MB_LIB.T6G(SCH_1):PAGE31
  AM32    GND @T6G_MB_LIB.T6G(SCH_1):GND    I22 @T6G_MB_LIB.T6G(SCH_1):PAGE31
  AM33    GND @T6G_MB_LIB.T6G(SCH_1):GND    I22 @T6G_MB_LIB.T6G(SCH_1):PAGE31
  AM34    GND @T6G_MB_LIB.T6G(SCH_1):GND    I22 @T6G_MB_LIB.T6G(SCH_1):PAGE31
  AM39    GND @T6G_MB_LIB.T6G(SCH_1):GND    I22 @T6G_MB_LIB.T6G(SCH_1):PAGE31
  AD49    GND @T6G_MB_LIB.T6G(SCH_1):GND    I22 @T6G_MB_LIB.T6G(SCH_1):PAGE31
  AD50    GND @T6G_MB_LIB.T6G(SCH_1):GND    I22 @T6G_MB_LIB.T6G(SCH_1):PAGE31
  AD51    GND @T6G_MB_LIB.T6G(SCH_1):GND    I22 @T6G_MB_LIB.T6G(SCH_1):PAGE31
  AD52    GND @T6G_MB_LIB.T6G(SCH_1):GND    I22 @T6G_MB_LIB.T6G(SCH_1):PAGE31
  AD53    GND @T6G_MB_LIB.T6G(SCH_1):GND    I22 @T6G_MB_LIB.T6G(SCH_1):PAGE31
  AD57    GND @T6G_MB_LIB.T6G(SCH_1):GND    I22 @T6G_MB_LIB.T6G(SCH_1):PAGE31
  AD59    GND @T6G_MB_LIB.T6G(SCH_1):GND    I22 @T6G_MB_LIB.T6G(SCH_1):PAGE31
  AD61    GND @T6G_MB_LIB.T6G(SCH_1):GND    I22 @T6G_MB_LIB.T6G(SCH_1):PAGE31
  AD64    GND @T6G_MB_LIB.T6G(SCH_1):GND    I22 @T6G_MB_LIB.T6G(SCH_1):PAGE31
  AD66    GND @T6G_MB_LIB.T6G(SCH_1):GND    I22 @T6G_MB_LIB.T6G(SCH_1):PAGE31
  AD68    GND @T6G_MB_LIB.T6G(SCH_1):GND    I22 @T6G_MB_LIB.T6G(SCH_1):PAGE31
  AD71    GND @T6G_MB_LIB.T6G(SCH_1):GND    I22 @T6G_MB_LIB.T6G(SCH_1):PAGE31
  AD73    GND @T6G_MB_LIB.T6G(SCH_1):GND    I22 @T6G_MB_LIB.T6G(SCH_1):PAGE31
   AE1    GND @T6G_MB_LIB.T6G(SCH_1):GND    I22 @T6G_MB_LIB.T6G(SCH_1):PAGE31
   AE6    GND @T6G_MB_LIB.T6G(SCH_1):GND    I22 @T6G_MB_LIB.T6G(SCH_1):PAGE31
   AE8    GND @T6G_MB_LIB.T6G(SCH_1):GND    I22 @T6G_MB_LIB.T6G(SCH_1):PAGE31
  AE11    GND @T6G_MB_LIB.T6G(SCH_1):GND    I22 @T6G_MB_LIB.T6G(SCH_1):PAGE31
  AE13    GND @T6G_MB_LIB.T6G(SCH_1):GND    I22 @T6G_MB_LIB.T6G(SCH_1):PAGE31
  AE15    GND @T6G_MB_LIB.T6G(SCH_1):GND    I22 @T6G_MB_LIB.T6G(SCH_1):PAGE31
  AE18    GND @T6G_MB_LIB.T6G(SCH_1):GND    I22 @T6G_MB_LIB.T6G(SCH_1):PAGE31
  AE20    GND @T6G_MB_LIB.T6G(SCH_1):GND    I22 @T6G_MB_LIB.T6G(SCH_1):PAGE31
  AE22    GND @T6G_MB_LIB.T6G(SCH_1):GND    I22 @T6G_MB_LIB.T6G(SCH_1):PAGE31
  AE25    GND @T6G_MB_LIB.T6G(SCH_1):GND    I22 @T6G_MB_LIB.T6G(SCH_1):PAGE31
  AE28    GND @T6G_MB_LIB.T6G(SCH_1):GND    I22 @T6G_MB_LIB.T6G(SCH_1):PAGE31
  AE31    GND @T6G_MB_LIB.T6G(SCH_1):GND    I22 @T6G_MB_LIB.T6G(SCH_1):PAGE31
  AE34    GND @T6G_MB_LIB.T6G(SCH_1):GND    I22 @T6G_MB_LIB.T6G(SCH_1):PAGE31
  AE35    GND @T6G_MB_LIB.T6G(SCH_1):GND    I22 @T6G_MB_LIB.T6G(SCH_1):PAGE31
  AE36    GND @T6G_MB_LIB.T6G(SCH_1):GND    I22 @T6G_MB_LIB.T6G(SCH_1):PAGE31
  AE40    GND @T6G_MB_LIB.T6G(SCH_1):GND    I22 @T6G_MB_LIB.T6G(SCH_1):PAGE31
  AE41    GND @T6G_MB_LIB.T6G(SCH_1):GND    I22 @T6G_MB_LIB.T6G(SCH_1):PAGE31
  AE42    GND @T6G_MB_LIB.T6G(SCH_1):GND    I22 @T6G_MB_LIB.T6G(SCH_1):PAGE31
  AE45    GND @T6G_MB_LIB.T6G(SCH_1):GND    I22 @T6G_MB_LIB.T6G(SCH_1):PAGE31
  AE48    GND @T6G_MB_LIB.T6G(SCH_1):GND    I22 @T6G_MB_LIB.T6G(SCH_1):PAGE31
  AE51    GND @T6G_MB_LIB.T6G(SCH_1):GND    I22 @T6G_MB_LIB.T6G(SCH_1):PAGE31
  AE54    GND @T6G_MB_LIB.T6G(SCH_1):GND    I22 @T6G_MB_LIB.T6G(SCH_1):PAGE31
  AE56    GND @T6G_MB_LIB.T6G(SCH_1):GND    I22 @T6G_MB_LIB.T6G(SCH_1):PAGE31
  AE58    GND @T6G_MB_LIB.T6G(SCH_1):GND    I22 @T6G_MB_LIB.T6G(SCH_1):PAGE31
  AE61    GND @T6G_MB_LIB.T6G(SCH_1):GND    I22 @T6G_MB_LIB.T6G(SCH_1):PAGE31
  AE63    GND @T6G_MB_LIB.T6G(SCH_1):GND    I22 @T6G_MB_LIB.T6G(SCH_1):PAGE31
  AE65    GND @T6G_MB_LIB.T6G(SCH_1):GND    I22 @T6G_MB_LIB.T6G(SCH_1):PAGE31
  AE68    GND @T6G_MB_LIB.T6G(SCH_1):GND    I22 @T6G_MB_LIB.T6G(SCH_1):PAGE31
  AE70    GND @T6G_MB_LIB.T6G(SCH_1):GND    I22 @T6G_MB_LIB.T6G(SCH_1):PAGE31
  AE72    GND @T6G_MB_LIB.T6G(SCH_1):GND    I22 @T6G_MB_LIB.T6G(SCH_1):PAGE31
  AE75    GND @T6G_MB_LIB.T6G(SCH_1):GND    I22 @T6G_MB_LIB.T6G(SCH_1):PAGE31
   AF3    GND @T6G_MB_LIB.T6G(SCH_1):GND    I22 @T6G_MB_LIB.T6G(SCH_1):PAGE31
   AF8    GND @T6G_MB_LIB.T6G(SCH_1):GND    I22 @T6G_MB_LIB.T6G(SCH_1):PAGE31
  AF10    GND @T6G_MB_LIB.T6G(SCH_1):GND    I22 @T6G_MB_LIB.T6G(SCH_1):PAGE31
  AF15    GND @T6G_MB_LIB.T6G(SCH_1):GND    I22 @T6G_MB_LIB.T6G(SCH_1):PAGE31
  AF17    GND @T6G_MB_LIB.T6G(SCH_1):GND    I22 @T6G_MB_LIB.T6G(SCH_1):PAGE31
  AF22    GND @T6G_MB_LIB.T6G(SCH_1):GND    I22 @T6G_MB_LIB.T6G(SCH_1):PAGE31
  AF25    GND @T6G_MB_LIB.T6G(SCH_1):GND    I22 @T6G_MB_LIB.T6G(SCH_1):PAGE31
  AF28    GND @T6G_MB_LIB.T6G(SCH_1):GND    I22 @T6G_MB_LIB.T6G(SCH_1):PAGE31
  AF31    GND @T6G_MB_LIB.T6G(SCH_1):GND    I22 @T6G_MB_LIB.T6G(SCH_1):PAGE31
  AF34    GND @T6G_MB_LIB.T6G(SCH_1):GND    I22 @T6G_MB_LIB.T6G(SCH_1):PAGE31
  AF37    GND @T6G_MB_LIB.T6G(SCH_1):GND    I22 @T6G_MB_LIB.T6G(SCH_1):PAGE31
  AF39    GND @T6G_MB_LIB.T6G(SCH_1):GND    I22 @T6G_MB_LIB.T6G(SCH_1):PAGE31
  AF42    GND @T6G_MB_LIB.T6G(SCH_1):GND    I22 @T6G_MB_LIB.T6G(SCH_1):PAGE31
  AF45    GND @T6G_MB_LIB.T6G(SCH_1):GND    I22 @T6G_MB_LIB.T6G(SCH_1):PAGE31
  AF48    GND @T6G_MB_LIB.T6G(SCH_1):GND    I22 @T6G_MB_LIB.T6G(SCH_1):PAGE31
  AF51    GND @T6G_MB_LIB.T6G(SCH_1):GND    I22 @T6G_MB_LIB.T6G(SCH_1):PAGE31
  AF54    GND @T6G_MB_LIB.T6G(SCH_1):GND    I22 @T6G_MB_LIB.T6G(SCH_1):PAGE31
  AF59    GND @T6G_MB_LIB.T6G(SCH_1):GND    I22 @T6G_MB_LIB.T6G(SCH_1):PAGE31
  AF61    GND @T6G_MB_LIB.T6G(SCH_1):GND    I22 @T6G_MB_LIB.T6G(SCH_1):PAGE31
  AF66    GND @T6G_MB_LIB.T6G(SCH_1):GND    I22 @T6G_MB_LIB.T6G(SCH_1):PAGE31
  AF68    GND @T6G_MB_LIB.T6G(SCH_1):GND    I22 @T6G_MB_LIB.T6G(SCH_1):PAGE31
  AF73    GND @T6G_MB_LIB.T6G(SCH_1):GND    I22 @T6G_MB_LIB.T6G(SCH_1):PAGE31
   AG1    GND @T6G_MB_LIB.T6G(SCH_1):GND    I22 @T6G_MB_LIB.T6G(SCH_1):PAGE31
   AG4    GND @T6G_MB_LIB.T6G(SCH_1):GND    I22 @T6G_MB_LIB.T6G(SCH_1):PAGE31
   AG6    GND @T6G_MB_LIB.T6G(SCH_1):GND    I22 @T6G_MB_LIB.T6G(SCH_1):PAGE31
   AG8    GND @T6G_MB_LIB.T6G(SCH_1):GND    I22 @T6G_MB_LIB.T6G(SCH_1):PAGE31
  AG11    GND @T6G_MB_LIB.T6G(SCH_1):GND    I22 @T6G_MB_LIB.T6G(SCH_1):PAGE31
  AG13    GND @T6G_MB_LIB.T6G(SCH_1):GND    I22 @T6G_MB_LIB.T6G(SCH_1):PAGE31
  AG15    GND @T6G_MB_LIB.T6G(SCH_1):GND    I22 @T6G_MB_LIB.T6G(SCH_1):PAGE31
  AG18    GND @T6G_MB_LIB.T6G(SCH_1):GND    I22 @T6G_MB_LIB.T6G(SCH_1):PAGE31
  AG20    GND @T6G_MB_LIB.T6G(SCH_1):GND    I22 @T6G_MB_LIB.T6G(SCH_1):PAGE31
  AG22    GND @T6G_MB_LIB.T6G(SCH_1):GND    I22 @T6G_MB_LIB.T6G(SCH_1):PAGE31
  AG25    GND @T6G_MB_LIB.T6G(SCH_1):GND    I22 @T6G_MB_LIB.T6G(SCH_1):PAGE31
  AG28    GND @T6G_MB_LIB.T6G(SCH_1):GND    I22 @T6G_MB_LIB.T6G(SCH_1):PAGE31
  AG31    GND @T6G_MB_LIB.T6G(SCH_1):GND    I22 @T6G_MB_LIB.T6G(SCH_1):PAGE31
  AG34    GND @T6G_MB_LIB.T6G(SCH_1):GND    I22 @T6G_MB_LIB.T6G(SCH_1):PAGE31
  AG42    GND @T6G_MB_LIB.T6G(SCH_1):GND    I22 @T6G_MB_LIB.T6G(SCH_1):PAGE31
  AG45    GND @T6G_MB_LIB.T6G(SCH_1):GND    I22 @T6G_MB_LIB.T6G(SCH_1):PAGE31
  AG48    GND @T6G_MB_LIB.T6G(SCH_1):GND    I22 @T6G_MB_LIB.T6G(SCH_1):PAGE31
  AG51    GND @T6G_MB_LIB.T6G(SCH_1):GND    I22 @T6G_MB_LIB.T6G(SCH_1):PAGE31
  AG54    GND @T6G_MB_LIB.T6G(SCH_1):GND    I22 @T6G_MB_LIB.T6G(SCH_1):PAGE31
  AG56    GND @T6G_MB_LIB.T6G(SCH_1):GND    I22 @T6G_MB_LIB.T6G(SCH_1):PAGE31
  AG58    GND @T6G_MB_LIB.T6G(SCH_1):GND    I22 @T6G_MB_LIB.T6G(SCH_1):PAGE31
  AG61    GND @T6G_MB_LIB.T6G(SCH_1):GND    I22 @T6G_MB_LIB.T6G(SCH_1):PAGE31
  AG63    GND @T6G_MB_LIB.T6G(SCH_1):GND    I22 @T6G_MB_LIB.T6G(SCH_1):PAGE31
  AG65    GND @T6G_MB_LIB.T6G(SCH_1):GND    I22 @T6G_MB_LIB.T6G(SCH_1):PAGE31
  AG68    GND @T6G_MB_LIB.T6G(SCH_1):GND    I22 @T6G_MB_LIB.T6G(SCH_1):PAGE31
  AG70    GND @T6G_MB_LIB.T6G(SCH_1):GND    I22 @T6G_MB_LIB.T6G(SCH_1):PAGE31
  AG72    GND @T6G_MB_LIB.T6G(SCH_1):GND    I22 @T6G_MB_LIB.T6G(SCH_1):PAGE31
  AG75    GND @T6G_MB_LIB.T6G(SCH_1):GND    I22 @T6G_MB_LIB.T6G(SCH_1):PAGE31
   AH3    GND @T6G_MB_LIB.T6G(SCH_1):GND    I22 @T6G_MB_LIB.T6G(SCH_1):PAGE31
   AH5    GND @T6G_MB_LIB.T6G(SCH_1):GND    I22 @T6G_MB_LIB.T6G(SCH_1):PAGE31
   AH8    GND @T6G_MB_LIB.T6G(SCH_1):GND    I22 @T6G_MB_LIB.T6G(SCH_1):PAGE31
  AH10    GND @T6G_MB_LIB.T6G(SCH_1):GND    I22 @T6G_MB_LIB.T6G(SCH_1):PAGE31
  AH12    GND @T6G_MB_LIB.T6G(SCH_1):GND    I22 @T6G_MB_LIB.T6G(SCH_1):PAGE31
  AH15    GND @T6G_MB_LIB.T6G(SCH_1):GND    I22 @T6G_MB_LIB.T6G(SCH_1):PAGE31
  AH17    GND @T6G_MB_LIB.T6G(SCH_1):GND    I22 @T6G_MB_LIB.T6G(SCH_1):PAGE31
  AH19    GND @T6G_MB_LIB.T6G(SCH_1):GND    I22 @T6G_MB_LIB.T6G(SCH_1):PAGE31
  AH23    GND @T6G_MB_LIB.T6G(SCH_1):GND    I22 @T6G_MB_LIB.T6G(SCH_1):PAGE31
  AH24    GND @T6G_MB_LIB.T6G(SCH_1):GND    I22 @T6G_MB_LIB.T6G(SCH_1):PAGE31
  AH25    GND @T6G_MB_LIB.T6G(SCH_1):GND    I22 @T6G_MB_LIB.T6G(SCH_1):PAGE31
  AH26    GND @T6G_MB_LIB.T6G(SCH_1):GND    I22 @T6G_MB_LIB.T6G(SCH_1):PAGE31
  AH27    GND @T6G_MB_LIB.T6G(SCH_1):GND    I22 @T6G_MB_LIB.T6G(SCH_1):PAGE31
  AH28    GND @T6G_MB_LIB.T6G(SCH_1):GND    I22 @T6G_MB_LIB.T6G(SCH_1):PAGE31
  AH29    GND @T6G_MB_LIB.T6G(SCH_1):GND    I22 @T6G_MB_LIB.T6G(SCH_1):PAGE31
  AH30    GND @T6G_MB_LIB.T6G(SCH_1):GND    I22 @T6G_MB_LIB.T6G(SCH_1):PAGE31
  AH31    GND @T6G_MB_LIB.T6G(SCH_1):GND    I22 @T6G_MB_LIB.T6G(SCH_1):PAGE31
  AH32    GND @T6G_MB_LIB.T6G(SCH_1):GND    I22 @T6G_MB_LIB.T6G(SCH_1):PAGE31
  AH34    GND @T6G_MB_LIB.T6G(SCH_1):GND    I22 @T6G_MB_LIB.T6G(SCH_1):PAGE31
  AH37    GND @T6G_MB_LIB.T6G(SCH_1):GND    I22 @T6G_MB_LIB.T6G(SCH_1):PAGE31
  AH39    GND @T6G_MB_LIB.T6G(SCH_1):GND    I22 @T6G_MB_LIB.T6G(SCH_1):PAGE31
  AH42    GND @T6G_MB_LIB.T6G(SCH_1):GND    I22 @T6G_MB_LIB.T6G(SCH_1):PAGE31
  AH43    GND @T6G_MB_LIB.T6G(SCH_1):GND    I22 @T6G_MB_LIB.T6G(SCH_1):PAGE31
  AH44    GND @T6G_MB_LIB.T6G(SCH_1):GND    I22 @T6G_MB_LIB.T6G(SCH_1):PAGE31
  AH45    GND @T6G_MB_LIB.T6G(SCH_1):GND    I22 @T6G_MB_LIB.T6G(SCH_1):PAGE31
  AH46    GND @T6G_MB_LIB.T6G(SCH_1):GND    I22 @T6G_MB_LIB.T6G(SCH_1):PAGE31
  AH47    GND @T6G_MB_LIB.T6G(SCH_1):GND    I22 @T6G_MB_LIB.T6G(SCH_1):PAGE31
  AH48    GND @T6G_MB_LIB.T6G(SCH_1):GND    I22 @T6G_MB_LIB.T6G(SCH_1):PAGE31
  AH49    GND @T6G_MB_LIB.T6G(SCH_1):GND    I22 @T6G_MB_LIB.T6G(SCH_1):PAGE31
  AH50    GND @T6G_MB_LIB.T6G(SCH_1):GND    I22 @T6G_MB_LIB.T6G(SCH_1):PAGE31
  AH51    GND @T6G_MB_LIB.T6G(SCH_1):GND    I22 @T6G_MB_LIB.T6G(SCH_1):PAGE31
  AH52    GND @T6G_MB_LIB.T6G(SCH_1):GND    I22 @T6G_MB_LIB.T6G(SCH_1):PAGE31
  AH53    GND @T6G_MB_LIB.T6G(SCH_1):GND    I22 @T6G_MB_LIB.T6G(SCH_1):PAGE31
  AH57    GND @T6G_MB_LIB.T6G(SCH_1):GND    I22 @T6G_MB_LIB.T6G(SCH_1):PAGE31
  AH59    GND @T6G_MB_LIB.T6G(SCH_1):GND    I22 @T6G_MB_LIB.T6G(SCH_1):PAGE31
  AH61    GND @T6G_MB_LIB.T6G(SCH_1):GND    I22 @T6G_MB_LIB.T6G(SCH_1):PAGE31
  AH64    GND @T6G_MB_LIB.T6G(SCH_1):GND    I22 @T6G_MB_LIB.T6G(SCH_1):PAGE31
  AH66    GND @T6G_MB_LIB.T6G(SCH_1):GND    I22 @T6G_MB_LIB.T6G(SCH_1):PAGE31
  AH68    GND @T6G_MB_LIB.T6G(SCH_1):GND    I22 @T6G_MB_LIB.T6G(SCH_1):PAGE31
  AH71    GND @T6G_MB_LIB.T6G(SCH_1):GND    I22 @T6G_MB_LIB.T6G(SCH_1):PAGE31
  AH73    GND @T6G_MB_LIB.T6G(SCH_1):GND    I22 @T6G_MB_LIB.T6G(SCH_1):PAGE31
   AJ1    GND @T6G_MB_LIB.T6G(SCH_1):GND    I22 @T6G_MB_LIB.T6G(SCH_1):PAGE31
   AJ6    GND @T6G_MB_LIB.T6G(SCH_1):GND    I22 @T6G_MB_LIB.T6G(SCH_1):PAGE31
   AJ8    GND @T6G_MB_LIB.T6G(SCH_1):GND    I22 @T6G_MB_LIB.T6G(SCH_1):PAGE31
  AJ15    GND @T6G_MB_LIB.T6G(SCH_1):GND    I22 @T6G_MB_LIB.T6G(SCH_1):PAGE31
  AJ20    GND @T6G_MB_LIB.T6G(SCH_1):GND    I22 @T6G_MB_LIB.T6G(SCH_1):PAGE31
  AJ22    GND @T6G_MB_LIB.T6G(SCH_1):GND    I22 @T6G_MB_LIB.T6G(SCH_1):PAGE31
  AJ25    GND @T6G_MB_LIB.T6G(SCH_1):GND    I22 @T6G_MB_LIB.T6G(SCH_1):PAGE31
  AJ28    GND @T6G_MB_LIB.T6G(SCH_1):GND    I22 @T6G_MB_LIB.T6G(SCH_1):PAGE31
  AJ31    GND @T6G_MB_LIB.T6G(SCH_1):GND    I22 @T6G_MB_LIB.T6G(SCH_1):PAGE31
  AJ34    GND @T6G_MB_LIB.T6G(SCH_1):GND    I22 @T6G_MB_LIB.T6G(SCH_1):PAGE31
  AJ35    GND @T6G_MB_LIB.T6G(SCH_1):GND    I22 @T6G_MB_LIB.T6G(SCH_1):PAGE31
  AJ36    GND @T6G_MB_LIB.T6G(SCH_1):GND    I22 @T6G_MB_LIB.T6G(SCH_1):PAGE31
  AJ40    GND @T6G_MB_LIB.T6G(SCH_1):GND    I22 @T6G_MB_LIB.T6G(SCH_1):PAGE31
  AJ41    GND @T6G_MB_LIB.T6G(SCH_1):GND    I22 @T6G_MB_LIB.T6G(SCH_1):PAGE31
  AJ42    GND @T6G_MB_LIB.T6G(SCH_1):GND    I22 @T6G_MB_LIB.T6G(SCH_1):PAGE31
  AJ45    GND @T6G_MB_LIB.T6G(SCH_1):GND    I22 @T6G_MB_LIB.T6G(SCH_1):PAGE31
  AJ48    GND @T6G_MB_LIB.T6G(SCH_1):GND    I22 @T6G_MB_LIB.T6G(SCH_1):PAGE31
  AJ51    GND @T6G_MB_LIB.T6G(SCH_1):GND    I22 @T6G_MB_LIB.T6G(SCH_1):PAGE31
  AJ54    GND @T6G_MB_LIB.T6G(SCH_1):GND    I22 @T6G_MB_LIB.T6G(SCH_1):PAGE31
  AJ56    GND @T6G_MB_LIB.T6G(SCH_1):GND    I22 @T6G_MB_LIB.T6G(SCH_1):PAGE31
  AJ61    GND @T6G_MB_LIB.T6G(SCH_1):GND    I22 @T6G_MB_LIB.T6G(SCH_1):PAGE31
  AJ63    GND @T6G_MB_LIB.T6G(SCH_1):GND    I22 @T6G_MB_LIB.T6G(SCH_1):PAGE31
  AJ68    GND @T6G_MB_LIB.T6G(SCH_1):GND    I22 @T6G_MB_LIB.T6G(SCH_1):PAGE31
  AJ70    GND @T6G_MB_LIB.T6G(SCH_1):GND    I22 @T6G_MB_LIB.T6G(SCH_1):PAGE31
  AJ75    GND @T6G_MB_LIB.T6G(SCH_1):GND    I22 @T6G_MB_LIB.T6G(SCH_1):PAGE31
   AK3    GND @T6G_MB_LIB.T6G(SCH_1):GND    I22 @T6G_MB_LIB.T6G(SCH_1):PAGE31
   AK5    GND @T6G_MB_LIB.T6G(SCH_1):GND    I22 @T6G_MB_LIB.T6G(SCH_1):PAGE31
   AK8    GND @T6G_MB_LIB.T6G(SCH_1):GND    I22 @T6G_MB_LIB.T6G(SCH_1):PAGE31
  AM42    GND @T6G_MB_LIB.T6G(SCH_1):GND    I23 @T6G_MB_LIB.T6G(SCH_1):PAGE31
  AM43    GND @T6G_MB_LIB.T6G(SCH_1):GND    I23 @T6G_MB_LIB.T6G(SCH_1):PAGE31
  AM44    GND @T6G_MB_LIB.T6G(SCH_1):GND    I23 @T6G_MB_LIB.T6G(SCH_1):PAGE31
  AM45    GND @T6G_MB_LIB.T6G(SCH_1):GND    I23 @T6G_MB_LIB.T6G(SCH_1):PAGE31
  AM46    GND @T6G_MB_LIB.T6G(SCH_1):GND    I23 @T6G_MB_LIB.T6G(SCH_1):PAGE31
  AM47    GND @T6G_MB_LIB.T6G(SCH_1):GND    I23 @T6G_MB_LIB.T6G(SCH_1):PAGE31
  AM48    GND @T6G_MB_LIB.T6G(SCH_1):GND    I23 @T6G_MB_LIB.T6G(SCH_1):PAGE31
  AM49    GND @T6G_MB_LIB.T6G(SCH_1):GND    I23 @T6G_MB_LIB.T6G(SCH_1):PAGE31
  AM50    GND @T6G_MB_LIB.T6G(SCH_1):GND    I23 @T6G_MB_LIB.T6G(SCH_1):PAGE31
  AM51    GND @T6G_MB_LIB.T6G(SCH_1):GND    I23 @T6G_MB_LIB.T6G(SCH_1):PAGE31
  AM52    GND @T6G_MB_LIB.T6G(SCH_1):GND    I23 @T6G_MB_LIB.T6G(SCH_1):PAGE31
  AM53    GND @T6G_MB_LIB.T6G(SCH_1):GND    I23 @T6G_MB_LIB.T6G(SCH_1):PAGE31
  AM59    GND @T6G_MB_LIB.T6G(SCH_1):GND    I23 @T6G_MB_LIB.T6G(SCH_1):PAGE31
  AM61    GND @T6G_MB_LIB.T6G(SCH_1):GND    I23 @T6G_MB_LIB.T6G(SCH_1):PAGE31
  AM66    GND @T6G_MB_LIB.T6G(SCH_1):GND    I23 @T6G_MB_LIB.T6G(SCH_1):PAGE31
  AM68    GND @T6G_MB_LIB.T6G(SCH_1):GND    I23 @T6G_MB_LIB.T6G(SCH_1):PAGE31
  AM73    GND @T6G_MB_LIB.T6G(SCH_1):GND    I23 @T6G_MB_LIB.T6G(SCH_1):PAGE31
   AN1    GND @T6G_MB_LIB.T6G(SCH_1):GND    I23 @T6G_MB_LIB.T6G(SCH_1):PAGE31
   AN4    GND @T6G_MB_LIB.T6G(SCH_1):GND    I23 @T6G_MB_LIB.T6G(SCH_1):PAGE31
   AN6    GND @T6G_MB_LIB.T6G(SCH_1):GND    I23 @T6G_MB_LIB.T6G(SCH_1):PAGE31
   AN8    GND @T6G_MB_LIB.T6G(SCH_1):GND    I23 @T6G_MB_LIB.T6G(SCH_1):PAGE31
  AN11    GND @T6G_MB_LIB.T6G(SCH_1):GND    I23 @T6G_MB_LIB.T6G(SCH_1):PAGE31
  AN13    GND @T6G_MB_LIB.T6G(SCH_1):GND    I23 @T6G_MB_LIB.T6G(SCH_1):PAGE31
  AN15    GND @T6G_MB_LIB.T6G(SCH_1):GND    I23 @T6G_MB_LIB.T6G(SCH_1):PAGE31
  AN18    GND @T6G_MB_LIB.T6G(SCH_1):GND    I23 @T6G_MB_LIB.T6G(SCH_1):PAGE31
  AN22    GND @T6G_MB_LIB.T6G(SCH_1):GND    I23 @T6G_MB_LIB.T6G(SCH_1):PAGE31
  AN25    GND @T6G_MB_LIB.T6G(SCH_1):GND    I23 @T6G_MB_LIB.T6G(SCH_1):PAGE31
  AN28    GND @T6G_MB_LIB.T6G(SCH_1):GND    I23 @T6G_MB_LIB.T6G(SCH_1):PAGE31
  AN31    GND @T6G_MB_LIB.T6G(SCH_1):GND    I23 @T6G_MB_LIB.T6G(SCH_1):PAGE31
  AN34    GND @T6G_MB_LIB.T6G(SCH_1):GND    I23 @T6G_MB_LIB.T6G(SCH_1):PAGE31
  AN35    GND @T6G_MB_LIB.T6G(SCH_1):GND    I23 @T6G_MB_LIB.T6G(SCH_1):PAGE31
  AN36    GND @T6G_MB_LIB.T6G(SCH_1):GND    I23 @T6G_MB_LIB.T6G(SCH_1):PAGE31
  AN40    GND @T6G_MB_LIB.T6G(SCH_1):GND    I23 @T6G_MB_LIB.T6G(SCH_1):PAGE31
  AN41    GND @T6G_MB_LIB.T6G(SCH_1):GND    I23 @T6G_MB_LIB.T6G(SCH_1):PAGE31
  AN42    GND @T6G_MB_LIB.T6G(SCH_1):GND    I23 @T6G_MB_LIB.T6G(SCH_1):PAGE31
  AN45    GND @T6G_MB_LIB.T6G(SCH_1):GND    I23 @T6G_MB_LIB.T6G(SCH_1):PAGE31
  AN48    GND @T6G_MB_LIB.T6G(SCH_1):GND    I23 @T6G_MB_LIB.T6G(SCH_1):PAGE31
  AN51    GND @T6G_MB_LIB.T6G(SCH_1):GND    I23 @T6G_MB_LIB.T6G(SCH_1):PAGE31
  AN54    GND @T6G_MB_LIB.T6G(SCH_1):GND    I23 @T6G_MB_LIB.T6G(SCH_1):PAGE31
  AN56    GND @T6G_MB_LIB.T6G(SCH_1):GND    I23 @T6G_MB_LIB.T6G(SCH_1):PAGE31
  AN58    GND @T6G_MB_LIB.T6G(SCH_1):GND    I23 @T6G_MB_LIB.T6G(SCH_1):PAGE31
  AN61    GND @T6G_MB_LIB.T6G(SCH_1):GND    I23 @T6G_MB_LIB.T6G(SCH_1):PAGE31
  AN63    GND @T6G_MB_LIB.T6G(SCH_1):GND    I23 @T6G_MB_LIB.T6G(SCH_1):PAGE31
  AN65    GND @T6G_MB_LIB.T6G(SCH_1):GND    I23 @T6G_MB_LIB.T6G(SCH_1):PAGE31
  AN68    GND @T6G_MB_LIB.T6G(SCH_1):GND    I23 @T6G_MB_LIB.T6G(SCH_1):PAGE31
  AN70    GND @T6G_MB_LIB.T6G(SCH_1):GND    I23 @T6G_MB_LIB.T6G(SCH_1):PAGE31
  AN72    GND @T6G_MB_LIB.T6G(SCH_1):GND    I23 @T6G_MB_LIB.T6G(SCH_1):PAGE31
  AN75    GND @T6G_MB_LIB.T6G(SCH_1):GND    I23 @T6G_MB_LIB.T6G(SCH_1):PAGE31
   AP3    GND @T6G_MB_LIB.T6G(SCH_1):GND    I23 @T6G_MB_LIB.T6G(SCH_1):PAGE31
   AP5    GND @T6G_MB_LIB.T6G(SCH_1):GND    I23 @T6G_MB_LIB.T6G(SCH_1):PAGE31
   AP8    GND @T6G_MB_LIB.T6G(SCH_1):GND    I23 @T6G_MB_LIB.T6G(SCH_1):PAGE31
  AP10    GND @T6G_MB_LIB.T6G(SCH_1):GND    I23 @T6G_MB_LIB.T6G(SCH_1):PAGE31
  AP12    GND @T6G_MB_LIB.T6G(SCH_1):GND    I23 @T6G_MB_LIB.T6G(SCH_1):PAGE31
  AP15    GND @T6G_MB_LIB.T6G(SCH_1):GND    I23 @T6G_MB_LIB.T6G(SCH_1):PAGE31
  AP17    GND @T6G_MB_LIB.T6G(SCH_1):GND    I23 @T6G_MB_LIB.T6G(SCH_1):PAGE31
  AP19    GND @T6G_MB_LIB.T6G(SCH_1):GND    I23 @T6G_MB_LIB.T6G(SCH_1):PAGE31
  AP22    GND @T6G_MB_LIB.T6G(SCH_1):GND    I23 @T6G_MB_LIB.T6G(SCH_1):PAGE31
  AP25    GND @T6G_MB_LIB.T6G(SCH_1):GND    I23 @T6G_MB_LIB.T6G(SCH_1):PAGE31
  AP28    GND @T6G_MB_LIB.T6G(SCH_1):GND    I23 @T6G_MB_LIB.T6G(SCH_1):PAGE31
  AP31    GND @T6G_MB_LIB.T6G(SCH_1):GND    I23 @T6G_MB_LIB.T6G(SCH_1):PAGE31
  AP34    GND @T6G_MB_LIB.T6G(SCH_1):GND    I23 @T6G_MB_LIB.T6G(SCH_1):PAGE31
  AP37    GND @T6G_MB_LIB.T6G(SCH_1):GND    I23 @T6G_MB_LIB.T6G(SCH_1):PAGE31
  AP39    GND @T6G_MB_LIB.T6G(SCH_1):GND    I23 @T6G_MB_LIB.T6G(SCH_1):PAGE31
  AP42    GND @T6G_MB_LIB.T6G(SCH_1):GND    I23 @T6G_MB_LIB.T6G(SCH_1):PAGE31
  AP45    GND @T6G_MB_LIB.T6G(SCH_1):GND    I23 @T6G_MB_LIB.T6G(SCH_1):PAGE31
  AP48    GND @T6G_MB_LIB.T6G(SCH_1):GND    I23 @T6G_MB_LIB.T6G(SCH_1):PAGE31
  AP51    GND @T6G_MB_LIB.T6G(SCH_1):GND    I23 @T6G_MB_LIB.T6G(SCH_1):PAGE31
  AP54    GND @T6G_MB_LIB.T6G(SCH_1):GND    I23 @T6G_MB_LIB.T6G(SCH_1):PAGE31
  AP57    GND @T6G_MB_LIB.T6G(SCH_1):GND    I23 @T6G_MB_LIB.T6G(SCH_1):PAGE31
  AP59    GND @T6G_MB_LIB.T6G(SCH_1):GND    I23 @T6G_MB_LIB.T6G(SCH_1):PAGE31
  AP61    GND @T6G_MB_LIB.T6G(SCH_1):GND    I23 @T6G_MB_LIB.T6G(SCH_1):PAGE31
  AP64    GND @T6G_MB_LIB.T6G(SCH_1):GND    I23 @T6G_MB_LIB.T6G(SCH_1):PAGE31
  AP66    GND @T6G_MB_LIB.T6G(SCH_1):GND    I23 @T6G_MB_LIB.T6G(SCH_1):PAGE31
  AP68    GND @T6G_MB_LIB.T6G(SCH_1):GND    I23 @T6G_MB_LIB.T6G(SCH_1):PAGE31
  AP71    GND @T6G_MB_LIB.T6G(SCH_1):GND    I23 @T6G_MB_LIB.T6G(SCH_1):PAGE31
  AP73    GND @T6G_MB_LIB.T6G(SCH_1):GND    I23 @T6G_MB_LIB.T6G(SCH_1):PAGE31
   AR1    GND @T6G_MB_LIB.T6G(SCH_1):GND    I23 @T6G_MB_LIB.T6G(SCH_1):PAGE31
   AR5    GND @T6G_MB_LIB.T6G(SCH_1):GND    I23 @T6G_MB_LIB.T6G(SCH_1):PAGE31
   AR6    GND @T6G_MB_LIB.T6G(SCH_1):GND    I23 @T6G_MB_LIB.T6G(SCH_1):PAGE31
   AR8    GND @T6G_MB_LIB.T6G(SCH_1):GND    I23 @T6G_MB_LIB.T6G(SCH_1):PAGE31
   AR9    GND @T6G_MB_LIB.T6G(SCH_1):GND    I23 @T6G_MB_LIB.T6G(SCH_1):PAGE31
  AR12    GND @T6G_MB_LIB.T6G(SCH_1):GND    I23 @T6G_MB_LIB.T6G(SCH_1):PAGE31
  AR13    GND @T6G_MB_LIB.T6G(SCH_1):GND    I23 @T6G_MB_LIB.T6G(SCH_1):PAGE31
  AR15    GND @T6G_MB_LIB.T6G(SCH_1):GND    I23 @T6G_MB_LIB.T6G(SCH_1):PAGE31
  AR16    GND @T6G_MB_LIB.T6G(SCH_1):GND    I23 @T6G_MB_LIB.T6G(SCH_1):PAGE31
  AR19    GND @T6G_MB_LIB.T6G(SCH_1):GND    I23 @T6G_MB_LIB.T6G(SCH_1):PAGE31
  AR20    GND @T6G_MB_LIB.T6G(SCH_1):GND    I23 @T6G_MB_LIB.T6G(SCH_1):PAGE31
  AR22    GND @T6G_MB_LIB.T6G(SCH_1):GND    I23 @T6G_MB_LIB.T6G(SCH_1):PAGE31
  AR24    GND @T6G_MB_LIB.T6G(SCH_1):GND    I23 @T6G_MB_LIB.T6G(SCH_1):PAGE31
  AR26    GND @T6G_MB_LIB.T6G(SCH_1):GND    I23 @T6G_MB_LIB.T6G(SCH_1):PAGE31
  AR28    GND @T6G_MB_LIB.T6G(SCH_1):GND    I23 @T6G_MB_LIB.T6G(SCH_1):PAGE31
  AR30    GND @T6G_MB_LIB.T6G(SCH_1):GND    I23 @T6G_MB_LIB.T6G(SCH_1):PAGE31
  AR32    GND @T6G_MB_LIB.T6G(SCH_1):GND    I23 @T6G_MB_LIB.T6G(SCH_1):PAGE31
  AR34    GND @T6G_MB_LIB.T6G(SCH_1):GND    I23 @T6G_MB_LIB.T6G(SCH_1):PAGE31
  AR36    GND @T6G_MB_LIB.T6G(SCH_1):GND    I23 @T6G_MB_LIB.T6G(SCH_1):PAGE31
  AR41    GND @T6G_MB_LIB.T6G(SCH_1):GND    I23 @T6G_MB_LIB.T6G(SCH_1):PAGE31
  AR43    GND @T6G_MB_LIB.T6G(SCH_1):GND    I23 @T6G_MB_LIB.T6G(SCH_1):PAGE31
  AR45    GND @T6G_MB_LIB.T6G(SCH_1):GND    I23 @T6G_MB_LIB.T6G(SCH_1):PAGE31
  AR47    GND @T6G_MB_LIB.T6G(SCH_1):GND    I23 @T6G_MB_LIB.T6G(SCH_1):PAGE31
  AR49    GND @T6G_MB_LIB.T6G(SCH_1):GND    I23 @T6G_MB_LIB.T6G(SCH_1):PAGE31
  AR51    GND @T6G_MB_LIB.T6G(SCH_1):GND    I23 @T6G_MB_LIB.T6G(SCH_1):PAGE31
  AR53    GND @T6G_MB_LIB.T6G(SCH_1):GND    I23 @T6G_MB_LIB.T6G(SCH_1):PAGE31
  AR56    GND @T6G_MB_LIB.T6G(SCH_1):GND    I23 @T6G_MB_LIB.T6G(SCH_1):PAGE31
  AR57    GND @T6G_MB_LIB.T6G(SCH_1):GND    I23 @T6G_MB_LIB.T6G(SCH_1):PAGE31
  AR60    GND @T6G_MB_LIB.T6G(SCH_1):GND    I23 @T6G_MB_LIB.T6G(SCH_1):PAGE31
  AR61    GND @T6G_MB_LIB.T6G(SCH_1):GND    I23 @T6G_MB_LIB.T6G(SCH_1):PAGE31
  AR63    GND @T6G_MB_LIB.T6G(SCH_1):GND    I23 @T6G_MB_LIB.T6G(SCH_1):PAGE31
  AR64    GND @T6G_MB_LIB.T6G(SCH_1):GND    I23 @T6G_MB_LIB.T6G(SCH_1):PAGE31
  AR67    GND @T6G_MB_LIB.T6G(SCH_1):GND    I23 @T6G_MB_LIB.T6G(SCH_1):PAGE31
  AR68    GND @T6G_MB_LIB.T6G(SCH_1):GND    I23 @T6G_MB_LIB.T6G(SCH_1):PAGE31
  AR70    GND @T6G_MB_LIB.T6G(SCH_1):GND    I23 @T6G_MB_LIB.T6G(SCH_1):PAGE31
  AR71    GND @T6G_MB_LIB.T6G(SCH_1):GND    I23 @T6G_MB_LIB.T6G(SCH_1):PAGE31
  AR75    GND @T6G_MB_LIB.T6G(SCH_1):GND    I23 @T6G_MB_LIB.T6G(SCH_1):PAGE31
   AT3    GND @T6G_MB_LIB.T6G(SCH_1):GND    I23 @T6G_MB_LIB.T6G(SCH_1):PAGE31
   AT4    GND @T6G_MB_LIB.T6G(SCH_1):GND    I23 @T6G_MB_LIB.T6G(SCH_1):PAGE31
   AT5    GND @T6G_MB_LIB.T6G(SCH_1):GND    I23 @T6G_MB_LIB.T6G(SCH_1):PAGE31
   AT6    GND @T6G_MB_LIB.T6G(SCH_1):GND    I23 @T6G_MB_LIB.T6G(SCH_1):PAGE31
   AT8    GND @T6G_MB_LIB.T6G(SCH_1):GND    I23 @T6G_MB_LIB.T6G(SCH_1):PAGE31
   AT9    GND @T6G_MB_LIB.T6G(SCH_1):GND    I23 @T6G_MB_LIB.T6G(SCH_1):PAGE31
  AT10    GND @T6G_MB_LIB.T6G(SCH_1):GND    I23 @T6G_MB_LIB.T6G(SCH_1):PAGE31
  AT12    GND @T6G_MB_LIB.T6G(SCH_1):GND    I23 @T6G_MB_LIB.T6G(SCH_1):PAGE31
  AT13    GND @T6G_MB_LIB.T6G(SCH_1):GND    I23 @T6G_MB_LIB.T6G(SCH_1):PAGE31
  AT15    GND @T6G_MB_LIB.T6G(SCH_1):GND    I23 @T6G_MB_LIB.T6G(SCH_1):PAGE31
  AT16    GND @T6G_MB_LIB.T6G(SCH_1):GND    I23 @T6G_MB_LIB.T6G(SCH_1):PAGE31
  AT17    GND @T6G_MB_LIB.T6G(SCH_1):GND    I23 @T6G_MB_LIB.T6G(SCH_1):PAGE31
  AT19    GND @T6G_MB_LIB.T6G(SCH_1):GND    I23 @T6G_MB_LIB.T6G(SCH_1):PAGE31
  AT20    GND @T6G_MB_LIB.T6G(SCH_1):GND    I23 @T6G_MB_LIB.T6G(SCH_1):PAGE31
  AT23    GND @T6G_MB_LIB.T6G(SCH_1):GND    I23 @T6G_MB_LIB.T6G(SCH_1):PAGE31
  AT25    GND @T6G_MB_LIB.T6G(SCH_1):GND    I23 @T6G_MB_LIB.T6G(SCH_1):PAGE31
  AT27    GND @T6G_MB_LIB.T6G(SCH_1):GND    I23 @T6G_MB_LIB.T6G(SCH_1):PAGE31
  AT29    GND @T6G_MB_LIB.T6G(SCH_1):GND    I23 @T6G_MB_LIB.T6G(SCH_1):PAGE31
  AT31    GND @T6G_MB_LIB.T6G(SCH_1):GND    I23 @T6G_MB_LIB.T6G(SCH_1):PAGE31
  AT33    GND @T6G_MB_LIB.T6G(SCH_1):GND    I23 @T6G_MB_LIB.T6G(SCH_1):PAGE31
  AT35    GND @T6G_MB_LIB.T6G(SCH_1):GND    I23 @T6G_MB_LIB.T6G(SCH_1):PAGE31
  AT37    GND @T6G_MB_LIB.T6G(SCH_1):GND    I23 @T6G_MB_LIB.T6G(SCH_1):PAGE31
  AT40    GND @T6G_MB_LIB.T6G(SCH_1):GND    I23 @T6G_MB_LIB.T6G(SCH_1):PAGE31
  AT42    GND @T6G_MB_LIB.T6G(SCH_1):GND    I23 @T6G_MB_LIB.T6G(SCH_1):PAGE31
  AT44    GND @T6G_MB_LIB.T6G(SCH_1):GND    I23 @T6G_MB_LIB.T6G(SCH_1):PAGE31
  AT46    GND @T6G_MB_LIB.T6G(SCH_1):GND    I23 @T6G_MB_LIB.T6G(SCH_1):PAGE31
  AT48    GND @T6G_MB_LIB.T6G(SCH_1):GND    I23 @T6G_MB_LIB.T6G(SCH_1):PAGE31
  AT50    GND @T6G_MB_LIB.T6G(SCH_1):GND    I23 @T6G_MB_LIB.T6G(SCH_1):PAGE31
  AT52    GND @T6G_MB_LIB.T6G(SCH_1):GND    I23 @T6G_MB_LIB.T6G(SCH_1):PAGE31
  AT54    GND @T6G_MB_LIB.T6G(SCH_1):GND    I23 @T6G_MB_LIB.T6G(SCH_1):PAGE31
  AT56    GND @T6G_MB_LIB.T6G(SCH_1):GND    I23 @T6G_MB_LIB.T6G(SCH_1):PAGE31
  AT57    GND @T6G_MB_LIB.T6G(SCH_1):GND    I23 @T6G_MB_LIB.T6G(SCH_1):PAGE31
  AT59    GND @T6G_MB_LIB.T6G(SCH_1):GND    I23 @T6G_MB_LIB.T6G(SCH_1):PAGE31
  AT60    GND @T6G_MB_LIB.T6G(SCH_1):GND    I23 @T6G_MB_LIB.T6G(SCH_1):PAGE31
  AT61    GND @T6G_MB_LIB.T6G(SCH_1):GND    I23 @T6G_MB_LIB.T6G(SCH_1):PAGE31
  AT63    GND @T6G_MB_LIB.T6G(SCH_1):GND    I23 @T6G_MB_LIB.T6G(SCH_1):PAGE31
  AT64    GND @T6G_MB_LIB.T6G(SCH_1):GND    I23 @T6G_MB_LIB.T6G(SCH_1):PAGE31
  AT66    GND @T6G_MB_LIB.T6G(SCH_1):GND    I23 @T6G_MB_LIB.T6G(SCH_1):PAGE31
  AT67    GND @T6G_MB_LIB.T6G(SCH_1):GND    I23 @T6G_MB_LIB.T6G(SCH_1):PAGE31
  AT68    GND @T6G_MB_LIB.T6G(SCH_1):GND    I23 @T6G_MB_LIB.T6G(SCH_1):PAGE31
  AT70    GND @T6G_MB_LIB.T6G(SCH_1):GND    I23 @T6G_MB_LIB.T6G(SCH_1):PAGE31
  AT71    GND @T6G_MB_LIB.T6G(SCH_1):GND    I23 @T6G_MB_LIB.T6G(SCH_1):PAGE31
  AT72    GND @T6G_MB_LIB.T6G(SCH_1):GND    I23 @T6G_MB_LIB.T6G(SCH_1):PAGE31
  AT73    GND @T6G_MB_LIB.T6G(SCH_1):GND    I23 @T6G_MB_LIB.T6G(SCH_1):PAGE31
   AU1    GND @T6G_MB_LIB.T6G(SCH_1):GND    I23 @T6G_MB_LIB.T6G(SCH_1):PAGE31
   AU3    GND @T6G_MB_LIB.T6G(SCH_1):GND    I23 @T6G_MB_LIB.T6G(SCH_1):PAGE31
   AU4    GND @T6G_MB_LIB.T6G(SCH_1):GND    I23 @T6G_MB_LIB.T6G(SCH_1):PAGE31
   AU6    GND @T6G_MB_LIB.T6G(SCH_1):GND    I23 @T6G_MB_LIB.T6G(SCH_1):PAGE31
   AU8    GND @T6G_MB_LIB.T6G(SCH_1):GND    I23 @T6G_MB_LIB.T6G(SCH_1):PAGE31
  AU11    GND @T6G_MB_LIB.T6G(SCH_1):GND    I23 @T6G_MB_LIB.T6G(SCH_1):PAGE31
  AU13    GND @T6G_MB_LIB.T6G(SCH_1):GND    I23 @T6G_MB_LIB.T6G(SCH_1):PAGE31
  AU15    GND @T6G_MB_LIB.T6G(SCH_1):GND    I23 @T6G_MB_LIB.T6G(SCH_1):PAGE31
  AU18    GND @T6G_MB_LIB.T6G(SCH_1):GND    I23 @T6G_MB_LIB.T6G(SCH_1):PAGE31
  AU20    GND @T6G_MB_LIB.T6G(SCH_1):GND    I23 @T6G_MB_LIB.T6G(SCH_1):PAGE31
  AU22    GND @T6G_MB_LIB.T6G(SCH_1):GND    I23 @T6G_MB_LIB.T6G(SCH_1):PAGE31
  AU24    GND @T6G_MB_LIB.T6G(SCH_1):GND    I23 @T6G_MB_LIB.T6G(SCH_1):PAGE31
  AU26    GND @T6G_MB_LIB.T6G(SCH_1):GND    I23 @T6G_MB_LIB.T6G(SCH_1):PAGE31
  AU28    GND @T6G_MB_LIB.T6G(SCH_1):GND    I23 @T6G_MB_LIB.T6G(SCH_1):PAGE31
  AU30    GND @T6G_MB_LIB.T6G(SCH_1):GND    I23 @T6G_MB_LIB.T6G(SCH_1):PAGE31
  AU32    GND @T6G_MB_LIB.T6G(SCH_1):GND    I23 @T6G_MB_LIB.T6G(SCH_1):PAGE31
  AU34    GND @T6G_MB_LIB.T6G(SCH_1):GND    I23 @T6G_MB_LIB.T6G(SCH_1):PAGE31
  AU36    GND @T6G_MB_LIB.T6G(SCH_1):GND    I23 @T6G_MB_LIB.T6G(SCH_1):PAGE31
  AU41    GND @T6G_MB_LIB.T6G(SCH_1):GND    I23 @T6G_MB_LIB.T6G(SCH_1):PAGE31
  AU43    GND @T6G_MB_LIB.T6G(SCH_1):GND    I23 @T6G_MB_LIB.T6G(SCH_1):PAGE31
  AU45    GND @T6G_MB_LIB.T6G(SCH_1):GND    I23 @T6G_MB_LIB.T6G(SCH_1):PAGE31
  AU47    GND @T6G_MB_LIB.T6G(SCH_1):GND    I23 @T6G_MB_LIB.T6G(SCH_1):PAGE31
  AU49    GND @T6G_MB_LIB.T6G(SCH_1):GND    I23 @T6G_MB_LIB.T6G(SCH_1):PAGE31
  AU51    GND @T6G_MB_LIB.T6G(SCH_1):GND    I23 @T6G_MB_LIB.T6G(SCH_1):PAGE31
  AU53    GND @T6G_MB_LIB.T6G(SCH_1):GND    I23 @T6G_MB_LIB.T6G(SCH_1):PAGE31
  AU56    GND @T6G_MB_LIB.T6G(SCH_1):GND    I23 @T6G_MB_LIB.T6G(SCH_1):PAGE31
  AU58    GND @T6G_MB_LIB.T6G(SCH_1):GND    I23 @T6G_MB_LIB.T6G(SCH_1):PAGE31
  AU61    GND @T6G_MB_LIB.T6G(SCH_1):GND    I23 @T6G_MB_LIB.T6G(SCH_1):PAGE31
  AU63    GND @T6G_MB_LIB.T6G(SCH_1):GND    I23 @T6G_MB_LIB.T6G(SCH_1):PAGE31
  AU65    GND @T6G_MB_LIB.T6G(SCH_1):GND    I23 @T6G_MB_LIB.T6G(SCH_1):PAGE31
  AU68    GND @T6G_MB_LIB.T6G(SCH_1):GND    I23 @T6G_MB_LIB.T6G(SCH_1):PAGE31
  AU70    GND @T6G_MB_LIB.T6G(SCH_1):GND    I23 @T6G_MB_LIB.T6G(SCH_1):PAGE31
  AU72    GND @T6G_MB_LIB.T6G(SCH_1):GND    I23 @T6G_MB_LIB.T6G(SCH_1):PAGE31
  AU73    GND @T6G_MB_LIB.T6G(SCH_1):GND    I23 @T6G_MB_LIB.T6G(SCH_1):PAGE31
  AU75    GND @T6G_MB_LIB.T6G(SCH_1):GND    I23 @T6G_MB_LIB.T6G(SCH_1):PAGE31
   AV3    GND @T6G_MB_LIB.T6G(SCH_1):GND    I23 @T6G_MB_LIB.T6G(SCH_1):PAGE31
   AV8    GND @T6G_MB_LIB.T6G(SCH_1):GND    I23 @T6G_MB_LIB.T6G(SCH_1):PAGE31
  AV10    GND @T6G_MB_LIB.T6G(SCH_1):GND    I23 @T6G_MB_LIB.T6G(SCH_1):PAGE31
  AV15    GND @T6G_MB_LIB.T6G(SCH_1):GND    I23 @T6G_MB_LIB.T6G(SCH_1):PAGE31
  AV17    GND @T6G_MB_LIB.T6G(SCH_1):GND    I23 @T6G_MB_LIB.T6G(SCH_1):PAGE31
  AV23    GND @T6G_MB_LIB.T6G(SCH_1):GND    I23 @T6G_MB_LIB.T6G(SCH_1):PAGE31
  AV25    GND @T6G_MB_LIB.T6G(SCH_1):GND    I23 @T6G_MB_LIB.T6G(SCH_1):PAGE31
  AV27    GND @T6G_MB_LIB.T6G(SCH_1):GND    I23 @T6G_MB_LIB.T6G(SCH_1):PAGE31
  AV29    GND @T6G_MB_LIB.T6G(SCH_1):GND    I23 @T6G_MB_LIB.T6G(SCH_1):PAGE31
  AV31    GND @T6G_MB_LIB.T6G(SCH_1):GND    I23 @T6G_MB_LIB.T6G(SCH_1):PAGE31
  AV33    GND @T6G_MB_LIB.T6G(SCH_1):GND    I23 @T6G_MB_LIB.T6G(SCH_1):PAGE31
  AV35    GND @T6G_MB_LIB.T6G(SCH_1):GND    I23 @T6G_MB_LIB.T6G(SCH_1):PAGE31
  AV37    GND @T6G_MB_LIB.T6G(SCH_1):GND    I23 @T6G_MB_LIB.T6G(SCH_1):PAGE31
  AV40    GND @T6G_MB_LIB.T6G(SCH_1):GND    I23 @T6G_MB_LIB.T6G(SCH_1):PAGE31
  AV42    GND @T6G_MB_LIB.T6G(SCH_1):GND    I23 @T6G_MB_LIB.T6G(SCH_1):PAGE31
  AV44    GND @T6G_MB_LIB.T6G(SCH_1):GND    I23 @T6G_MB_LIB.T6G(SCH_1):PAGE31
  AV46    GND @T6G_MB_LIB.T6G(SCH_1):GND    I23 @T6G_MB_LIB.T6G(SCH_1):PAGE31
  AV48    GND @T6G_MB_LIB.T6G(SCH_1):GND    I23 @T6G_MB_LIB.T6G(SCH_1):PAGE31
  AV50    GND @T6G_MB_LIB.T6G(SCH_1):GND    I23 @T6G_MB_LIB.T6G(SCH_1):PAGE31
  AV52    GND @T6G_MB_LIB.T6G(SCH_1):GND    I23 @T6G_MB_LIB.T6G(SCH_1):PAGE31
  AV54    GND @T6G_MB_LIB.T6G(SCH_1):GND    I23 @T6G_MB_LIB.T6G(SCH_1):PAGE31
  AV59    GND @T6G_MB_LIB.T6G(SCH_1):GND    I23 @T6G_MB_LIB.T6G(SCH_1):PAGE31
  AV61    GND @T6G_MB_LIB.T6G(SCH_1):GND    I23 @T6G_MB_LIB.T6G(SCH_1):PAGE31
  AV66    GND @T6G_MB_LIB.T6G(SCH_1):GND    I23 @T6G_MB_LIB.T6G(SCH_1):PAGE31
  AV68    GND @T6G_MB_LIB.T6G(SCH_1):GND    I23 @T6G_MB_LIB.T6G(SCH_1):PAGE31
  AV73    GND @T6G_MB_LIB.T6G(SCH_1):GND    I23 @T6G_MB_LIB.T6G(SCH_1):PAGE31
   AW1    GND @T6G_MB_LIB.T6G(SCH_1):GND    I23 @T6G_MB_LIB.T6G(SCH_1):PAGE31
   AW4    GND @T6G_MB_LIB.T6G(SCH_1):GND    I23 @T6G_MB_LIB.T6G(SCH_1):PAGE31
   AW6    GND @T6G_MB_LIB.T6G(SCH_1):GND    I23 @T6G_MB_LIB.T6G(SCH_1):PAGE31
   AW8    GND @T6G_MB_LIB.T6G(SCH_1):GND    I23 @T6G_MB_LIB.T6G(SCH_1):PAGE31
  AW11    GND @T6G_MB_LIB.T6G(SCH_1):GND    I23 @T6G_MB_LIB.T6G(SCH_1):PAGE31
  AW13    GND @T6G_MB_LIB.T6G(SCH_1):GND    I23 @T6G_MB_LIB.T6G(SCH_1):PAGE31
  AW15    GND @T6G_MB_LIB.T6G(SCH_1):GND    I23 @T6G_MB_LIB.T6G(SCH_1):PAGE31
  AW18    GND @T6G_MB_LIB.T6G(SCH_1):GND    I23 @T6G_MB_LIB.T6G(SCH_1):PAGE31
  AW20    GND @T6G_MB_LIB.T6G(SCH_1):GND    I23 @T6G_MB_LIB.T6G(SCH_1):PAGE31
  AW22    GND @T6G_MB_LIB.T6G(SCH_1):GND    I23 @T6G_MB_LIB.T6G(SCH_1):PAGE31
  AW24    GND @T6G_MB_LIB.T6G(SCH_1):GND    I23 @T6G_MB_LIB.T6G(SCH_1):PAGE31
  AW26    GND @T6G_MB_LIB.T6G(SCH_1):GND    I23 @T6G_MB_LIB.T6G(SCH_1):PAGE31
  AW28    GND @T6G_MB_LIB.T6G(SCH_1):GND    I23 @T6G_MB_LIB.T6G(SCH_1):PAGE31
  AW49    GND @T6G_MB_LIB.T6G(SCH_1):GND    I23 @T6G_MB_LIB.T6G(SCH_1):PAGE31
  AW51    GND @T6G_MB_LIB.T6G(SCH_1):GND    I23 @T6G_MB_LIB.T6G(SCH_1):PAGE31
  AW53    GND @T6G_MB_LIB.T6G(SCH_1):GND    I23 @T6G_MB_LIB.T6G(SCH_1):PAGE31
  AW56    GND @T6G_MB_LIB.T6G(SCH_1):GND    I23 @T6G_MB_LIB.T6G(SCH_1):PAGE31
  AW58    GND @T6G_MB_LIB.T6G(SCH_1):GND    I23 @T6G_MB_LIB.T6G(SCH_1):PAGE31
  AW61    GND @T6G_MB_LIB.T6G(SCH_1):GND    I23 @T6G_MB_LIB.T6G(SCH_1):PAGE31
  AW63    GND @T6G_MB_LIB.T6G(SCH_1):GND    I24 @T6G_MB_LIB.T6G(SCH_1):PAGE31
  AW65    GND @T6G_MB_LIB.T6G(SCH_1):GND    I24 @T6G_MB_LIB.T6G(SCH_1):PAGE31
  AW68    GND @T6G_MB_LIB.T6G(SCH_1):GND    I24 @T6G_MB_LIB.T6G(SCH_1):PAGE31
  AW70    GND @T6G_MB_LIB.T6G(SCH_1):GND    I24 @T6G_MB_LIB.T6G(SCH_1):PAGE31
  AW72    GND @T6G_MB_LIB.T6G(SCH_1):GND    I24 @T6G_MB_LIB.T6G(SCH_1):PAGE31
  AW75    GND @T6G_MB_LIB.T6G(SCH_1):GND    I24 @T6G_MB_LIB.T6G(SCH_1):PAGE31
   AY3    GND @T6G_MB_LIB.T6G(SCH_1):GND    I24 @T6G_MB_LIB.T6G(SCH_1):PAGE31
   AY5    GND @T6G_MB_LIB.T6G(SCH_1):GND    I24 @T6G_MB_LIB.T6G(SCH_1):PAGE31
   AY8    GND @T6G_MB_LIB.T6G(SCH_1):GND    I24 @T6G_MB_LIB.T6G(SCH_1):PAGE31
  AY10    GND @T6G_MB_LIB.T6G(SCH_1):GND    I24 @T6G_MB_LIB.T6G(SCH_1):PAGE31
  AY12    GND @T6G_MB_LIB.T6G(SCH_1):GND    I24 @T6G_MB_LIB.T6G(SCH_1):PAGE31
  AY15    GND @T6G_MB_LIB.T6G(SCH_1):GND    I24 @T6G_MB_LIB.T6G(SCH_1):PAGE31
  AY17    GND @T6G_MB_LIB.T6G(SCH_1):GND    I24 @T6G_MB_LIB.T6G(SCH_1):PAGE31
  AY19    GND @T6G_MB_LIB.T6G(SCH_1):GND    I24 @T6G_MB_LIB.T6G(SCH_1):PAGE31
  AY23    GND @T6G_MB_LIB.T6G(SCH_1):GND    I24 @T6G_MB_LIB.T6G(SCH_1):PAGE31
  AY25    GND @T6G_MB_LIB.T6G(SCH_1):GND    I24 @T6G_MB_LIB.T6G(SCH_1):PAGE31
  AY27    GND @T6G_MB_LIB.T6G(SCH_1):GND    I24 @T6G_MB_LIB.T6G(SCH_1):PAGE31
  AY48    GND @T6G_MB_LIB.T6G(SCH_1):GND    I24 @T6G_MB_LIB.T6G(SCH_1):PAGE31
  AY50    GND @T6G_MB_LIB.T6G(SCH_1):GND    I24 @T6G_MB_LIB.T6G(SCH_1):PAGE31
  AY52    GND @T6G_MB_LIB.T6G(SCH_1):GND    I24 @T6G_MB_LIB.T6G(SCH_1):PAGE31
  AY54    GND @T6G_MB_LIB.T6G(SCH_1):GND    I24 @T6G_MB_LIB.T6G(SCH_1):PAGE31
  AY57    GND @T6G_MB_LIB.T6G(SCH_1):GND    I24 @T6G_MB_LIB.T6G(SCH_1):PAGE31
  AY59    GND @T6G_MB_LIB.T6G(SCH_1):GND    I24 @T6G_MB_LIB.T6G(SCH_1):PAGE31
  AY61    GND @T6G_MB_LIB.T6G(SCH_1):GND    I24 @T6G_MB_LIB.T6G(SCH_1):PAGE31
  AY64    GND @T6G_MB_LIB.T6G(SCH_1):GND    I24 @T6G_MB_LIB.T6G(SCH_1):PAGE31
  AY66    GND @T6G_MB_LIB.T6G(SCH_1):GND    I24 @T6G_MB_LIB.T6G(SCH_1):PAGE31
  AY68    GND @T6G_MB_LIB.T6G(SCH_1):GND    I24 @T6G_MB_LIB.T6G(SCH_1):PAGE31
  AY71    GND @T6G_MB_LIB.T6G(SCH_1):GND    I24 @T6G_MB_LIB.T6G(SCH_1):PAGE31
  AY73    GND @T6G_MB_LIB.T6G(SCH_1):GND    I24 @T6G_MB_LIB.T6G(SCH_1):PAGE31
   BA1    GND @T6G_MB_LIB.T6G(SCH_1):GND    I24 @T6G_MB_LIB.T6G(SCH_1):PAGE31
   BA6    GND @T6G_MB_LIB.T6G(SCH_1):GND    I24 @T6G_MB_LIB.T6G(SCH_1):PAGE31
   BA8    GND @T6G_MB_LIB.T6G(SCH_1):GND    I24 @T6G_MB_LIB.T6G(SCH_1):PAGE31
  BA13    GND @T6G_MB_LIB.T6G(SCH_1):GND    I24 @T6G_MB_LIB.T6G(SCH_1):PAGE31
  BA15    GND @T6G_MB_LIB.T6G(SCH_1):GND    I24 @T6G_MB_LIB.T6G(SCH_1):PAGE31
  BA20    GND @T6G_MB_LIB.T6G(SCH_1):GND    I24 @T6G_MB_LIB.T6G(SCH_1):PAGE31
  BA22    GND @T6G_MB_LIB.T6G(SCH_1):GND    I24 @T6G_MB_LIB.T6G(SCH_1):PAGE31
  BA24    GND @T6G_MB_LIB.T6G(SCH_1):GND    I24 @T6G_MB_LIB.T6G(SCH_1):PAGE31
  BA26    GND @T6G_MB_LIB.T6G(SCH_1):GND    I24 @T6G_MB_LIB.T6G(SCH_1):PAGE31
  BA28    GND @T6G_MB_LIB.T6G(SCH_1):GND    I24 @T6G_MB_LIB.T6G(SCH_1):PAGE31
  BA49    GND @T6G_MB_LIB.T6G(SCH_1):GND    I24 @T6G_MB_LIB.T6G(SCH_1):PAGE31
  BA51    GND @T6G_MB_LIB.T6G(SCH_1):GND    I24 @T6G_MB_LIB.T6G(SCH_1):PAGE31
  BA53    GND @T6G_MB_LIB.T6G(SCH_1):GND    I24 @T6G_MB_LIB.T6G(SCH_1):PAGE31
  BA56    GND @T6G_MB_LIB.T6G(SCH_1):GND    I24 @T6G_MB_LIB.T6G(SCH_1):PAGE31
  BA61    GND @T6G_MB_LIB.T6G(SCH_1):GND    I24 @T6G_MB_LIB.T6G(SCH_1):PAGE31
  BA63    GND @T6G_MB_LIB.T6G(SCH_1):GND    I24 @T6G_MB_LIB.T6G(SCH_1):PAGE31
  BA68    GND @T6G_MB_LIB.T6G(SCH_1):GND    I24 @T6G_MB_LIB.T6G(SCH_1):PAGE31
  BA70    GND @T6G_MB_LIB.T6G(SCH_1):GND    I24 @T6G_MB_LIB.T6G(SCH_1):PAGE31
  BA75    GND @T6G_MB_LIB.T6G(SCH_1):GND    I24 @T6G_MB_LIB.T6G(SCH_1):PAGE31
   BB3    GND @T6G_MB_LIB.T6G(SCH_1):GND    I24 @T6G_MB_LIB.T6G(SCH_1):PAGE31
   BB5    GND @T6G_MB_LIB.T6G(SCH_1):GND    I24 @T6G_MB_LIB.T6G(SCH_1):PAGE31
   BB8    GND @T6G_MB_LIB.T6G(SCH_1):GND    I24 @T6G_MB_LIB.T6G(SCH_1):PAGE31
  BB10    GND @T6G_MB_LIB.T6G(SCH_1):GND    I24 @T6G_MB_LIB.T6G(SCH_1):PAGE31
  BB12    GND @T6G_MB_LIB.T6G(SCH_1):GND    I24 @T6G_MB_LIB.T6G(SCH_1):PAGE31
  BB15    GND @T6G_MB_LIB.T6G(SCH_1):GND    I24 @T6G_MB_LIB.T6G(SCH_1):PAGE31
  BB17    GND @T6G_MB_LIB.T6G(SCH_1):GND    I24 @T6G_MB_LIB.T6G(SCH_1):PAGE31
  BB19    GND @T6G_MB_LIB.T6G(SCH_1):GND    I24 @T6G_MB_LIB.T6G(SCH_1):PAGE31
  BB23    GND @T6G_MB_LIB.T6G(SCH_1):GND    I24 @T6G_MB_LIB.T6G(SCH_1):PAGE31
  BB25    GND @T6G_MB_LIB.T6G(SCH_1):GND    I24 @T6G_MB_LIB.T6G(SCH_1):PAGE31
  BB27    GND @T6G_MB_LIB.T6G(SCH_1):GND    I24 @T6G_MB_LIB.T6G(SCH_1):PAGE31
  BB48    GND @T6G_MB_LIB.T6G(SCH_1):GND    I24 @T6G_MB_LIB.T6G(SCH_1):PAGE31
  BB50    GND @T6G_MB_LIB.T6G(SCH_1):GND    I24 @T6G_MB_LIB.T6G(SCH_1):PAGE31
  BB52    GND @T6G_MB_LIB.T6G(SCH_1):GND    I24 @T6G_MB_LIB.T6G(SCH_1):PAGE31
  BB54    GND @T6G_MB_LIB.T6G(SCH_1):GND    I24 @T6G_MB_LIB.T6G(SCH_1):PAGE31
  BB57    GND @T6G_MB_LIB.T6G(SCH_1):GND    I24 @T6G_MB_LIB.T6G(SCH_1):PAGE31
  BB59    GND @T6G_MB_LIB.T6G(SCH_1):GND    I24 @T6G_MB_LIB.T6G(SCH_1):PAGE31
  BB61    GND @T6G_MB_LIB.T6G(SCH_1):GND    I24 @T6G_MB_LIB.T6G(SCH_1):PAGE31
  BB64    GND @T6G_MB_LIB.T6G(SCH_1):GND    I24 @T6G_MB_LIB.T6G(SCH_1):PAGE31
  BB66    GND @T6G_MB_LIB.T6G(SCH_1):GND    I24 @T6G_MB_LIB.T6G(SCH_1):PAGE31
  BB68    GND @T6G_MB_LIB.T6G(SCH_1):GND    I24 @T6G_MB_LIB.T6G(SCH_1):PAGE31
  BB71    GND @T6G_MB_LIB.T6G(SCH_1):GND    I24 @T6G_MB_LIB.T6G(SCH_1):PAGE31
  BB73    GND @T6G_MB_LIB.T6G(SCH_1):GND    I24 @T6G_MB_LIB.T6G(SCH_1):PAGE31
   BC1    GND @T6G_MB_LIB.T6G(SCH_1):GND    I24 @T6G_MB_LIB.T6G(SCH_1):PAGE31
   BC4    GND @T6G_MB_LIB.T6G(SCH_1):GND    I24 @T6G_MB_LIB.T6G(SCH_1):PAGE31
   BC6    GND @T6G_MB_LIB.T6G(SCH_1):GND    I24 @T6G_MB_LIB.T6G(SCH_1):PAGE31
   BC8    GND @T6G_MB_LIB.T6G(SCH_1):GND    I24 @T6G_MB_LIB.T6G(SCH_1):PAGE31
  BC11    GND @T6G_MB_LIB.T6G(SCH_1):GND    I24 @T6G_MB_LIB.T6G(SCH_1):PAGE31
  BC13    GND @T6G_MB_LIB.T6G(SCH_1):GND    I24 @T6G_MB_LIB.T6G(SCH_1):PAGE31
  BC15    GND @T6G_MB_LIB.T6G(SCH_1):GND    I24 @T6G_MB_LIB.T6G(SCH_1):PAGE31
  BC18    GND @T6G_MB_LIB.T6G(SCH_1):GND    I24 @T6G_MB_LIB.T6G(SCH_1):PAGE31
  BC20    GND @T6G_MB_LIB.T6G(SCH_1):GND    I24 @T6G_MB_LIB.T6G(SCH_1):PAGE31
  BC22    GND @T6G_MB_LIB.T6G(SCH_1):GND    I24 @T6G_MB_LIB.T6G(SCH_1):PAGE31
  BC24    GND @T6G_MB_LIB.T6G(SCH_1):GND    I24 @T6G_MB_LIB.T6G(SCH_1):PAGE31
  BC26    GND @T6G_MB_LIB.T6G(SCH_1):GND    I24 @T6G_MB_LIB.T6G(SCH_1):PAGE31
  BC28    GND @T6G_MB_LIB.T6G(SCH_1):GND    I24 @T6G_MB_LIB.T6G(SCH_1):PAGE31
  BC49    GND @T6G_MB_LIB.T6G(SCH_1):GND    I24 @T6G_MB_LIB.T6G(SCH_1):PAGE31
  BC50    GND @T6G_MB_LIB.T6G(SCH_1):GND    I24 @T6G_MB_LIB.T6G(SCH_1):PAGE31
  BC51    GND @T6G_MB_LIB.T6G(SCH_1):GND    I24 @T6G_MB_LIB.T6G(SCH_1):PAGE31
  BC53    GND @T6G_MB_LIB.T6G(SCH_1):GND    I24 @T6G_MB_LIB.T6G(SCH_1):PAGE31
  BC56    GND @T6G_MB_LIB.T6G(SCH_1):GND    I24 @T6G_MB_LIB.T6G(SCH_1):PAGE31
  BC58    GND @T6G_MB_LIB.T6G(SCH_1):GND    I24 @T6G_MB_LIB.T6G(SCH_1):PAGE31
  BC61    GND @T6G_MB_LIB.T6G(SCH_1):GND    I24 @T6G_MB_LIB.T6G(SCH_1):PAGE31
  BC63    GND @T6G_MB_LIB.T6G(SCH_1):GND    I24 @T6G_MB_LIB.T6G(SCH_1):PAGE31
  BC65    GND @T6G_MB_LIB.T6G(SCH_1):GND    I24 @T6G_MB_LIB.T6G(SCH_1):PAGE31
  BC68    GND @T6G_MB_LIB.T6G(SCH_1):GND    I24 @T6G_MB_LIB.T6G(SCH_1):PAGE31
  BC70    GND @T6G_MB_LIB.T6G(SCH_1):GND    I24 @T6G_MB_LIB.T6G(SCH_1):PAGE31
  BC72    GND @T6G_MB_LIB.T6G(SCH_1):GND    I24 @T6G_MB_LIB.T6G(SCH_1):PAGE31
  BC75    GND @T6G_MB_LIB.T6G(SCH_1):GND    I24 @T6G_MB_LIB.T6G(SCH_1):PAGE31
   BD3    GND @T6G_MB_LIB.T6G(SCH_1):GND    I24 @T6G_MB_LIB.T6G(SCH_1):PAGE31
   BD8    GND @T6G_MB_LIB.T6G(SCH_1):GND    I24 @T6G_MB_LIB.T6G(SCH_1):PAGE31
  BD10    GND @T6G_MB_LIB.T6G(SCH_1):GND    I24 @T6G_MB_LIB.T6G(SCH_1):PAGE31
  BD15    GND @T6G_MB_LIB.T6G(SCH_1):GND    I24 @T6G_MB_LIB.T6G(SCH_1):PAGE31
  BD17    GND @T6G_MB_LIB.T6G(SCH_1):GND    I24 @T6G_MB_LIB.T6G(SCH_1):PAGE31
  BD23    GND @T6G_MB_LIB.T6G(SCH_1):GND    I24 @T6G_MB_LIB.T6G(SCH_1):PAGE31
  BD25    GND @T6G_MB_LIB.T6G(SCH_1):GND    I24 @T6G_MB_LIB.T6G(SCH_1):PAGE31
  BD27    GND @T6G_MB_LIB.T6G(SCH_1):GND    I24 @T6G_MB_LIB.T6G(SCH_1):PAGE31
  BD49    GND @T6G_MB_LIB.T6G(SCH_1):GND    I24 @T6G_MB_LIB.T6G(SCH_1):PAGE31
  BD51    GND @T6G_MB_LIB.T6G(SCH_1):GND    I24 @T6G_MB_LIB.T6G(SCH_1):PAGE31
  BD53    GND @T6G_MB_LIB.T6G(SCH_1):GND    I24 @T6G_MB_LIB.T6G(SCH_1):PAGE31
  BD57    GND @T6G_MB_LIB.T6G(SCH_1):GND    I24 @T6G_MB_LIB.T6G(SCH_1):PAGE31
  BD59    GND @T6G_MB_LIB.T6G(SCH_1):GND    I24 @T6G_MB_LIB.T6G(SCH_1):PAGE31
  BD61    GND @T6G_MB_LIB.T6G(SCH_1):GND    I24 @T6G_MB_LIB.T6G(SCH_1):PAGE31
  BD64    GND @T6G_MB_LIB.T6G(SCH_1):GND    I24 @T6G_MB_LIB.T6G(SCH_1):PAGE31
  BD66    GND @T6G_MB_LIB.T6G(SCH_1):GND    I24 @T6G_MB_LIB.T6G(SCH_1):PAGE31
  BD68    GND @T6G_MB_LIB.T6G(SCH_1):GND    I24 @T6G_MB_LIB.T6G(SCH_1):PAGE31
  BD71    GND @T6G_MB_LIB.T6G(SCH_1):GND    I24 @T6G_MB_LIB.T6G(SCH_1):PAGE31
  BD73    GND @T6G_MB_LIB.T6G(SCH_1):GND    I24 @T6G_MB_LIB.T6G(SCH_1):PAGE31
   BF3    GND @T6G_MB_LIB.T6G(SCH_1):GND    I24 @T6G_MB_LIB.T6G(SCH_1):PAGE31
   BF5    GND @T6G_MB_LIB.T6G(SCH_1):GND    I24 @T6G_MB_LIB.T6G(SCH_1):PAGE31
   BF8    GND @T6G_MB_LIB.T6G(SCH_1):GND    I24 @T6G_MB_LIB.T6G(SCH_1):PAGE31
  BF10    GND @T6G_MB_LIB.T6G(SCH_1):GND    I24 @T6G_MB_LIB.T6G(SCH_1):PAGE31
  BF12    GND @T6G_MB_LIB.T6G(SCH_1):GND    I24 @T6G_MB_LIB.T6G(SCH_1):PAGE31
  BF15    GND @T6G_MB_LIB.T6G(SCH_1):GND    I24 @T6G_MB_LIB.T6G(SCH_1):PAGE31
  BF17    GND @T6G_MB_LIB.T6G(SCH_1):GND    I24 @T6G_MB_LIB.T6G(SCH_1):PAGE31
  BF19    GND @T6G_MB_LIB.T6G(SCH_1):GND    I24 @T6G_MB_LIB.T6G(SCH_1):PAGE31
  BF22    GND @T6G_MB_LIB.T6G(SCH_1):GND    I24 @T6G_MB_LIB.T6G(SCH_1):PAGE31
  BF24    GND @T6G_MB_LIB.T6G(SCH_1):GND    I24 @T6G_MB_LIB.T6G(SCH_1):PAGE31
  BF26    GND @T6G_MB_LIB.T6G(SCH_1):GND    I24 @T6G_MB_LIB.T6G(SCH_1):PAGE31
  BF28    GND @T6G_MB_LIB.T6G(SCH_1):GND    I24 @T6G_MB_LIB.T6G(SCH_1):PAGE31
  BF49    GND @T6G_MB_LIB.T6G(SCH_1):GND    I24 @T6G_MB_LIB.T6G(SCH_1):PAGE31
  BF50    GND @T6G_MB_LIB.T6G(SCH_1):GND    I24 @T6G_MB_LIB.T6G(SCH_1):PAGE31
  BF52    GND @T6G_MB_LIB.T6G(SCH_1):GND    I24 @T6G_MB_LIB.T6G(SCH_1):PAGE31
  BF54    GND @T6G_MB_LIB.T6G(SCH_1):GND    I24 @T6G_MB_LIB.T6G(SCH_1):PAGE31
  BF59    GND @T6G_MB_LIB.T6G(SCH_1):GND    I24 @T6G_MB_LIB.T6G(SCH_1):PAGE31
  BF61    GND @T6G_MB_LIB.T6G(SCH_1):GND    I24 @T6G_MB_LIB.T6G(SCH_1):PAGE31
  BF66    GND @T6G_MB_LIB.T6G(SCH_1):GND    I24 @T6G_MB_LIB.T6G(SCH_1):PAGE31
  BF68    GND @T6G_MB_LIB.T6G(SCH_1):GND    I24 @T6G_MB_LIB.T6G(SCH_1):PAGE31
  BF73    GND @T6G_MB_LIB.T6G(SCH_1):GND    I24 @T6G_MB_LIB.T6G(SCH_1):PAGE31
   BG1    GND @T6G_MB_LIB.T6G(SCH_1):GND    I24 @T6G_MB_LIB.T6G(SCH_1):PAGE31
   BG4    GND @T6G_MB_LIB.T6G(SCH_1):GND    I24 @T6G_MB_LIB.T6G(SCH_1):PAGE31
   BG6    GND @T6G_MB_LIB.T6G(SCH_1):GND    I24 @T6G_MB_LIB.T6G(SCH_1):PAGE31
   BG8    GND @T6G_MB_LIB.T6G(SCH_1):GND    I24 @T6G_MB_LIB.T6G(SCH_1):PAGE31
  BG11    GND @T6G_MB_LIB.T6G(SCH_1):GND    I24 @T6G_MB_LIB.T6G(SCH_1):PAGE31
  BG13    GND @T6G_MB_LIB.T6G(SCH_1):GND    I24 @T6G_MB_LIB.T6G(SCH_1):PAGE31
  BG15    GND @T6G_MB_LIB.T6G(SCH_1):GND    I24 @T6G_MB_LIB.T6G(SCH_1):PAGE31
  BG18    GND @T6G_MB_LIB.T6G(SCH_1):GND    I24 @T6G_MB_LIB.T6G(SCH_1):PAGE31
  BG20    GND @T6G_MB_LIB.T6G(SCH_1):GND    I24 @T6G_MB_LIB.T6G(SCH_1):PAGE31
  BG23    GND @T6G_MB_LIB.T6G(SCH_1):GND    I24 @T6G_MB_LIB.T6G(SCH_1):PAGE31
  BG25    GND @T6G_MB_LIB.T6G(SCH_1):GND    I24 @T6G_MB_LIB.T6G(SCH_1):PAGE31
  BG27    GND @T6G_MB_LIB.T6G(SCH_1):GND    I24 @T6G_MB_LIB.T6G(SCH_1):PAGE31
  BG49    GND @T6G_MB_LIB.T6G(SCH_1):GND    I24 @T6G_MB_LIB.T6G(SCH_1):PAGE31
  BG51    GND @T6G_MB_LIB.T6G(SCH_1):GND    I24 @T6G_MB_LIB.T6G(SCH_1):PAGE31
  BG53    GND @T6G_MB_LIB.T6G(SCH_1):GND    I24 @T6G_MB_LIB.T6G(SCH_1):PAGE31
  BG56    GND @T6G_MB_LIB.T6G(SCH_1):GND    I24 @T6G_MB_LIB.T6G(SCH_1):PAGE31
  BG58    GND @T6G_MB_LIB.T6G(SCH_1):GND    I24 @T6G_MB_LIB.T6G(SCH_1):PAGE31
  BG61    GND @T6G_MB_LIB.T6G(SCH_1):GND    I24 @T6G_MB_LIB.T6G(SCH_1):PAGE31
  BG63    GND @T6G_MB_LIB.T6G(SCH_1):GND    I24 @T6G_MB_LIB.T6G(SCH_1):PAGE31
  BG65    GND @T6G_MB_LIB.T6G(SCH_1):GND    I24 @T6G_MB_LIB.T6G(SCH_1):PAGE31
  BG68    GND @T6G_MB_LIB.T6G(SCH_1):GND    I24 @T6G_MB_LIB.T6G(SCH_1):PAGE31
  BG70    GND @T6G_MB_LIB.T6G(SCH_1):GND    I24 @T6G_MB_LIB.T6G(SCH_1):PAGE31
  BG72    GND @T6G_MB_LIB.T6G(SCH_1):GND    I24 @T6G_MB_LIB.T6G(SCH_1):PAGE31
  BG75    GND @T6G_MB_LIB.T6G(SCH_1):GND    I24 @T6G_MB_LIB.T6G(SCH_1):PAGE31
   BH3    GND @T6G_MB_LIB.T6G(SCH_1):GND    I24 @T6G_MB_LIB.T6G(SCH_1):PAGE31
   BH5    GND @T6G_MB_LIB.T6G(SCH_1):GND    I24 @T6G_MB_LIB.T6G(SCH_1):PAGE31
   BH8    GND @T6G_MB_LIB.T6G(SCH_1):GND    I24 @T6G_MB_LIB.T6G(SCH_1):PAGE31
  BH10    GND @T6G_MB_LIB.T6G(SCH_1):GND    I24 @T6G_MB_LIB.T6G(SCH_1):PAGE31
  BH12    GND @T6G_MB_LIB.T6G(SCH_1):GND    I24 @T6G_MB_LIB.T6G(SCH_1):PAGE31
  BH15    GND @T6G_MB_LIB.T6G(SCH_1):GND    I24 @T6G_MB_LIB.T6G(SCH_1):PAGE31
  BH17    GND @T6G_MB_LIB.T6G(SCH_1):GND    I24 @T6G_MB_LIB.T6G(SCH_1):PAGE31
  BH19    GND @T6G_MB_LIB.T6G(SCH_1):GND    I24 @T6G_MB_LIB.T6G(SCH_1):PAGE31
  BH22    GND @T6G_MB_LIB.T6G(SCH_1):GND    I24 @T6G_MB_LIB.T6G(SCH_1):PAGE31
  BH24    GND @T6G_MB_LIB.T6G(SCH_1):GND    I24 @T6G_MB_LIB.T6G(SCH_1):PAGE31
  BH26    GND @T6G_MB_LIB.T6G(SCH_1):GND    I24 @T6G_MB_LIB.T6G(SCH_1):PAGE31
  BH28    GND @T6G_MB_LIB.T6G(SCH_1):GND    I24 @T6G_MB_LIB.T6G(SCH_1):PAGE31
  BH49    GND @T6G_MB_LIB.T6G(SCH_1):GND    I24 @T6G_MB_LIB.T6G(SCH_1):PAGE31
  BH50    GND @T6G_MB_LIB.T6G(SCH_1):GND    I24 @T6G_MB_LIB.T6G(SCH_1):PAGE31
  BH52    GND @T6G_MB_LIB.T6G(SCH_1):GND    I24 @T6G_MB_LIB.T6G(SCH_1):PAGE31
  BH54    GND @T6G_MB_LIB.T6G(SCH_1):GND    I24 @T6G_MB_LIB.T6G(SCH_1):PAGE31
  BH57    GND @T6G_MB_LIB.T6G(SCH_1):GND    I24 @T6G_MB_LIB.T6G(SCH_1):PAGE31
  BH59    GND @T6G_MB_LIB.T6G(SCH_1):GND    I24 @T6G_MB_LIB.T6G(SCH_1):PAGE31
  BH61    GND @T6G_MB_LIB.T6G(SCH_1):GND    I24 @T6G_MB_LIB.T6G(SCH_1):PAGE31
  BH64    GND @T6G_MB_LIB.T6G(SCH_1):GND    I24 @T6G_MB_LIB.T6G(SCH_1):PAGE31
  BH66    GND @T6G_MB_LIB.T6G(SCH_1):GND    I24 @T6G_MB_LIB.T6G(SCH_1):PAGE31
  BH68    GND @T6G_MB_LIB.T6G(SCH_1):GND    I24 @T6G_MB_LIB.T6G(SCH_1):PAGE31
  BH71    GND @T6G_MB_LIB.T6G(SCH_1):GND    I24 @T6G_MB_LIB.T6G(SCH_1):PAGE31
  BH73    GND @T6G_MB_LIB.T6G(SCH_1):GND    I24 @T6G_MB_LIB.T6G(SCH_1):PAGE31
   BJ1    GND @T6G_MB_LIB.T6G(SCH_1):GND    I24 @T6G_MB_LIB.T6G(SCH_1):PAGE31
   BJ6    GND @T6G_MB_LIB.T6G(SCH_1):GND    I24 @T6G_MB_LIB.T6G(SCH_1):PAGE31
   BJ8    GND @T6G_MB_LIB.T6G(SCH_1):GND    I24 @T6G_MB_LIB.T6G(SCH_1):PAGE31
  BJ13    GND @T6G_MB_LIB.T6G(SCH_1):GND    I24 @T6G_MB_LIB.T6G(SCH_1):PAGE31
  BJ15    GND @T6G_MB_LIB.T6G(SCH_1):GND    I24 @T6G_MB_LIB.T6G(SCH_1):PAGE31
  BJ20    GND @T6G_MB_LIB.T6G(SCH_1):GND    I24 @T6G_MB_LIB.T6G(SCH_1):PAGE31
  BJ22    GND @T6G_MB_LIB.T6G(SCH_1):GND    I24 @T6G_MB_LIB.T6G(SCH_1):PAGE31
  BJ24    GND @T6G_MB_LIB.T6G(SCH_1):GND    I24 @T6G_MB_LIB.T6G(SCH_1):PAGE31
  BJ26    GND @T6G_MB_LIB.T6G(SCH_1):GND    I24 @T6G_MB_LIB.T6G(SCH_1):PAGE31
  BJ28    GND @T6G_MB_LIB.T6G(SCH_1):GND    I24 @T6G_MB_LIB.T6G(SCH_1):PAGE31
  BJ49    GND @T6G_MB_LIB.T6G(SCH_1):GND    I24 @T6G_MB_LIB.T6G(SCH_1):PAGE31
  BJ51    GND @T6G_MB_LIB.T6G(SCH_1):GND    I24 @T6G_MB_LIB.T6G(SCH_1):PAGE31
  BJ53    GND @T6G_MB_LIB.T6G(SCH_1):GND    I24 @T6G_MB_LIB.T6G(SCH_1):PAGE31
  BJ56    GND @T6G_MB_LIB.T6G(SCH_1):GND    I24 @T6G_MB_LIB.T6G(SCH_1):PAGE31
  BJ61    GND @T6G_MB_LIB.T6G(SCH_1):GND    I24 @T6G_MB_LIB.T6G(SCH_1):PAGE31
  BJ63    GND @T6G_MB_LIB.T6G(SCH_1):GND    I24 @T6G_MB_LIB.T6G(SCH_1):PAGE31
  BJ68    GND @T6G_MB_LIB.T6G(SCH_1):GND    I24 @T6G_MB_LIB.T6G(SCH_1):PAGE31
  BJ70    GND @T6G_MB_LIB.T6G(SCH_1):GND    I24 @T6G_MB_LIB.T6G(SCH_1):PAGE31
  BJ75    GND @T6G_MB_LIB.T6G(SCH_1):GND    I24 @T6G_MB_LIB.T6G(SCH_1):PAGE31
   BK3    GND @T6G_MB_LIB.T6G(SCH_1):GND    I24 @T6G_MB_LIB.T6G(SCH_1):PAGE31
   BK5    GND @T6G_MB_LIB.T6G(SCH_1):GND    I24 @T6G_MB_LIB.T6G(SCH_1):PAGE31
   BK8    GND @T6G_MB_LIB.T6G(SCH_1):GND    I24 @T6G_MB_LIB.T6G(SCH_1):PAGE31
  BK10    GND @T6G_MB_LIB.T6G(SCH_1):GND    I24 @T6G_MB_LIB.T6G(SCH_1):PAGE31
  BK12    GND @T6G_MB_LIB.T6G(SCH_1):GND    I24 @T6G_MB_LIB.T6G(SCH_1):PAGE31
  BK15    GND @T6G_MB_LIB.T6G(SCH_1):GND    I24 @T6G_MB_LIB.T6G(SCH_1):PAGE31
  BK17    GND @T6G_MB_LIB.T6G(SCH_1):GND    I24 @T6G_MB_LIB.T6G(SCH_1):PAGE31
  BK19    GND @T6G_MB_LIB.T6G(SCH_1):GND    I24 @T6G_MB_LIB.T6G(SCH_1):PAGE31
  BK23    GND @T6G_MB_LIB.T6G(SCH_1):GND    I24 @T6G_MB_LIB.T6G(SCH_1):PAGE31
  BK25    GND @T6G_MB_LIB.T6G(SCH_1):GND    I24 @T6G_MB_LIB.T6G(SCH_1):PAGE31
  BK27    GND @T6G_MB_LIB.T6G(SCH_1):GND    I24 @T6G_MB_LIB.T6G(SCH_1):PAGE31
  BK48    GND @T6G_MB_LIB.T6G(SCH_1):GND    I24 @T6G_MB_LIB.T6G(SCH_1):PAGE31
  BK50    GND @T6G_MB_LIB.T6G(SCH_1):GND    I24 @T6G_MB_LIB.T6G(SCH_1):PAGE31
  BK52    GND @T6G_MB_LIB.T6G(SCH_1):GND    I24 @T6G_MB_LIB.T6G(SCH_1):PAGE31
  BK54    GND @T6G_MB_LIB.T6G(SCH_1):GND    I24 @T6G_MB_LIB.T6G(SCH_1):PAGE31
  BK57    GND @T6G_MB_LIB.T6G(SCH_1):GND    I24 @T6G_MB_LIB.T6G(SCH_1):PAGE31
  BK59    GND @T6G_MB_LIB.T6G(SCH_1):GND    I24 @T6G_MB_LIB.T6G(SCH_1):PAGE31
  BK61    GND @T6G_MB_LIB.T6G(SCH_1):GND    I24 @T6G_MB_LIB.T6G(SCH_1):PAGE31
  BK64    GND @T6G_MB_LIB.T6G(SCH_1):GND    I24 @T6G_MB_LIB.T6G(SCH_1):PAGE31
  BK66    GND @T6G_MB_LIB.T6G(SCH_1):GND    I24 @T6G_MB_LIB.T6G(SCH_1):PAGE31
  BK68    GND @T6G_MB_LIB.T6G(SCH_1):GND    I24 @T6G_MB_LIB.T6G(SCH_1):PAGE31
  BK71    GND @T6G_MB_LIB.T6G(SCH_1):GND    I24 @T6G_MB_LIB.T6G(SCH_1):PAGE31
  BK73    GND @T6G_MB_LIB.T6G(SCH_1):GND    I24 @T6G_MB_LIB.T6G(SCH_1):PAGE31
   BL1    GND @T6G_MB_LIB.T6G(SCH_1):GND    I24 @T6G_MB_LIB.T6G(SCH_1):PAGE31
   BL4    GND @T6G_MB_LIB.T6G(SCH_1):GND    I24 @T6G_MB_LIB.T6G(SCH_1):PAGE31
   BL6    GND @T6G_MB_LIB.T6G(SCH_1):GND    I24 @T6G_MB_LIB.T6G(SCH_1):PAGE31
   BL8    GND @T6G_MB_LIB.T6G(SCH_1):GND    I24 @T6G_MB_LIB.T6G(SCH_1):PAGE31
  BL11    GND @T6G_MB_LIB.T6G(SCH_1):GND    I24 @T6G_MB_LIB.T6G(SCH_1):PAGE31
  BL13    GND @T6G_MB_LIB.T6G(SCH_1):GND    I24 @T6G_MB_LIB.T6G(SCH_1):PAGE31
  BL15    GND @T6G_MB_LIB.T6G(SCH_1):GND    I24 @T6G_MB_LIB.T6G(SCH_1):PAGE31
  BL18    GND @T6G_MB_LIB.T6G(SCH_1):GND    I24 @T6G_MB_LIB.T6G(SCH_1):PAGE31
  BL20    GND @T6G_MB_LIB.T6G(SCH_1):GND    I24 @T6G_MB_LIB.T6G(SCH_1):PAGE31
  BL22    GND @T6G_MB_LIB.T6G(SCH_1):GND    I24 @T6G_MB_LIB.T6G(SCH_1):PAGE31
  BL24    GND @T6G_MB_LIB.T6G(SCH_1):GND    I24 @T6G_MB_LIB.T6G(SCH_1):PAGE31
  BV37    GND @T6G_MB_LIB.T6G(SCH_1):GND    I13 @T6G_MB_LIB.T6G(SCH_1):PAGE32
  BL26    GND @T6G_MB_LIB.T6G(SCH_1):GND    I13 @T6G_MB_LIB.T6G(SCH_1):PAGE32
  BL28    GND @T6G_MB_LIB.T6G(SCH_1):GND    I13 @T6G_MB_LIB.T6G(SCH_1):PAGE32
  BL49    GND @T6G_MB_LIB.T6G(SCH_1):GND    I13 @T6G_MB_LIB.T6G(SCH_1):PAGE32
  BL51    GND @T6G_MB_LIB.T6G(SCH_1):GND    I13 @T6G_MB_LIB.T6G(SCH_1):PAGE32
  BL53    GND @T6G_MB_LIB.T6G(SCH_1):GND    I13 @T6G_MB_LIB.T6G(SCH_1):PAGE32
  BL56    GND @T6G_MB_LIB.T6G(SCH_1):GND    I13 @T6G_MB_LIB.T6G(SCH_1):PAGE32
  BL58    GND @T6G_MB_LIB.T6G(SCH_1):GND    I13 @T6G_MB_LIB.T6G(SCH_1):PAGE32
  BL61    GND @T6G_MB_LIB.T6G(SCH_1):GND    I13 @T6G_MB_LIB.T6G(SCH_1):PAGE32
  BL63    GND @T6G_MB_LIB.T6G(SCH_1):GND    I13 @T6G_MB_LIB.T6G(SCH_1):PAGE32
  BL65    GND @T6G_MB_LIB.T6G(SCH_1):GND    I13 @T6G_MB_LIB.T6G(SCH_1):PAGE32
  BL68    GND @T6G_MB_LIB.T6G(SCH_1):GND    I13 @T6G_MB_LIB.T6G(SCH_1):PAGE32
  BL70    GND @T6G_MB_LIB.T6G(SCH_1):GND    I13 @T6G_MB_LIB.T6G(SCH_1):PAGE32
  BL72    GND @T6G_MB_LIB.T6G(SCH_1):GND    I13 @T6G_MB_LIB.T6G(SCH_1):PAGE32
  BL75    GND @T6G_MB_LIB.T6G(SCH_1):GND    I13 @T6G_MB_LIB.T6G(SCH_1):PAGE32
   BM3    GND @T6G_MB_LIB.T6G(SCH_1):GND    I13 @T6G_MB_LIB.T6G(SCH_1):PAGE32
   BM8    GND @T6G_MB_LIB.T6G(SCH_1):GND    I13 @T6G_MB_LIB.T6G(SCH_1):PAGE32
  BM10    GND @T6G_MB_LIB.T6G(SCH_1):GND    I13 @T6G_MB_LIB.T6G(SCH_1):PAGE32
  BM15    GND @T6G_MB_LIB.T6G(SCH_1):GND    I13 @T6G_MB_LIB.T6G(SCH_1):PAGE32
  BM17    GND @T6G_MB_LIB.T6G(SCH_1):GND    I13 @T6G_MB_LIB.T6G(SCH_1):PAGE32
  BM23    GND @T6G_MB_LIB.T6G(SCH_1):GND    I13 @T6G_MB_LIB.T6G(SCH_1):PAGE32
  BM25    GND @T6G_MB_LIB.T6G(SCH_1):GND    I13 @T6G_MB_LIB.T6G(SCH_1):PAGE32
  BM27    GND @T6G_MB_LIB.T6G(SCH_1):GND    I13 @T6G_MB_LIB.T6G(SCH_1):PAGE32
  BM29    GND @T6G_MB_LIB.T6G(SCH_1):GND    I13 @T6G_MB_LIB.T6G(SCH_1):PAGE32
  BM31    GND @T6G_MB_LIB.T6G(SCH_1):GND    I13 @T6G_MB_LIB.T6G(SCH_1):PAGE32
  BM33    GND @T6G_MB_LIB.T6G(SCH_1):GND    I13 @T6G_MB_LIB.T6G(SCH_1):PAGE32
  BM35    GND @T6G_MB_LIB.T6G(SCH_1):GND    I13 @T6G_MB_LIB.T6G(SCH_1):PAGE32
  BM37    GND @T6G_MB_LIB.T6G(SCH_1):GND    I13 @T6G_MB_LIB.T6G(SCH_1):PAGE32
  BM40    GND @T6G_MB_LIB.T6G(SCH_1):GND    I13 @T6G_MB_LIB.T6G(SCH_1):PAGE32
  BM42    GND @T6G_MB_LIB.T6G(SCH_1):GND    I13 @T6G_MB_LIB.T6G(SCH_1):PAGE32
  BM44    GND @T6G_MB_LIB.T6G(SCH_1):GND    I13 @T6G_MB_LIB.T6G(SCH_1):PAGE32
  BM46    GND @T6G_MB_LIB.T6G(SCH_1):GND    I13 @T6G_MB_LIB.T6G(SCH_1):PAGE32
  BM48    GND @T6G_MB_LIB.T6G(SCH_1):GND    I13 @T6G_MB_LIB.T6G(SCH_1):PAGE32
  BM50    GND @T6G_MB_LIB.T6G(SCH_1):GND    I13 @T6G_MB_LIB.T6G(SCH_1):PAGE32
  BM52    GND @T6G_MB_LIB.T6G(SCH_1):GND    I13 @T6G_MB_LIB.T6G(SCH_1):PAGE32
  BM54    GND @T6G_MB_LIB.T6G(SCH_1):GND    I13 @T6G_MB_LIB.T6G(SCH_1):PAGE32
  BM59    GND @T6G_MB_LIB.T6G(SCH_1):GND    I13 @T6G_MB_LIB.T6G(SCH_1):PAGE32
  BM61    GND @T6G_MB_LIB.T6G(SCH_1):GND    I13 @T6G_MB_LIB.T6G(SCH_1):PAGE32
  BM66    GND @T6G_MB_LIB.T6G(SCH_1):GND    I13 @T6G_MB_LIB.T6G(SCH_1):PAGE32
  BM68    GND @T6G_MB_LIB.T6G(SCH_1):GND    I13 @T6G_MB_LIB.T6G(SCH_1):PAGE32
  BM73    GND @T6G_MB_LIB.T6G(SCH_1):GND    I13 @T6G_MB_LIB.T6G(SCH_1):PAGE32
   BN1    GND @T6G_MB_LIB.T6G(SCH_1):GND    I13 @T6G_MB_LIB.T6G(SCH_1):PAGE32
   BN4    GND @T6G_MB_LIB.T6G(SCH_1):GND    I13 @T6G_MB_LIB.T6G(SCH_1):PAGE32
   BN6    GND @T6G_MB_LIB.T6G(SCH_1):GND    I13 @T6G_MB_LIB.T6G(SCH_1):PAGE32
   BN8    GND @T6G_MB_LIB.T6G(SCH_1):GND    I13 @T6G_MB_LIB.T6G(SCH_1):PAGE32
  BN11    GND @T6G_MB_LIB.T6G(SCH_1):GND    I13 @T6G_MB_LIB.T6G(SCH_1):PAGE32
  BN13    GND @T6G_MB_LIB.T6G(SCH_1):GND    I13 @T6G_MB_LIB.T6G(SCH_1):PAGE32
  BN15    GND @T6G_MB_LIB.T6G(SCH_1):GND    I13 @T6G_MB_LIB.T6G(SCH_1):PAGE32
  BN18    GND @T6G_MB_LIB.T6G(SCH_1):GND    I13 @T6G_MB_LIB.T6G(SCH_1):PAGE32
  BN20    GND @T6G_MB_LIB.T6G(SCH_1):GND    I13 @T6G_MB_LIB.T6G(SCH_1):PAGE32
  BN22    GND @T6G_MB_LIB.T6G(SCH_1):GND    I13 @T6G_MB_LIB.T6G(SCH_1):PAGE32
  BN24    GND @T6G_MB_LIB.T6G(SCH_1):GND    I13 @T6G_MB_LIB.T6G(SCH_1):PAGE32
  BN26    GND @T6G_MB_LIB.T6G(SCH_1):GND    I13 @T6G_MB_LIB.T6G(SCH_1):PAGE32
  BN28    GND @T6G_MB_LIB.T6G(SCH_1):GND    I13 @T6G_MB_LIB.T6G(SCH_1):PAGE32
  BN30    GND @T6G_MB_LIB.T6G(SCH_1):GND    I13 @T6G_MB_LIB.T6G(SCH_1):PAGE32
  BN32    GND @T6G_MB_LIB.T6G(SCH_1):GND    I13 @T6G_MB_LIB.T6G(SCH_1):PAGE32
  BN34    GND @T6G_MB_LIB.T6G(SCH_1):GND    I13 @T6G_MB_LIB.T6G(SCH_1):PAGE32
  BN36    GND @T6G_MB_LIB.T6G(SCH_1):GND    I13 @T6G_MB_LIB.T6G(SCH_1):PAGE32
  BN41    GND @T6G_MB_LIB.T6G(SCH_1):GND    I13 @T6G_MB_LIB.T6G(SCH_1):PAGE32
  BN43    GND @T6G_MB_LIB.T6G(SCH_1):GND    I13 @T6G_MB_LIB.T6G(SCH_1):PAGE32
  BN45    GND @T6G_MB_LIB.T6G(SCH_1):GND    I13 @T6G_MB_LIB.T6G(SCH_1):PAGE32
  BN47    GND @T6G_MB_LIB.T6G(SCH_1):GND    I13 @T6G_MB_LIB.T6G(SCH_1):PAGE32
  BN49    GND @T6G_MB_LIB.T6G(SCH_1):GND    I13 @T6G_MB_LIB.T6G(SCH_1):PAGE32
  BN51    GND @T6G_MB_LIB.T6G(SCH_1):GND    I13 @T6G_MB_LIB.T6G(SCH_1):PAGE32
  BN53    GND @T6G_MB_LIB.T6G(SCH_1):GND    I13 @T6G_MB_LIB.T6G(SCH_1):PAGE32
  BN56    GND @T6G_MB_LIB.T6G(SCH_1):GND    I13 @T6G_MB_LIB.T6G(SCH_1):PAGE32
  BN58    GND @T6G_MB_LIB.T6G(SCH_1):GND    I13 @T6G_MB_LIB.T6G(SCH_1):PAGE32
  BN61    GND @T6G_MB_LIB.T6G(SCH_1):GND    I13 @T6G_MB_LIB.T6G(SCH_1):PAGE32
  BN63    GND @T6G_MB_LIB.T6G(SCH_1):GND    I13 @T6G_MB_LIB.T6G(SCH_1):PAGE32
  BN65    GND @T6G_MB_LIB.T6G(SCH_1):GND    I13 @T6G_MB_LIB.T6G(SCH_1):PAGE32
  BN68    GND @T6G_MB_LIB.T6G(SCH_1):GND    I13 @T6G_MB_LIB.T6G(SCH_1):PAGE32
  BN70    GND @T6G_MB_LIB.T6G(SCH_1):GND    I13 @T6G_MB_LIB.T6G(SCH_1):PAGE32
  BN72    GND @T6G_MB_LIB.T6G(SCH_1):GND    I13 @T6G_MB_LIB.T6G(SCH_1):PAGE32
  BN75    GND @T6G_MB_LIB.T6G(SCH_1):GND    I13 @T6G_MB_LIB.T6G(SCH_1):PAGE32
   BP3    GND @T6G_MB_LIB.T6G(SCH_1):GND    I13 @T6G_MB_LIB.T6G(SCH_1):PAGE32
   BP5    GND @T6G_MB_LIB.T6G(SCH_1):GND    I13 @T6G_MB_LIB.T6G(SCH_1):PAGE32
   BP8    GND @T6G_MB_LIB.T6G(SCH_1):GND    I13 @T6G_MB_LIB.T6G(SCH_1):PAGE32
  BP10    GND @T6G_MB_LIB.T6G(SCH_1):GND    I13 @T6G_MB_LIB.T6G(SCH_1):PAGE32
  BP12    GND @T6G_MB_LIB.T6G(SCH_1):GND    I13 @T6G_MB_LIB.T6G(SCH_1):PAGE32
  BP15    GND @T6G_MB_LIB.T6G(SCH_1):GND    I13 @T6G_MB_LIB.T6G(SCH_1):PAGE32
  BP17    GND @T6G_MB_LIB.T6G(SCH_1):GND    I13 @T6G_MB_LIB.T6G(SCH_1):PAGE32
  BP19    GND @T6G_MB_LIB.T6G(SCH_1):GND    I13 @T6G_MB_LIB.T6G(SCH_1):PAGE32
  BP23    GND @T6G_MB_LIB.T6G(SCH_1):GND    I13 @T6G_MB_LIB.T6G(SCH_1):PAGE32
  BP25    GND @T6G_MB_LIB.T6G(SCH_1):GND    I13 @T6G_MB_LIB.T6G(SCH_1):PAGE32
  BP27    GND @T6G_MB_LIB.T6G(SCH_1):GND    I13 @T6G_MB_LIB.T6G(SCH_1):PAGE32
  BP29    GND @T6G_MB_LIB.T6G(SCH_1):GND    I13 @T6G_MB_LIB.T6G(SCH_1):PAGE32
  BP31    GND @T6G_MB_LIB.T6G(SCH_1):GND    I13 @T6G_MB_LIB.T6G(SCH_1):PAGE32
  BP33    GND @T6G_MB_LIB.T6G(SCH_1):GND    I13 @T6G_MB_LIB.T6G(SCH_1):PAGE32
  BP35    GND @T6G_MB_LIB.T6G(SCH_1):GND    I13 @T6G_MB_LIB.T6G(SCH_1):PAGE32
  BP37    GND @T6G_MB_LIB.T6G(SCH_1):GND    I13 @T6G_MB_LIB.T6G(SCH_1):PAGE32
  BP40    GND @T6G_MB_LIB.T6G(SCH_1):GND    I13 @T6G_MB_LIB.T6G(SCH_1):PAGE32
  BP42    GND @T6G_MB_LIB.T6G(SCH_1):GND    I13 @T6G_MB_LIB.T6G(SCH_1):PAGE32
  BP44    GND @T6G_MB_LIB.T6G(SCH_1):GND    I13 @T6G_MB_LIB.T6G(SCH_1):PAGE32
  BP46    GND @T6G_MB_LIB.T6G(SCH_1):GND    I13 @T6G_MB_LIB.T6G(SCH_1):PAGE32
  BP48    GND @T6G_MB_LIB.T6G(SCH_1):GND    I13 @T6G_MB_LIB.T6G(SCH_1):PAGE32
  BP50    GND @T6G_MB_LIB.T6G(SCH_1):GND    I13 @T6G_MB_LIB.T6G(SCH_1):PAGE32
  BP52    GND @T6G_MB_LIB.T6G(SCH_1):GND    I13 @T6G_MB_LIB.T6G(SCH_1):PAGE32
  BP54    GND @T6G_MB_LIB.T6G(SCH_1):GND    I13 @T6G_MB_LIB.T6G(SCH_1):PAGE32
  BP57    GND @T6G_MB_LIB.T6G(SCH_1):GND    I13 @T6G_MB_LIB.T6G(SCH_1):PAGE32
  BP59    GND @T6G_MB_LIB.T6G(SCH_1):GND    I13 @T6G_MB_LIB.T6G(SCH_1):PAGE32
  BP61    GND @T6G_MB_LIB.T6G(SCH_1):GND    I13 @T6G_MB_LIB.T6G(SCH_1):PAGE32
  BP64    GND @T6G_MB_LIB.T6G(SCH_1):GND    I13 @T6G_MB_LIB.T6G(SCH_1):PAGE32
  BP66    GND @T6G_MB_LIB.T6G(SCH_1):GND    I13 @T6G_MB_LIB.T6G(SCH_1):PAGE32
  BP68    GND @T6G_MB_LIB.T6G(SCH_1):GND    I13 @T6G_MB_LIB.T6G(SCH_1):PAGE32
  BP71    GND @T6G_MB_LIB.T6G(SCH_1):GND    I13 @T6G_MB_LIB.T6G(SCH_1):PAGE32
  BP73    GND @T6G_MB_LIB.T6G(SCH_1):GND    I13 @T6G_MB_LIB.T6G(SCH_1):PAGE32
   BR1    GND @T6G_MB_LIB.T6G(SCH_1):GND    I13 @T6G_MB_LIB.T6G(SCH_1):PAGE32
   BR3    GND @T6G_MB_LIB.T6G(SCH_1):GND    I13 @T6G_MB_LIB.T6G(SCH_1):PAGE32
   BR6    GND @T6G_MB_LIB.T6G(SCH_1):GND    I13 @T6G_MB_LIB.T6G(SCH_1):PAGE32
   BR7    GND @T6G_MB_LIB.T6G(SCH_1):GND    I13 @T6G_MB_LIB.T6G(SCH_1):PAGE32
   BR8    GND @T6G_MB_LIB.T6G(SCH_1):GND    I13 @T6G_MB_LIB.T6G(SCH_1):PAGE32
  BR10    GND @T6G_MB_LIB.T6G(SCH_1):GND    I13 @T6G_MB_LIB.T6G(SCH_1):PAGE32
  BR13    GND @T6G_MB_LIB.T6G(SCH_1):GND    I13 @T6G_MB_LIB.T6G(SCH_1):PAGE32
  BR14    GND @T6G_MB_LIB.T6G(SCH_1):GND    I13 @T6G_MB_LIB.T6G(SCH_1):PAGE32
  BR15    GND @T6G_MB_LIB.T6G(SCH_1):GND    I13 @T6G_MB_LIB.T6G(SCH_1):PAGE32
  BR17    GND @T6G_MB_LIB.T6G(SCH_1):GND    I13 @T6G_MB_LIB.T6G(SCH_1):PAGE32
  BR20    GND @T6G_MB_LIB.T6G(SCH_1):GND    I13 @T6G_MB_LIB.T6G(SCH_1):PAGE32
  BR21    GND @T6G_MB_LIB.T6G(SCH_1):GND    I13 @T6G_MB_LIB.T6G(SCH_1):PAGE32
  BR22    GND @T6G_MB_LIB.T6G(SCH_1):GND    I13 @T6G_MB_LIB.T6G(SCH_1):PAGE32
  BR24    GND @T6G_MB_LIB.T6G(SCH_1):GND    I13 @T6G_MB_LIB.T6G(SCH_1):PAGE32
  BR26    GND @T6G_MB_LIB.T6G(SCH_1):GND    I13 @T6G_MB_LIB.T6G(SCH_1):PAGE32
  BR28    GND @T6G_MB_LIB.T6G(SCH_1):GND    I13 @T6G_MB_LIB.T6G(SCH_1):PAGE32
  BR30    GND @T6G_MB_LIB.T6G(SCH_1):GND    I13 @T6G_MB_LIB.T6G(SCH_1):PAGE32
  BR32    GND @T6G_MB_LIB.T6G(SCH_1):GND    I13 @T6G_MB_LIB.T6G(SCH_1):PAGE32
  BR34    GND @T6G_MB_LIB.T6G(SCH_1):GND    I13 @T6G_MB_LIB.T6G(SCH_1):PAGE32
  BR36    GND @T6G_MB_LIB.T6G(SCH_1):GND    I13 @T6G_MB_LIB.T6G(SCH_1):PAGE32
  BR41    GND @T6G_MB_LIB.T6G(SCH_1):GND    I13 @T6G_MB_LIB.T6G(SCH_1):PAGE32
  BR43    GND @T6G_MB_LIB.T6G(SCH_1):GND    I13 @T6G_MB_LIB.T6G(SCH_1):PAGE32
  BR45    GND @T6G_MB_LIB.T6G(SCH_1):GND    I13 @T6G_MB_LIB.T6G(SCH_1):PAGE32
  BR47    GND @T6G_MB_LIB.T6G(SCH_1):GND    I13 @T6G_MB_LIB.T6G(SCH_1):PAGE32
  BR49    GND @T6G_MB_LIB.T6G(SCH_1):GND    I13 @T6G_MB_LIB.T6G(SCH_1):PAGE32
  BR51    GND @T6G_MB_LIB.T6G(SCH_1):GND    I13 @T6G_MB_LIB.T6G(SCH_1):PAGE32
  BR55    GND @T6G_MB_LIB.T6G(SCH_1):GND    I13 @T6G_MB_LIB.T6G(SCH_1):PAGE32
  BR56    GND @T6G_MB_LIB.T6G(SCH_1):GND    I13 @T6G_MB_LIB.T6G(SCH_1):PAGE32
  BR59    GND @T6G_MB_LIB.T6G(SCH_1):GND    I13 @T6G_MB_LIB.T6G(SCH_1):PAGE32
  BR61    GND @T6G_MB_LIB.T6G(SCH_1):GND    I13 @T6G_MB_LIB.T6G(SCH_1):PAGE32
  BR62    GND @T6G_MB_LIB.T6G(SCH_1):GND    I13 @T6G_MB_LIB.T6G(SCH_1):PAGE32
  BR63    GND @T6G_MB_LIB.T6G(SCH_1):GND    I13 @T6G_MB_LIB.T6G(SCH_1):PAGE32
  BR66    GND @T6G_MB_LIB.T6G(SCH_1):GND    I13 @T6G_MB_LIB.T6G(SCH_1):PAGE32
  BR68    GND @T6G_MB_LIB.T6G(SCH_1):GND    I13 @T6G_MB_LIB.T6G(SCH_1):PAGE32
  BR69    GND @T6G_MB_LIB.T6G(SCH_1):GND    I13 @T6G_MB_LIB.T6G(SCH_1):PAGE32
  BR70    GND @T6G_MB_LIB.T6G(SCH_1):GND    I13 @T6G_MB_LIB.T6G(SCH_1):PAGE32
  BR73    GND @T6G_MB_LIB.T6G(SCH_1):GND    I13 @T6G_MB_LIB.T6G(SCH_1):PAGE32
  BR75    GND @T6G_MB_LIB.T6G(SCH_1):GND    I13 @T6G_MB_LIB.T6G(SCH_1):PAGE32
   BT3    GND @T6G_MB_LIB.T6G(SCH_1):GND    I13 @T6G_MB_LIB.T6G(SCH_1):PAGE32
   BT4    GND @T6G_MB_LIB.T6G(SCH_1):GND    I13 @T6G_MB_LIB.T6G(SCH_1):PAGE32
   BT5    GND @T6G_MB_LIB.T6G(SCH_1):GND    I13 @T6G_MB_LIB.T6G(SCH_1):PAGE32
   BT7    GND @T6G_MB_LIB.T6G(SCH_1):GND    I13 @T6G_MB_LIB.T6G(SCH_1):PAGE32
   BT8    GND @T6G_MB_LIB.T6G(SCH_1):GND    I13 @T6G_MB_LIB.T6G(SCH_1):PAGE32
  BT10    GND @T6G_MB_LIB.T6G(SCH_1):GND    I13 @T6G_MB_LIB.T6G(SCH_1):PAGE32
  BT11    GND @T6G_MB_LIB.T6G(SCH_1):GND    I13 @T6G_MB_LIB.T6G(SCH_1):PAGE32
  BT12    GND @T6G_MB_LIB.T6G(SCH_1):GND    I13 @T6G_MB_LIB.T6G(SCH_1):PAGE32
  BT14    GND @T6G_MB_LIB.T6G(SCH_1):GND    I13 @T6G_MB_LIB.T6G(SCH_1):PAGE32
  BT15    GND @T6G_MB_LIB.T6G(SCH_1):GND    I13 @T6G_MB_LIB.T6G(SCH_1):PAGE32
  BT17    GND @T6G_MB_LIB.T6G(SCH_1):GND    I13 @T6G_MB_LIB.T6G(SCH_1):PAGE32
  BT18    GND @T6G_MB_LIB.T6G(SCH_1):GND    I13 @T6G_MB_LIB.T6G(SCH_1):PAGE32
  BT19    GND @T6G_MB_LIB.T6G(SCH_1):GND    I13 @T6G_MB_LIB.T6G(SCH_1):PAGE32
  BT21    GND @T6G_MB_LIB.T6G(SCH_1):GND    I13 @T6G_MB_LIB.T6G(SCH_1):PAGE32
  BT22    GND @T6G_MB_LIB.T6G(SCH_1):GND    I13 @T6G_MB_LIB.T6G(SCH_1):PAGE32
  BT25    GND @T6G_MB_LIB.T6G(SCH_1):GND    I13 @T6G_MB_LIB.T6G(SCH_1):PAGE32
  BT28    GND @T6G_MB_LIB.T6G(SCH_1):GND    I13 @T6G_MB_LIB.T6G(SCH_1):PAGE32
  BT31    GND @T6G_MB_LIB.T6G(SCH_1):GND    I13 @T6G_MB_LIB.T6G(SCH_1):PAGE32
  BT34    GND @T6G_MB_LIB.T6G(SCH_1):GND    I13 @T6G_MB_LIB.T6G(SCH_1):PAGE32
  BT37    GND @T6G_MB_LIB.T6G(SCH_1):GND    I13 @T6G_MB_LIB.T6G(SCH_1):PAGE32
  BT39    GND @T6G_MB_LIB.T6G(SCH_1):GND    I13 @T6G_MB_LIB.T6G(SCH_1):PAGE32
  BT42    GND @T6G_MB_LIB.T6G(SCH_1):GND    I13 @T6G_MB_LIB.T6G(SCH_1):PAGE32
  BT45    GND @T6G_MB_LIB.T6G(SCH_1):GND    I13 @T6G_MB_LIB.T6G(SCH_1):PAGE32
  BT48    GND @T6G_MB_LIB.T6G(SCH_1):GND    I13 @T6G_MB_LIB.T6G(SCH_1):PAGE32
  BT51    GND @T6G_MB_LIB.T6G(SCH_1):GND    I13 @T6G_MB_LIB.T6G(SCH_1):PAGE32
  BT54    GND @T6G_MB_LIB.T6G(SCH_1):GND    I13 @T6G_MB_LIB.T6G(SCH_1):PAGE32
  BT55    GND @T6G_MB_LIB.T6G(SCH_1):GND    I13 @T6G_MB_LIB.T6G(SCH_1):PAGE32
  BT57    GND @T6G_MB_LIB.T6G(SCH_1):GND    I13 @T6G_MB_LIB.T6G(SCH_1):PAGE32
  BT58    GND @T6G_MB_LIB.T6G(SCH_1):GND    I13 @T6G_MB_LIB.T6G(SCH_1):PAGE32
  BT59    GND @T6G_MB_LIB.T6G(SCH_1):GND    I13 @T6G_MB_LIB.T6G(SCH_1):PAGE32
  BT61    GND @T6G_MB_LIB.T6G(SCH_1):GND    I13 @T6G_MB_LIB.T6G(SCH_1):PAGE32
  BT62    GND @T6G_MB_LIB.T6G(SCH_1):GND    I13 @T6G_MB_LIB.T6G(SCH_1):PAGE32
  BT64    GND @T6G_MB_LIB.T6G(SCH_1):GND    I13 @T6G_MB_LIB.T6G(SCH_1):PAGE32
  BT65    GND @T6G_MB_LIB.T6G(SCH_1):GND    I13 @T6G_MB_LIB.T6G(SCH_1):PAGE32
  BT66    GND @T6G_MB_LIB.T6G(SCH_1):GND    I13 @T6G_MB_LIB.T6G(SCH_1):PAGE32
  BT68    GND @T6G_MB_LIB.T6G(SCH_1):GND    I13 @T6G_MB_LIB.T6G(SCH_1):PAGE32
  BT69    GND @T6G_MB_LIB.T6G(SCH_1):GND    I13 @T6G_MB_LIB.T6G(SCH_1):PAGE32
  BT71    GND @T6G_MB_LIB.T6G(SCH_1):GND    I13 @T6G_MB_LIB.T6G(SCH_1):PAGE32
  BT72    GND @T6G_MB_LIB.T6G(SCH_1):GND    I13 @T6G_MB_LIB.T6G(SCH_1):PAGE32
  BT73    GND @T6G_MB_LIB.T6G(SCH_1):GND    I13 @T6G_MB_LIB.T6G(SCH_1):PAGE32
   BU1    GND @T6G_MB_LIB.T6G(SCH_1):GND    I13 @T6G_MB_LIB.T6G(SCH_1):PAGE32
   BU4    GND @T6G_MB_LIB.T6G(SCH_1):GND    I13 @T6G_MB_LIB.T6G(SCH_1):PAGE32
   BU6    GND @T6G_MB_LIB.T6G(SCH_1):GND    I13 @T6G_MB_LIB.T6G(SCH_1):PAGE32
   BU8    GND @T6G_MB_LIB.T6G(SCH_1):GND    I13 @T6G_MB_LIB.T6G(SCH_1):PAGE32
  BU11    GND @T6G_MB_LIB.T6G(SCH_1):GND    I13 @T6G_MB_LIB.T6G(SCH_1):PAGE32
  BU13    GND @T6G_MB_LIB.T6G(SCH_1):GND    I13 @T6G_MB_LIB.T6G(SCH_1):PAGE32
  BU15    GND @T6G_MB_LIB.T6G(SCH_1):GND    I13 @T6G_MB_LIB.T6G(SCH_1):PAGE32
  BU18    GND @T6G_MB_LIB.T6G(SCH_1):GND    I13 @T6G_MB_LIB.T6G(SCH_1):PAGE32
  BU20    GND @T6G_MB_LIB.T6G(SCH_1):GND    I13 @T6G_MB_LIB.T6G(SCH_1):PAGE32
  BU22    GND @T6G_MB_LIB.T6G(SCH_1):GND    I13 @T6G_MB_LIB.T6G(SCH_1):PAGE32
  BU25    GND @T6G_MB_LIB.T6G(SCH_1):GND    I13 @T6G_MB_LIB.T6G(SCH_1):PAGE32
  BU28    GND @T6G_MB_LIB.T6G(SCH_1):GND    I13 @T6G_MB_LIB.T6G(SCH_1):PAGE32
  BU31    GND @T6G_MB_LIB.T6G(SCH_1):GND    I13 @T6G_MB_LIB.T6G(SCH_1):PAGE32
  BU34    GND @T6G_MB_LIB.T6G(SCH_1):GND    I13 @T6G_MB_LIB.T6G(SCH_1):PAGE32
  BU35    GND @T6G_MB_LIB.T6G(SCH_1):GND    I13 @T6G_MB_LIB.T6G(SCH_1):PAGE32
  BU36    GND @T6G_MB_LIB.T6G(SCH_1):GND    I13 @T6G_MB_LIB.T6G(SCH_1):PAGE32
  BU40    GND @T6G_MB_LIB.T6G(SCH_1):GND    I13 @T6G_MB_LIB.T6G(SCH_1):PAGE32
  BU41    GND @T6G_MB_LIB.T6G(SCH_1):GND    I13 @T6G_MB_LIB.T6G(SCH_1):PAGE32
  BU42    GND @T6G_MB_LIB.T6G(SCH_1):GND    I13 @T6G_MB_LIB.T6G(SCH_1):PAGE32
  BU45    GND @T6G_MB_LIB.T6G(SCH_1):GND    I13 @T6G_MB_LIB.T6G(SCH_1):PAGE32
  BU48    GND @T6G_MB_LIB.T6G(SCH_1):GND    I13 @T6G_MB_LIB.T6G(SCH_1):PAGE32
  BU51    GND @T6G_MB_LIB.T6G(SCH_1):GND    I13 @T6G_MB_LIB.T6G(SCH_1):PAGE32
  BU54    GND @T6G_MB_LIB.T6G(SCH_1):GND    I13 @T6G_MB_LIB.T6G(SCH_1):PAGE32
  BU56    GND @T6G_MB_LIB.T6G(SCH_1):GND    I13 @T6G_MB_LIB.T6G(SCH_1):PAGE32
  BU58    GND @T6G_MB_LIB.T6G(SCH_1):GND    I13 @T6G_MB_LIB.T6G(SCH_1):PAGE32
  BU61    GND @T6G_MB_LIB.T6G(SCH_1):GND    I13 @T6G_MB_LIB.T6G(SCH_1):PAGE32
  BU63    GND @T6G_MB_LIB.T6G(SCH_1):GND    I13 @T6G_MB_LIB.T6G(SCH_1):PAGE32
  BU65    GND @T6G_MB_LIB.T6G(SCH_1):GND    I13 @T6G_MB_LIB.T6G(SCH_1):PAGE32
  BU68    GND @T6G_MB_LIB.T6G(SCH_1):GND    I13 @T6G_MB_LIB.T6G(SCH_1):PAGE32
  BU70    GND @T6G_MB_LIB.T6G(SCH_1):GND    I13 @T6G_MB_LIB.T6G(SCH_1):PAGE32
  BU72    GND @T6G_MB_LIB.T6G(SCH_1):GND    I13 @T6G_MB_LIB.T6G(SCH_1):PAGE32
  BU75    GND @T6G_MB_LIB.T6G(SCH_1):GND    I13 @T6G_MB_LIB.T6G(SCH_1):PAGE32
   BV3    GND @T6G_MB_LIB.T6G(SCH_1):GND    I13 @T6G_MB_LIB.T6G(SCH_1):PAGE32
   BV8    GND @T6G_MB_LIB.T6G(SCH_1):GND    I13 @T6G_MB_LIB.T6G(SCH_1):PAGE32
  BV10    GND @T6G_MB_LIB.T6G(SCH_1):GND    I13 @T6G_MB_LIB.T6G(SCH_1):PAGE32
  BV15    GND @T6G_MB_LIB.T6G(SCH_1):GND    I13 @T6G_MB_LIB.T6G(SCH_1):PAGE32
  BV17    GND @T6G_MB_LIB.T6G(SCH_1):GND    I13 @T6G_MB_LIB.T6G(SCH_1):PAGE32
  BV23    GND @T6G_MB_LIB.T6G(SCH_1):GND    I13 @T6G_MB_LIB.T6G(SCH_1):PAGE32
  BV24    GND @T6G_MB_LIB.T6G(SCH_1):GND    I13 @T6G_MB_LIB.T6G(SCH_1):PAGE32
  BV25    GND @T6G_MB_LIB.T6G(SCH_1):GND    I13 @T6G_MB_LIB.T6G(SCH_1):PAGE32
  BV26    GND @T6G_MB_LIB.T6G(SCH_1):GND    I13 @T6G_MB_LIB.T6G(SCH_1):PAGE32
  BV27    GND @T6G_MB_LIB.T6G(SCH_1):GND    I13 @T6G_MB_LIB.T6G(SCH_1):PAGE32
  BV28    GND @T6G_MB_LIB.T6G(SCH_1):GND    I13 @T6G_MB_LIB.T6G(SCH_1):PAGE32
  BV29    GND @T6G_MB_LIB.T6G(SCH_1):GND    I13 @T6G_MB_LIB.T6G(SCH_1):PAGE32
  BV30    GND @T6G_MB_LIB.T6G(SCH_1):GND    I13 @T6G_MB_LIB.T6G(SCH_1):PAGE32
  BV31    GND @T6G_MB_LIB.T6G(SCH_1):GND    I13 @T6G_MB_LIB.T6G(SCH_1):PAGE32
  BV32    GND @T6G_MB_LIB.T6G(SCH_1):GND    I13 @T6G_MB_LIB.T6G(SCH_1):PAGE32
  BV33    GND @T6G_MB_LIB.T6G(SCH_1):GND    I13 @T6G_MB_LIB.T6G(SCH_1):PAGE32
  BV34    GND @T6G_MB_LIB.T6G(SCH_1):GND    I13 @T6G_MB_LIB.T6G(SCH_1):PAGE32
  BV39    GND @T6G_MB_LIB.T6G(SCH_1):GND    I13 @T6G_MB_LIB.T6G(SCH_1):PAGE32
  BV43    GND @T6G_MB_LIB.T6G(SCH_1):GND    I13 @T6G_MB_LIB.T6G(SCH_1):PAGE32
  BV44    GND @T6G_MB_LIB.T6G(SCH_1):GND    I13 @T6G_MB_LIB.T6G(SCH_1):PAGE32
  BV45    GND @T6G_MB_LIB.T6G(SCH_1):GND    I13 @T6G_MB_LIB.T6G(SCH_1):PAGE32
   BW9 M_L_CPU0_SB_DQS_DN<9> @T6G_MB_LIB.T6G(SCH_1):M_L_CPU0_SB_DQS_DN(9)   I159 @T6G_MB_LIB.T6G(SCH_1):PAGE21
  CF11 M_L_CPU0_SB_DQS_DP<5> @T6G_MB_LIB.T6G(SCH_1):M_L_CPU0_SB_DQS_DP(5)   I159 @T6G_MB_LIB.T6G(SCH_1):PAGE21
   CF9 M_L_CPU0_SB_DQ<4> @T6G_MB_LIB.T6G(SCH_1):M_L_CPU0_SB_DQ(4)   I159 @T6G_MB_LIB.T6G(SCH_1):PAGE21
  BH11 M_L_CPU0_SB_CA<1> @T6G_MB_LIB.T6G(SCH_1):M_L_CPU0_SB_CA(1)   I159 @T6G_MB_LIB.T6G(SCH_1):PAGE21
   AB9 M_L_CPU0_SA_DQ<22> @T6G_MB_LIB.T6G(SCH_1):M_L_CPU0_SA_DQ(22)   I159 @T6G_MB_LIB.T6G(SCH_1):PAGE21
   N10 M_L_CPU0_SA_DQ<11> @T6G_MB_LIB.T6G(SCH_1):M_L_CPU0_SA_DQ(11)   I159 @T6G_MB_LIB.T6G(SCH_1):PAGE21
   K11 M_L_CPU0_SA_DQ<5> @T6G_MB_LIB.T6G(SCH_1):M_L_CPU0_SA_DQ(5)   I159 @T6G_MB_LIB.T6G(SCH_1):PAGE21
   AK9 M_L_CPU0_SA_CB<2> @T6G_MB_LIB.T6G(SCH_1):M_L_CPU0_SA_CB(2)   I159 @T6G_MB_LIB.T6G(SCH_1):PAGE21
  AY11 M_L_CPU0_SA_CA<2> @T6G_MB_LIB.T6G(SCH_1):M_L_CPU0_SA_CA(2)   I159 @T6G_MB_LIB.T6G(SCH_1):PAGE21
  AU10 M_L_CPU0_RESET_N @T6G_MB_LIB.T6G(SCH_1):M_L_CPU0_RESET_N   I159 @T6G_MB_LIB.T6G(SCH_1):PAGE21
  CM11 M_L_CPU0_SB_DQS_DP<6> @T6G_MB_LIB.T6G(SCH_1):M_L_CPU0_SB_DQS_DP(6)   I159 @T6G_MB_LIB.T6G(SCH_1):PAGE21
  CG10 M_L_CPU0_SB_DQ<5> @T6G_MB_LIB.T6G(SCH_1):M_L_CPU0_SB_DQ(5)   I159 @T6G_MB_LIB.T6G(SCH_1):PAGE21
   BH9 M_L_CPU0_SB_CA<2> @T6G_MB_LIB.T6G(SCH_1):M_L_CPU0_SB_CA(2)   I159 @T6G_MB_LIB.T6G(SCH_1):PAGE21
  BM11 M_L_CPU0_SB_CS_N<0> @T6G_MB_LIB.T6G(SCH_1):M_L_CPU0_SB_CS_N(0)   I159 @T6G_MB_LIB.T6G(SCH_1):PAGE21
  AC10 M_L_CPU0_SA_DQ<23> @T6G_MB_LIB.T6G(SCH_1):M_L_CPU0_SA_DQ(23)   I159 @T6G_MB_LIB.T6G(SCH_1):PAGE21
    R9 M_L_CPU0_SA_DQ<12> @T6G_MB_LIB.T6G(SCH_1):M_L_CPU0_SA_DQ(12)   I159 @T6G_MB_LIB.T6G(SCH_1):PAGE21
    K9 M_L_CPU0_SA_DQ<6> @T6G_MB_LIB.T6G(SCH_1):M_L_CPU0_SA_DQ(6)   I159 @T6G_MB_LIB.T6G(SCH_1):PAGE21
  AL10 M_L_CPU0_SA_CB<3> @T6G_MB_LIB.T6G(SCH_1):M_L_CPU0_SA_CB(3)   I159 @T6G_MB_LIB.T6G(SCH_1):PAGE21
  BA10 M_L_CPU0_SA_CA<3> @T6G_MB_LIB.T6G(SCH_1):M_L_CPU0_SA_CA(3)   I159 @T6G_MB_LIB.T6G(SCH_1):PAGE21
  CV11 M_L_CPU0_SB_DQS_DP<7> @T6G_MB_LIB.T6G(SCH_1):M_L_CPU0_SB_DQS_DP(7)   I159 @T6G_MB_LIB.T6G(SCH_1):PAGE21
   CG9 M_L_CPU0_SB_DQ<6> @T6G_MB_LIB.T6G(SCH_1):M_L_CPU0_SB_DQ(6)   I159 @T6G_MB_LIB.T6G(SCH_1):PAGE21
   BJ9 M_L_CPU0_SB_CA<3> @T6G_MB_LIB.T6G(SCH_1):M_L_CPU0_SB_CA(3)   I159 @T6G_MB_LIB.T6G(SCH_1):PAGE21
   BL9     NC     NC   I159 @T6G_MB_LIB.T6G(SCH_1):PAGE21
   BN9 M_L_CPU0_SB_CS_N<1> @T6G_MB_LIB.T6G(SCH_1):M_L_CPU0_SB_CS_N(1)   I159 @T6G_MB_LIB.T6G(SCH_1):PAGE21
    H9 M_L_CPU0_SA_DQS_DN<0> @T6G_MB_LIB.T6G(SCH_1):M_L_CPU0_SA_DQS_DN(0)   I159 @T6G_MB_LIB.T6G(SCH_1):PAGE21
   AC9 M_L_CPU0_SA_DQ<24> @T6G_MB_LIB.T6G(SCH_1):M_L_CPU0_SA_DQ(24)   I159 @T6G_MB_LIB.T6G(SCH_1):PAGE21
   T11 M_L_CPU0_SA_DQ<13> @T6G_MB_LIB.T6G(SCH_1):M_L_CPU0_SA_DQ(13)   I159 @T6G_MB_LIB.T6G(SCH_1):PAGE21
   L10 M_L_CPU0_SA_DQ<7> @T6G_MB_LIB.T6G(SCH_1):M_L_CPU0_SA_DQ(7)   I159 @T6G_MB_LIB.T6G(SCH_1):PAGE21
   AN9 M_L_CPU0_SA_CB<4> @T6G_MB_LIB.T6G(SCH_1):M_L_CPU0_SA_CB(4)   I159 @T6G_MB_LIB.T6G(SCH_1):PAGE21
   BA9 M_L_CPU0_SA_CA<4> @T6G_MB_LIB.T6G(SCH_1):M_L_CPU0_SA_CA(4)   I159 @T6G_MB_LIB.T6G(SCH_1):PAGE21
  DD11 M_L_CPU0_SB_DQS_DP<8> @T6G_MB_LIB.T6G(SCH_1):M_L_CPU0_SB_DQS_DP(8)   I159 @T6G_MB_LIB.T6G(SCH_1):PAGE21
   DE9 M_L_CPU0_SB_DQ<30> @T6G_MB_LIB.T6G(SCH_1):M_L_CPU0_SB_DQ(30)   I159 @T6G_MB_LIB.T6G(SCH_1):PAGE21
  CH11 M_L_CPU0_SB_DQ<7> @T6G_MB_LIB.T6G(SCH_1):M_L_CPU0_SB_DQ(7)   I159 @T6G_MB_LIB.T6G(SCH_1):PAGE21
  BJ10 M_L_CPU0_SB_CA<4> @T6G_MB_LIB.T6G(SCH_1):M_L_CPU0_SB_CA(4)   I159 @T6G_MB_LIB.T6G(SCH_1):PAGE21
   BM9     NC     NC   I159 @T6G_MB_LIB.T6G(SCH_1):PAGE21
    P9 M_L_CPU0_SA_DQS_DN<1> @T6G_MB_LIB.T6G(SCH_1):M_L_CPU0_SA_DQS_DN(1)   I159 @T6G_MB_LIB.T6G(SCH_1):PAGE21
  AD11 M_L_CPU0_SA_DQ<25> @T6G_MB_LIB.T6G(SCH_1):M_L_CPU0_SA_DQ(25)   I159 @T6G_MB_LIB.T6G(SCH_1):PAGE21
    T9 M_L_CPU0_SA_DQ<14> @T6G_MB_LIB.T6G(SCH_1):M_L_CPU0_SA_DQ(14)   I159 @T6G_MB_LIB.T6G(SCH_1):PAGE21
    L9 M_L_CPU0_SA_DQ<8> @T6G_MB_LIB.T6G(SCH_1):M_L_CPU0_SA_DQ(8)   I159 @T6G_MB_LIB.T6G(SCH_1):PAGE21
  AP11 M_L_CPU0_SA_CB<5> @T6G_MB_LIB.T6G(SCH_1):M_L_CPU0_SA_CB(5)   I159 @T6G_MB_LIB.T6G(SCH_1):PAGE21
   BB9 M_L_CPU0_SA_CA<5> @T6G_MB_LIB.T6G(SCH_1):M_L_CPU0_SA_CA(5)   I159 @T6G_MB_LIB.T6G(SCH_1):PAGE21
   BV9 M_L_CPU0_SB_DQS_DP<9> @T6G_MB_LIB.T6G(SCH_1):M_L_CPU0_SB_DQS_DP(9)   I159 @T6G_MB_LIB.T6G(SCH_1):PAGE21
   DF9 M_L_CPU0_SB_DQ<31> @T6G_MB_LIB.T6G(SCH_1):M_L_CPU0_SB_DQ(31)   I159 @T6G_MB_LIB.T6G(SCH_1):PAGE21
   CV9 M_L_CPU0_SB_DQ<20> @T6G_MB_LIB.T6G(SCH_1):M_L_CPU0_SB_DQ(20)   I159 @T6G_MB_LIB.T6G(SCH_1):PAGE21
   CH9 M_L_CPU0_SB_DQ<8> @T6G_MB_LIB.T6G(SCH_1):M_L_CPU0_SB_DQ(8)   I159 @T6G_MB_LIB.T6G(SCH_1):PAGE21
   BY9 M_L_CPU0_SB_CB<0> @T6G_MB_LIB.T6G(SCH_1):M_L_CPU0_SB_CB(0)   I159 @T6G_MB_LIB.T6G(SCH_1):PAGE21
  BK11 M_L_CPU0_SB_CA<5> @T6G_MB_LIB.T6G(SCH_1):M_L_CPU0_SB_CA(5)   I159 @T6G_MB_LIB.T6G(SCH_1):PAGE21
    Y9 M_L_CPU0_SA_DQS_DN<2> @T6G_MB_LIB.T6G(SCH_1):M_L_CPU0_SA_DQS_DN(2)   I159 @T6G_MB_LIB.T6G(SCH_1):PAGE21
   AD9 M_L_CPU0_SA_DQ<26> @T6G_MB_LIB.T6G(SCH_1):M_L_CPU0_SA_DQ(26)   I159 @T6G_MB_LIB.T6G(SCH_1):PAGE21
   U10 M_L_CPU0_SA_DQ<15> @T6G_MB_LIB.T6G(SCH_1):M_L_CPU0_SA_DQ(15)   I159 @T6G_MB_LIB.T6G(SCH_1):PAGE21
   M11 M_L_CPU0_SA_DQ<9> @T6G_MB_LIB.T6G(SCH_1):M_L_CPU0_SA_DQ(9)   I159 @T6G_MB_LIB.T6G(SCH_1):PAGE21
   AP9 M_L_CPU0_SA_CB<6> @T6G_MB_LIB.T6G(SCH_1):M_L_CPU0_SA_CB(6)   I159 @T6G_MB_LIB.T6G(SCH_1):PAGE21
  BB11 M_L_CPU0_SA_CA<6> @T6G_MB_LIB.T6G(SCH_1):M_L_CPU0_SA_CA(6)   I159 @T6G_MB_LIB.T6G(SCH_1):PAGE21
  BN10 M_L_CPU0_SA_RSP<0> @T6G_MB_LIB.T6G(SCH_1):M_L_CPU0_SA_RSP(0)   I159 @T6G_MB_LIB.T6G(SCH_1):PAGE21
  CW10 M_L_CPU0_SB_DQ<21> @T6G_MB_LIB.T6G(SCH_1):M_L_CPU0_SB_DQ(21)   I159 @T6G_MB_LIB.T6G(SCH_1):PAGE21
   CJ9 M_L_CPU0_SB_DQ<10> @T6G_MB_LIB.T6G(SCH_1):M_L_CPU0_SB_DQ(10)   I159 @T6G_MB_LIB.T6G(SCH_1):PAGE21
  CJ10 M_L_CPU0_SB_DQ<9> @T6G_MB_LIB.T6G(SCH_1):M_L_CPU0_SB_DQ(9)   I159 @T6G_MB_LIB.T6G(SCH_1):PAGE21
  CA10 M_L_CPU0_SB_CB<1> @T6G_MB_LIB.T6G(SCH_1):M_L_CPU0_SB_CB(1)   I159 @T6G_MB_LIB.T6G(SCH_1):PAGE21
   BK9 M_L_CPU0_SB_CA<6> @T6G_MB_LIB.T6G(SCH_1):M_L_CPU0_SB_CA(6)   I159 @T6G_MB_LIB.T6G(SCH_1):PAGE21
   AF9 M_L_CPU0_SA_DQS_DN<3> @T6G_MB_LIB.T6G(SCH_1):M_L_CPU0_SA_DQS_DN(3)   I159 @T6G_MB_LIB.T6G(SCH_1):PAGE21
  AE10 M_L_CPU0_SA_DQ<27> @T6G_MB_LIB.T6G(SCH_1):M_L_CPU0_SA_DQ(27)   I159 @T6G_MB_LIB.T6G(SCH_1):PAGE21
    U9 M_L_CPU0_SA_DQ<16> @T6G_MB_LIB.T6G(SCH_1):M_L_CPU0_SA_DQ(16)   I159 @T6G_MB_LIB.T6G(SCH_1):PAGE21
  AR10 M_L_CPU0_SA_CB<7> @T6G_MB_LIB.T6G(SCH_1):M_L_CPU0_SA_CB(7)   I159 @T6G_MB_LIB.T6G(SCH_1):PAGE21
  BP11     NC     NC   I159 @T6G_MB_LIB.T6G(SCH_1):PAGE21
  AT11 M_L_CPU0_ALERT_R_N @T6G_MB_LIB.T6G(SCH_1):M_L_CPU0_ALERT_R_N   I159 @T6G_MB_LIB.T6G(SCH_1):PAGE21
   CW9 M_L_CPU0_SB_DQ<22> @T6G_MB_LIB.T6G(SCH_1):M_L_CPU0_SB_DQ(22)   I159 @T6G_MB_LIB.T6G(SCH_1):PAGE21
  CK11 M_L_CPU0_SB_DQ<11> @T6G_MB_LIB.T6G(SCH_1):M_L_CPU0_SB_DQ(11)   I159 @T6G_MB_LIB.T6G(SCH_1):PAGE21
   CA9 M_L_CPU0_SB_CB<2> @T6G_MB_LIB.T6G(SCH_1):M_L_CPU0_SB_CB(2)   I159 @T6G_MB_LIB.T6G(SCH_1):PAGE21
   AM9 M_L_CPU0_SA_DQS_DN<4> @T6G_MB_LIB.T6G(SCH_1):M_L_CPU0_SA_DQS_DN(4)   I159 @T6G_MB_LIB.T6G(SCH_1):PAGE21
    G9 M_L_CPU0_SA_DQS_DP<0> @T6G_MB_LIB.T6G(SCH_1):M_L_CPU0_SA_DQS_DP(0)   I159 @T6G_MB_LIB.T6G(SCH_1):PAGE21
   AG9 M_L_CPU0_SA_DQ<28> @T6G_MB_LIB.T6G(SCH_1):M_L_CPU0_SA_DQ(28)   I159 @T6G_MB_LIB.T6G(SCH_1):PAGE21
   V11 M_L_CPU0_SA_DQ<17> @T6G_MB_LIB.T6G(SCH_1):M_L_CPU0_SA_DQ(17)   I159 @T6G_MB_LIB.T6G(SCH_1):PAGE21
  CY11 M_L_CPU0_SB_DQ<23> @T6G_MB_LIB.T6G(SCH_1):M_L_CPU0_SB_DQ(23)   I159 @T6G_MB_LIB.T6G(SCH_1):PAGE21
   CM9 M_L_CPU0_SB_DQ<12> @T6G_MB_LIB.T6G(SCH_1):M_L_CPU0_SB_DQ(12)   I159 @T6G_MB_LIB.T6G(SCH_1):PAGE21
  CB11 M_L_CPU0_SB_CB<3> @T6G_MB_LIB.T6G(SCH_1):M_L_CPU0_SB_CB(3)   I159 @T6G_MB_LIB.T6G(SCH_1):PAGE21
   H11 M_L_CPU0_SA_DQS_DN<5> @T6G_MB_LIB.T6G(SCH_1):M_L_CPU0_SA_DQS_DN(5)   I159 @T6G_MB_LIB.T6G(SCH_1):PAGE21
    N9 M_L_CPU0_SA_DQS_DP<1> @T6G_MB_LIB.T6G(SCH_1):M_L_CPU0_SA_DQS_DP(1)   I159 @T6G_MB_LIB.T6G(SCH_1):PAGE21
  AH11 M_L_CPU0_SA_DQ<29> @T6G_MB_LIB.T6G(SCH_1):M_L_CPU0_SA_DQ(29)   I159 @T6G_MB_LIB.T6G(SCH_1):PAGE21
    V9 M_L_CPU0_SA_DQ<18> @T6G_MB_LIB.T6G(SCH_1):M_L_CPU0_SA_DQ(18)   I159 @T6G_MB_LIB.T6G(SCH_1):PAGE21
   BC9 M_L_CPU0_CLK_DP<0> @T6G_MB_LIB.T6G(SCH_1):M_L_CPU0_CLK_DP(0)   I159 @T6G_MB_LIB.T6G(SCH_1):PAGE21
   CE9 M_L_CPU0_SB_DQS_DN<0> @T6G_MB_LIB.T6G(SCH_1):M_L_CPU0_SB_DQS_DN(0)   I159 @T6G_MB_LIB.T6G(SCH_1):PAGE21
   CY9 M_L_CPU0_SB_DQ<24> @T6G_MB_LIB.T6G(SCH_1):M_L_CPU0_SB_DQ(24)   I159 @T6G_MB_LIB.T6G(SCH_1):PAGE21
  CN10 M_L_CPU0_SB_DQ<13> @T6G_MB_LIB.T6G(SCH_1):M_L_CPU0_SB_DQ(13)   I159 @T6G_MB_LIB.T6G(SCH_1):PAGE21
   BT9 M_L_CPU0_SB_CB<4> @T6G_MB_LIB.T6G(SCH_1):M_L_CPU0_SB_CB(4)   I159 @T6G_MB_LIB.T6G(SCH_1):PAGE21
   P11 M_L_CPU0_SA_DQS_DN<6> @T6G_MB_LIB.T6G(SCH_1):M_L_CPU0_SA_DQS_DN(6)   I159 @T6G_MB_LIB.T6G(SCH_1):PAGE21
    W9 M_L_CPU0_SA_DQS_DP<2> @T6G_MB_LIB.T6G(SCH_1):M_L_CPU0_SA_DQS_DP(2)   I159 @T6G_MB_LIB.T6G(SCH_1):PAGE21
   W10 M_L_CPU0_SA_DQ<19> @T6G_MB_LIB.T6G(SCH_1):M_L_CPU0_SA_DQ(19)   I159 @T6G_MB_LIB.T6G(SCH_1):PAGE21
   BF9     NC     NC   I159 @T6G_MB_LIB.T6G(SCH_1):PAGE21
   CL9 M_L_CPU0_SB_DQS_DN<1> @T6G_MB_LIB.T6G(SCH_1):M_L_CPU0_SB_DQS_DN(1)   I159 @T6G_MB_LIB.T6G(SCH_1):PAGE21
  DA10 M_L_CPU0_SB_DQ<25> @T6G_MB_LIB.T6G(SCH_1):M_L_CPU0_SB_DQ(25)   I159 @T6G_MB_LIB.T6G(SCH_1):PAGE21
   CN9 M_L_CPU0_SB_DQ<14> @T6G_MB_LIB.T6G(SCH_1):M_L_CPU0_SB_DQ(14)   I159 @T6G_MB_LIB.T6G(SCH_1):PAGE21
  BU10 M_L_CPU0_SB_CB<5> @T6G_MB_LIB.T6G(SCH_1):M_L_CPU0_SB_CB(5)   I159 @T6G_MB_LIB.T6G(SCH_1):PAGE21
   Y11 M_L_CPU0_SA_DQS_DN<7> @T6G_MB_LIB.T6G(SCH_1):M_L_CPU0_SA_DQS_DN(7)   I159 @T6G_MB_LIB.T6G(SCH_1):PAGE21
   AE9 M_L_CPU0_SA_DQS_DP<3> @T6G_MB_LIB.T6G(SCH_1):M_L_CPU0_SA_DQS_DP(3)   I159 @T6G_MB_LIB.T6G(SCH_1):PAGE21
   CU9 M_L_CPU0_SB_DQS_DN<2> @T6G_MB_LIB.T6G(SCH_1):M_L_CPU0_SB_DQS_DN(2)   I159 @T6G_MB_LIB.T6G(SCH_1):PAGE21
   DA9 M_L_CPU0_SB_DQ<26> @T6G_MB_LIB.T6G(SCH_1):M_L_CPU0_SB_DQ(26)   I159 @T6G_MB_LIB.T6G(SCH_1):PAGE21
  CP11 M_L_CPU0_SB_DQ<15> @T6G_MB_LIB.T6G(SCH_1):M_L_CPU0_SB_DQ(15)   I159 @T6G_MB_LIB.T6G(SCH_1):PAGE21
   BU9 M_L_CPU0_SB_CB<6> @T6G_MB_LIB.T6G(SCH_1):M_L_CPU0_SB_CB(6)   I159 @T6G_MB_LIB.T6G(SCH_1):PAGE21
   BP9 M_L_CPU0_SB_RSP<0> @T6G_MB_LIB.T6G(SCH_1):M_L_CPU0_SB_RSP(0)   I159 @T6G_MB_LIB.T6G(SCH_1):PAGE21
  AF11 M_L_CPU0_SA_DQS_DN<8> @T6G_MB_LIB.T6G(SCH_1):M_L_CPU0_SA_DQS_DN(8)   I159 @T6G_MB_LIB.T6G(SCH_1):PAGE21
   AL9 M_L_CPU0_SA_DQS_DP<4> @T6G_MB_LIB.T6G(SCH_1):M_L_CPU0_SA_DQS_DP(4)   I159 @T6G_MB_LIB.T6G(SCH_1):PAGE21
   DC9 M_L_CPU0_SB_DQS_DN<3> @T6G_MB_LIB.T6G(SCH_1):M_L_CPU0_SB_DQS_DN(3)   I159 @T6G_MB_LIB.T6G(SCH_1):PAGE21
  DB11 M_L_CPU0_SB_DQ<27> @T6G_MB_LIB.T6G(SCH_1):M_L_CPU0_SB_DQ(27)   I159 @T6G_MB_LIB.T6G(SCH_1):PAGE21
   CP9 M_L_CPU0_SB_DQ<16> @T6G_MB_LIB.T6G(SCH_1):M_L_CPU0_SB_DQ(16)   I159 @T6G_MB_LIB.T6G(SCH_1):PAGE21
  BV11 M_L_CPU0_SB_CB<7> @T6G_MB_LIB.T6G(SCH_1):M_L_CPU0_SB_CB(7)   I159 @T6G_MB_LIB.T6G(SCH_1):PAGE21
   BR9     NC     NC   I159 @T6G_MB_LIB.T6G(SCH_1):PAGE21
  BC10 M_L_CPU0_SA_PAR @T6G_MB_LIB.T6G(SCH_1):M_L_CPU0_SA_PAR   I159 @T6G_MB_LIB.T6G(SCH_1):PAGE21
  AM11 M_L_CPU0_SA_DQS_DN<9> @T6G_MB_LIB.T6G(SCH_1):M_L_CPU0_SA_DQS_DN(9)   I159 @T6G_MB_LIB.T6G(SCH_1):PAGE21
   J10 M_L_CPU0_SA_DQS_DP<5> @T6G_MB_LIB.T6G(SCH_1):M_L_CPU0_SA_DQS_DP(5)   I159 @T6G_MB_LIB.T6G(SCH_1):PAGE21
   BD9 M_L_CPU0_CLK_DN<0> @T6G_MB_LIB.T6G(SCH_1):M_L_CPU0_CLK_DN(0)   I159 @T6G_MB_LIB.T6G(SCH_1):PAGE21
  BL10 M_L_CPU0_SB_PAR @T6G_MB_LIB.T6G(SCH_1):M_L_CPU0_SB_PAR   I159 @T6G_MB_LIB.T6G(SCH_1):PAGE21
  BW10 M_L_CPU0_SB_DQS_DN<4> @T6G_MB_LIB.T6G(SCH_1):M_L_CPU0_SB_DQS_DN(4)   I159 @T6G_MB_LIB.T6G(SCH_1):PAGE21
   CD9 M_L_CPU0_SB_DQS_DP<0> @T6G_MB_LIB.T6G(SCH_1):M_L_CPU0_SB_DQS_DP(0)   I159 @T6G_MB_LIB.T6G(SCH_1):PAGE21
   DD9 M_L_CPU0_SB_DQ<28> @T6G_MB_LIB.T6G(SCH_1):M_L_CPU0_SB_DQ(28)   I159 @T6G_MB_LIB.T6G(SCH_1):PAGE21
  CR10 M_L_CPU0_SB_DQ<17> @T6G_MB_LIB.T6G(SCH_1):M_L_CPU0_SB_DQ(17)   I159 @T6G_MB_LIB.T6G(SCH_1):PAGE21
   R10 M_L_CPU0_SA_DQS_DP<6> @T6G_MB_LIB.T6G(SCH_1):M_L_CPU0_SA_DQS_DP(6)   I159 @T6G_MB_LIB.T6G(SCH_1):PAGE21
    E9 M_L_CPU0_SA_DQ<0> @T6G_MB_LIB.T6G(SCH_1):M_L_CPU0_SA_DQ(0)   I159 @T6G_MB_LIB.T6G(SCH_1):PAGE21
   AU9 M_L_CPU0_SA_CS_N<0> @T6G_MB_LIB.T6G(SCH_1):M_L_CPU0_SA_CS_N(0)   I159 @T6G_MB_LIB.T6G(SCH_1):PAGE21
   BG9     NC     NC   I159 @T6G_MB_LIB.T6G(SCH_1):PAGE21
  CE10 M_L_CPU0_SB_DQS_DN<5> @T6G_MB_LIB.T6G(SCH_1):M_L_CPU0_SB_DQS_DN(5)   I159 @T6G_MB_LIB.T6G(SCH_1):PAGE21
   CK9 M_L_CPU0_SB_DQS_DP<1> @T6G_MB_LIB.T6G(SCH_1):M_L_CPU0_SB_DQS_DP(1)   I159 @T6G_MB_LIB.T6G(SCH_1):PAGE21
  DE10 M_L_CPU0_SB_DQ<29> @T6G_MB_LIB.T6G(SCH_1):M_L_CPU0_SB_DQ(29)   I159 @T6G_MB_LIB.T6G(SCH_1):PAGE21
   CR9 M_L_CPU0_SB_DQ<18> @T6G_MB_LIB.T6G(SCH_1):M_L_CPU0_SB_DQ(18)   I159 @T6G_MB_LIB.T6G(SCH_1):PAGE21
   CB9 M_L_CPU0_SB_DQ<0> @T6G_MB_LIB.T6G(SCH_1):M_L_CPU0_SB_DQ(0)   I159 @T6G_MB_LIB.T6G(SCH_1):PAGE21
  AA10 M_L_CPU0_SA_DQS_DP<7> @T6G_MB_LIB.T6G(SCH_1):M_L_CPU0_SA_DQS_DP(7)   I159 @T6G_MB_LIB.T6G(SCH_1):PAGE21
   F11 M_L_CPU0_SA_DQ<1> @T6G_MB_LIB.T6G(SCH_1):M_L_CPU0_SA_DQ(1)   I159 @T6G_MB_LIB.T6G(SCH_1):PAGE21
   AV9     NC     NC   I159 @T6G_MB_LIB.T6G(SCH_1):PAGE21
  AV11 M_L_CPU0_SA_CS_N<1> @T6G_MB_LIB.T6G(SCH_1):M_L_CPU0_SA_CS_N(1)   I159 @T6G_MB_LIB.T6G(SCH_1):PAGE21
  CL10 M_L_CPU0_SB_DQS_DN<6> @T6G_MB_LIB.T6G(SCH_1):M_L_CPU0_SB_DQS_DN(6)   I159 @T6G_MB_LIB.T6G(SCH_1):PAGE21
   CT9 M_L_CPU0_SB_DQS_DP<2> @T6G_MB_LIB.T6G(SCH_1):M_L_CPU0_SB_DQS_DP(2)   I159 @T6G_MB_LIB.T6G(SCH_1):PAGE21
  CT11 M_L_CPU0_SB_DQ<19> @T6G_MB_LIB.T6G(SCH_1):M_L_CPU0_SB_DQ(19)   I159 @T6G_MB_LIB.T6G(SCH_1):PAGE21
  CC10 M_L_CPU0_SB_DQ<1> @T6G_MB_LIB.T6G(SCH_1):M_L_CPU0_SB_DQ(1)   I159 @T6G_MB_LIB.T6G(SCH_1):PAGE21
  AG10 M_L_CPU0_SA_DQS_DP<8> @T6G_MB_LIB.T6G(SCH_1):M_L_CPU0_SA_DQS_DP(8)   I159 @T6G_MB_LIB.T6G(SCH_1):PAGE21
   AH9 M_L_CPU0_SA_DQ<30> @T6G_MB_LIB.T6G(SCH_1):M_L_CPU0_SA_DQ(30)   I159 @T6G_MB_LIB.T6G(SCH_1):PAGE21
    F9 M_L_CPU0_SA_DQ<2> @T6G_MB_LIB.T6G(SCH_1):M_L_CPU0_SA_DQ(2)   I159 @T6G_MB_LIB.T6G(SCH_1):PAGE21
  AW10     NC     NC   I159 @T6G_MB_LIB.T6G(SCH_1):PAGE21
  CU10 M_L_CPU0_SB_DQS_DN<7> @T6G_MB_LIB.T6G(SCH_1):M_L_CPU0_SB_DQS_DN(7)   I159 @T6G_MB_LIB.T6G(SCH_1):PAGE21
   DB9 M_L_CPU0_SB_DQS_DP<3> @T6G_MB_LIB.T6G(SCH_1):M_L_CPU0_SB_DQS_DP(3)   I159 @T6G_MB_LIB.T6G(SCH_1):PAGE21
   CC9 M_L_CPU0_SB_DQ<2> @T6G_MB_LIB.T6G(SCH_1):M_L_CPU0_SB_DQ(2)   I159 @T6G_MB_LIB.T6G(SCH_1):PAGE21
  AN10 M_L_CPU0_SA_DQS_DP<9> @T6G_MB_LIB.T6G(SCH_1):M_L_CPU0_SA_DQS_DP(9)   I159 @T6G_MB_LIB.T6G(SCH_1):PAGE21
  AJ10 M_L_CPU0_SA_DQ<31> @T6G_MB_LIB.T6G(SCH_1):M_L_CPU0_SA_DQ(31)   I159 @T6G_MB_LIB.T6G(SCH_1):PAGE21
   AA9 M_L_CPU0_SA_DQ<20> @T6G_MB_LIB.T6G(SCH_1):M_L_CPU0_SA_DQ(20)   I159 @T6G_MB_LIB.T6G(SCH_1):PAGE21
   G10 M_L_CPU0_SA_DQ<3> @T6G_MB_LIB.T6G(SCH_1):M_L_CPU0_SA_DQ(3)   I159 @T6G_MB_LIB.T6G(SCH_1):PAGE21
   AJ9 M_L_CPU0_SA_CB<0> @T6G_MB_LIB.T6G(SCH_1):M_L_CPU0_SA_CB(0)   I159 @T6G_MB_LIB.T6G(SCH_1):PAGE21
   AW9 M_L_CPU0_SA_CA<0> @T6G_MB_LIB.T6G(SCH_1):M_L_CPU0_SA_CA(0)   I159 @T6G_MB_LIB.T6G(SCH_1):PAGE21
  DC10 M_L_CPU0_SB_DQS_DN<8> @T6G_MB_LIB.T6G(SCH_1):M_L_CPU0_SB_DQS_DN(8)   I159 @T6G_MB_LIB.T6G(SCH_1):PAGE21
  BY11 M_L_CPU0_SB_DQS_DP<4> @T6G_MB_LIB.T6G(SCH_1):M_L_CPU0_SB_DQS_DP(4)   I159 @T6G_MB_LIB.T6G(SCH_1):PAGE21
  CD11 M_L_CPU0_SB_DQ<3> @T6G_MB_LIB.T6G(SCH_1):M_L_CPU0_SB_DQ(3)   I159 @T6G_MB_LIB.T6G(SCH_1):PAGE21
  BG10 M_L_CPU0_SB_CA<0> @T6G_MB_LIB.T6G(SCH_1):M_L_CPU0_SB_CA(0)   I159 @T6G_MB_LIB.T6G(SCH_1):PAGE21
  AB11 M_L_CPU0_SA_DQ<21> @T6G_MB_LIB.T6G(SCH_1):M_L_CPU0_SA_DQ(21)   I159 @T6G_MB_LIB.T6G(SCH_1):PAGE21
    M9 M_L_CPU0_SA_DQ<10> @T6G_MB_LIB.T6G(SCH_1):M_L_CPU0_SA_DQ(10)   I159 @T6G_MB_LIB.T6G(SCH_1):PAGE21
    J9 M_L_CPU0_SA_DQ<4> @T6G_MB_LIB.T6G(SCH_1):M_L_CPU0_SA_DQ(4)   I159 @T6G_MB_LIB.T6G(SCH_1):PAGE21
  AK11 M_L_CPU0_SA_CB<1> @T6G_MB_LIB.T6G(SCH_1):M_L_CPU0_SA_CB(1)   I159 @T6G_MB_LIB.T6G(SCH_1):PAGE21
   AY9 M_L_CPU0_SA_CA<1> @T6G_MB_LIB.T6G(SCH_1):M_L_CPU0_SA_CA(1)   I159 @T6G_MB_LIB.T6G(SCH_1):PAGE21
  BF11 TP_M_L_CPU0_SA_TEST39L @T6G_MB_LIB.T6G(SCH_1):TP_M_L_CPU0_SA_TEST39L   I159 @T6G_MB_LIB.T6G(SCH_1):PAGE21
   CL7 M_K_CPU0_SB_DQS_DN<6> @T6G_MB_LIB.T6G(SCH_1):M_K_CPU0_SB_DQS_DN(6)   I159 @T6G_MB_LIB.T6G(SCH_1):PAGE20
   CT6 M_K_CPU0_SB_DQS_DP<2> @T6G_MB_LIB.T6G(SCH_1):M_K_CPU0_SB_DQS_DP(2)   I159 @T6G_MB_LIB.T6G(SCH_1):PAGE20
   CT7 M_K_CPU0_SB_DQ<19> @T6G_MB_LIB.T6G(SCH_1):M_K_CPU0_SB_DQ(19)   I159 @T6G_MB_LIB.T6G(SCH_1):PAGE20
   BG7 M_K_CPU0_SB_CA<0> @T6G_MB_LIB.T6G(SCH_1):M_K_CPU0_SB_CA(0)   I159 @T6G_MB_LIB.T6G(SCH_1):PAGE20
   AG7 M_K_CPU0_SA_DQS_DP<8> @T6G_MB_LIB.T6G(SCH_1):M_K_CPU0_SA_DQS_DP(8)   I159 @T6G_MB_LIB.T6G(SCH_1):PAGE20
   AH6 M_K_CPU0_SA_DQ<30> @T6G_MB_LIB.T6G(SCH_1):M_K_CPU0_SA_DQ(30)   I159 @T6G_MB_LIB.T6G(SCH_1):PAGE20
   AY6 M_K_CPU0_SA_CA<1> @T6G_MB_LIB.T6G(SCH_1):M_K_CPU0_SA_CA(1)   I159 @T6G_MB_LIB.T6G(SCH_1):PAGE20
   AV6     NC     NC   I159 @T6G_MB_LIB.T6G(SCH_1):PAGE20
   AV7 M_K_CPU0_SA_CS_N<1> @T6G_MB_LIB.T6G(SCH_1):M_K_CPU0_SA_CS_N(1)   I159 @T6G_MB_LIB.T6G(SCH_1):PAGE20
   CU7 M_K_CPU0_SB_DQS_DN<7> @T6G_MB_LIB.T6G(SCH_1):M_K_CPU0_SB_DQS_DN(7)   I159 @T6G_MB_LIB.T6G(SCH_1):PAGE20
   DB6 M_K_CPU0_SB_DQS_DP<3> @T6G_MB_LIB.T6G(SCH_1):M_K_CPU0_SB_DQS_DP(3)   I159 @T6G_MB_LIB.T6G(SCH_1):PAGE20
   BH7 M_K_CPU0_SB_CA<1> @T6G_MB_LIB.T6G(SCH_1):M_K_CPU0_SB_CA(1)   I159 @T6G_MB_LIB.T6G(SCH_1):PAGE20
   AN7 M_K_CPU0_SA_DQS_DP<9> @T6G_MB_LIB.T6G(SCH_1):M_K_CPU0_SA_DQS_DP(9)   I159 @T6G_MB_LIB.T6G(SCH_1):PAGE20
   AJ7 M_K_CPU0_SA_DQ<31> @T6G_MB_LIB.T6G(SCH_1):M_K_CPU0_SA_DQ(31)   I159 @T6G_MB_LIB.T6G(SCH_1):PAGE20
   AA5 M_K_CPU0_SA_DQ<20> @T6G_MB_LIB.T6G(SCH_1):M_K_CPU0_SA_DQ(20)   I159 @T6G_MB_LIB.T6G(SCH_1):PAGE20
   AJ5 M_K_CPU0_SA_CB<0> @T6G_MB_LIB.T6G(SCH_1):M_K_CPU0_SA_CB(0)   I159 @T6G_MB_LIB.T6G(SCH_1):PAGE20
   AY7 M_K_CPU0_SA_CA<2> @T6G_MB_LIB.T6G(SCH_1):M_K_CPU0_SA_CA(2)   I159 @T6G_MB_LIB.T6G(SCH_1):PAGE20
   AW7     NC     NC   I159 @T6G_MB_LIB.T6G(SCH_1):PAGE20
   BC5 M_K_CPU0_CLK_DP<0> @T6G_MB_LIB.T6G(SCH_1):M_K_CPU0_CLK_DP(0)   I159 @T6G_MB_LIB.T6G(SCH_1):PAGE20
   DC7 M_K_CPU0_SB_DQS_DN<8> @T6G_MB_LIB.T6G(SCH_1):M_K_CPU0_SB_DQS_DN(8)   I159 @T6G_MB_LIB.T6G(SCH_1):PAGE20
   BY7 M_K_CPU0_SB_DQS_DP<4> @T6G_MB_LIB.T6G(SCH_1):M_K_CPU0_SB_DQS_DP(4)   I159 @T6G_MB_LIB.T6G(SCH_1):PAGE20
   BH6 M_K_CPU0_SB_CA<2> @T6G_MB_LIB.T6G(SCH_1):M_K_CPU0_SB_CA(2)   I159 @T6G_MB_LIB.T6G(SCH_1):PAGE20
   AB7 M_K_CPU0_SA_DQ<21> @T6G_MB_LIB.T6G(SCH_1):M_K_CPU0_SA_DQ(21)   I159 @T6G_MB_LIB.T6G(SCH_1):PAGE20
    M6 M_K_CPU0_SA_DQ<10> @T6G_MB_LIB.T6G(SCH_1):M_K_CPU0_SA_DQ(10)   I159 @T6G_MB_LIB.T6G(SCH_1):PAGE20
   AK7 M_K_CPU0_SA_CB<1> @T6G_MB_LIB.T6G(SCH_1):M_K_CPU0_SA_CB(1)   I159 @T6G_MB_LIB.T6G(SCH_1):PAGE20
   BA7 M_K_CPU0_SA_CA<3> @T6G_MB_LIB.T6G(SCH_1):M_K_CPU0_SA_CA(3)   I159 @T6G_MB_LIB.T6G(SCH_1):PAGE20
   BF6     NC     NC   I159 @T6G_MB_LIB.T6G(SCH_1):PAGE20
   BW5 M_K_CPU0_SB_DQS_DN<9> @T6G_MB_LIB.T6G(SCH_1):M_K_CPU0_SB_DQS_DN(9)   I159 @T6G_MB_LIB.T6G(SCH_1):PAGE20
   CF7 M_K_CPU0_SB_DQS_DP<5> @T6G_MB_LIB.T6G(SCH_1):M_K_CPU0_SB_DQS_DP(5)   I159 @T6G_MB_LIB.T6G(SCH_1):PAGE20
   BJ5 M_K_CPU0_SB_CA<3> @T6G_MB_LIB.T6G(SCH_1):M_K_CPU0_SB_CA(3)   I159 @T6G_MB_LIB.T6G(SCH_1):PAGE20
   AB6 M_K_CPU0_SA_DQ<22> @T6G_MB_LIB.T6G(SCH_1):M_K_CPU0_SA_DQ(22)   I159 @T6G_MB_LIB.T6G(SCH_1):PAGE20
    N7 M_K_CPU0_SA_DQ<11> @T6G_MB_LIB.T6G(SCH_1):M_K_CPU0_SA_DQ(11)   I159 @T6G_MB_LIB.T6G(SCH_1):PAGE20
   AK6 M_K_CPU0_SA_CB<2> @T6G_MB_LIB.T6G(SCH_1):M_K_CPU0_SA_CB(2)   I159 @T6G_MB_LIB.T6G(SCH_1):PAGE20
   BA5 M_K_CPU0_SA_CA<4> @T6G_MB_LIB.T6G(SCH_1):M_K_CPU0_SA_CA(4)   I159 @T6G_MB_LIB.T6G(SCH_1):PAGE20
   AU7 M_K_CPU0_RESET_N @T6G_MB_LIB.T6G(SCH_1):M_K_CPU0_RESET_N   I159 @T6G_MB_LIB.T6G(SCH_1):PAGE20
   CM7 M_K_CPU0_SB_DQS_DP<6> @T6G_MB_LIB.T6G(SCH_1):M_K_CPU0_SB_DQS_DP(6)   I159 @T6G_MB_LIB.T6G(SCH_1):PAGE20
   BJ7 M_K_CPU0_SB_CA<4> @T6G_MB_LIB.T6G(SCH_1):M_K_CPU0_SB_CA(4)   I159 @T6G_MB_LIB.T6G(SCH_1):PAGE20
   AC7 M_K_CPU0_SA_DQ<23> @T6G_MB_LIB.T6G(SCH_1):M_K_CPU0_SA_DQ(23)   I159 @T6G_MB_LIB.T6G(SCH_1):PAGE20
    R5 M_K_CPU0_SA_DQ<12> @T6G_MB_LIB.T6G(SCH_1):M_K_CPU0_SA_DQ(12)   I159 @T6G_MB_LIB.T6G(SCH_1):PAGE20
   AL7 M_K_CPU0_SA_CB<3> @T6G_MB_LIB.T6G(SCH_1):M_K_CPU0_SA_CB(3)   I159 @T6G_MB_LIB.T6G(SCH_1):PAGE20
   BB6 M_K_CPU0_SA_CA<5> @T6G_MB_LIB.T6G(SCH_1):M_K_CPU0_SA_CA(5)   I159 @T6G_MB_LIB.T6G(SCH_1):PAGE20
   CV7 M_K_CPU0_SB_DQS_DP<7> @T6G_MB_LIB.T6G(SCH_1):M_K_CPU0_SB_DQS_DP(7)   I159 @T6G_MB_LIB.T6G(SCH_1):PAGE20
   BK7 M_K_CPU0_SB_CA<5> @T6G_MB_LIB.T6G(SCH_1):M_K_CPU0_SB_CA(5)   I159 @T6G_MB_LIB.T6G(SCH_1):PAGE20
   BM7 M_K_CPU0_SB_CS_N<0> @T6G_MB_LIB.T6G(SCH_1):M_K_CPU0_SB_CS_N(0)   I159 @T6G_MB_LIB.T6G(SCH_1):PAGE20
    H6 M_K_CPU0_SA_DQS_DN<0> @T6G_MB_LIB.T6G(SCH_1):M_K_CPU0_SA_DQS_DN(0)   I159 @T6G_MB_LIB.T6G(SCH_1):PAGE20
   AC5 M_K_CPU0_SA_DQ<24> @T6G_MB_LIB.T6G(SCH_1):M_K_CPU0_SA_DQ(24)   I159 @T6G_MB_LIB.T6G(SCH_1):PAGE20
    T7 M_K_CPU0_SA_DQ<13> @T6G_MB_LIB.T6G(SCH_1):M_K_CPU0_SA_DQ(13)   I159 @T6G_MB_LIB.T6G(SCH_1):PAGE20
   AN5 M_K_CPU0_SA_CB<4> @T6G_MB_LIB.T6G(SCH_1):M_K_CPU0_SA_CB(4)   I159 @T6G_MB_LIB.T6G(SCH_1):PAGE20
   BB7 M_K_CPU0_SA_CA<6> @T6G_MB_LIB.T6G(SCH_1):M_K_CPU0_SA_CA(6)   I159 @T6G_MB_LIB.T6G(SCH_1):PAGE20
   BD6 M_K_CPU0_CLK_DN<0> @T6G_MB_LIB.T6G(SCH_1):M_K_CPU0_CLK_DN(0)   I159 @T6G_MB_LIB.T6G(SCH_1):PAGE20
   DD7 M_K_CPU0_SB_DQS_DP<8> @T6G_MB_LIB.T6G(SCH_1):M_K_CPU0_SB_DQS_DP(8)   I159 @T6G_MB_LIB.T6G(SCH_1):PAGE20
   DE5 M_K_CPU0_SB_DQ<30> @T6G_MB_LIB.T6G(SCH_1):M_K_CPU0_SB_DQ(30)   I159 @T6G_MB_LIB.T6G(SCH_1):PAGE20
   BK6 M_K_CPU0_SB_CA<6> @T6G_MB_LIB.T6G(SCH_1):M_K_CPU0_SB_CA(6)   I159 @T6G_MB_LIB.T6G(SCH_1):PAGE20
   BL5     NC     NC   I159 @T6G_MB_LIB.T6G(SCH_1):PAGE20
   BN5 M_K_CPU0_SB_CS_N<1> @T6G_MB_LIB.T6G(SCH_1):M_K_CPU0_SB_CS_N(1)   I159 @T6G_MB_LIB.T6G(SCH_1):PAGE20
    P6 M_K_CPU0_SA_DQS_DN<1> @T6G_MB_LIB.T6G(SCH_1):M_K_CPU0_SA_DQS_DN(1)   I159 @T6G_MB_LIB.T6G(SCH_1):PAGE20
   AD7 M_K_CPU0_SA_DQ<25> @T6G_MB_LIB.T6G(SCH_1):M_K_CPU0_SA_DQ(25)   I159 @T6G_MB_LIB.T6G(SCH_1):PAGE20
    T6 M_K_CPU0_SA_DQ<14> @T6G_MB_LIB.T6G(SCH_1):M_K_CPU0_SA_DQ(14)   I159 @T6G_MB_LIB.T6G(SCH_1):PAGE20
    E5 M_K_CPU0_SA_DQ<0> @T6G_MB_LIB.T6G(SCH_1):M_K_CPU0_SA_DQ(0)   I159 @T6G_MB_LIB.T6G(SCH_1):PAGE20
   AP7 M_K_CPU0_SA_CB<5> @T6G_MB_LIB.T6G(SCH_1):M_K_CPU0_SA_CB(5)   I159 @T6G_MB_LIB.T6G(SCH_1):PAGE20
   BG5     NC     NC   I159 @T6G_MB_LIB.T6G(SCH_1):PAGE20
   BV6 M_K_CPU0_SB_DQS_DP<9> @T6G_MB_LIB.T6G(SCH_1):M_K_CPU0_SB_DQS_DP(9)   I159 @T6G_MB_LIB.T6G(SCH_1):PAGE20
   DF7 M_K_CPU0_SB_DQ<31> @T6G_MB_LIB.T6G(SCH_1):M_K_CPU0_SB_DQ(31)   I159 @T6G_MB_LIB.T6G(SCH_1):PAGE20
   CV6 M_K_CPU0_SB_DQ<20> @T6G_MB_LIB.T6G(SCH_1):M_K_CPU0_SB_DQ(20)   I159 @T6G_MB_LIB.T6G(SCH_1):PAGE20
   CB6 M_K_CPU0_SB_DQ<0> @T6G_MB_LIB.T6G(SCH_1):M_K_CPU0_SB_DQ(0)   I159 @T6G_MB_LIB.T6G(SCH_1):PAGE20
   BY6 M_K_CPU0_SB_CB<0> @T6G_MB_LIB.T6G(SCH_1):M_K_CPU0_SB_CB(0)   I159 @T6G_MB_LIB.T6G(SCH_1):PAGE20
   BM6     NC     NC   I159 @T6G_MB_LIB.T6G(SCH_1):PAGE20
    Y6 M_K_CPU0_SA_DQS_DN<2> @T6G_MB_LIB.T6G(SCH_1):M_K_CPU0_SA_DQS_DN(2)   I159 @T6G_MB_LIB.T6G(SCH_1):PAGE20
   AD6 M_K_CPU0_SA_DQ<26> @T6G_MB_LIB.T6G(SCH_1):M_K_CPU0_SA_DQ(26)   I159 @T6G_MB_LIB.T6G(SCH_1):PAGE20
    U7 M_K_CPU0_SA_DQ<15> @T6G_MB_LIB.T6G(SCH_1):M_K_CPU0_SA_DQ(15)   I159 @T6G_MB_LIB.T6G(SCH_1):PAGE20
    F7 M_K_CPU0_SA_DQ<1> @T6G_MB_LIB.T6G(SCH_1):M_K_CPU0_SA_DQ(1)   I159 @T6G_MB_LIB.T6G(SCH_1):PAGE20
   AP6 M_K_CPU0_SA_CB<6> @T6G_MB_LIB.T6G(SCH_1):M_K_CPU0_SA_CB(6)   I159 @T6G_MB_LIB.T6G(SCH_1):PAGE20
   CW7 M_K_CPU0_SB_DQ<21> @T6G_MB_LIB.T6G(SCH_1):M_K_CPU0_SB_DQ(21)   I159 @T6G_MB_LIB.T6G(SCH_1):PAGE20
   CJ5 M_K_CPU0_SB_DQ<10> @T6G_MB_LIB.T6G(SCH_1):M_K_CPU0_SB_DQ(10)   I159 @T6G_MB_LIB.T6G(SCH_1):PAGE20
   CC7 M_K_CPU0_SB_DQ<1> @T6G_MB_LIB.T6G(SCH_1):M_K_CPU0_SB_DQ(1)   I159 @T6G_MB_LIB.T6G(SCH_1):PAGE20
   CA7 M_K_CPU0_SB_CB<1> @T6G_MB_LIB.T6G(SCH_1):M_K_CPU0_SB_CB(1)   I159 @T6G_MB_LIB.T6G(SCH_1):PAGE20
   AF6 M_K_CPU0_SA_DQS_DN<3> @T6G_MB_LIB.T6G(SCH_1):M_K_CPU0_SA_DQS_DN(3)   I159 @T6G_MB_LIB.T6G(SCH_1):PAGE20
   AE7 M_K_CPU0_SA_DQ<27> @T6G_MB_LIB.T6G(SCH_1):M_K_CPU0_SA_DQ(27)   I159 @T6G_MB_LIB.T6G(SCH_1):PAGE20
    U5 M_K_CPU0_SA_DQ<16> @T6G_MB_LIB.T6G(SCH_1):M_K_CPU0_SA_DQ(16)   I159 @T6G_MB_LIB.T6G(SCH_1):PAGE20
    F6 M_K_CPU0_SA_DQ<2> @T6G_MB_LIB.T6G(SCH_1):M_K_CPU0_SA_DQ(2)   I159 @T6G_MB_LIB.T6G(SCH_1):PAGE20
   AR7 M_K_CPU0_SA_CB<7> @T6G_MB_LIB.T6G(SCH_1):M_K_CPU0_SA_CB(7)   I159 @T6G_MB_LIB.T6G(SCH_1):PAGE20
   BN7 M_K_CPU0_SA_RSP<0> @T6G_MB_LIB.T6G(SCH_1):M_K_CPU0_SA_RSP(0)   I159 @T6G_MB_LIB.T6G(SCH_1):PAGE20
   AT7 M_K_CPU0_ALERT_R_N @T6G_MB_LIB.T6G(SCH_1):M_K_CPU0_ALERT_R_N   I159 @T6G_MB_LIB.T6G(SCH_1):PAGE20
   CW5 M_K_CPU0_SB_DQ<22> @T6G_MB_LIB.T6G(SCH_1):M_K_CPU0_SB_DQ(22)   I159 @T6G_MB_LIB.T6G(SCH_1):PAGE20
   CK7 M_K_CPU0_SB_DQ<11> @T6G_MB_LIB.T6G(SCH_1):M_K_CPU0_SB_DQ(11)   I159 @T6G_MB_LIB.T6G(SCH_1):PAGE20
   CC5 M_K_CPU0_SB_DQ<2> @T6G_MB_LIB.T6G(SCH_1):M_K_CPU0_SB_DQ(2)   I159 @T6G_MB_LIB.T6G(SCH_1):PAGE20
   CA5 M_K_CPU0_SB_CB<2> @T6G_MB_LIB.T6G(SCH_1):M_K_CPU0_SB_CB(2)   I159 @T6G_MB_LIB.T6G(SCH_1):PAGE20
   AM6 M_K_CPU0_SA_DQS_DN<4> @T6G_MB_LIB.T6G(SCH_1):M_K_CPU0_SA_DQS_DN(4)   I159 @T6G_MB_LIB.T6G(SCH_1):PAGE20
    G5 M_K_CPU0_SA_DQS_DP<0> @T6G_MB_LIB.T6G(SCH_1):M_K_CPU0_SA_DQS_DP(0)   I159 @T6G_MB_LIB.T6G(SCH_1):PAGE20
   AG5 M_K_CPU0_SA_DQ<28> @T6G_MB_LIB.T6G(SCH_1):M_K_CPU0_SA_DQ(28)   I159 @T6G_MB_LIB.T6G(SCH_1):PAGE20
    V7 M_K_CPU0_SA_DQ<17> @T6G_MB_LIB.T6G(SCH_1):M_K_CPU0_SA_DQ(17)   I159 @T6G_MB_LIB.T6G(SCH_1):PAGE20
    G7 M_K_CPU0_SA_DQ<3> @T6G_MB_LIB.T6G(SCH_1):M_K_CPU0_SA_DQ(3)   I159 @T6G_MB_LIB.T6G(SCH_1):PAGE20
   BP7     NC     NC   I159 @T6G_MB_LIB.T6G(SCH_1):PAGE20
   CY7 M_K_CPU0_SB_DQ<23> @T6G_MB_LIB.T6G(SCH_1):M_K_CPU0_SB_DQ(23)   I159 @T6G_MB_LIB.T6G(SCH_1):PAGE20
   CM6 M_K_CPU0_SB_DQ<12> @T6G_MB_LIB.T6G(SCH_1):M_K_CPU0_SB_DQ(12)   I159 @T6G_MB_LIB.T6G(SCH_1):PAGE20
   CD7 M_K_CPU0_SB_DQ<3> @T6G_MB_LIB.T6G(SCH_1):M_K_CPU0_SB_DQ(3)   I159 @T6G_MB_LIB.T6G(SCH_1):PAGE20
   CB7 M_K_CPU0_SB_CB<3> @T6G_MB_LIB.T6G(SCH_1):M_K_CPU0_SB_CB(3)   I159 @T6G_MB_LIB.T6G(SCH_1):PAGE20
    H7 M_K_CPU0_SA_DQS_DN<5> @T6G_MB_LIB.T6G(SCH_1):M_K_CPU0_SA_DQS_DN(5)   I159 @T6G_MB_LIB.T6G(SCH_1):PAGE20
    N5 M_K_CPU0_SA_DQS_DP<1> @T6G_MB_LIB.T6G(SCH_1):M_K_CPU0_SA_DQS_DP(1)   I159 @T6G_MB_LIB.T6G(SCH_1):PAGE20
   AH7 M_K_CPU0_SA_DQ<29> @T6G_MB_LIB.T6G(SCH_1):M_K_CPU0_SA_DQ(29)   I159 @T6G_MB_LIB.T6G(SCH_1):PAGE20
    V6 M_K_CPU0_SA_DQ<18> @T6G_MB_LIB.T6G(SCH_1):M_K_CPU0_SA_DQ(18)   I159 @T6G_MB_LIB.T6G(SCH_1):PAGE20
    J5 M_K_CPU0_SA_DQ<4> @T6G_MB_LIB.T6G(SCH_1):M_K_CPU0_SA_DQ(4)   I159 @T6G_MB_LIB.T6G(SCH_1):PAGE20
   CE5 M_K_CPU0_SB_DQS_DN<0> @T6G_MB_LIB.T6G(SCH_1):M_K_CPU0_SB_DQS_DN(0)   I159 @T6G_MB_LIB.T6G(SCH_1):PAGE20
   CY6 M_K_CPU0_SB_DQ<24> @T6G_MB_LIB.T6G(SCH_1):M_K_CPU0_SB_DQ(24)   I159 @T6G_MB_LIB.T6G(SCH_1):PAGE20
   CN7 M_K_CPU0_SB_DQ<13> @T6G_MB_LIB.T6G(SCH_1):M_K_CPU0_SB_DQ(13)   I159 @T6G_MB_LIB.T6G(SCH_1):PAGE20
   CF6 M_K_CPU0_SB_DQ<4> @T6G_MB_LIB.T6G(SCH_1):M_K_CPU0_SB_DQ(4)   I159 @T6G_MB_LIB.T6G(SCH_1):PAGE20
   BT6 M_K_CPU0_SB_CB<4> @T6G_MB_LIB.T6G(SCH_1):M_K_CPU0_SB_CB(4)   I159 @T6G_MB_LIB.T6G(SCH_1):PAGE20
    P7 M_K_CPU0_SA_DQS_DN<6> @T6G_MB_LIB.T6G(SCH_1):M_K_CPU0_SA_DQS_DN(6)   I159 @T6G_MB_LIB.T6G(SCH_1):PAGE20
    W5 M_K_CPU0_SA_DQS_DP<2> @T6G_MB_LIB.T6G(SCH_1):M_K_CPU0_SA_DQS_DP(2)   I159 @T6G_MB_LIB.T6G(SCH_1):PAGE20
    W7 M_K_CPU0_SA_DQ<19> @T6G_MB_LIB.T6G(SCH_1):M_K_CPU0_SA_DQ(19)   I159 @T6G_MB_LIB.T6G(SCH_1):PAGE20
    K7 M_K_CPU0_SA_DQ<5> @T6G_MB_LIB.T6G(SCH_1):M_K_CPU0_SA_DQ(5)   I159 @T6G_MB_LIB.T6G(SCH_1):PAGE20
   CL5 M_K_CPU0_SB_DQS_DN<1> @T6G_MB_LIB.T6G(SCH_1):M_K_CPU0_SB_DQS_DN(1)   I159 @T6G_MB_LIB.T6G(SCH_1):PAGE20
   DA7 M_K_CPU0_SB_DQ<25> @T6G_MB_LIB.T6G(SCH_1):M_K_CPU0_SB_DQ(25)   I159 @T6G_MB_LIB.T6G(SCH_1):PAGE20
   CN5 M_K_CPU0_SB_DQ<14> @T6G_MB_LIB.T6G(SCH_1):M_K_CPU0_SB_DQ(14)   I159 @T6G_MB_LIB.T6G(SCH_1):PAGE20
   CG7 M_K_CPU0_SB_DQ<5> @T6G_MB_LIB.T6G(SCH_1):M_K_CPU0_SB_DQ(5)   I159 @T6G_MB_LIB.T6G(SCH_1):PAGE20
   BU7 M_K_CPU0_SB_CB<5> @T6G_MB_LIB.T6G(SCH_1):M_K_CPU0_SB_CB(5)   I159 @T6G_MB_LIB.T6G(SCH_1):PAGE20
   BC7 M_K_CPU0_SA_PAR @T6G_MB_LIB.T6G(SCH_1):M_K_CPU0_SA_PAR   I159 @T6G_MB_LIB.T6G(SCH_1):PAGE20
    Y7 M_K_CPU0_SA_DQS_DN<7> @T6G_MB_LIB.T6G(SCH_1):M_K_CPU0_SA_DQS_DN(7)   I159 @T6G_MB_LIB.T6G(SCH_1):PAGE20
   AE5 M_K_CPU0_SA_DQS_DP<3> @T6G_MB_LIB.T6G(SCH_1):M_K_CPU0_SA_DQS_DP(3)   I159 @T6G_MB_LIB.T6G(SCH_1):PAGE20
    K6 M_K_CPU0_SA_DQ<6> @T6G_MB_LIB.T6G(SCH_1):M_K_CPU0_SA_DQ(6)   I159 @T6G_MB_LIB.T6G(SCH_1):PAGE20
   BL7 M_K_CPU0_SB_PAR @T6G_MB_LIB.T6G(SCH_1):M_K_CPU0_SB_PAR   I159 @T6G_MB_LIB.T6G(SCH_1):PAGE20
   CU5 M_K_CPU0_SB_DQS_DN<2> @T6G_MB_LIB.T6G(SCH_1):M_K_CPU0_SB_DQS_DN(2)   I159 @T6G_MB_LIB.T6G(SCH_1):PAGE20
   DA5 M_K_CPU0_SB_DQ<26> @T6G_MB_LIB.T6G(SCH_1):M_K_CPU0_SB_DQ(26)   I159 @T6G_MB_LIB.T6G(SCH_1):PAGE20
   CP7 M_K_CPU0_SB_DQ<15> @T6G_MB_LIB.T6G(SCH_1):M_K_CPU0_SB_DQ(15)   I159 @T6G_MB_LIB.T6G(SCH_1):PAGE20
   CG5 M_K_CPU0_SB_DQ<6> @T6G_MB_LIB.T6G(SCH_1):M_K_CPU0_SB_DQ(6)   I159 @T6G_MB_LIB.T6G(SCH_1):PAGE20
   BU5 M_K_CPU0_SB_CB<6> @T6G_MB_LIB.T6G(SCH_1):M_K_CPU0_SB_CB(6)   I159 @T6G_MB_LIB.T6G(SCH_1):PAGE20
   AF7 M_K_CPU0_SA_DQS_DN<8> @T6G_MB_LIB.T6G(SCH_1):M_K_CPU0_SA_DQS_DN(8)   I159 @T6G_MB_LIB.T6G(SCH_1):PAGE20
   AL5 M_K_CPU0_SA_DQS_DP<4> @T6G_MB_LIB.T6G(SCH_1):M_K_CPU0_SA_DQS_DP(4)   I159 @T6G_MB_LIB.T6G(SCH_1):PAGE20
    L7 M_K_CPU0_SA_DQ<7> @T6G_MB_LIB.T6G(SCH_1):M_K_CPU0_SA_DQ(7)   I159 @T6G_MB_LIB.T6G(SCH_1):PAGE20
   DC5 M_K_CPU0_SB_DQS_DN<3> @T6G_MB_LIB.T6G(SCH_1):M_K_CPU0_SB_DQS_DN(3)   I159 @T6G_MB_LIB.T6G(SCH_1):PAGE20
   DB7 M_K_CPU0_SB_DQ<27> @T6G_MB_LIB.T6G(SCH_1):M_K_CPU0_SB_DQ(27)   I159 @T6G_MB_LIB.T6G(SCH_1):PAGE20
   CP6 M_K_CPU0_SB_DQ<16> @T6G_MB_LIB.T6G(SCH_1):M_K_CPU0_SB_DQ(16)   I159 @T6G_MB_LIB.T6G(SCH_1):PAGE20
   CH7 M_K_CPU0_SB_DQ<7> @T6G_MB_LIB.T6G(SCH_1):M_K_CPU0_SB_DQ(7)   I159 @T6G_MB_LIB.T6G(SCH_1):PAGE20
   BV7 M_K_CPU0_SB_CB<7> @T6G_MB_LIB.T6G(SCH_1):M_K_CPU0_SB_CB(7)   I159 @T6G_MB_LIB.T6G(SCH_1):PAGE20
   BP6 M_K_CPU0_SB_RSP<0> @T6G_MB_LIB.T6G(SCH_1):M_K_CPU0_SB_RSP(0)   I159 @T6G_MB_LIB.T6G(SCH_1):PAGE20
   AM7 M_K_CPU0_SA_DQS_DN<9> @T6G_MB_LIB.T6G(SCH_1):M_K_CPU0_SA_DQS_DN(9)   I159 @T6G_MB_LIB.T6G(SCH_1):PAGE20
    J7 M_K_CPU0_SA_DQS_DP<5> @T6G_MB_LIB.T6G(SCH_1):M_K_CPU0_SA_DQS_DP(5)   I159 @T6G_MB_LIB.T6G(SCH_1):PAGE20
    L5 M_K_CPU0_SA_DQ<8> @T6G_MB_LIB.T6G(SCH_1):M_K_CPU0_SA_DQ(8)   I159 @T6G_MB_LIB.T6G(SCH_1):PAGE20
   BW7 M_K_CPU0_SB_DQS_DN<4> @T6G_MB_LIB.T6G(SCH_1):M_K_CPU0_SB_DQS_DN(4)   I159 @T6G_MB_LIB.T6G(SCH_1):PAGE20
   CD6 M_K_CPU0_SB_DQS_DP<0> @T6G_MB_LIB.T6G(SCH_1):M_K_CPU0_SB_DQS_DP(0)   I159 @T6G_MB_LIB.T6G(SCH_1):PAGE20
   DD6 M_K_CPU0_SB_DQ<28> @T6G_MB_LIB.T6G(SCH_1):M_K_CPU0_SB_DQ(28)   I159 @T6G_MB_LIB.T6G(SCH_1):PAGE20
   CR7 M_K_CPU0_SB_DQ<17> @T6G_MB_LIB.T6G(SCH_1):M_K_CPU0_SB_DQ(17)   I159 @T6G_MB_LIB.T6G(SCH_1):PAGE20
   CH6 M_K_CPU0_SB_DQ<8> @T6G_MB_LIB.T6G(SCH_1):M_K_CPU0_SB_DQ(8)   I159 @T6G_MB_LIB.T6G(SCH_1):PAGE20
   BR5     NC     NC   I159 @T6G_MB_LIB.T6G(SCH_1):PAGE20
    R7 M_K_CPU0_SA_DQS_DP<6> @T6G_MB_LIB.T6G(SCH_1):M_K_CPU0_SA_DQS_DP(6)   I159 @T6G_MB_LIB.T6G(SCH_1):PAGE20
    M7 M_K_CPU0_SA_DQ<9> @T6G_MB_LIB.T6G(SCH_1):M_K_CPU0_SA_DQ(9)   I159 @T6G_MB_LIB.T6G(SCH_1):PAGE20
   CE7 M_K_CPU0_SB_DQS_DN<5> @T6G_MB_LIB.T6G(SCH_1):M_K_CPU0_SB_DQS_DN(5)   I159 @T6G_MB_LIB.T6G(SCH_1):PAGE20
   CK6 M_K_CPU0_SB_DQS_DP<1> @T6G_MB_LIB.T6G(SCH_1):M_K_CPU0_SB_DQS_DP(1)   I159 @T6G_MB_LIB.T6G(SCH_1):PAGE20
   DE7 M_K_CPU0_SB_DQ<29> @T6G_MB_LIB.T6G(SCH_1):M_K_CPU0_SB_DQ(29)   I159 @T6G_MB_LIB.T6G(SCH_1):PAGE20
   CR5 M_K_CPU0_SB_DQ<18> @T6G_MB_LIB.T6G(SCH_1):M_K_CPU0_SB_DQ(18)   I159 @T6G_MB_LIB.T6G(SCH_1):PAGE20
   CJ7 M_K_CPU0_SB_DQ<9> @T6G_MB_LIB.T6G(SCH_1):M_K_CPU0_SB_DQ(9)   I159 @T6G_MB_LIB.T6G(SCH_1):PAGE20
   AA7 M_K_CPU0_SA_DQS_DP<7> @T6G_MB_LIB.T6G(SCH_1):M_K_CPU0_SA_DQS_DP(7)   I159 @T6G_MB_LIB.T6G(SCH_1):PAGE20
   AW5 M_K_CPU0_SA_CA<0> @T6G_MB_LIB.T6G(SCH_1):M_K_CPU0_SA_CA(0)   I159 @T6G_MB_LIB.T6G(SCH_1):PAGE20
   AU5 M_K_CPU0_SA_CS_N<0> @T6G_MB_LIB.T6G(SCH_1):M_K_CPU0_SA_CS_N(0)   I159 @T6G_MB_LIB.T6G(SCH_1):PAGE20
   BF7 TP_M_K_CPU0_SA_TEST39K @T6G_MB_LIB.T6G(SCH_1):TP_M_K_CPU0_SA_TEST39K   I159 @T6G_MB_LIB.T6G(SCH_1):PAGE20
  BV46    GND @T6G_MB_LIB.T6G(SCH_1):GND    I14 @T6G_MB_LIB.T6G(SCH_1):PAGE32
  BV47    GND @T6G_MB_LIB.T6G(SCH_1):GND    I14 @T6G_MB_LIB.T6G(SCH_1):PAGE32
  BV48    GND @T6G_MB_LIB.T6G(SCH_1):GND    I14 @T6G_MB_LIB.T6G(SCH_1):PAGE32
  BV49    GND @T6G_MB_LIB.T6G(SCH_1):GND    I14 @T6G_MB_LIB.T6G(SCH_1):PAGE32
  BV50    GND @T6G_MB_LIB.T6G(SCH_1):GND    I14 @T6G_MB_LIB.T6G(SCH_1):PAGE32
  BV51    GND @T6G_MB_LIB.T6G(SCH_1):GND    I14 @T6G_MB_LIB.T6G(SCH_1):PAGE32
  BV52    GND @T6G_MB_LIB.T6G(SCH_1):GND    I14 @T6G_MB_LIB.T6G(SCH_1):PAGE32
  BV53    GND @T6G_MB_LIB.T6G(SCH_1):GND    I14 @T6G_MB_LIB.T6G(SCH_1):PAGE32
  BV59    GND @T6G_MB_LIB.T6G(SCH_1):GND    I14 @T6G_MB_LIB.T6G(SCH_1):PAGE32
  BV61    GND @T6G_MB_LIB.T6G(SCH_1):GND    I14 @T6G_MB_LIB.T6G(SCH_1):PAGE32
  BV66    GND @T6G_MB_LIB.T6G(SCH_1):GND    I14 @T6G_MB_LIB.T6G(SCH_1):PAGE32
  BV68    GND @T6G_MB_LIB.T6G(SCH_1):GND    I14 @T6G_MB_LIB.T6G(SCH_1):PAGE32
  BV73    GND @T6G_MB_LIB.T6G(SCH_1):GND    I14 @T6G_MB_LIB.T6G(SCH_1):PAGE32
   BW1    GND @T6G_MB_LIB.T6G(SCH_1):GND    I14 @T6G_MB_LIB.T6G(SCH_1):PAGE32
   BW4    GND @T6G_MB_LIB.T6G(SCH_1):GND    I14 @T6G_MB_LIB.T6G(SCH_1):PAGE32
   BW6    GND @T6G_MB_LIB.T6G(SCH_1):GND    I14 @T6G_MB_LIB.T6G(SCH_1):PAGE32
   BW8    GND @T6G_MB_LIB.T6G(SCH_1):GND    I14 @T6G_MB_LIB.T6G(SCH_1):PAGE32
  BW11    GND @T6G_MB_LIB.T6G(SCH_1):GND    I14 @T6G_MB_LIB.T6G(SCH_1):PAGE32
  BW13    GND @T6G_MB_LIB.T6G(SCH_1):GND    I14 @T6G_MB_LIB.T6G(SCH_1):PAGE32
  BW15    GND @T6G_MB_LIB.T6G(SCH_1):GND    I14 @T6G_MB_LIB.T6G(SCH_1):PAGE32
  BW18    GND @T6G_MB_LIB.T6G(SCH_1):GND    I14 @T6G_MB_LIB.T6G(SCH_1):PAGE32
  BW20    GND @T6G_MB_LIB.T6G(SCH_1):GND    I14 @T6G_MB_LIB.T6G(SCH_1):PAGE32
  BW22    GND @T6G_MB_LIB.T6G(SCH_1):GND    I14 @T6G_MB_LIB.T6G(SCH_1):PAGE32
  BW28    GND @T6G_MB_LIB.T6G(SCH_1):GND    I14 @T6G_MB_LIB.T6G(SCH_1):PAGE32
  BW31    GND @T6G_MB_LIB.T6G(SCH_1):GND    I14 @T6G_MB_LIB.T6G(SCH_1):PAGE32
  BW34    GND @T6G_MB_LIB.T6G(SCH_1):GND    I14 @T6G_MB_LIB.T6G(SCH_1):PAGE32
  BW42    GND @T6G_MB_LIB.T6G(SCH_1):GND    I14 @T6G_MB_LIB.T6G(SCH_1):PAGE32
  BW45    GND @T6G_MB_LIB.T6G(SCH_1):GND    I14 @T6G_MB_LIB.T6G(SCH_1):PAGE32
  BW48    GND @T6G_MB_LIB.T6G(SCH_1):GND    I14 @T6G_MB_LIB.T6G(SCH_1):PAGE32
  BW51    GND @T6G_MB_LIB.T6G(SCH_1):GND    I14 @T6G_MB_LIB.T6G(SCH_1):PAGE32
  BW54    GND @T6G_MB_LIB.T6G(SCH_1):GND    I14 @T6G_MB_LIB.T6G(SCH_1):PAGE32
  BW56    GND @T6G_MB_LIB.T6G(SCH_1):GND    I14 @T6G_MB_LIB.T6G(SCH_1):PAGE32
  BW58    GND @T6G_MB_LIB.T6G(SCH_1):GND    I14 @T6G_MB_LIB.T6G(SCH_1):PAGE32
  BW61    GND @T6G_MB_LIB.T6G(SCH_1):GND    I14 @T6G_MB_LIB.T6G(SCH_1):PAGE32
  BW63    GND @T6G_MB_LIB.T6G(SCH_1):GND    I14 @T6G_MB_LIB.T6G(SCH_1):PAGE32
  BW65    GND @T6G_MB_LIB.T6G(SCH_1):GND    I14 @T6G_MB_LIB.T6G(SCH_1):PAGE32
  BW68    GND @T6G_MB_LIB.T6G(SCH_1):GND    I14 @T6G_MB_LIB.T6G(SCH_1):PAGE32
  BW70    GND @T6G_MB_LIB.T6G(SCH_1):GND    I14 @T6G_MB_LIB.T6G(SCH_1):PAGE32
  BW72    GND @T6G_MB_LIB.T6G(SCH_1):GND    I14 @T6G_MB_LIB.T6G(SCH_1):PAGE32
  BW75    GND @T6G_MB_LIB.T6G(SCH_1):GND    I14 @T6G_MB_LIB.T6G(SCH_1):PAGE32
   BY3    GND @T6G_MB_LIB.T6G(SCH_1):GND    I14 @T6G_MB_LIB.T6G(SCH_1):PAGE32
   BY5    GND @T6G_MB_LIB.T6G(SCH_1):GND    I14 @T6G_MB_LIB.T6G(SCH_1):PAGE32
   BY8    GND @T6G_MB_LIB.T6G(SCH_1):GND    I14 @T6G_MB_LIB.T6G(SCH_1):PAGE32
  BY10    GND @T6G_MB_LIB.T6G(SCH_1):GND    I14 @T6G_MB_LIB.T6G(SCH_1):PAGE32
  BY12    GND @T6G_MB_LIB.T6G(SCH_1):GND    I14 @T6G_MB_LIB.T6G(SCH_1):PAGE32
  BY15    GND @T6G_MB_LIB.T6G(SCH_1):GND    I14 @T6G_MB_LIB.T6G(SCH_1):PAGE32
  BY17    GND @T6G_MB_LIB.T6G(SCH_1):GND    I14 @T6G_MB_LIB.T6G(SCH_1):PAGE32
  BY19    GND @T6G_MB_LIB.T6G(SCH_1):GND    I14 @T6G_MB_LIB.T6G(SCH_1):PAGE32
  BY22    GND @T6G_MB_LIB.T6G(SCH_1):GND    I14 @T6G_MB_LIB.T6G(SCH_1):PAGE32
  BY25    GND @T6G_MB_LIB.T6G(SCH_1):GND    I14 @T6G_MB_LIB.T6G(SCH_1):PAGE32
  BY28    GND @T6G_MB_LIB.T6G(SCH_1):GND    I14 @T6G_MB_LIB.T6G(SCH_1):PAGE32
  BY31    GND @T6G_MB_LIB.T6G(SCH_1):GND    I14 @T6G_MB_LIB.T6G(SCH_1):PAGE32
  BY34    GND @T6G_MB_LIB.T6G(SCH_1):GND    I14 @T6G_MB_LIB.T6G(SCH_1):PAGE32
  BY37    GND @T6G_MB_LIB.T6G(SCH_1):GND    I14 @T6G_MB_LIB.T6G(SCH_1):PAGE32
  BY39    GND @T6G_MB_LIB.T6G(SCH_1):GND    I14 @T6G_MB_LIB.T6G(SCH_1):PAGE32
  BY42    GND @T6G_MB_LIB.T6G(SCH_1):GND    I14 @T6G_MB_LIB.T6G(SCH_1):PAGE32
  BY45    GND @T6G_MB_LIB.T6G(SCH_1):GND    I14 @T6G_MB_LIB.T6G(SCH_1):PAGE32
  BY48    GND @T6G_MB_LIB.T6G(SCH_1):GND    I14 @T6G_MB_LIB.T6G(SCH_1):PAGE32
  BY51    GND @T6G_MB_LIB.T6G(SCH_1):GND    I14 @T6G_MB_LIB.T6G(SCH_1):PAGE32
  BY54    GND @T6G_MB_LIB.T6G(SCH_1):GND    I14 @T6G_MB_LIB.T6G(SCH_1):PAGE32
  BY57    GND @T6G_MB_LIB.T6G(SCH_1):GND    I14 @T6G_MB_LIB.T6G(SCH_1):PAGE32
  BY59    GND @T6G_MB_LIB.T6G(SCH_1):GND    I14 @T6G_MB_LIB.T6G(SCH_1):PAGE32
  BY61    GND @T6G_MB_LIB.T6G(SCH_1):GND    I14 @T6G_MB_LIB.T6G(SCH_1):PAGE32
  BY64    GND @T6G_MB_LIB.T6G(SCH_1):GND    I14 @T6G_MB_LIB.T6G(SCH_1):PAGE32
  BY66    GND @T6G_MB_LIB.T6G(SCH_1):GND    I14 @T6G_MB_LIB.T6G(SCH_1):PAGE32
  BY68    GND @T6G_MB_LIB.T6G(SCH_1):GND    I14 @T6G_MB_LIB.T6G(SCH_1):PAGE32
  BY71    GND @T6G_MB_LIB.T6G(SCH_1):GND    I14 @T6G_MB_LIB.T6G(SCH_1):PAGE32
  BY73    GND @T6G_MB_LIB.T6G(SCH_1):GND    I14 @T6G_MB_LIB.T6G(SCH_1):PAGE32
   CA1    GND @T6G_MB_LIB.T6G(SCH_1):GND    I14 @T6G_MB_LIB.T6G(SCH_1):PAGE32
   CA6    GND @T6G_MB_LIB.T6G(SCH_1):GND    I14 @T6G_MB_LIB.T6G(SCH_1):PAGE32
   CA8    GND @T6G_MB_LIB.T6G(SCH_1):GND    I14 @T6G_MB_LIB.T6G(SCH_1):PAGE32
  CA13    GND @T6G_MB_LIB.T6G(SCH_1):GND    I14 @T6G_MB_LIB.T6G(SCH_1):PAGE32
  CA15    GND @T6G_MB_LIB.T6G(SCH_1):GND    I14 @T6G_MB_LIB.T6G(SCH_1):PAGE32
  CA20    GND @T6G_MB_LIB.T6G(SCH_1):GND    I14 @T6G_MB_LIB.T6G(SCH_1):PAGE32
  CA22    GND @T6G_MB_LIB.T6G(SCH_1):GND    I14 @T6G_MB_LIB.T6G(SCH_1):PAGE32
  CA25    GND @T6G_MB_LIB.T6G(SCH_1):GND    I14 @T6G_MB_LIB.T6G(SCH_1):PAGE32
  CA28    GND @T6G_MB_LIB.T6G(SCH_1):GND    I14 @T6G_MB_LIB.T6G(SCH_1):PAGE32
  CA31    GND @T6G_MB_LIB.T6G(SCH_1):GND    I14 @T6G_MB_LIB.T6G(SCH_1):PAGE32
  CA34    GND @T6G_MB_LIB.T6G(SCH_1):GND    I14 @T6G_MB_LIB.T6G(SCH_1):PAGE32
  CA35    GND @T6G_MB_LIB.T6G(SCH_1):GND    I14 @T6G_MB_LIB.T6G(SCH_1):PAGE32
  CA36    GND @T6G_MB_LIB.T6G(SCH_1):GND    I14 @T6G_MB_LIB.T6G(SCH_1):PAGE32
  CA40    GND @T6G_MB_LIB.T6G(SCH_1):GND    I14 @T6G_MB_LIB.T6G(SCH_1):PAGE32
  CA41    GND @T6G_MB_LIB.T6G(SCH_1):GND    I14 @T6G_MB_LIB.T6G(SCH_1):PAGE32
  CA42    GND @T6G_MB_LIB.T6G(SCH_1):GND    I14 @T6G_MB_LIB.T6G(SCH_1):PAGE32
  CA45    GND @T6G_MB_LIB.T6G(SCH_1):GND    I14 @T6G_MB_LIB.T6G(SCH_1):PAGE32
  CA48    GND @T6G_MB_LIB.T6G(SCH_1):GND    I14 @T6G_MB_LIB.T6G(SCH_1):PAGE32
  CA51    GND @T6G_MB_LIB.T6G(SCH_1):GND    I14 @T6G_MB_LIB.T6G(SCH_1):PAGE32
  CA54    GND @T6G_MB_LIB.T6G(SCH_1):GND    I14 @T6G_MB_LIB.T6G(SCH_1):PAGE32
  CA56    GND @T6G_MB_LIB.T6G(SCH_1):GND    I14 @T6G_MB_LIB.T6G(SCH_1):PAGE32
  CA61    GND @T6G_MB_LIB.T6G(SCH_1):GND    I14 @T6G_MB_LIB.T6G(SCH_1):PAGE32
  CA63    GND @T6G_MB_LIB.T6G(SCH_1):GND    I14 @T6G_MB_LIB.T6G(SCH_1):PAGE32
  CA68    GND @T6G_MB_LIB.T6G(SCH_1):GND    I14 @T6G_MB_LIB.T6G(SCH_1):PAGE32
  CA70    GND @T6G_MB_LIB.T6G(SCH_1):GND    I14 @T6G_MB_LIB.T6G(SCH_1):PAGE32
  CA75    GND @T6G_MB_LIB.T6G(SCH_1):GND    I14 @T6G_MB_LIB.T6G(SCH_1):PAGE32
   CB3    GND @T6G_MB_LIB.T6G(SCH_1):GND    I14 @T6G_MB_LIB.T6G(SCH_1):PAGE32
   CB5    GND @T6G_MB_LIB.T6G(SCH_1):GND    I14 @T6G_MB_LIB.T6G(SCH_1):PAGE32
   CB8    GND @T6G_MB_LIB.T6G(SCH_1):GND    I14 @T6G_MB_LIB.T6G(SCH_1):PAGE32
  CB10    GND @T6G_MB_LIB.T6G(SCH_1):GND    I14 @T6G_MB_LIB.T6G(SCH_1):PAGE32
  CB12    GND @T6G_MB_LIB.T6G(SCH_1):GND    I14 @T6G_MB_LIB.T6G(SCH_1):PAGE32
  CB15    GND @T6G_MB_LIB.T6G(SCH_1):GND    I14 @T6G_MB_LIB.T6G(SCH_1):PAGE32
  CB17    GND @T6G_MB_LIB.T6G(SCH_1):GND    I14 @T6G_MB_LIB.T6G(SCH_1):PAGE32
  CB19    GND @T6G_MB_LIB.T6G(SCH_1):GND    I14 @T6G_MB_LIB.T6G(SCH_1):PAGE32
  CB23    GND @T6G_MB_LIB.T6G(SCH_1):GND    I14 @T6G_MB_LIB.T6G(SCH_1):PAGE32
  CB24    GND @T6G_MB_LIB.T6G(SCH_1):GND    I14 @T6G_MB_LIB.T6G(SCH_1):PAGE32
  CB25    GND @T6G_MB_LIB.T6G(SCH_1):GND    I14 @T6G_MB_LIB.T6G(SCH_1):PAGE32
  CB26    GND @T6G_MB_LIB.T6G(SCH_1):GND    I14 @T6G_MB_LIB.T6G(SCH_1):PAGE32
  CB27    GND @T6G_MB_LIB.T6G(SCH_1):GND    I14 @T6G_MB_LIB.T6G(SCH_1):PAGE32
  CB28    GND @T6G_MB_LIB.T6G(SCH_1):GND    I14 @T6G_MB_LIB.T6G(SCH_1):PAGE32
  CB29    GND @T6G_MB_LIB.T6G(SCH_1):GND    I14 @T6G_MB_LIB.T6G(SCH_1):PAGE32
  CB30    GND @T6G_MB_LIB.T6G(SCH_1):GND    I14 @T6G_MB_LIB.T6G(SCH_1):PAGE32
  CB31    GND @T6G_MB_LIB.T6G(SCH_1):GND    I14 @T6G_MB_LIB.T6G(SCH_1):PAGE32
  CB32    GND @T6G_MB_LIB.T6G(SCH_1):GND    I14 @T6G_MB_LIB.T6G(SCH_1):PAGE32
  CB33    GND @T6G_MB_LIB.T6G(SCH_1):GND    I14 @T6G_MB_LIB.T6G(SCH_1):PAGE32
  CB34    GND @T6G_MB_LIB.T6G(SCH_1):GND    I14 @T6G_MB_LIB.T6G(SCH_1):PAGE32
  CB37    GND @T6G_MB_LIB.T6G(SCH_1):GND    I14 @T6G_MB_LIB.T6G(SCH_1):PAGE32
  CB39    GND @T6G_MB_LIB.T6G(SCH_1):GND    I14 @T6G_MB_LIB.T6G(SCH_1):PAGE32
  CB42    GND @T6G_MB_LIB.T6G(SCH_1):GND    I14 @T6G_MB_LIB.T6G(SCH_1):PAGE32
  CB43    GND @T6G_MB_LIB.T6G(SCH_1):GND    I14 @T6G_MB_LIB.T6G(SCH_1):PAGE32
  CB45    GND @T6G_MB_LIB.T6G(SCH_1):GND    I14 @T6G_MB_LIB.T6G(SCH_1):PAGE32
  CB46    GND @T6G_MB_LIB.T6G(SCH_1):GND    I14 @T6G_MB_LIB.T6G(SCH_1):PAGE32
  CB47    GND @T6G_MB_LIB.T6G(SCH_1):GND    I14 @T6G_MB_LIB.T6G(SCH_1):PAGE32
  CB48    GND @T6G_MB_LIB.T6G(SCH_1):GND    I14 @T6G_MB_LIB.T6G(SCH_1):PAGE32
  CB49    GND @T6G_MB_LIB.T6G(SCH_1):GND    I14 @T6G_MB_LIB.T6G(SCH_1):PAGE32
  CB50    GND @T6G_MB_LIB.T6G(SCH_1):GND    I14 @T6G_MB_LIB.T6G(SCH_1):PAGE32
  CB51    GND @T6G_MB_LIB.T6G(SCH_1):GND    I14 @T6G_MB_LIB.T6G(SCH_1):PAGE32
  CB52    GND @T6G_MB_LIB.T6G(SCH_1):GND    I14 @T6G_MB_LIB.T6G(SCH_1):PAGE32
  CB53    GND @T6G_MB_LIB.T6G(SCH_1):GND    I14 @T6G_MB_LIB.T6G(SCH_1):PAGE32
  CB57    GND @T6G_MB_LIB.T6G(SCH_1):GND    I14 @T6G_MB_LIB.T6G(SCH_1):PAGE32
  CB59    GND @T6G_MB_LIB.T6G(SCH_1):GND    I14 @T6G_MB_LIB.T6G(SCH_1):PAGE32
  CB61    GND @T6G_MB_LIB.T6G(SCH_1):GND    I14 @T6G_MB_LIB.T6G(SCH_1):PAGE32
  CB64    GND @T6G_MB_LIB.T6G(SCH_1):GND    I14 @T6G_MB_LIB.T6G(SCH_1):PAGE32
  CB66    GND @T6G_MB_LIB.T6G(SCH_1):GND    I14 @T6G_MB_LIB.T6G(SCH_1):PAGE32
  CB68    GND @T6G_MB_LIB.T6G(SCH_1):GND    I14 @T6G_MB_LIB.T6G(SCH_1):PAGE32
  CB71    GND @T6G_MB_LIB.T6G(SCH_1):GND    I14 @T6G_MB_LIB.T6G(SCH_1):PAGE32
  CB73    GND @T6G_MB_LIB.T6G(SCH_1):GND    I14 @T6G_MB_LIB.T6G(SCH_1):PAGE32
   CC1    GND @T6G_MB_LIB.T6G(SCH_1):GND    I14 @T6G_MB_LIB.T6G(SCH_1):PAGE32
   CC4    GND @T6G_MB_LIB.T6G(SCH_1):GND    I14 @T6G_MB_LIB.T6G(SCH_1):PAGE32
   CC6    GND @T6G_MB_LIB.T6G(SCH_1):GND    I14 @T6G_MB_LIB.T6G(SCH_1):PAGE32
   CC8    GND @T6G_MB_LIB.T6G(SCH_1):GND    I14 @T6G_MB_LIB.T6G(SCH_1):PAGE32
  CC11    GND @T6G_MB_LIB.T6G(SCH_1):GND    I14 @T6G_MB_LIB.T6G(SCH_1):PAGE32
  CC13    GND @T6G_MB_LIB.T6G(SCH_1):GND    I14 @T6G_MB_LIB.T6G(SCH_1):PAGE32
  CC15    GND @T6G_MB_LIB.T6G(SCH_1):GND    I14 @T6G_MB_LIB.T6G(SCH_1):PAGE32
  CC18    GND @T6G_MB_LIB.T6G(SCH_1):GND    I14 @T6G_MB_LIB.T6G(SCH_1):PAGE32
  CC20    GND @T6G_MB_LIB.T6G(SCH_1):GND    I14 @T6G_MB_LIB.T6G(SCH_1):PAGE32
  CC25    GND @T6G_MB_LIB.T6G(SCH_1):GND    I14 @T6G_MB_LIB.T6G(SCH_1):PAGE32
  CC28    GND @T6G_MB_LIB.T6G(SCH_1):GND    I14 @T6G_MB_LIB.T6G(SCH_1):PAGE32
  CC31    GND @T6G_MB_LIB.T6G(SCH_1):GND    I14 @T6G_MB_LIB.T6G(SCH_1):PAGE32
  CC34    GND @T6G_MB_LIB.T6G(SCH_1):GND    I14 @T6G_MB_LIB.T6G(SCH_1):PAGE32
  CC42    GND @T6G_MB_LIB.T6G(SCH_1):GND    I14 @T6G_MB_LIB.T6G(SCH_1):PAGE32
  CC45    GND @T6G_MB_LIB.T6G(SCH_1):GND    I14 @T6G_MB_LIB.T6G(SCH_1):PAGE32
  CC48    GND @T6G_MB_LIB.T6G(SCH_1):GND    I14 @T6G_MB_LIB.T6G(SCH_1):PAGE32
  CC51    GND @T6G_MB_LIB.T6G(SCH_1):GND    I14 @T6G_MB_LIB.T6G(SCH_1):PAGE32
  CC54    GND @T6G_MB_LIB.T6G(SCH_1):GND    I14 @T6G_MB_LIB.T6G(SCH_1):PAGE32
  CC56    GND @T6G_MB_LIB.T6G(SCH_1):GND    I14 @T6G_MB_LIB.T6G(SCH_1):PAGE32
  CC58    GND @T6G_MB_LIB.T6G(SCH_1):GND    I14 @T6G_MB_LIB.T6G(SCH_1):PAGE32
  CC61    GND @T6G_MB_LIB.T6G(SCH_1):GND    I14 @T6G_MB_LIB.T6G(SCH_1):PAGE32
  CC63    GND @T6G_MB_LIB.T6G(SCH_1):GND    I14 @T6G_MB_LIB.T6G(SCH_1):PAGE32
  CC65    GND @T6G_MB_LIB.T6G(SCH_1):GND    I14 @T6G_MB_LIB.T6G(SCH_1):PAGE32
  CC68    GND @T6G_MB_LIB.T6G(SCH_1):GND    I14 @T6G_MB_LIB.T6G(SCH_1):PAGE32
  CC70    GND @T6G_MB_LIB.T6G(SCH_1):GND    I14 @T6G_MB_LIB.T6G(SCH_1):PAGE32
  CC72    GND @T6G_MB_LIB.T6G(SCH_1):GND    I14 @T6G_MB_LIB.T6G(SCH_1):PAGE32
  CC75    GND @T6G_MB_LIB.T6G(SCH_1):GND    I14 @T6G_MB_LIB.T6G(SCH_1):PAGE32
   CD3    GND @T6G_MB_LIB.T6G(SCH_1):GND    I14 @T6G_MB_LIB.T6G(SCH_1):PAGE32
   CD8    GND @T6G_MB_LIB.T6G(SCH_1):GND    I14 @T6G_MB_LIB.T6G(SCH_1):PAGE32
  CD10    GND @T6G_MB_LIB.T6G(SCH_1):GND    I14 @T6G_MB_LIB.T6G(SCH_1):PAGE32
  CD15    GND @T6G_MB_LIB.T6G(SCH_1):GND    I14 @T6G_MB_LIB.T6G(SCH_1):PAGE32
  CD17    GND @T6G_MB_LIB.T6G(SCH_1):GND    I14 @T6G_MB_LIB.T6G(SCH_1):PAGE32
  CD22    GND @T6G_MB_LIB.T6G(SCH_1):GND    I14 @T6G_MB_LIB.T6G(SCH_1):PAGE32
  CD25    GND @T6G_MB_LIB.T6G(SCH_1):GND    I14 @T6G_MB_LIB.T6G(SCH_1):PAGE32
  CD28    GND @T6G_MB_LIB.T6G(SCH_1):GND    I14 @T6G_MB_LIB.T6G(SCH_1):PAGE32
  CD31    GND @T6G_MB_LIB.T6G(SCH_1):GND    I14 @T6G_MB_LIB.T6G(SCH_1):PAGE32
  CD34    GND @T6G_MB_LIB.T6G(SCH_1):GND    I14 @T6G_MB_LIB.T6G(SCH_1):PAGE32
  CD37    GND @T6G_MB_LIB.T6G(SCH_1):GND    I14 @T6G_MB_LIB.T6G(SCH_1):PAGE32
  CD39    GND @T6G_MB_LIB.T6G(SCH_1):GND    I14 @T6G_MB_LIB.T6G(SCH_1):PAGE32
  CD42    GND @T6G_MB_LIB.T6G(SCH_1):GND    I14 @T6G_MB_LIB.T6G(SCH_1):PAGE32
  CD45    GND @T6G_MB_LIB.T6G(SCH_1):GND    I14 @T6G_MB_LIB.T6G(SCH_1):PAGE32
  CD48    GND @T6G_MB_LIB.T6G(SCH_1):GND    I14 @T6G_MB_LIB.T6G(SCH_1):PAGE32
  CD51    GND @T6G_MB_LIB.T6G(SCH_1):GND    I14 @T6G_MB_LIB.T6G(SCH_1):PAGE32
  CD54    GND @T6G_MB_LIB.T6G(SCH_1):GND    I14 @T6G_MB_LIB.T6G(SCH_1):PAGE32
  CD59    GND @T6G_MB_LIB.T6G(SCH_1):GND    I14 @T6G_MB_LIB.T6G(SCH_1):PAGE32
  CD61    GND @T6G_MB_LIB.T6G(SCH_1):GND    I14 @T6G_MB_LIB.T6G(SCH_1):PAGE32
  CD66    GND @T6G_MB_LIB.T6G(SCH_1):GND    I14 @T6G_MB_LIB.T6G(SCH_1):PAGE32
  CD68    GND @T6G_MB_LIB.T6G(SCH_1):GND    I14 @T6G_MB_LIB.T6G(SCH_1):PAGE32
  CD73    GND @T6G_MB_LIB.T6G(SCH_1):GND    I14 @T6G_MB_LIB.T6G(SCH_1):PAGE32
   CE1    GND @T6G_MB_LIB.T6G(SCH_1):GND    I14 @T6G_MB_LIB.T6G(SCH_1):PAGE32
   CE4    GND @T6G_MB_LIB.T6G(SCH_1):GND    I14 @T6G_MB_LIB.T6G(SCH_1):PAGE32
   CE6    GND @T6G_MB_LIB.T6G(SCH_1):GND    I14 @T6G_MB_LIB.T6G(SCH_1):PAGE32
   CE8    GND @T6G_MB_LIB.T6G(SCH_1):GND    I14 @T6G_MB_LIB.T6G(SCH_1):PAGE32
  CE11    GND @T6G_MB_LIB.T6G(SCH_1):GND    I14 @T6G_MB_LIB.T6G(SCH_1):PAGE32
  CE13    GND @T6G_MB_LIB.T6G(SCH_1):GND    I14 @T6G_MB_LIB.T6G(SCH_1):PAGE32
  CE15    GND @T6G_MB_LIB.T6G(SCH_1):GND    I14 @T6G_MB_LIB.T6G(SCH_1):PAGE32
  CE18    GND @T6G_MB_LIB.T6G(SCH_1):GND    I14 @T6G_MB_LIB.T6G(SCH_1):PAGE32
  CE20    GND @T6G_MB_LIB.T6G(SCH_1):GND    I14 @T6G_MB_LIB.T6G(SCH_1):PAGE32
  CE22    GND @T6G_MB_LIB.T6G(SCH_1):GND    I14 @T6G_MB_LIB.T6G(SCH_1):PAGE32
  CE25    GND @T6G_MB_LIB.T6G(SCH_1):GND    I14 @T6G_MB_LIB.T6G(SCH_1):PAGE32
  CE28    GND @T6G_MB_LIB.T6G(SCH_1):GND    I14 @T6G_MB_LIB.T6G(SCH_1):PAGE32
  CE31    GND @T6G_MB_LIB.T6G(SCH_1):GND    I14 @T6G_MB_LIB.T6G(SCH_1):PAGE32
  CE34    GND @T6G_MB_LIB.T6G(SCH_1):GND    I14 @T6G_MB_LIB.T6G(SCH_1):PAGE32
  CE35    GND @T6G_MB_LIB.T6G(SCH_1):GND    I14 @T6G_MB_LIB.T6G(SCH_1):PAGE32
  CE36    GND @T6G_MB_LIB.T6G(SCH_1):GND    I14 @T6G_MB_LIB.T6G(SCH_1):PAGE32
  CE40    GND @T6G_MB_LIB.T6G(SCH_1):GND    I14 @T6G_MB_LIB.T6G(SCH_1):PAGE32
  CE41    GND @T6G_MB_LIB.T6G(SCH_1):GND    I14 @T6G_MB_LIB.T6G(SCH_1):PAGE32
  CE42    GND @T6G_MB_LIB.T6G(SCH_1):GND    I14 @T6G_MB_LIB.T6G(SCH_1):PAGE32
  CE45    GND @T6G_MB_LIB.T6G(SCH_1):GND    I14 @T6G_MB_LIB.T6G(SCH_1):PAGE32
  CE48    GND @T6G_MB_LIB.T6G(SCH_1):GND    I14 @T6G_MB_LIB.T6G(SCH_1):PAGE32
  CE51    GND @T6G_MB_LIB.T6G(SCH_1):GND    I14 @T6G_MB_LIB.T6G(SCH_1):PAGE32
  CE54    GND @T6G_MB_LIB.T6G(SCH_1):GND    I14 @T6G_MB_LIB.T6G(SCH_1):PAGE32
  CE56    GND @T6G_MB_LIB.T6G(SCH_1):GND    I14 @T6G_MB_LIB.T6G(SCH_1):PAGE32
  CE58    GND @T6G_MB_LIB.T6G(SCH_1):GND    I14 @T6G_MB_LIB.T6G(SCH_1):PAGE32
  CE61    GND @T6G_MB_LIB.T6G(SCH_1):GND    I14 @T6G_MB_LIB.T6G(SCH_1):PAGE32
  CE63    GND @T6G_MB_LIB.T6G(SCH_1):GND    I14 @T6G_MB_LIB.T6G(SCH_1):PAGE32
  CE65    GND @T6G_MB_LIB.T6G(SCH_1):GND    I14 @T6G_MB_LIB.T6G(SCH_1):PAGE32
  CE68    GND @T6G_MB_LIB.T6G(SCH_1):GND    I14 @T6G_MB_LIB.T6G(SCH_1):PAGE32
  CE70    GND @T6G_MB_LIB.T6G(SCH_1):GND    I14 @T6G_MB_LIB.T6G(SCH_1):PAGE32
  CE72    GND @T6G_MB_LIB.T6G(SCH_1):GND    I14 @T6G_MB_LIB.T6G(SCH_1):PAGE32
  CE75    GND @T6G_MB_LIB.T6G(SCH_1):GND    I14 @T6G_MB_LIB.T6G(SCH_1):PAGE32
   CF3    GND @T6G_MB_LIB.T6G(SCH_1):GND    I14 @T6G_MB_LIB.T6G(SCH_1):PAGE32
   CF5    GND @T6G_MB_LIB.T6G(SCH_1):GND    I14 @T6G_MB_LIB.T6G(SCH_1):PAGE32
   CF8    GND @T6G_MB_LIB.T6G(SCH_1):GND    I14 @T6G_MB_LIB.T6G(SCH_1):PAGE32
  CF10    GND @T6G_MB_LIB.T6G(SCH_1):GND    I14 @T6G_MB_LIB.T6G(SCH_1):PAGE32
  CF12    GND @T6G_MB_LIB.T6G(SCH_1):GND    I14 @T6G_MB_LIB.T6G(SCH_1):PAGE32
  CF15    GND @T6G_MB_LIB.T6G(SCH_1):GND    I14 @T6G_MB_LIB.T6G(SCH_1):PAGE32
  CF17    GND @T6G_MB_LIB.T6G(SCH_1):GND    I14 @T6G_MB_LIB.T6G(SCH_1):PAGE32
  CF19    GND @T6G_MB_LIB.T6G(SCH_1):GND    I14 @T6G_MB_LIB.T6G(SCH_1):PAGE32
  CF23    GND @T6G_MB_LIB.T6G(SCH_1):GND    I14 @T6G_MB_LIB.T6G(SCH_1):PAGE32
  CF24    GND @T6G_MB_LIB.T6G(SCH_1):GND    I14 @T6G_MB_LIB.T6G(SCH_1):PAGE32
  CF25    GND @T6G_MB_LIB.T6G(SCH_1):GND    I14 @T6G_MB_LIB.T6G(SCH_1):PAGE32
  CF26    GND @T6G_MB_LIB.T6G(SCH_1):GND    I14 @T6G_MB_LIB.T6G(SCH_1):PAGE32
  CF27    GND @T6G_MB_LIB.T6G(SCH_1):GND    I14 @T6G_MB_LIB.T6G(SCH_1):PAGE32
  CF28    GND @T6G_MB_LIB.T6G(SCH_1):GND    I14 @T6G_MB_LIB.T6G(SCH_1):PAGE32
  CF29    GND @T6G_MB_LIB.T6G(SCH_1):GND    I14 @T6G_MB_LIB.T6G(SCH_1):PAGE32
  CF30    GND @T6G_MB_LIB.T6G(SCH_1):GND    I14 @T6G_MB_LIB.T6G(SCH_1):PAGE32
  CF31    GND @T6G_MB_LIB.T6G(SCH_1):GND    I14 @T6G_MB_LIB.T6G(SCH_1):PAGE32
  CF32    GND @T6G_MB_LIB.T6G(SCH_1):GND    I14 @T6G_MB_LIB.T6G(SCH_1):PAGE32
  CF33    GND @T6G_MB_LIB.T6G(SCH_1):GND    I14 @T6G_MB_LIB.T6G(SCH_1):PAGE32
  CN56    GND @T6G_MB_LIB.T6G(SCH_1):GND    I15 @T6G_MB_LIB.T6G(SCH_1):PAGE32
  CN20    GND @T6G_MB_LIB.T6G(SCH_1):GND    I15 @T6G_MB_LIB.T6G(SCH_1):PAGE32
  CM61    GND @T6G_MB_LIB.T6G(SCH_1):GND    I15 @T6G_MB_LIB.T6G(SCH_1):PAGE32
  CM34    GND @T6G_MB_LIB.T6G(SCH_1):GND    I15 @T6G_MB_LIB.T6G(SCH_1):PAGE32
  CK33    GND @T6G_MB_LIB.T6G(SCH_1):GND    I15 @T6G_MB_LIB.T6G(SCH_1):PAGE32
  CK15    GND @T6G_MB_LIB.T6G(SCH_1):GND    I15 @T6G_MB_LIB.T6G(SCH_1):PAGE32
  CJ58    GND @T6G_MB_LIB.T6G(SCH_1):GND    I15 @T6G_MB_LIB.T6G(SCH_1):PAGE32
  CJ20    GND @T6G_MB_LIB.T6G(SCH_1):GND    I15 @T6G_MB_LIB.T6G(SCH_1):PAGE32
  CH68    GND @T6G_MB_LIB.T6G(SCH_1):GND    I15 @T6G_MB_LIB.T6G(SCH_1):PAGE32
  CH39    GND @T6G_MB_LIB.T6G(SCH_1):GND    I15 @T6G_MB_LIB.T6G(SCH_1):PAGE32
  CH10    GND @T6G_MB_LIB.T6G(SCH_1):GND    I15 @T6G_MB_LIB.T6G(SCH_1):PAGE32
  CN22    GND @T6G_MB_LIB.T6G(SCH_1):GND    I15 @T6G_MB_LIB.T6G(SCH_1):PAGE32
  CM64    GND @T6G_MB_LIB.T6G(SCH_1):GND    I15 @T6G_MB_LIB.T6G(SCH_1):PAGE32
  CM37    GND @T6G_MB_LIB.T6G(SCH_1):GND    I15 @T6G_MB_LIB.T6G(SCH_1):PAGE32
  CM24    GND @T6G_MB_LIB.T6G(SCH_1):GND    I15 @T6G_MB_LIB.T6G(SCH_1):PAGE32
  CK17    GND @T6G_MB_LIB.T6G(SCH_1):GND    I15 @T6G_MB_LIB.T6G(SCH_1):PAGE32
  CJ61    GND @T6G_MB_LIB.T6G(SCH_1):GND    I15 @T6G_MB_LIB.T6G(SCH_1):PAGE32
  CJ23    GND @T6G_MB_LIB.T6G(SCH_1):GND    I15 @T6G_MB_LIB.T6G(SCH_1):PAGE32
  CH71    GND @T6G_MB_LIB.T6G(SCH_1):GND    I15 @T6G_MB_LIB.T6G(SCH_1):PAGE32
  CH42    GND @T6G_MB_LIB.T6G(SCH_1):GND    I15 @T6G_MB_LIB.T6G(SCH_1):PAGE32
  CH12    GND @T6G_MB_LIB.T6G(SCH_1):GND    I15 @T6G_MB_LIB.T6G(SCH_1):PAGE32
  CM66    GND @T6G_MB_LIB.T6G(SCH_1):GND    I15 @T6G_MB_LIB.T6G(SCH_1):PAGE32
  CM39    GND @T6G_MB_LIB.T6G(SCH_1):GND    I15 @T6G_MB_LIB.T6G(SCH_1):PAGE32
  CM25    GND @T6G_MB_LIB.T6G(SCH_1):GND    I15 @T6G_MB_LIB.T6G(SCH_1):PAGE32
  CL75    GND @T6G_MB_LIB.T6G(SCH_1):GND    I15 @T6G_MB_LIB.T6G(SCH_1):PAGE32
  CJ63    GND @T6G_MB_LIB.T6G(SCH_1):GND    I15 @T6G_MB_LIB.T6G(SCH_1):PAGE32
  CJ31    GND @T6G_MB_LIB.T6G(SCH_1):GND    I15 @T6G_MB_LIB.T6G(SCH_1):PAGE32
  CH73    GND @T6G_MB_LIB.T6G(SCH_1):GND    I15 @T6G_MB_LIB.T6G(SCH_1):PAGE32
  CH45    GND @T6G_MB_LIB.T6G(SCH_1):GND    I15 @T6G_MB_LIB.T6G(SCH_1):PAGE32
  CH15    GND @T6G_MB_LIB.T6G(SCH_1):GND    I15 @T6G_MB_LIB.T6G(SCH_1):PAGE32
  CM42    GND @T6G_MB_LIB.T6G(SCH_1):GND    I15 @T6G_MB_LIB.T6G(SCH_1):PAGE32
  CM26    GND @T6G_MB_LIB.T6G(SCH_1):GND    I15 @T6G_MB_LIB.T6G(SCH_1):PAGE32
   CM3    GND @T6G_MB_LIB.T6G(SCH_1):GND    I15 @T6G_MB_LIB.T6G(SCH_1):PAGE32
  CL51    GND @T6G_MB_LIB.T6G(SCH_1):GND    I15 @T6G_MB_LIB.T6G(SCH_1):PAGE32
  CJ34    GND @T6G_MB_LIB.T6G(SCH_1):GND    I15 @T6G_MB_LIB.T6G(SCH_1):PAGE32
   CJ1    GND @T6G_MB_LIB.T6G(SCH_1):GND    I15 @T6G_MB_LIB.T6G(SCH_1):PAGE32
  CH48    GND @T6G_MB_LIB.T6G(SCH_1):GND    I15 @T6G_MB_LIB.T6G(SCH_1):PAGE32
  CH17    GND @T6G_MB_LIB.T6G(SCH_1):GND    I15 @T6G_MB_LIB.T6G(SCH_1):PAGE32
  CM43    GND @T6G_MB_LIB.T6G(SCH_1):GND    I15 @T6G_MB_LIB.T6G(SCH_1):PAGE32
  CM27    GND @T6G_MB_LIB.T6G(SCH_1):GND    I15 @T6G_MB_LIB.T6G(SCH_1):PAGE32
   CM5    GND @T6G_MB_LIB.T6G(SCH_1):GND    I15 @T6G_MB_LIB.T6G(SCH_1):PAGE32
  CL54    GND @T6G_MB_LIB.T6G(SCH_1):GND    I15 @T6G_MB_LIB.T6G(SCH_1):PAGE32
  CL28    GND @T6G_MB_LIB.T6G(SCH_1):GND    I15 @T6G_MB_LIB.T6G(SCH_1):PAGE32
   CJ4    GND @T6G_MB_LIB.T6G(SCH_1):GND    I15 @T6G_MB_LIB.T6G(SCH_1):PAGE32
  CH51    GND @T6G_MB_LIB.T6G(SCH_1):GND    I15 @T6G_MB_LIB.T6G(SCH_1):PAGE32
  CH19    GND @T6G_MB_LIB.T6G(SCH_1):GND    I15 @T6G_MB_LIB.T6G(SCH_1):PAGE32
  CF34    GND @T6G_MB_LIB.T6G(SCH_1):GND    I15 @T6G_MB_LIB.T6G(SCH_1):PAGE32
  CF37    GND @T6G_MB_LIB.T6G(SCH_1):GND    I15 @T6G_MB_LIB.T6G(SCH_1):PAGE32
  CF39    GND @T6G_MB_LIB.T6G(SCH_1):GND    I15 @T6G_MB_LIB.T6G(SCH_1):PAGE32
  CF42    GND @T6G_MB_LIB.T6G(SCH_1):GND    I15 @T6G_MB_LIB.T6G(SCH_1):PAGE32
  CF43    GND @T6G_MB_LIB.T6G(SCH_1):GND    I15 @T6G_MB_LIB.T6G(SCH_1):PAGE32
  CF44    GND @T6G_MB_LIB.T6G(SCH_1):GND    I15 @T6G_MB_LIB.T6G(SCH_1):PAGE32
  CF45    GND @T6G_MB_LIB.T6G(SCH_1):GND    I15 @T6G_MB_LIB.T6G(SCH_1):PAGE32
  CF47    GND @T6G_MB_LIB.T6G(SCH_1):GND    I15 @T6G_MB_LIB.T6G(SCH_1):PAGE32
  CF48    GND @T6G_MB_LIB.T6G(SCH_1):GND    I15 @T6G_MB_LIB.T6G(SCH_1):PAGE32
  CF49    GND @T6G_MB_LIB.T6G(SCH_1):GND    I15 @T6G_MB_LIB.T6G(SCH_1):PAGE32
  CF50    GND @T6G_MB_LIB.T6G(SCH_1):GND    I15 @T6G_MB_LIB.T6G(SCH_1):PAGE32
  CF51    GND @T6G_MB_LIB.T6G(SCH_1):GND    I15 @T6G_MB_LIB.T6G(SCH_1):PAGE32
  CF52    GND @T6G_MB_LIB.T6G(SCH_1):GND    I15 @T6G_MB_LIB.T6G(SCH_1):PAGE32
  CF53    GND @T6G_MB_LIB.T6G(SCH_1):GND    I15 @T6G_MB_LIB.T6G(SCH_1):PAGE32
  CF57    GND @T6G_MB_LIB.T6G(SCH_1):GND    I15 @T6G_MB_LIB.T6G(SCH_1):PAGE32
  CF59    GND @T6G_MB_LIB.T6G(SCH_1):GND    I15 @T6G_MB_LIB.T6G(SCH_1):PAGE32
  CF61    GND @T6G_MB_LIB.T6G(SCH_1):GND    I15 @T6G_MB_LIB.T6G(SCH_1):PAGE32
  CF64    GND @T6G_MB_LIB.T6G(SCH_1):GND    I15 @T6G_MB_LIB.T6G(SCH_1):PAGE32
  CF66    GND @T6G_MB_LIB.T6G(SCH_1):GND    I15 @T6G_MB_LIB.T6G(SCH_1):PAGE32
  CF68    GND @T6G_MB_LIB.T6G(SCH_1):GND    I15 @T6G_MB_LIB.T6G(SCH_1):PAGE32
  CF71    GND @T6G_MB_LIB.T6G(SCH_1):GND    I15 @T6G_MB_LIB.T6G(SCH_1):PAGE32
  CF73    GND @T6G_MB_LIB.T6G(SCH_1):GND    I15 @T6G_MB_LIB.T6G(SCH_1):PAGE32
   CG1    GND @T6G_MB_LIB.T6G(SCH_1):GND    I15 @T6G_MB_LIB.T6G(SCH_1):PAGE32
   CG6    GND @T6G_MB_LIB.T6G(SCH_1):GND    I15 @T6G_MB_LIB.T6G(SCH_1):PAGE32
   CG8    GND @T6G_MB_LIB.T6G(SCH_1):GND    I15 @T6G_MB_LIB.T6G(SCH_1):PAGE32
  CG13    GND @T6G_MB_LIB.T6G(SCH_1):GND    I15 @T6G_MB_LIB.T6G(SCH_1):PAGE32
  CG15    GND @T6G_MB_LIB.T6G(SCH_1):GND    I15 @T6G_MB_LIB.T6G(SCH_1):PAGE32
  CG20    GND @T6G_MB_LIB.T6G(SCH_1):GND    I15 @T6G_MB_LIB.T6G(SCH_1):PAGE32
  CG22    GND @T6G_MB_LIB.T6G(SCH_1):GND    I15 @T6G_MB_LIB.T6G(SCH_1):PAGE32
  CG25    GND @T6G_MB_LIB.T6G(SCH_1):GND    I15 @T6G_MB_LIB.T6G(SCH_1):PAGE32
  CG28    GND @T6G_MB_LIB.T6G(SCH_1):GND    I15 @T6G_MB_LIB.T6G(SCH_1):PAGE32
  CG31    GND @T6G_MB_LIB.T6G(SCH_1):GND    I15 @T6G_MB_LIB.T6G(SCH_1):PAGE32
  CG34    GND @T6G_MB_LIB.T6G(SCH_1):GND    I15 @T6G_MB_LIB.T6G(SCH_1):PAGE32
  CG45    GND @T6G_MB_LIB.T6G(SCH_1):GND    I15 @T6G_MB_LIB.T6G(SCH_1):PAGE32
  CG48    GND @T6G_MB_LIB.T6G(SCH_1):GND    I15 @T6G_MB_LIB.T6G(SCH_1):PAGE32
  CG51    GND @T6G_MB_LIB.T6G(SCH_1):GND    I15 @T6G_MB_LIB.T6G(SCH_1):PAGE32
  CG54    GND @T6G_MB_LIB.T6G(SCH_1):GND    I15 @T6G_MB_LIB.T6G(SCH_1):PAGE32
  CG56    GND @T6G_MB_LIB.T6G(SCH_1):GND    I15 @T6G_MB_LIB.T6G(SCH_1):PAGE32
  CG61    GND @T6G_MB_LIB.T6G(SCH_1):GND    I15 @T6G_MB_LIB.T6G(SCH_1):PAGE32
  CG63    GND @T6G_MB_LIB.T6G(SCH_1):GND    I15 @T6G_MB_LIB.T6G(SCH_1):PAGE32
  CG68    GND @T6G_MB_LIB.T6G(SCH_1):GND    I15 @T6G_MB_LIB.T6G(SCH_1):PAGE32
  CG70    GND @T6G_MB_LIB.T6G(SCH_1):GND    I15 @T6G_MB_LIB.T6G(SCH_1):PAGE32
  CG75    GND @T6G_MB_LIB.T6G(SCH_1):GND    I15 @T6G_MB_LIB.T6G(SCH_1):PAGE32
   CH3    GND @T6G_MB_LIB.T6G(SCH_1):GND    I15 @T6G_MB_LIB.T6G(SCH_1):PAGE32
   CH5    GND @T6G_MB_LIB.T6G(SCH_1):GND    I15 @T6G_MB_LIB.T6G(SCH_1):PAGE32
   CH8    GND @T6G_MB_LIB.T6G(SCH_1):GND    I15 @T6G_MB_LIB.T6G(SCH_1):PAGE32
  CH22    GND @T6G_MB_LIB.T6G(SCH_1):GND    I15 @T6G_MB_LIB.T6G(SCH_1):PAGE32
  CH25    GND @T6G_MB_LIB.T6G(SCH_1):GND    I15 @T6G_MB_LIB.T6G(SCH_1):PAGE32
  CH28    GND @T6G_MB_LIB.T6G(SCH_1):GND    I15 @T6G_MB_LIB.T6G(SCH_1):PAGE32
  CH31    GND @T6G_MB_LIB.T6G(SCH_1):GND    I15 @T6G_MB_LIB.T6G(SCH_1):PAGE32
  CH34    GND @T6G_MB_LIB.T6G(SCH_1):GND    I15 @T6G_MB_LIB.T6G(SCH_1):PAGE32
  CH37    GND @T6G_MB_LIB.T6G(SCH_1):GND    I15 @T6G_MB_LIB.T6G(SCH_1):PAGE32
  CH54    GND @T6G_MB_LIB.T6G(SCH_1):GND    I15 @T6G_MB_LIB.T6G(SCH_1):PAGE32
  CH57    GND @T6G_MB_LIB.T6G(SCH_1):GND    I15 @T6G_MB_LIB.T6G(SCH_1):PAGE32
  CH59    GND @T6G_MB_LIB.T6G(SCH_1):GND    I15 @T6G_MB_LIB.T6G(SCH_1):PAGE32
  CH61    GND @T6G_MB_LIB.T6G(SCH_1):GND    I15 @T6G_MB_LIB.T6G(SCH_1):PAGE32
  CH64    GND @T6G_MB_LIB.T6G(SCH_1):GND    I15 @T6G_MB_LIB.T6G(SCH_1):PAGE32
  CH66    GND @T6G_MB_LIB.T6G(SCH_1):GND    I15 @T6G_MB_LIB.T6G(SCH_1):PAGE32
   CJ6    GND @T6G_MB_LIB.T6G(SCH_1):GND    I15 @T6G_MB_LIB.T6G(SCH_1):PAGE32
   CJ8    GND @T6G_MB_LIB.T6G(SCH_1):GND    I15 @T6G_MB_LIB.T6G(SCH_1):PAGE32
  CJ11    GND @T6G_MB_LIB.T6G(SCH_1):GND    I15 @T6G_MB_LIB.T6G(SCH_1):PAGE32
  CJ13    GND @T6G_MB_LIB.T6G(SCH_1):GND    I15 @T6G_MB_LIB.T6G(SCH_1):PAGE32
  CJ15    GND @T6G_MB_LIB.T6G(SCH_1):GND    I15 @T6G_MB_LIB.T6G(SCH_1):PAGE32
  CJ18    GND @T6G_MB_LIB.T6G(SCH_1):GND    I15 @T6G_MB_LIB.T6G(SCH_1):PAGE32
  CJ35    GND @T6G_MB_LIB.T6G(SCH_1):GND    I15 @T6G_MB_LIB.T6G(SCH_1):PAGE32
  CJ36    GND @T6G_MB_LIB.T6G(SCH_1):GND    I15 @T6G_MB_LIB.T6G(SCH_1):PAGE32
  CJ40    GND @T6G_MB_LIB.T6G(SCH_1):GND    I15 @T6G_MB_LIB.T6G(SCH_1):PAGE32
  CJ41    GND @T6G_MB_LIB.T6G(SCH_1):GND    I15 @T6G_MB_LIB.T6G(SCH_1):PAGE32
  CJ42    GND @T6G_MB_LIB.T6G(SCH_1):GND    I15 @T6G_MB_LIB.T6G(SCH_1):PAGE32
  CJ45    GND @T6G_MB_LIB.T6G(SCH_1):GND    I15 @T6G_MB_LIB.T6G(SCH_1):PAGE32
  CJ56    GND @T6G_MB_LIB.T6G(SCH_1):GND    I15 @T6G_MB_LIB.T6G(SCH_1):PAGE32
  CJ65    GND @T6G_MB_LIB.T6G(SCH_1):GND    I15 @T6G_MB_LIB.T6G(SCH_1):PAGE32
  CJ68    GND @T6G_MB_LIB.T6G(SCH_1):GND    I15 @T6G_MB_LIB.T6G(SCH_1):PAGE32
  CJ70    GND @T6G_MB_LIB.T6G(SCH_1):GND    I15 @T6G_MB_LIB.T6G(SCH_1):PAGE32
  CJ72    GND @T6G_MB_LIB.T6G(SCH_1):GND    I15 @T6G_MB_LIB.T6G(SCH_1):PAGE32
  CJ75    GND @T6G_MB_LIB.T6G(SCH_1):GND    I15 @T6G_MB_LIB.T6G(SCH_1):PAGE32
   CK3    GND @T6G_MB_LIB.T6G(SCH_1):GND    I15 @T6G_MB_LIB.T6G(SCH_1):PAGE32
   CK8    GND @T6G_MB_LIB.T6G(SCH_1):GND    I15 @T6G_MB_LIB.T6G(SCH_1):PAGE32
  CK22    GND @T6G_MB_LIB.T6G(SCH_1):GND    I15 @T6G_MB_LIB.T6G(SCH_1):PAGE32
  CK23    GND @T6G_MB_LIB.T6G(SCH_1):GND    I15 @T6G_MB_LIB.T6G(SCH_1):PAGE32
  CK24    GND @T6G_MB_LIB.T6G(SCH_1):GND    I15 @T6G_MB_LIB.T6G(SCH_1):PAGE32
  CK25    GND @T6G_MB_LIB.T6G(SCH_1):GND    I15 @T6G_MB_LIB.T6G(SCH_1):PAGE32
  CK26    GND @T6G_MB_LIB.T6G(SCH_1):GND    I15 @T6G_MB_LIB.T6G(SCH_1):PAGE32
  CK27    GND @T6G_MB_LIB.T6G(SCH_1):GND    I15 @T6G_MB_LIB.T6G(SCH_1):PAGE32
  CK28    GND @T6G_MB_LIB.T6G(SCH_1):GND    I15 @T6G_MB_LIB.T6G(SCH_1):PAGE32
  CK32    GND @T6G_MB_LIB.T6G(SCH_1):GND    I15 @T6G_MB_LIB.T6G(SCH_1):PAGE32
  CK34    GND @T6G_MB_LIB.T6G(SCH_1):GND    I15 @T6G_MB_LIB.T6G(SCH_1):PAGE32
  CK37    GND @T6G_MB_LIB.T6G(SCH_1):GND    I15 @T6G_MB_LIB.T6G(SCH_1):PAGE32
  CK39    GND @T6G_MB_LIB.T6G(SCH_1):GND    I15 @T6G_MB_LIB.T6G(SCH_1):PAGE32
  CK42    GND @T6G_MB_LIB.T6G(SCH_1):GND    I15 @T6G_MB_LIB.T6G(SCH_1):PAGE32
  CK43    GND @T6G_MB_LIB.T6G(SCH_1):GND    I15 @T6G_MB_LIB.T6G(SCH_1):PAGE32
  CK44    GND @T6G_MB_LIB.T6G(SCH_1):GND    I15 @T6G_MB_LIB.T6G(SCH_1):PAGE32
  CK45    GND @T6G_MB_LIB.T6G(SCH_1):GND    I15 @T6G_MB_LIB.T6G(SCH_1):PAGE32
  CK48    GND @T6G_MB_LIB.T6G(SCH_1):GND    I15 @T6G_MB_LIB.T6G(SCH_1):PAGE32
  CK49    GND @T6G_MB_LIB.T6G(SCH_1):GND    I15 @T6G_MB_LIB.T6G(SCH_1):PAGE32
  CK50    GND @T6G_MB_LIB.T6G(SCH_1):GND    I15 @T6G_MB_LIB.T6G(SCH_1):PAGE32
  CK51    GND @T6G_MB_LIB.T6G(SCH_1):GND    I15 @T6G_MB_LIB.T6G(SCH_1):PAGE32
  CK52    GND @T6G_MB_LIB.T6G(SCH_1):GND    I15 @T6G_MB_LIB.T6G(SCH_1):PAGE32
  CK53    GND @T6G_MB_LIB.T6G(SCH_1):GND    I15 @T6G_MB_LIB.T6G(SCH_1):PAGE32
  CK54    GND @T6G_MB_LIB.T6G(SCH_1):GND    I15 @T6G_MB_LIB.T6G(SCH_1):PAGE32
  CK59    GND @T6G_MB_LIB.T6G(SCH_1):GND    I15 @T6G_MB_LIB.T6G(SCH_1):PAGE32
  CK61    GND @T6G_MB_LIB.T6G(SCH_1):GND    I15 @T6G_MB_LIB.T6G(SCH_1):PAGE32
  CK66    GND @T6G_MB_LIB.T6G(SCH_1):GND    I15 @T6G_MB_LIB.T6G(SCH_1):PAGE32
  CK68    GND @T6G_MB_LIB.T6G(SCH_1):GND    I15 @T6G_MB_LIB.T6G(SCH_1):PAGE32
  CK73    GND @T6G_MB_LIB.T6G(SCH_1):GND    I15 @T6G_MB_LIB.T6G(SCH_1):PAGE32
   CL1    GND @T6G_MB_LIB.T6G(SCH_1):GND    I15 @T6G_MB_LIB.T6G(SCH_1):PAGE32
   CL4    GND @T6G_MB_LIB.T6G(SCH_1):GND    I15 @T6G_MB_LIB.T6G(SCH_1):PAGE32
   CL6    GND @T6G_MB_LIB.T6G(SCH_1):GND    I15 @T6G_MB_LIB.T6G(SCH_1):PAGE32
   CL8    GND @T6G_MB_LIB.T6G(SCH_1):GND    I15 @T6G_MB_LIB.T6G(SCH_1):PAGE32
  CL11    GND @T6G_MB_LIB.T6G(SCH_1):GND    I15 @T6G_MB_LIB.T6G(SCH_1):PAGE32
  CL13    GND @T6G_MB_LIB.T6G(SCH_1):GND    I15 @T6G_MB_LIB.T6G(SCH_1):PAGE32
  CL15    GND @T6G_MB_LIB.T6G(SCH_1):GND    I15 @T6G_MB_LIB.T6G(SCH_1):PAGE32
  CL18    GND @T6G_MB_LIB.T6G(SCH_1):GND    I15 @T6G_MB_LIB.T6G(SCH_1):PAGE32
  CL20    GND @T6G_MB_LIB.T6G(SCH_1):GND    I15 @T6G_MB_LIB.T6G(SCH_1):PAGE32
  CL22    GND @T6G_MB_LIB.T6G(SCH_1):GND    I15 @T6G_MB_LIB.T6G(SCH_1):PAGE32
  CL25    GND @T6G_MB_LIB.T6G(SCH_1):GND    I15 @T6G_MB_LIB.T6G(SCH_1):PAGE32
  CL31    GND @T6G_MB_LIB.T6G(SCH_1):GND    I15 @T6G_MB_LIB.T6G(SCH_1):PAGE32
  CL34    GND @T6G_MB_LIB.T6G(SCH_1):GND    I15 @T6G_MB_LIB.T6G(SCH_1):PAGE32
  CL35    GND @T6G_MB_LIB.T6G(SCH_1):GND    I15 @T6G_MB_LIB.T6G(SCH_1):PAGE32
  CL36    GND @T6G_MB_LIB.T6G(SCH_1):GND    I15 @T6G_MB_LIB.T6G(SCH_1):PAGE32
  CL40    GND @T6G_MB_LIB.T6G(SCH_1):GND    I15 @T6G_MB_LIB.T6G(SCH_1):PAGE32
  CL41    GND @T6G_MB_LIB.T6G(SCH_1):GND    I15 @T6G_MB_LIB.T6G(SCH_1):PAGE32
  CL42    GND @T6G_MB_LIB.T6G(SCH_1):GND    I15 @T6G_MB_LIB.T6G(SCH_1):PAGE32
  CL45    GND @T6G_MB_LIB.T6G(SCH_1):GND    I15 @T6G_MB_LIB.T6G(SCH_1):PAGE32
  CL48    GND @T6G_MB_LIB.T6G(SCH_1):GND    I15 @T6G_MB_LIB.T6G(SCH_1):PAGE32
  CL56    GND @T6G_MB_LIB.T6G(SCH_1):GND    I15 @T6G_MB_LIB.T6G(SCH_1):PAGE32
  CL58    GND @T6G_MB_LIB.T6G(SCH_1):GND    I15 @T6G_MB_LIB.T6G(SCH_1):PAGE32
  CL61    GND @T6G_MB_LIB.T6G(SCH_1):GND    I15 @T6G_MB_LIB.T6G(SCH_1):PAGE32
  CL63    GND @T6G_MB_LIB.T6G(SCH_1):GND    I15 @T6G_MB_LIB.T6G(SCH_1):PAGE32
  CL65    GND @T6G_MB_LIB.T6G(SCH_1):GND    I15 @T6G_MB_LIB.T6G(SCH_1):PAGE32
  CL68    GND @T6G_MB_LIB.T6G(SCH_1):GND    I15 @T6G_MB_LIB.T6G(SCH_1):PAGE32
  CL70    GND @T6G_MB_LIB.T6G(SCH_1):GND    I15 @T6G_MB_LIB.T6G(SCH_1):PAGE32
  CL72    GND @T6G_MB_LIB.T6G(SCH_1):GND    I15 @T6G_MB_LIB.T6G(SCH_1):PAGE32
   CM8    GND @T6G_MB_LIB.T6G(SCH_1):GND    I15 @T6G_MB_LIB.T6G(SCH_1):PAGE32
  CM10    GND @T6G_MB_LIB.T6G(SCH_1):GND    I15 @T6G_MB_LIB.T6G(SCH_1):PAGE32
  CM12    GND @T6G_MB_LIB.T6G(SCH_1):GND    I15 @T6G_MB_LIB.T6G(SCH_1):PAGE32
  CM15    GND @T6G_MB_LIB.T6G(SCH_1):GND    I15 @T6G_MB_LIB.T6G(SCH_1):PAGE32
  CM17    GND @T6G_MB_LIB.T6G(SCH_1):GND    I15 @T6G_MB_LIB.T6G(SCH_1):PAGE32
  CM19    GND @T6G_MB_LIB.T6G(SCH_1):GND    I15 @T6G_MB_LIB.T6G(SCH_1):PAGE32
  CM23    GND @T6G_MB_LIB.T6G(SCH_1):GND    I15 @T6G_MB_LIB.T6G(SCH_1):PAGE32
  CM28    GND @T6G_MB_LIB.T6G(SCH_1):GND    I15 @T6G_MB_LIB.T6G(SCH_1):PAGE32
  CM29    GND @T6G_MB_LIB.T6G(SCH_1):GND    I15 @T6G_MB_LIB.T6G(SCH_1):PAGE32
  CM30    GND @T6G_MB_LIB.T6G(SCH_1):GND    I15 @T6G_MB_LIB.T6G(SCH_1):PAGE32
  CM31    GND @T6G_MB_LIB.T6G(SCH_1):GND    I15 @T6G_MB_LIB.T6G(SCH_1):PAGE32
  CM32    GND @T6G_MB_LIB.T6G(SCH_1):GND    I15 @T6G_MB_LIB.T6G(SCH_1):PAGE32
  CM33    GND @T6G_MB_LIB.T6G(SCH_1):GND    I15 @T6G_MB_LIB.T6G(SCH_1):PAGE32
  CM44    GND @T6G_MB_LIB.T6G(SCH_1):GND    I15 @T6G_MB_LIB.T6G(SCH_1):PAGE32
  CM45    GND @T6G_MB_LIB.T6G(SCH_1):GND    I15 @T6G_MB_LIB.T6G(SCH_1):PAGE32
  CM46    GND @T6G_MB_LIB.T6G(SCH_1):GND    I15 @T6G_MB_LIB.T6G(SCH_1):PAGE32
  CM47    GND @T6G_MB_LIB.T6G(SCH_1):GND    I15 @T6G_MB_LIB.T6G(SCH_1):PAGE32
  CM48    GND @T6G_MB_LIB.T6G(SCH_1):GND    I15 @T6G_MB_LIB.T6G(SCH_1):PAGE32
  CM49    GND @T6G_MB_LIB.T6G(SCH_1):GND    I15 @T6G_MB_LIB.T6G(SCH_1):PAGE32
  CM51    GND @T6G_MB_LIB.T6G(SCH_1):GND    I15 @T6G_MB_LIB.T6G(SCH_1):PAGE32
  CM52    GND @T6G_MB_LIB.T6G(SCH_1):GND    I15 @T6G_MB_LIB.T6G(SCH_1):PAGE32
  CM53    GND @T6G_MB_LIB.T6G(SCH_1):GND    I15 @T6G_MB_LIB.T6G(SCH_1):PAGE32
  CM57    GND @T6G_MB_LIB.T6G(SCH_1):GND    I15 @T6G_MB_LIB.T6G(SCH_1):PAGE32
  CM59    GND @T6G_MB_LIB.T6G(SCH_1):GND    I15 @T6G_MB_LIB.T6G(SCH_1):PAGE32
  CM68    GND @T6G_MB_LIB.T6G(SCH_1):GND    I15 @T6G_MB_LIB.T6G(SCH_1):PAGE32
  CM71    GND @T6G_MB_LIB.T6G(SCH_1):GND    I15 @T6G_MB_LIB.T6G(SCH_1):PAGE32
  CM73    GND @T6G_MB_LIB.T6G(SCH_1):GND    I15 @T6G_MB_LIB.T6G(SCH_1):PAGE32
   CN1    GND @T6G_MB_LIB.T6G(SCH_1):GND    I15 @T6G_MB_LIB.T6G(SCH_1):PAGE32
   CN6    GND @T6G_MB_LIB.T6G(SCH_1):GND    I15 @T6G_MB_LIB.T6G(SCH_1):PAGE32
   CN8    GND @T6G_MB_LIB.T6G(SCH_1):GND    I15 @T6G_MB_LIB.T6G(SCH_1):PAGE32
  CN13    GND @T6G_MB_LIB.T6G(SCH_1):GND    I15 @T6G_MB_LIB.T6G(SCH_1):PAGE32
  CN15    GND @T6G_MB_LIB.T6G(SCH_1):GND    I15 @T6G_MB_LIB.T6G(SCH_1):PAGE32
  CN25    GND @T6G_MB_LIB.T6G(SCH_1):GND    I15 @T6G_MB_LIB.T6G(SCH_1):PAGE32
  CN28    GND @T6G_MB_LIB.T6G(SCH_1):GND    I15 @T6G_MB_LIB.T6G(SCH_1):PAGE32
  CN31    GND @T6G_MB_LIB.T6G(SCH_1):GND    I15 @T6G_MB_LIB.T6G(SCH_1):PAGE32
  CN34    GND @T6G_MB_LIB.T6G(SCH_1):GND    I15 @T6G_MB_LIB.T6G(SCH_1):PAGE32
  CN42    GND @T6G_MB_LIB.T6G(SCH_1):GND    I15 @T6G_MB_LIB.T6G(SCH_1):PAGE32
  CN45    GND @T6G_MB_LIB.T6G(SCH_1):GND    I15 @T6G_MB_LIB.T6G(SCH_1):PAGE32
  CN48    GND @T6G_MB_LIB.T6G(SCH_1):GND    I15 @T6G_MB_LIB.T6G(SCH_1):PAGE32
  CN51    GND @T6G_MB_LIB.T6G(SCH_1):GND    I15 @T6G_MB_LIB.T6G(SCH_1):PAGE32
  CN61    GND @T6G_MB_LIB.T6G(SCH_1):GND    I15 @T6G_MB_LIB.T6G(SCH_1):PAGE32
  CN63    GND @T6G_MB_LIB.T6G(SCH_1):GND    I15 @T6G_MB_LIB.T6G(SCH_1):PAGE32
  CN68    GND @T6G_MB_LIB.T6G(SCH_1):GND    I15 @T6G_MB_LIB.T6G(SCH_1):PAGE32
  CN70    GND @T6G_MB_LIB.T6G(SCH_1):GND    I15 @T6G_MB_LIB.T6G(SCH_1):PAGE32
  CN75    GND @T6G_MB_LIB.T6G(SCH_1):GND    I15 @T6G_MB_LIB.T6G(SCH_1):PAGE32
   CP3    GND @T6G_MB_LIB.T6G(SCH_1):GND    I15 @T6G_MB_LIB.T6G(SCH_1):PAGE32
   CP5    GND @T6G_MB_LIB.T6G(SCH_1):GND    I15 @T6G_MB_LIB.T6G(SCH_1):PAGE32
   CP8    GND @T6G_MB_LIB.T6G(SCH_1):GND    I15 @T6G_MB_LIB.T6G(SCH_1):PAGE32
  CP10    GND @T6G_MB_LIB.T6G(SCH_1):GND    I15 @T6G_MB_LIB.T6G(SCH_1):PAGE32
  CP12    GND @T6G_MB_LIB.T6G(SCH_1):GND    I15 @T6G_MB_LIB.T6G(SCH_1):PAGE32
  CP15    GND @T6G_MB_LIB.T6G(SCH_1):GND    I15 @T6G_MB_LIB.T6G(SCH_1):PAGE32
  CP17    GND @T6G_MB_LIB.T6G(SCH_1):GND    I15 @T6G_MB_LIB.T6G(SCH_1):PAGE32
  CP19    GND @T6G_MB_LIB.T6G(SCH_1):GND    I15 @T6G_MB_LIB.T6G(SCH_1):PAGE32
  CP22    GND @T6G_MB_LIB.T6G(SCH_1):GND    I16 @T6G_MB_LIB.T6G(SCH_1):PAGE32
  CP42    GND @T6G_MB_LIB.T6G(SCH_1):GND    I16 @T6G_MB_LIB.T6G(SCH_1):PAGE32
  CP45    GND @T6G_MB_LIB.T6G(SCH_1):GND    I16 @T6G_MB_LIB.T6G(SCH_1):PAGE32
  CP48    GND @T6G_MB_LIB.T6G(SCH_1):GND    I16 @T6G_MB_LIB.T6G(SCH_1):PAGE32
  CP51    GND @T6G_MB_LIB.T6G(SCH_1):GND    I16 @T6G_MB_LIB.T6G(SCH_1):PAGE32
  CP54    GND @T6G_MB_LIB.T6G(SCH_1):GND    I16 @T6G_MB_LIB.T6G(SCH_1):PAGE32
  CP71    GND @T6G_MB_LIB.T6G(SCH_1):GND    I16 @T6G_MB_LIB.T6G(SCH_1):PAGE32
  CP73    GND @T6G_MB_LIB.T6G(SCH_1):GND    I16 @T6G_MB_LIB.T6G(SCH_1):PAGE32
   CR1    GND @T6G_MB_LIB.T6G(SCH_1):GND    I16 @T6G_MB_LIB.T6G(SCH_1):PAGE32
   CR4    GND @T6G_MB_LIB.T6G(SCH_1):GND    I16 @T6G_MB_LIB.T6G(SCH_1):PAGE32
   CR6    GND @T6G_MB_LIB.T6G(SCH_1):GND    I16 @T6G_MB_LIB.T6G(SCH_1):PAGE32
  CR22    GND @T6G_MB_LIB.T6G(SCH_1):GND    I16 @T6G_MB_LIB.T6G(SCH_1):PAGE32
  CR25    GND @T6G_MB_LIB.T6G(SCH_1):GND    I16 @T6G_MB_LIB.T6G(SCH_1):PAGE32
  CR28    GND @T6G_MB_LIB.T6G(SCH_1):GND    I16 @T6G_MB_LIB.T6G(SCH_1):PAGE32
  CR31    GND @T6G_MB_LIB.T6G(SCH_1):GND    I16 @T6G_MB_LIB.T6G(SCH_1):PAGE32
  CR34    GND @T6G_MB_LIB.T6G(SCH_1):GND    I16 @T6G_MB_LIB.T6G(SCH_1):PAGE32
  CR48    GND @T6G_MB_LIB.T6G(SCH_1):GND    I16 @T6G_MB_LIB.T6G(SCH_1):PAGE32
  CR51    GND @T6G_MB_LIB.T6G(SCH_1):GND    I16 @T6G_MB_LIB.T6G(SCH_1):PAGE32
  CR54    GND @T6G_MB_LIB.T6G(SCH_1):GND    I16 @T6G_MB_LIB.T6G(SCH_1):PAGE32
  CR56    GND @T6G_MB_LIB.T6G(SCH_1):GND    I16 @T6G_MB_LIB.T6G(SCH_1):PAGE32
  CR58    GND @T6G_MB_LIB.T6G(SCH_1):GND    I16 @T6G_MB_LIB.T6G(SCH_1):PAGE32
  CR75    GND @T6G_MB_LIB.T6G(SCH_1):GND    I16 @T6G_MB_LIB.T6G(SCH_1):PAGE32
   CT3    GND @T6G_MB_LIB.T6G(SCH_1):GND    I16 @T6G_MB_LIB.T6G(SCH_1):PAGE32
   CT8    GND @T6G_MB_LIB.T6G(SCH_1):GND    I16 @T6G_MB_LIB.T6G(SCH_1):PAGE32
  CT10    GND @T6G_MB_LIB.T6G(SCH_1):GND    I16 @T6G_MB_LIB.T6G(SCH_1):PAGE32
  CT15    GND @T6G_MB_LIB.T6G(SCH_1):GND    I16 @T6G_MB_LIB.T6G(SCH_1):PAGE32
  CT48    GND @T6G_MB_LIB.T6G(SCH_1):GND    I16 @T6G_MB_LIB.T6G(SCH_1):PAGE32
  CT73    GND @T6G_MB_LIB.T6G(SCH_1):GND    I16 @T6G_MB_LIB.T6G(SCH_1):PAGE32
   CU1    GND @T6G_MB_LIB.T6G(SCH_1):GND    I16 @T6G_MB_LIB.T6G(SCH_1):PAGE32
  CU22    GND @T6G_MB_LIB.T6G(SCH_1):GND    I16 @T6G_MB_LIB.T6G(SCH_1):PAGE32
  CU25    GND @T6G_MB_LIB.T6G(SCH_1):GND    I16 @T6G_MB_LIB.T6G(SCH_1):PAGE32
  CU28    GND @T6G_MB_LIB.T6G(SCH_1):GND    I16 @T6G_MB_LIB.T6G(SCH_1):PAGE32
  CU56    GND @T6G_MB_LIB.T6G(SCH_1):GND    I16 @T6G_MB_LIB.T6G(SCH_1):PAGE32
  CU61    GND @T6G_MB_LIB.T6G(SCH_1):GND    I16 @T6G_MB_LIB.T6G(SCH_1):PAGE32
  CU63    GND @T6G_MB_LIB.T6G(SCH_1):GND    I16 @T6G_MB_LIB.T6G(SCH_1):PAGE32
   CV5    GND @T6G_MB_LIB.T6G(SCH_1):GND    I16 @T6G_MB_LIB.T6G(SCH_1):PAGE32
   CV8    GND @T6G_MB_LIB.T6G(SCH_1):GND    I16 @T6G_MB_LIB.T6G(SCH_1):PAGE32
  CV10    GND @T6G_MB_LIB.T6G(SCH_1):GND    I16 @T6G_MB_LIB.T6G(SCH_1):PAGE32
  CV12    GND @T6G_MB_LIB.T6G(SCH_1):GND    I16 @T6G_MB_LIB.T6G(SCH_1):PAGE32
  CV15    GND @T6G_MB_LIB.T6G(SCH_1):GND    I16 @T6G_MB_LIB.T6G(SCH_1):PAGE32
  CV34    GND @T6G_MB_LIB.T6G(SCH_1):GND    I16 @T6G_MB_LIB.T6G(SCH_1):PAGE32
  CV37    GND @T6G_MB_LIB.T6G(SCH_1):GND    I16 @T6G_MB_LIB.T6G(SCH_1):PAGE32
  CV39    GND @T6G_MB_LIB.T6G(SCH_1):GND    I16 @T6G_MB_LIB.T6G(SCH_1):PAGE32
  CV42    GND @T6G_MB_LIB.T6G(SCH_1):GND    I16 @T6G_MB_LIB.T6G(SCH_1):PAGE32
  CV45    GND @T6G_MB_LIB.T6G(SCH_1):GND    I16 @T6G_MB_LIB.T6G(SCH_1):PAGE32
  CV64    GND @T6G_MB_LIB.T6G(SCH_1):GND    I16 @T6G_MB_LIB.T6G(SCH_1):PAGE32
  CV66    GND @T6G_MB_LIB.T6G(SCH_1):GND    I16 @T6G_MB_LIB.T6G(SCH_1):PAGE32
  CV68    GND @T6G_MB_LIB.T6G(SCH_1):GND    I16 @T6G_MB_LIB.T6G(SCH_1):PAGE32
  CV71    GND @T6G_MB_LIB.T6G(SCH_1):GND    I16 @T6G_MB_LIB.T6G(SCH_1):PAGE32
  CV73    GND @T6G_MB_LIB.T6G(SCH_1):GND    I16 @T6G_MB_LIB.T6G(SCH_1):PAGE32
  CW22    GND @T6G_MB_LIB.T6G(SCH_1):GND    I16 @T6G_MB_LIB.T6G(SCH_1):PAGE32
  CW25    GND @T6G_MB_LIB.T6G(SCH_1):GND    I16 @T6G_MB_LIB.T6G(SCH_1):PAGE32
  CW28    GND @T6G_MB_LIB.T6G(SCH_1):GND    I16 @T6G_MB_LIB.T6G(SCH_1):PAGE32
  CW31    GND @T6G_MB_LIB.T6G(SCH_1):GND    I16 @T6G_MB_LIB.T6G(SCH_1):PAGE32
  CW34    GND @T6G_MB_LIB.T6G(SCH_1):GND    I16 @T6G_MB_LIB.T6G(SCH_1):PAGE32
  CY32    GND @T6G_MB_LIB.T6G(SCH_1):GND    I16 @T6G_MB_LIB.T6G(SCH_1):PAGE32
  CY47    GND @T6G_MB_LIB.T6G(SCH_1):GND    I16 @T6G_MB_LIB.T6G(SCH_1):PAGE32
  CY48    GND @T6G_MB_LIB.T6G(SCH_1):GND    I16 @T6G_MB_LIB.T6G(SCH_1):PAGE32
  CY64    GND @T6G_MB_LIB.T6G(SCH_1):GND    I16 @T6G_MB_LIB.T6G(SCH_1):PAGE32
  CY66    GND @T6G_MB_LIB.T6G(SCH_1):GND    I16 @T6G_MB_LIB.T6G(SCH_1):PAGE32
  CY68    GND @T6G_MB_LIB.T6G(SCH_1):GND    I16 @T6G_MB_LIB.T6G(SCH_1):PAGE32
  DA13    GND @T6G_MB_LIB.T6G(SCH_1):GND    I16 @T6G_MB_LIB.T6G(SCH_1):PAGE32
  DA15    GND @T6G_MB_LIB.T6G(SCH_1):GND    I16 @T6G_MB_LIB.T6G(SCH_1):PAGE32
  DA18    GND @T6G_MB_LIB.T6G(SCH_1):GND    I16 @T6G_MB_LIB.T6G(SCH_1):PAGE32
  DA20    GND @T6G_MB_LIB.T6G(SCH_1):GND    I16 @T6G_MB_LIB.T6G(SCH_1):PAGE32
  DA45    GND @T6G_MB_LIB.T6G(SCH_1):GND    I16 @T6G_MB_LIB.T6G(SCH_1):PAGE32
  DA48    GND @T6G_MB_LIB.T6G(SCH_1):GND    I16 @T6G_MB_LIB.T6G(SCH_1):PAGE32
  DA51    GND @T6G_MB_LIB.T6G(SCH_1):GND    I16 @T6G_MB_LIB.T6G(SCH_1):PAGE32
  DA54    GND @T6G_MB_LIB.T6G(SCH_1):GND    I16 @T6G_MB_LIB.T6G(SCH_1):PAGE32
  CP25    GND @T6G_MB_LIB.T6G(SCH_1):GND    I16 @T6G_MB_LIB.T6G(SCH_1):PAGE32
  CP28    GND @T6G_MB_LIB.T6G(SCH_1):GND    I16 @T6G_MB_LIB.T6G(SCH_1):PAGE32
  CP31    GND @T6G_MB_LIB.T6G(SCH_1):GND    I16 @T6G_MB_LIB.T6G(SCH_1):PAGE32
  CP34    GND @T6G_MB_LIB.T6G(SCH_1):GND    I16 @T6G_MB_LIB.T6G(SCH_1):PAGE32
  CP37    GND @T6G_MB_LIB.T6G(SCH_1):GND    I16 @T6G_MB_LIB.T6G(SCH_1):PAGE32
  CP39    GND @T6G_MB_LIB.T6G(SCH_1):GND    I16 @T6G_MB_LIB.T6G(SCH_1):PAGE32
  CP57    GND @T6G_MB_LIB.T6G(SCH_1):GND    I16 @T6G_MB_LIB.T6G(SCH_1):PAGE32
  CP59    GND @T6G_MB_LIB.T6G(SCH_1):GND    I16 @T6G_MB_LIB.T6G(SCH_1):PAGE32
  CP61    GND @T6G_MB_LIB.T6G(SCH_1):GND    I16 @T6G_MB_LIB.T6G(SCH_1):PAGE32
  CP64    GND @T6G_MB_LIB.T6G(SCH_1):GND    I16 @T6G_MB_LIB.T6G(SCH_1):PAGE32
  CP66    GND @T6G_MB_LIB.T6G(SCH_1):GND    I16 @T6G_MB_LIB.T6G(SCH_1):PAGE32
  CP68    GND @T6G_MB_LIB.T6G(SCH_1):GND    I16 @T6G_MB_LIB.T6G(SCH_1):PAGE32
   CR8    GND @T6G_MB_LIB.T6G(SCH_1):GND    I16 @T6G_MB_LIB.T6G(SCH_1):PAGE32
  CR11    GND @T6G_MB_LIB.T6G(SCH_1):GND    I16 @T6G_MB_LIB.T6G(SCH_1):PAGE32
  CR13    GND @T6G_MB_LIB.T6G(SCH_1):GND    I16 @T6G_MB_LIB.T6G(SCH_1):PAGE32
  CR15    GND @T6G_MB_LIB.T6G(SCH_1):GND    I16 @T6G_MB_LIB.T6G(SCH_1):PAGE32
  CR18    GND @T6G_MB_LIB.T6G(SCH_1):GND    I16 @T6G_MB_LIB.T6G(SCH_1):PAGE32
  CR20    GND @T6G_MB_LIB.T6G(SCH_1):GND    I16 @T6G_MB_LIB.T6G(SCH_1):PAGE32
  CR35    GND @T6G_MB_LIB.T6G(SCH_1):GND    I16 @T6G_MB_LIB.T6G(SCH_1):PAGE32
  CR36    GND @T6G_MB_LIB.T6G(SCH_1):GND    I16 @T6G_MB_LIB.T6G(SCH_1):PAGE32
  CR40    GND @T6G_MB_LIB.T6G(SCH_1):GND    I16 @T6G_MB_LIB.T6G(SCH_1):PAGE32
  CR41    GND @T6G_MB_LIB.T6G(SCH_1):GND    I16 @T6G_MB_LIB.T6G(SCH_1):PAGE32
  CR42    GND @T6G_MB_LIB.T6G(SCH_1):GND    I16 @T6G_MB_LIB.T6G(SCH_1):PAGE32
  CR45    GND @T6G_MB_LIB.T6G(SCH_1):GND    I16 @T6G_MB_LIB.T6G(SCH_1):PAGE32
  CR61    GND @T6G_MB_LIB.T6G(SCH_1):GND    I16 @T6G_MB_LIB.T6G(SCH_1):PAGE32
  CR63    GND @T6G_MB_LIB.T6G(SCH_1):GND    I16 @T6G_MB_LIB.T6G(SCH_1):PAGE32
  CR65    GND @T6G_MB_LIB.T6G(SCH_1):GND    I16 @T6G_MB_LIB.T6G(SCH_1):PAGE32
  CR68    GND @T6G_MB_LIB.T6G(SCH_1):GND    I16 @T6G_MB_LIB.T6G(SCH_1):PAGE32
  CR70    GND @T6G_MB_LIB.T6G(SCH_1):GND    I16 @T6G_MB_LIB.T6G(SCH_1):PAGE32
  CR72    GND @T6G_MB_LIB.T6G(SCH_1):GND    I16 @T6G_MB_LIB.T6G(SCH_1):PAGE32
  CT17    GND @T6G_MB_LIB.T6G(SCH_1):GND    I16 @T6G_MB_LIB.T6G(SCH_1):PAGE32
  CT23    GND @T6G_MB_LIB.T6G(SCH_1):GND    I16 @T6G_MB_LIB.T6G(SCH_1):PAGE32
  CT24    GND @T6G_MB_LIB.T6G(SCH_1):GND    I16 @T6G_MB_LIB.T6G(SCH_1):PAGE32
  CT25    GND @T6G_MB_LIB.T6G(SCH_1):GND    I16 @T6G_MB_LIB.T6G(SCH_1):PAGE32
  CT26    GND @T6G_MB_LIB.T6G(SCH_1):GND    I16 @T6G_MB_LIB.T6G(SCH_1):PAGE32
  CT27    GND @T6G_MB_LIB.T6G(SCH_1):GND    I16 @T6G_MB_LIB.T6G(SCH_1):PAGE32
  CT28    GND @T6G_MB_LIB.T6G(SCH_1):GND    I16 @T6G_MB_LIB.T6G(SCH_1):PAGE32
  CT29    GND @T6G_MB_LIB.T6G(SCH_1):GND    I16 @T6G_MB_LIB.T6G(SCH_1):PAGE32
  CT30    GND @T6G_MB_LIB.T6G(SCH_1):GND    I16 @T6G_MB_LIB.T6G(SCH_1):PAGE32
  CT31    GND @T6G_MB_LIB.T6G(SCH_1):GND    I16 @T6G_MB_LIB.T6G(SCH_1):PAGE32
  CT32    GND @T6G_MB_LIB.T6G(SCH_1):GND    I16 @T6G_MB_LIB.T6G(SCH_1):PAGE32
  CT33    GND @T6G_MB_LIB.T6G(SCH_1):GND    I16 @T6G_MB_LIB.T6G(SCH_1):PAGE32
  CT34    GND @T6G_MB_LIB.T6G(SCH_1):GND    I16 @T6G_MB_LIB.T6G(SCH_1):PAGE32
  CT37    GND @T6G_MB_LIB.T6G(SCH_1):GND    I16 @T6G_MB_LIB.T6G(SCH_1):PAGE32
  CT39    GND @T6G_MB_LIB.T6G(SCH_1):GND    I16 @T6G_MB_LIB.T6G(SCH_1):PAGE32
  CT42    GND @T6G_MB_LIB.T6G(SCH_1):GND    I16 @T6G_MB_LIB.T6G(SCH_1):PAGE32
  CT43    GND @T6G_MB_LIB.T6G(SCH_1):GND    I16 @T6G_MB_LIB.T6G(SCH_1):PAGE32
  CT44    GND @T6G_MB_LIB.T6G(SCH_1):GND    I16 @T6G_MB_LIB.T6G(SCH_1):PAGE32
  CT45    GND @T6G_MB_LIB.T6G(SCH_1):GND    I16 @T6G_MB_LIB.T6G(SCH_1):PAGE32
  CT46    GND @T6G_MB_LIB.T6G(SCH_1):GND    I16 @T6G_MB_LIB.T6G(SCH_1):PAGE32
  CT47    GND @T6G_MB_LIB.T6G(SCH_1):GND    I16 @T6G_MB_LIB.T6G(SCH_1):PAGE32
  CT49    GND @T6G_MB_LIB.T6G(SCH_1):GND    I16 @T6G_MB_LIB.T6G(SCH_1):PAGE32
  CT50    GND @T6G_MB_LIB.T6G(SCH_1):GND    I16 @T6G_MB_LIB.T6G(SCH_1):PAGE32
  CT51    GND @T6G_MB_LIB.T6G(SCH_1):GND    I16 @T6G_MB_LIB.T6G(SCH_1):PAGE32
  CT53    GND @T6G_MB_LIB.T6G(SCH_1):GND    I16 @T6G_MB_LIB.T6G(SCH_1):PAGE32
  CT59    GND @T6G_MB_LIB.T6G(SCH_1):GND    I16 @T6G_MB_LIB.T6G(SCH_1):PAGE32
  CT61    GND @T6G_MB_LIB.T6G(SCH_1):GND    I16 @T6G_MB_LIB.T6G(SCH_1):PAGE32
  CT66    GND @T6G_MB_LIB.T6G(SCH_1):GND    I16 @T6G_MB_LIB.T6G(SCH_1):PAGE32
  CT68    GND @T6G_MB_LIB.T6G(SCH_1):GND    I16 @T6G_MB_LIB.T6G(SCH_1):PAGE32
   CU4    GND @T6G_MB_LIB.T6G(SCH_1):GND    I16 @T6G_MB_LIB.T6G(SCH_1):PAGE32
   CU6    GND @T6G_MB_LIB.T6G(SCH_1):GND    I16 @T6G_MB_LIB.T6G(SCH_1):PAGE32
   CU8    GND @T6G_MB_LIB.T6G(SCH_1):GND    I16 @T6G_MB_LIB.T6G(SCH_1):PAGE32
  CU11    GND @T6G_MB_LIB.T6G(SCH_1):GND    I16 @T6G_MB_LIB.T6G(SCH_1):PAGE32
  CU13    GND @T6G_MB_LIB.T6G(SCH_1):GND    I16 @T6G_MB_LIB.T6G(SCH_1):PAGE32
  CU15    GND @T6G_MB_LIB.T6G(SCH_1):GND    I16 @T6G_MB_LIB.T6G(SCH_1):PAGE32
  CU18    GND @T6G_MB_LIB.T6G(SCH_1):GND    I16 @T6G_MB_LIB.T6G(SCH_1):PAGE32
  CU20    GND @T6G_MB_LIB.T6G(SCH_1):GND    I16 @T6G_MB_LIB.T6G(SCH_1):PAGE32
  CU31    GND @T6G_MB_LIB.T6G(SCH_1):GND    I16 @T6G_MB_LIB.T6G(SCH_1):PAGE32
  CU34    GND @T6G_MB_LIB.T6G(SCH_1):GND    I16 @T6G_MB_LIB.T6G(SCH_1):PAGE32
  CU42    GND @T6G_MB_LIB.T6G(SCH_1):GND    I16 @T6G_MB_LIB.T6G(SCH_1):PAGE32
  CU45    GND @T6G_MB_LIB.T6G(SCH_1):GND    I16 @T6G_MB_LIB.T6G(SCH_1):PAGE32
  CU48    GND @T6G_MB_LIB.T6G(SCH_1):GND    I16 @T6G_MB_LIB.T6G(SCH_1):PAGE32
  CU51    GND @T6G_MB_LIB.T6G(SCH_1):GND    I16 @T6G_MB_LIB.T6G(SCH_1):PAGE32
  CU54    GND @T6G_MB_LIB.T6G(SCH_1):GND    I16 @T6G_MB_LIB.T6G(SCH_1):PAGE32
  CU65    GND @T6G_MB_LIB.T6G(SCH_1):GND    I16 @T6G_MB_LIB.T6G(SCH_1):PAGE32
  CU68    GND @T6G_MB_LIB.T6G(SCH_1):GND    I16 @T6G_MB_LIB.T6G(SCH_1):PAGE32
  CU70    GND @T6G_MB_LIB.T6G(SCH_1):GND    I16 @T6G_MB_LIB.T6G(SCH_1):PAGE32
  CU72    GND @T6G_MB_LIB.T6G(SCH_1):GND    I16 @T6G_MB_LIB.T6G(SCH_1):PAGE32
  CU75    GND @T6G_MB_LIB.T6G(SCH_1):GND    I16 @T6G_MB_LIB.T6G(SCH_1):PAGE32
   CV3    GND @T6G_MB_LIB.T6G(SCH_1):GND    I16 @T6G_MB_LIB.T6G(SCH_1):PAGE32
  CV17    GND @T6G_MB_LIB.T6G(SCH_1):GND    I16 @T6G_MB_LIB.T6G(SCH_1):PAGE32
  CV19    GND @T6G_MB_LIB.T6G(SCH_1):GND    I16 @T6G_MB_LIB.T6G(SCH_1):PAGE32
  CV22    GND @T6G_MB_LIB.T6G(SCH_1):GND    I16 @T6G_MB_LIB.T6G(SCH_1):PAGE32
  CV25    GND @T6G_MB_LIB.T6G(SCH_1):GND    I16 @T6G_MB_LIB.T6G(SCH_1):PAGE32
  CV28    GND @T6G_MB_LIB.T6G(SCH_1):GND    I16 @T6G_MB_LIB.T6G(SCH_1):PAGE32
  CV31    GND @T6G_MB_LIB.T6G(SCH_1):GND    I16 @T6G_MB_LIB.T6G(SCH_1):PAGE32
  CV48    GND @T6G_MB_LIB.T6G(SCH_1):GND    I16 @T6G_MB_LIB.T6G(SCH_1):PAGE32
  CV51    GND @T6G_MB_LIB.T6G(SCH_1):GND    I16 @T6G_MB_LIB.T6G(SCH_1):PAGE32
  CV54    GND @T6G_MB_LIB.T6G(SCH_1):GND    I16 @T6G_MB_LIB.T6G(SCH_1):PAGE32
  CV57    GND @T6G_MB_LIB.T6G(SCH_1):GND    I16 @T6G_MB_LIB.T6G(SCH_1):PAGE32
  CV59    GND @T6G_MB_LIB.T6G(SCH_1):GND    I16 @T6G_MB_LIB.T6G(SCH_1):PAGE32
  CV61    GND @T6G_MB_LIB.T6G(SCH_1):GND    I16 @T6G_MB_LIB.T6G(SCH_1):PAGE32
   CW1    GND @T6G_MB_LIB.T6G(SCH_1):GND    I16 @T6G_MB_LIB.T6G(SCH_1):PAGE32
   CW6    GND @T6G_MB_LIB.T6G(SCH_1):GND    I16 @T6G_MB_LIB.T6G(SCH_1):PAGE32
   CW8    GND @T6G_MB_LIB.T6G(SCH_1):GND    I16 @T6G_MB_LIB.T6G(SCH_1):PAGE32
  CW13    GND @T6G_MB_LIB.T6G(SCH_1):GND    I16 @T6G_MB_LIB.T6G(SCH_1):PAGE32
  CW15    GND @T6G_MB_LIB.T6G(SCH_1):GND    I16 @T6G_MB_LIB.T6G(SCH_1):PAGE32
  CW20    GND @T6G_MB_LIB.T6G(SCH_1):GND    I16 @T6G_MB_LIB.T6G(SCH_1):PAGE32
  CW35    GND @T6G_MB_LIB.T6G(SCH_1):GND    I16 @T6G_MB_LIB.T6G(SCH_1):PAGE32
  CW36    GND @T6G_MB_LIB.T6G(SCH_1):GND    I16 @T6G_MB_LIB.T6G(SCH_1):PAGE32
  CW40    GND @T6G_MB_LIB.T6G(SCH_1):GND    I16 @T6G_MB_LIB.T6G(SCH_1):PAGE32
  CW41    GND @T6G_MB_LIB.T6G(SCH_1):GND    I16 @T6G_MB_LIB.T6G(SCH_1):PAGE32
  CW42    GND @T6G_MB_LIB.T6G(SCH_1):GND    I16 @T6G_MB_LIB.T6G(SCH_1):PAGE32
  CW45    GND @T6G_MB_LIB.T6G(SCH_1):GND    I16 @T6G_MB_LIB.T6G(SCH_1):PAGE32
  CW48    GND @T6G_MB_LIB.T6G(SCH_1):GND    I16 @T6G_MB_LIB.T6G(SCH_1):PAGE32
  CW51    GND @T6G_MB_LIB.T6G(SCH_1):GND    I16 @T6G_MB_LIB.T6G(SCH_1):PAGE32
  CW54    GND @T6G_MB_LIB.T6G(SCH_1):GND    I16 @T6G_MB_LIB.T6G(SCH_1):PAGE32
  CW56    GND @T6G_MB_LIB.T6G(SCH_1):GND    I16 @T6G_MB_LIB.T6G(SCH_1):PAGE32
  CW61    GND @T6G_MB_LIB.T6G(SCH_1):GND    I16 @T6G_MB_LIB.T6G(SCH_1):PAGE32
  CW63    GND @T6G_MB_LIB.T6G(SCH_1):GND    I16 @T6G_MB_LIB.T6G(SCH_1):PAGE32
  CW68    GND @T6G_MB_LIB.T6G(SCH_1):GND    I16 @T6G_MB_LIB.T6G(SCH_1):PAGE32
  CW70    GND @T6G_MB_LIB.T6G(SCH_1):GND    I16 @T6G_MB_LIB.T6G(SCH_1):PAGE32
  CW75    GND @T6G_MB_LIB.T6G(SCH_1):GND    I16 @T6G_MB_LIB.T6G(SCH_1):PAGE32
   CY3    GND @T6G_MB_LIB.T6G(SCH_1):GND    I16 @T6G_MB_LIB.T6G(SCH_1):PAGE32
   CY5    GND @T6G_MB_LIB.T6G(SCH_1):GND    I16 @T6G_MB_LIB.T6G(SCH_1):PAGE32
   CY8    GND @T6G_MB_LIB.T6G(SCH_1):GND    I16 @T6G_MB_LIB.T6G(SCH_1):PAGE32
  CY10    GND @T6G_MB_LIB.T6G(SCH_1):GND    I16 @T6G_MB_LIB.T6G(SCH_1):PAGE32
  CY12    GND @T6G_MB_LIB.T6G(SCH_1):GND    I16 @T6G_MB_LIB.T6G(SCH_1):PAGE32
  CY15    GND @T6G_MB_LIB.T6G(SCH_1):GND    I16 @T6G_MB_LIB.T6G(SCH_1):PAGE32
  CY17    GND @T6G_MB_LIB.T6G(SCH_1):GND    I16 @T6G_MB_LIB.T6G(SCH_1):PAGE32
  CY19    GND @T6G_MB_LIB.T6G(SCH_1):GND    I16 @T6G_MB_LIB.T6G(SCH_1):PAGE32
  CY23    GND @T6G_MB_LIB.T6G(SCH_1):GND    I16 @T6G_MB_LIB.T6G(SCH_1):PAGE32
  CY24    GND @T6G_MB_LIB.T6G(SCH_1):GND    I16 @T6G_MB_LIB.T6G(SCH_1):PAGE32
  CY25    GND @T6G_MB_LIB.T6G(SCH_1):GND    I16 @T6G_MB_LIB.T6G(SCH_1):PAGE32
  CY26    GND @T6G_MB_LIB.T6G(SCH_1):GND    I16 @T6G_MB_LIB.T6G(SCH_1):PAGE32
  CY27    GND @T6G_MB_LIB.T6G(SCH_1):GND    I16 @T6G_MB_LIB.T6G(SCH_1):PAGE32
  CY28    GND @T6G_MB_LIB.T6G(SCH_1):GND    I16 @T6G_MB_LIB.T6G(SCH_1):PAGE32
  CY29    GND @T6G_MB_LIB.T6G(SCH_1):GND    I16 @T6G_MB_LIB.T6G(SCH_1):PAGE32
  CY30    GND @T6G_MB_LIB.T6G(SCH_1):GND    I16 @T6G_MB_LIB.T6G(SCH_1):PAGE32
  CY31    GND @T6G_MB_LIB.T6G(SCH_1):GND    I16 @T6G_MB_LIB.T6G(SCH_1):PAGE32
  CY33    GND @T6G_MB_LIB.T6G(SCH_1):GND    I16 @T6G_MB_LIB.T6G(SCH_1):PAGE32
  CY34    GND @T6G_MB_LIB.T6G(SCH_1):GND    I16 @T6G_MB_LIB.T6G(SCH_1):PAGE32
  CY37    GND @T6G_MB_LIB.T6G(SCH_1):GND    I16 @T6G_MB_LIB.T6G(SCH_1):PAGE32
  CY39    GND @T6G_MB_LIB.T6G(SCH_1):GND    I16 @T6G_MB_LIB.T6G(SCH_1):PAGE32
  CY42    GND @T6G_MB_LIB.T6G(SCH_1):GND    I16 @T6G_MB_LIB.T6G(SCH_1):PAGE32
  CY43    GND @T6G_MB_LIB.T6G(SCH_1):GND    I16 @T6G_MB_LIB.T6G(SCH_1):PAGE32
  CY44    GND @T6G_MB_LIB.T6G(SCH_1):GND    I16 @T6G_MB_LIB.T6G(SCH_1):PAGE32
  CY45    GND @T6G_MB_LIB.T6G(SCH_1):GND    I16 @T6G_MB_LIB.T6G(SCH_1):PAGE32
  CY46    GND @T6G_MB_LIB.T6G(SCH_1):GND    I16 @T6G_MB_LIB.T6G(SCH_1):PAGE32
  CY49    GND @T6G_MB_LIB.T6G(SCH_1):GND    I16 @T6G_MB_LIB.T6G(SCH_1):PAGE32
  CY50    GND @T6G_MB_LIB.T6G(SCH_1):GND    I16 @T6G_MB_LIB.T6G(SCH_1):PAGE32
  CY51    GND @T6G_MB_LIB.T6G(SCH_1):GND    I16 @T6G_MB_LIB.T6G(SCH_1):PAGE32
  CY52    GND @T6G_MB_LIB.T6G(SCH_1):GND    I16 @T6G_MB_LIB.T6G(SCH_1):PAGE32
  CY53    GND @T6G_MB_LIB.T6G(SCH_1):GND    I16 @T6G_MB_LIB.T6G(SCH_1):PAGE32
  CY59    GND @T6G_MB_LIB.T6G(SCH_1):GND    I16 @T6G_MB_LIB.T6G(SCH_1):PAGE32
  CY61    GND @T6G_MB_LIB.T6G(SCH_1):GND    I16 @T6G_MB_LIB.T6G(SCH_1):PAGE32
  CY71    GND @T6G_MB_LIB.T6G(SCH_1):GND    I16 @T6G_MB_LIB.T6G(SCH_1):PAGE32
  CY73    GND @T6G_MB_LIB.T6G(SCH_1):GND    I16 @T6G_MB_LIB.T6G(SCH_1):PAGE32
   DA1    GND @T6G_MB_LIB.T6G(SCH_1):GND    I16 @T6G_MB_LIB.T6G(SCH_1):PAGE32
   DA4    GND @T6G_MB_LIB.T6G(SCH_1):GND    I16 @T6G_MB_LIB.T6G(SCH_1):PAGE32
   DA6    GND @T6G_MB_LIB.T6G(SCH_1):GND    I16 @T6G_MB_LIB.T6G(SCH_1):PAGE32
   DA8    GND @T6G_MB_LIB.T6G(SCH_1):GND    I16 @T6G_MB_LIB.T6G(SCH_1):PAGE32
  DA11    GND @T6G_MB_LIB.T6G(SCH_1):GND    I16 @T6G_MB_LIB.T6G(SCH_1):PAGE32
  DA22    GND @T6G_MB_LIB.T6G(SCH_1):GND    I16 @T6G_MB_LIB.T6G(SCH_1):PAGE32
  DA25    GND @T6G_MB_LIB.T6G(SCH_1):GND    I16 @T6G_MB_LIB.T6G(SCH_1):PAGE32
  DA28    GND @T6G_MB_LIB.T6G(SCH_1):GND    I16 @T6G_MB_LIB.T6G(SCH_1):PAGE32
  DA31    GND @T6G_MB_LIB.T6G(SCH_1):GND    I16 @T6G_MB_LIB.T6G(SCH_1):PAGE32
  DA34    GND @T6G_MB_LIB.T6G(SCH_1):GND    I16 @T6G_MB_LIB.T6G(SCH_1):PAGE32
  DA42    GND @T6G_MB_LIB.T6G(SCH_1):GND    I16 @T6G_MB_LIB.T6G(SCH_1):PAGE32
  DA58    GND @T6G_MB_LIB.T6G(SCH_1):GND    I16 @T6G_MB_LIB.T6G(SCH_1):PAGE32
  DA61    GND @T6G_MB_LIB.T6G(SCH_1):GND    I16 @T6G_MB_LIB.T6G(SCH_1):PAGE32
  DA63    GND @T6G_MB_LIB.T6G(SCH_1):GND    I16 @T6G_MB_LIB.T6G(SCH_1):PAGE32
  DA65    GND @T6G_MB_LIB.T6G(SCH_1):GND    I16 @T6G_MB_LIB.T6G(SCH_1):PAGE32
  DA68    GND @T6G_MB_LIB.T6G(SCH_1):GND    I16 @T6G_MB_LIB.T6G(SCH_1):PAGE32
  DA70    GND @T6G_MB_LIB.T6G(SCH_1):GND    I16 @T6G_MB_LIB.T6G(SCH_1):PAGE32
  DB15    GND @T6G_MB_LIB.T6G(SCH_1):GND     I4 @T6G_MB_LIB.T6G(SCH_1):PAGE33
  DB17    GND @T6G_MB_LIB.T6G(SCH_1):GND     I4 @T6G_MB_LIB.T6G(SCH_1):PAGE33
  DB22    GND @T6G_MB_LIB.T6G(SCH_1):GND     I4 @T6G_MB_LIB.T6G(SCH_1):PAGE33
  DB25    GND @T6G_MB_LIB.T6G(SCH_1):GND     I4 @T6G_MB_LIB.T6G(SCH_1):PAGE33
  DB48    GND @T6G_MB_LIB.T6G(SCH_1):GND     I4 @T6G_MB_LIB.T6G(SCH_1):PAGE33
  DB51    GND @T6G_MB_LIB.T6G(SCH_1):GND     I4 @T6G_MB_LIB.T6G(SCH_1):PAGE33
  DB54    GND @T6G_MB_LIB.T6G(SCH_1):GND     I4 @T6G_MB_LIB.T6G(SCH_1):PAGE33
  DB59    GND @T6G_MB_LIB.T6G(SCH_1):GND     I4 @T6G_MB_LIB.T6G(SCH_1):PAGE33
  DC13    GND @T6G_MB_LIB.T6G(SCH_1):GND     I4 @T6G_MB_LIB.T6G(SCH_1):PAGE33
  DC15    GND @T6G_MB_LIB.T6G(SCH_1):GND     I4 @T6G_MB_LIB.T6G(SCH_1):PAGE33
  DC45    GND @T6G_MB_LIB.T6G(SCH_1):GND     I4 @T6G_MB_LIB.T6G(SCH_1):PAGE33
  DC48    GND @T6G_MB_LIB.T6G(SCH_1):GND     I4 @T6G_MB_LIB.T6G(SCH_1):PAGE33
  DC51    GND @T6G_MB_LIB.T6G(SCH_1):GND     I4 @T6G_MB_LIB.T6G(SCH_1):PAGE33
  DC70    GND @T6G_MB_LIB.T6G(SCH_1):GND     I4 @T6G_MB_LIB.T6G(SCH_1):PAGE33
  DC72    GND @T6G_MB_LIB.T6G(SCH_1):GND     I4 @T6G_MB_LIB.T6G(SCH_1):PAGE33
  DC75    GND @T6G_MB_LIB.T6G(SCH_1):GND     I4 @T6G_MB_LIB.T6G(SCH_1):PAGE33
   DD3    GND @T6G_MB_LIB.T6G(SCH_1):GND     I4 @T6G_MB_LIB.T6G(SCH_1):PAGE33
  DD23    GND @T6G_MB_LIB.T6G(SCH_1):GND     I4 @T6G_MB_LIB.T6G(SCH_1):PAGE33
  DD24    GND @T6G_MB_LIB.T6G(SCH_1):GND     I4 @T6G_MB_LIB.T6G(SCH_1):PAGE33
  DD26    GND @T6G_MB_LIB.T6G(SCH_1):GND     I4 @T6G_MB_LIB.T6G(SCH_1):PAGE33
  DD27    GND @T6G_MB_LIB.T6G(SCH_1):GND     I4 @T6G_MB_LIB.T6G(SCH_1):PAGE33
  DD39    GND @T6G_MB_LIB.T6G(SCH_1):GND     I4 @T6G_MB_LIB.T6G(SCH_1):PAGE33
  DD40    GND @T6G_MB_LIB.T6G(SCH_1):GND     I4 @T6G_MB_LIB.T6G(SCH_1):PAGE33
  DD41    GND @T6G_MB_LIB.T6G(SCH_1):GND     I4 @T6G_MB_LIB.T6G(SCH_1):PAGE33
  DD43    GND @T6G_MB_LIB.T6G(SCH_1):GND     I4 @T6G_MB_LIB.T6G(SCH_1):PAGE33
  DD57    GND @T6G_MB_LIB.T6G(SCH_1):GND     I4 @T6G_MB_LIB.T6G(SCH_1):PAGE33
  DD59    GND @T6G_MB_LIB.T6G(SCH_1):GND     I4 @T6G_MB_LIB.T6G(SCH_1):PAGE33
  DD61    GND @T6G_MB_LIB.T6G(SCH_1):GND     I4 @T6G_MB_LIB.T6G(SCH_1):PAGE33
  DD64    GND @T6G_MB_LIB.T6G(SCH_1):GND     I4 @T6G_MB_LIB.T6G(SCH_1):PAGE33
  DE13    GND @T6G_MB_LIB.T6G(SCH_1):GND     I4 @T6G_MB_LIB.T6G(SCH_1):PAGE33
  DE15    GND @T6G_MB_LIB.T6G(SCH_1):GND     I4 @T6G_MB_LIB.T6G(SCH_1):PAGE33
  DE20    GND @T6G_MB_LIB.T6G(SCH_1):GND     I4 @T6G_MB_LIB.T6G(SCH_1):PAGE33
  DE23    GND @T6G_MB_LIB.T6G(SCH_1):GND     I4 @T6G_MB_LIB.T6G(SCH_1):PAGE33
  DE70    GND @T6G_MB_LIB.T6G(SCH_1):GND     I4 @T6G_MB_LIB.T6G(SCH_1):PAGE33
  DE75    GND @T6G_MB_LIB.T6G(SCH_1):GND     I4 @T6G_MB_LIB.T6G(SCH_1):PAGE33
   DF3    GND @T6G_MB_LIB.T6G(SCH_1):GND     I4 @T6G_MB_LIB.T6G(SCH_1):PAGE33
   DF4    GND @T6G_MB_LIB.T6G(SCH_1):GND     I4 @T6G_MB_LIB.T6G(SCH_1):PAGE33
  DF15    GND @T6G_MB_LIB.T6G(SCH_1):GND     I4 @T6G_MB_LIB.T6G(SCH_1):PAGE33
  DF17    GND @T6G_MB_LIB.T6G(SCH_1):GND     I4 @T6G_MB_LIB.T6G(SCH_1):PAGE33
  DF18    GND @T6G_MB_LIB.T6G(SCH_1):GND     I4 @T6G_MB_LIB.T6G(SCH_1):PAGE33
  DF19    GND @T6G_MB_LIB.T6G(SCH_1):GND     I4 @T6G_MB_LIB.T6G(SCH_1):PAGE33
  DF43    GND @T6G_MB_LIB.T6G(SCH_1):GND     I4 @T6G_MB_LIB.T6G(SCH_1):PAGE33
  DF53    GND @T6G_MB_LIB.T6G(SCH_1):GND     I4 @T6G_MB_LIB.T6G(SCH_1):PAGE33
  DF54    GND @T6G_MB_LIB.T6G(SCH_1):GND     I4 @T6G_MB_LIB.T6G(SCH_1):PAGE33
  DF66    GND @T6G_MB_LIB.T6G(SCH_1):GND     I4 @T6G_MB_LIB.T6G(SCH_1):PAGE33
  DF68    GND @T6G_MB_LIB.T6G(SCH_1):GND     I4 @T6G_MB_LIB.T6G(SCH_1):PAGE33
  DF70    GND @T6G_MB_LIB.T6G(SCH_1):GND     I4 @T6G_MB_LIB.T6G(SCH_1):PAGE33
   DG8    GND @T6G_MB_LIB.T6G(SCH_1):GND     I4 @T6G_MB_LIB.T6G(SCH_1):PAGE33
   DG9    GND @T6G_MB_LIB.T6G(SCH_1):GND     I4 @T6G_MB_LIB.T6G(SCH_1):PAGE33
  DG13    GND @T6G_MB_LIB.T6G(SCH_1):GND     I4 @T6G_MB_LIB.T6G(SCH_1):PAGE33
  DG14    GND @T6G_MB_LIB.T6G(SCH_1):GND     I4 @T6G_MB_LIB.T6G(SCH_1):PAGE33
  DG30    GND @T6G_MB_LIB.T6G(SCH_1):GND     I4 @T6G_MB_LIB.T6G(SCH_1):PAGE33
  DG33    GND @T6G_MB_LIB.T6G(SCH_1):GND     I4 @T6G_MB_LIB.T6G(SCH_1):PAGE33
  DG41    GND @T6G_MB_LIB.T6G(SCH_1):GND     I4 @T6G_MB_LIB.T6G(SCH_1):PAGE33
  DG43    GND @T6G_MB_LIB.T6G(SCH_1):GND     I4 @T6G_MB_LIB.T6G(SCH_1):PAGE33
  DG61    GND @T6G_MB_LIB.T6G(SCH_1):GND     I4 @T6G_MB_LIB.T6G(SCH_1):PAGE33
  DG62    GND @T6G_MB_LIB.T6G(SCH_1):GND     I4 @T6G_MB_LIB.T6G(SCH_1):PAGE33
  DG63    GND @T6G_MB_LIB.T6G(SCH_1):GND     I4 @T6G_MB_LIB.T6G(SCH_1):PAGE33
  DG65    GND @T6G_MB_LIB.T6G(SCH_1):GND     I4 @T6G_MB_LIB.T6G(SCH_1):PAGE33
   DH5    GND @T6G_MB_LIB.T6G(SCH_1):GND     I4 @T6G_MB_LIB.T6G(SCH_1):PAGE33
  DH11    GND @T6G_MB_LIB.T6G(SCH_1):GND     I4 @T6G_MB_LIB.T6G(SCH_1):PAGE33
  DH18    GND @T6G_MB_LIB.T6G(SCH_1):GND     I4 @T6G_MB_LIB.T6G(SCH_1):PAGE33
  DH37    GND @T6G_MB_LIB.T6G(SCH_1):GND     I4 @T6G_MB_LIB.T6G(SCH_1):PAGE33
  DH61    GND @T6G_MB_LIB.T6G(SCH_1):GND     I4 @T6G_MB_LIB.T6G(SCH_1):PAGE33
  DH63    GND @T6G_MB_LIB.T6G(SCH_1):GND     I4 @T6G_MB_LIB.T6G(SCH_1):PAGE33
  DH64    GND @T6G_MB_LIB.T6G(SCH_1):GND     I4 @T6G_MB_LIB.T6G(SCH_1):PAGE33
  DH66    GND @T6G_MB_LIB.T6G(SCH_1):GND     I4 @T6G_MB_LIB.T6G(SCH_1):PAGE33
  DA72    GND @T6G_MB_LIB.T6G(SCH_1):GND     I4 @T6G_MB_LIB.T6G(SCH_1):PAGE33
  DA75    GND @T6G_MB_LIB.T6G(SCH_1):GND     I4 @T6G_MB_LIB.T6G(SCH_1):PAGE33
   DB3    GND @T6G_MB_LIB.T6G(SCH_1):GND     I4 @T6G_MB_LIB.T6G(SCH_1):PAGE33
   DB8    GND @T6G_MB_LIB.T6G(SCH_1):GND     I4 @T6G_MB_LIB.T6G(SCH_1):PAGE33
  DB10    GND @T6G_MB_LIB.T6G(SCH_1):GND     I4 @T6G_MB_LIB.T6G(SCH_1):PAGE33
  DB28    GND @T6G_MB_LIB.T6G(SCH_1):GND     I4 @T6G_MB_LIB.T6G(SCH_1):PAGE33
  DB31    GND @T6G_MB_LIB.T6G(SCH_1):GND     I4 @T6G_MB_LIB.T6G(SCH_1):PAGE33
  DB34    GND @T6G_MB_LIB.T6G(SCH_1):GND     I4 @T6G_MB_LIB.T6G(SCH_1):PAGE33
  DB37    GND @T6G_MB_LIB.T6G(SCH_1):GND     I4 @T6G_MB_LIB.T6G(SCH_1):PAGE33
  DB39    GND @T6G_MB_LIB.T6G(SCH_1):GND     I4 @T6G_MB_LIB.T6G(SCH_1):PAGE33
  DB42    GND @T6G_MB_LIB.T6G(SCH_1):GND     I4 @T6G_MB_LIB.T6G(SCH_1):PAGE33
  DB45    GND @T6G_MB_LIB.T6G(SCH_1):GND     I4 @T6G_MB_LIB.T6G(SCH_1):PAGE33
  DB61    GND @T6G_MB_LIB.T6G(SCH_1):GND     I4 @T6G_MB_LIB.T6G(SCH_1):PAGE33
  DB66    GND @T6G_MB_LIB.T6G(SCH_1):GND     I4 @T6G_MB_LIB.T6G(SCH_1):PAGE33
  DB68    GND @T6G_MB_LIB.T6G(SCH_1):GND     I4 @T6G_MB_LIB.T6G(SCH_1):PAGE33
  DB73    GND @T6G_MB_LIB.T6G(SCH_1):GND     I4 @T6G_MB_LIB.T6G(SCH_1):PAGE33
   DC1    GND @T6G_MB_LIB.T6G(SCH_1):GND     I4 @T6G_MB_LIB.T6G(SCH_1):PAGE33
   DC4    GND @T6G_MB_LIB.T6G(SCH_1):GND     I4 @T6G_MB_LIB.T6G(SCH_1):PAGE33
   DC6    GND @T6G_MB_LIB.T6G(SCH_1):GND     I4 @T6G_MB_LIB.T6G(SCH_1):PAGE33
   DC8    GND @T6G_MB_LIB.T6G(SCH_1):GND     I4 @T6G_MB_LIB.T6G(SCH_1):PAGE33
  DC11    GND @T6G_MB_LIB.T6G(SCH_1):GND     I4 @T6G_MB_LIB.T6G(SCH_1):PAGE33
  DC18    GND @T6G_MB_LIB.T6G(SCH_1):GND     I4 @T6G_MB_LIB.T6G(SCH_1):PAGE33
  DC20    GND @T6G_MB_LIB.T6G(SCH_1):GND     I4 @T6G_MB_LIB.T6G(SCH_1):PAGE33
  DC22    GND @T6G_MB_LIB.T6G(SCH_1):GND     I4 @T6G_MB_LIB.T6G(SCH_1):PAGE33
  DC25    GND @T6G_MB_LIB.T6G(SCH_1):GND     I4 @T6G_MB_LIB.T6G(SCH_1):PAGE33
  DC28    GND @T6G_MB_LIB.T6G(SCH_1):GND     I4 @T6G_MB_LIB.T6G(SCH_1):PAGE33
  DC31    GND @T6G_MB_LIB.T6G(SCH_1):GND     I4 @T6G_MB_LIB.T6G(SCH_1):PAGE33
  DC34    GND @T6G_MB_LIB.T6G(SCH_1):GND     I4 @T6G_MB_LIB.T6G(SCH_1):PAGE33
  DC42    GND @T6G_MB_LIB.T6G(SCH_1):GND     I4 @T6G_MB_LIB.T6G(SCH_1):PAGE33
  DC54    GND @T6G_MB_LIB.T6G(SCH_1):GND     I4 @T6G_MB_LIB.T6G(SCH_1):PAGE33
  DC56    GND @T6G_MB_LIB.T6G(SCH_1):GND     I4 @T6G_MB_LIB.T6G(SCH_1):PAGE33
  DC58    GND @T6G_MB_LIB.T6G(SCH_1):GND     I4 @T6G_MB_LIB.T6G(SCH_1):PAGE33
  DC61    GND @T6G_MB_LIB.T6G(SCH_1):GND     I4 @T6G_MB_LIB.T6G(SCH_1):PAGE33
  DC63    GND @T6G_MB_LIB.T6G(SCH_1):GND     I4 @T6G_MB_LIB.T6G(SCH_1):PAGE33
  DC65    GND @T6G_MB_LIB.T6G(SCH_1):GND     I4 @T6G_MB_LIB.T6G(SCH_1):PAGE33
  DC68    GND @T6G_MB_LIB.T6G(SCH_1):GND     I4 @T6G_MB_LIB.T6G(SCH_1):PAGE33
   DD5    GND @T6G_MB_LIB.T6G(SCH_1):GND     I4 @T6G_MB_LIB.T6G(SCH_1):PAGE33
   DD8    GND @T6G_MB_LIB.T6G(SCH_1):GND     I4 @T6G_MB_LIB.T6G(SCH_1):PAGE33
  DD10    GND @T6G_MB_LIB.T6G(SCH_1):GND     I4 @T6G_MB_LIB.T6G(SCH_1):PAGE33
  DD12    GND @T6G_MB_LIB.T6G(SCH_1):GND     I4 @T6G_MB_LIB.T6G(SCH_1):PAGE33
  DD15    GND @T6G_MB_LIB.T6G(SCH_1):GND     I4 @T6G_MB_LIB.T6G(SCH_1):PAGE33
  DD17    GND @T6G_MB_LIB.T6G(SCH_1):GND     I4 @T6G_MB_LIB.T6G(SCH_1):PAGE33
  DD19    GND @T6G_MB_LIB.T6G(SCH_1):GND     I4 @T6G_MB_LIB.T6G(SCH_1):PAGE33
  DD29    GND @T6G_MB_LIB.T6G(SCH_1):GND     I4 @T6G_MB_LIB.T6G(SCH_1):PAGE33
  DD30    GND @T6G_MB_LIB.T6G(SCH_1):GND     I4 @T6G_MB_LIB.T6G(SCH_1):PAGE33
  DD32    GND @T6G_MB_LIB.T6G(SCH_1):GND     I4 @T6G_MB_LIB.T6G(SCH_1):PAGE33
  DD33    GND @T6G_MB_LIB.T6G(SCH_1):GND     I4 @T6G_MB_LIB.T6G(SCH_1):PAGE33
  DD35    GND @T6G_MB_LIB.T6G(SCH_1):GND     I4 @T6G_MB_LIB.T6G(SCH_1):PAGE33
  DD36    GND @T6G_MB_LIB.T6G(SCH_1):GND     I4 @T6G_MB_LIB.T6G(SCH_1):PAGE33
  DD37    GND @T6G_MB_LIB.T6G(SCH_1):GND     I4 @T6G_MB_LIB.T6G(SCH_1):PAGE33
  DD44    GND @T6G_MB_LIB.T6G(SCH_1):GND     I4 @T6G_MB_LIB.T6G(SCH_1):PAGE33
  DD46    GND @T6G_MB_LIB.T6G(SCH_1):GND     I4 @T6G_MB_LIB.T6G(SCH_1):PAGE33
  DD47    GND @T6G_MB_LIB.T6G(SCH_1):GND     I4 @T6G_MB_LIB.T6G(SCH_1):PAGE33
  DD49    GND @T6G_MB_LIB.T6G(SCH_1):GND     I4 @T6G_MB_LIB.T6G(SCH_1):PAGE33
  DD50    GND @T6G_MB_LIB.T6G(SCH_1):GND     I4 @T6G_MB_LIB.T6G(SCH_1):PAGE33
  DD52    GND @T6G_MB_LIB.T6G(SCH_1):GND     I4 @T6G_MB_LIB.T6G(SCH_1):PAGE33
  DD53    GND @T6G_MB_LIB.T6G(SCH_1):GND     I4 @T6G_MB_LIB.T6G(SCH_1):PAGE33
  DD66    GND @T6G_MB_LIB.T6G(SCH_1):GND     I4 @T6G_MB_LIB.T6G(SCH_1):PAGE33
  DD68    GND @T6G_MB_LIB.T6G(SCH_1):GND     I4 @T6G_MB_LIB.T6G(SCH_1):PAGE33
  DD71    GND @T6G_MB_LIB.T6G(SCH_1):GND     I4 @T6G_MB_LIB.T6G(SCH_1):PAGE33
  DD73    GND @T6G_MB_LIB.T6G(SCH_1):GND     I4 @T6G_MB_LIB.T6G(SCH_1):PAGE33
   DE1    GND @T6G_MB_LIB.T6G(SCH_1):GND     I4 @T6G_MB_LIB.T6G(SCH_1):PAGE33
   DE6    GND @T6G_MB_LIB.T6G(SCH_1):GND     I4 @T6G_MB_LIB.T6G(SCH_1):PAGE33
   DE8    GND @T6G_MB_LIB.T6G(SCH_1):GND     I4 @T6G_MB_LIB.T6G(SCH_1):PAGE33
  DE26    GND @T6G_MB_LIB.T6G(SCH_1):GND     I4 @T6G_MB_LIB.T6G(SCH_1):PAGE33
  DE29    GND @T6G_MB_LIB.T6G(SCH_1):GND     I4 @T6G_MB_LIB.T6G(SCH_1):PAGE33
  DE33    GND @T6G_MB_LIB.T6G(SCH_1):GND     I4 @T6G_MB_LIB.T6G(SCH_1):PAGE33
  DE56    GND @T6G_MB_LIB.T6G(SCH_1):GND     I4 @T6G_MB_LIB.T6G(SCH_1):PAGE33
  DE61    GND @T6G_MB_LIB.T6G(SCH_1):GND     I4 @T6G_MB_LIB.T6G(SCH_1):PAGE33
  DE63    GND @T6G_MB_LIB.T6G(SCH_1):GND     I4 @T6G_MB_LIB.T6G(SCH_1):PAGE33
  DE68    GND @T6G_MB_LIB.T6G(SCH_1):GND     I4 @T6G_MB_LIB.T6G(SCH_1):PAGE33
   DF5    GND @T6G_MB_LIB.T6G(SCH_1):GND     I4 @T6G_MB_LIB.T6G(SCH_1):PAGE33
   DF6    GND @T6G_MB_LIB.T6G(SCH_1):GND     I4 @T6G_MB_LIB.T6G(SCH_1):PAGE33
   DF8    GND @T6G_MB_LIB.T6G(SCH_1):GND     I4 @T6G_MB_LIB.T6G(SCH_1):PAGE33
  DF10    GND @T6G_MB_LIB.T6G(SCH_1):GND     I4 @T6G_MB_LIB.T6G(SCH_1):PAGE33
  DF11    GND @T6G_MB_LIB.T6G(SCH_1):GND     I4 @T6G_MB_LIB.T6G(SCH_1):PAGE33
  DF12    GND @T6G_MB_LIB.T6G(SCH_1):GND     I4 @T6G_MB_LIB.T6G(SCH_1):PAGE33
  DF13    GND @T6G_MB_LIB.T6G(SCH_1):GND     I4 @T6G_MB_LIB.T6G(SCH_1):PAGE33
  DF20    GND @T6G_MB_LIB.T6G(SCH_1):GND     I4 @T6G_MB_LIB.T6G(SCH_1):PAGE33
  DF22    GND @T6G_MB_LIB.T6G(SCH_1):GND     I4 @T6G_MB_LIB.T6G(SCH_1):PAGE33
  DF23    GND @T6G_MB_LIB.T6G(SCH_1):GND     I4 @T6G_MB_LIB.T6G(SCH_1):PAGE33
  DF26    GND @T6G_MB_LIB.T6G(SCH_1):GND     I4 @T6G_MB_LIB.T6G(SCH_1):PAGE33
  DF29    GND @T6G_MB_LIB.T6G(SCH_1):GND     I4 @T6G_MB_LIB.T6G(SCH_1):PAGE33
  DF32    GND @T6G_MB_LIB.T6G(SCH_1):GND     I4 @T6G_MB_LIB.T6G(SCH_1):PAGE33
  DF35    GND @T6G_MB_LIB.T6G(SCH_1):GND     I4 @T6G_MB_LIB.T6G(SCH_1):PAGE33
  DF37    GND @T6G_MB_LIB.T6G(SCH_1):GND     I4 @T6G_MB_LIB.T6G(SCH_1):PAGE33
  DF39    GND @T6G_MB_LIB.T6G(SCH_1):GND     I4 @T6G_MB_LIB.T6G(SCH_1):PAGE33
  DF42    GND @T6G_MB_LIB.T6G(SCH_1):GND     I4 @T6G_MB_LIB.T6G(SCH_1):PAGE33
  DF44    GND @T6G_MB_LIB.T6G(SCH_1):GND     I4 @T6G_MB_LIB.T6G(SCH_1):PAGE33
  DF45    GND @T6G_MB_LIB.T6G(SCH_1):GND     I4 @T6G_MB_LIB.T6G(SCH_1):PAGE33
  DF46    GND @T6G_MB_LIB.T6G(SCH_1):GND     I4 @T6G_MB_LIB.T6G(SCH_1):PAGE33
  DF47    GND @T6G_MB_LIB.T6G(SCH_1):GND     I4 @T6G_MB_LIB.T6G(SCH_1):PAGE33
  DF48    GND @T6G_MB_LIB.T6G(SCH_1):GND     I4 @T6G_MB_LIB.T6G(SCH_1):PAGE33
  DF49    GND @T6G_MB_LIB.T6G(SCH_1):GND     I4 @T6G_MB_LIB.T6G(SCH_1):PAGE33
  DF50    GND @T6G_MB_LIB.T6G(SCH_1):GND     I4 @T6G_MB_LIB.T6G(SCH_1):PAGE33
  DF51    GND @T6G_MB_LIB.T6G(SCH_1):GND     I4 @T6G_MB_LIB.T6G(SCH_1):PAGE33
  DF52    GND @T6G_MB_LIB.T6G(SCH_1):GND     I4 @T6G_MB_LIB.T6G(SCH_1):PAGE33
  DF56    GND @T6G_MB_LIB.T6G(SCH_1):GND     I4 @T6G_MB_LIB.T6G(SCH_1):PAGE33
  DF57    GND @T6G_MB_LIB.T6G(SCH_1):GND     I4 @T6G_MB_LIB.T6G(SCH_1):PAGE33
  DF58    GND @T6G_MB_LIB.T6G(SCH_1):GND     I4 @T6G_MB_LIB.T6G(SCH_1):PAGE33
  DF59    GND @T6G_MB_LIB.T6G(SCH_1):GND     I4 @T6G_MB_LIB.T6G(SCH_1):PAGE33
  DF61    GND @T6G_MB_LIB.T6G(SCH_1):GND     I4 @T6G_MB_LIB.T6G(SCH_1):PAGE33
  DF63    GND @T6G_MB_LIB.T6G(SCH_1):GND     I4 @T6G_MB_LIB.T6G(SCH_1):PAGE33
  DF64    GND @T6G_MB_LIB.T6G(SCH_1):GND     I4 @T6G_MB_LIB.T6G(SCH_1):PAGE33
  DF65    GND @T6G_MB_LIB.T6G(SCH_1):GND     I4 @T6G_MB_LIB.T6G(SCH_1):PAGE33
  DF71    GND @T6G_MB_LIB.T6G(SCH_1):GND     I4 @T6G_MB_LIB.T6G(SCH_1):PAGE33
  DF72    GND @T6G_MB_LIB.T6G(SCH_1):GND     I4 @T6G_MB_LIB.T6G(SCH_1):PAGE33
  DF73    GND @T6G_MB_LIB.T6G(SCH_1):GND     I4 @T6G_MB_LIB.T6G(SCH_1):PAGE33
   DG1    GND @T6G_MB_LIB.T6G(SCH_1):GND     I4 @T6G_MB_LIB.T6G(SCH_1):PAGE33
   DG2    GND @T6G_MB_LIB.T6G(SCH_1):GND     I4 @T6G_MB_LIB.T6G(SCH_1):PAGE33
   DG6    GND @T6G_MB_LIB.T6G(SCH_1):GND     I4 @T6G_MB_LIB.T6G(SCH_1):PAGE33
   DG7    GND @T6G_MB_LIB.T6G(SCH_1):GND     I4 @T6G_MB_LIB.T6G(SCH_1):PAGE33
  DG15    GND @T6G_MB_LIB.T6G(SCH_1):GND     I4 @T6G_MB_LIB.T6G(SCH_1):PAGE33
  DG16    GND @T6G_MB_LIB.T6G(SCH_1):GND     I4 @T6G_MB_LIB.T6G(SCH_1):PAGE33
  DG18    GND @T6G_MB_LIB.T6G(SCH_1):GND     I4 @T6G_MB_LIB.T6G(SCH_1):PAGE33
  DG20    GND @T6G_MB_LIB.T6G(SCH_1):GND     I4 @T6G_MB_LIB.T6G(SCH_1):PAGE33
  DG21    GND @T6G_MB_LIB.T6G(SCH_1):GND     I4 @T6G_MB_LIB.T6G(SCH_1):PAGE33
  DG24    GND @T6G_MB_LIB.T6G(SCH_1):GND     I4 @T6G_MB_LIB.T6G(SCH_1):PAGE33
  DG27    GND @T6G_MB_LIB.T6G(SCH_1):GND     I4 @T6G_MB_LIB.T6G(SCH_1):PAGE33
  DG46    GND @T6G_MB_LIB.T6G(SCH_1):GND     I4 @T6G_MB_LIB.T6G(SCH_1):PAGE33
  DG49    GND @T6G_MB_LIB.T6G(SCH_1):GND     I4 @T6G_MB_LIB.T6G(SCH_1):PAGE33
  DG52    GND @T6G_MB_LIB.T6G(SCH_1):GND     I4 @T6G_MB_LIB.T6G(SCH_1):PAGE33
  DG55    GND @T6G_MB_LIB.T6G(SCH_1):GND     I4 @T6G_MB_LIB.T6G(SCH_1):PAGE33
  DG56    GND @T6G_MB_LIB.T6G(SCH_1):GND     I4 @T6G_MB_LIB.T6G(SCH_1):PAGE33
  DG59    GND @T6G_MB_LIB.T6G(SCH_1):GND     I4 @T6G_MB_LIB.T6G(SCH_1):PAGE33
  DG60    GND @T6G_MB_LIB.T6G(SCH_1):GND     I4 @T6G_MB_LIB.T6G(SCH_1):PAGE33
  DG66    GND @T6G_MB_LIB.T6G(SCH_1):GND     I4 @T6G_MB_LIB.T6G(SCH_1):PAGE33
  DG67    GND @T6G_MB_LIB.T6G(SCH_1):GND     I4 @T6G_MB_LIB.T6G(SCH_1):PAGE33
  DG68    GND @T6G_MB_LIB.T6G(SCH_1):GND     I4 @T6G_MB_LIB.T6G(SCH_1):PAGE33
  DG69    GND @T6G_MB_LIB.T6G(SCH_1):GND     I4 @T6G_MB_LIB.T6G(SCH_1):PAGE33
  DG70    GND @T6G_MB_LIB.T6G(SCH_1):GND     I4 @T6G_MB_LIB.T6G(SCH_1):PAGE33
  DG74    GND @T6G_MB_LIB.T6G(SCH_1):GND     I4 @T6G_MB_LIB.T6G(SCH_1):PAGE33
  DG75    GND @T6G_MB_LIB.T6G(SCH_1):GND     I4 @T6G_MB_LIB.T6G(SCH_1):PAGE33
  DH39    GND @T6G_MB_LIB.T6G(SCH_1):GND     I4 @T6G_MB_LIB.T6G(SCH_1):PAGE33
  DH43    GND @T6G_MB_LIB.T6G(SCH_1):GND     I4 @T6G_MB_LIB.T6G(SCH_1):PAGE33
  DH46    GND @T6G_MB_LIB.T6G(SCH_1):GND     I4 @T6G_MB_LIB.T6G(SCH_1):PAGE33
  DH49    GND @T6G_MB_LIB.T6G(SCH_1):GND     I4 @T6G_MB_LIB.T6G(SCH_1):PAGE33
  DH52    GND @T6G_MB_LIB.T6G(SCH_1):GND     I4 @T6G_MB_LIB.T6G(SCH_1):PAGE33
  DH55    GND @T6G_MB_LIB.T6G(SCH_1):GND     I4 @T6G_MB_LIB.T6G(SCH_1):PAGE33
  DH59    GND @T6G_MB_LIB.T6G(SCH_1):GND     I4 @T6G_MB_LIB.T6G(SCH_1):PAGE33
  DH68    GND @T6G_MB_LIB.T6G(SCH_1):GND     I4 @T6G_MB_LIB.T6G(SCH_1):PAGE33
  DH70    GND @T6G_MB_LIB.T6G(SCH_1):GND     I4 @T6G_MB_LIB.T6G(SCH_1):PAGE33
   DJ7    GND @T6G_MB_LIB.T6G(SCH_1):GND     I4 @T6G_MB_LIB.T6G(SCH_1):PAGE33
  DJ15    GND @T6G_MB_LIB.T6G(SCH_1):GND     I4 @T6G_MB_LIB.T6G(SCH_1):PAGE33
  DJ19    GND @T6G_MB_LIB.T6G(SCH_1):GND     I4 @T6G_MB_LIB.T6G(SCH_1):PAGE33
  DJ43    GND @T6G_MB_LIB.T6G(SCH_1):GND     I4 @T6G_MB_LIB.T6G(SCH_1):PAGE33
  DJ49    GND @T6G_MB_LIB.T6G(SCH_1):GND     I4 @T6G_MB_LIB.T6G(SCH_1):PAGE33
  DJ59    GND @T6G_MB_LIB.T6G(SCH_1):GND     I4 @T6G_MB_LIB.T6G(SCH_1):PAGE33
  DJ61    GND @T6G_MB_LIB.T6G(SCH_1):GND     I4 @T6G_MB_LIB.T6G(SCH_1):PAGE33
  DJ63    GND @T6G_MB_LIB.T6G(SCH_1):GND     I4 @T6G_MB_LIB.T6G(SCH_1):PAGE33
  DJ66    GND @T6G_MB_LIB.T6G(SCH_1):GND     I4 @T6G_MB_LIB.T6G(SCH_1):PAGE33
  DJ68    GND @T6G_MB_LIB.T6G(SCH_1):GND     I4 @T6G_MB_LIB.T6G(SCH_1):PAGE33
  DJ73    GND @T6G_MB_LIB.T6G(SCH_1):GND     I4 @T6G_MB_LIB.T6G(SCH_1):PAGE33
  CY57    GND @T6G_MB_LIB.T6G(SCH_1):GND     I4 @T6G_MB_LIB.T6G(SCH_1):PAGE33
  CK31    GND @T6G_MB_LIB.T6G(SCH_1):GND     I4 @T6G_MB_LIB.T6G(SCH_1):PAGE33
  CB44    GND @T6G_MB_LIB.T6G(SCH_1):GND     I4 @T6G_MB_LIB.T6G(SCH_1):PAGE33
  AM37    GND @T6G_MB_LIB.T6G(SCH_1):GND     I4 @T6G_MB_LIB.T6G(SCH_1):PAGE33
   K23    GND @T6G_MB_LIB.T6G(SCH_1):GND     I4 @T6G_MB_LIB.T6G(SCH_1):PAGE33
  CN54    GND @T6G_MB_LIB.T6G(SCH_1):GND     I4 @T6G_MB_LIB.T6G(SCH_1):PAGE33
  CK10    GND @T6G_MB_LIB.T6G(SCH_1):GND     I4 @T6G_MB_LIB.T6G(SCH_1):PAGE33
  AA72    GND @T6G_MB_LIB.T6G(SCH_1):GND     I4 @T6G_MB_LIB.T6G(SCH_1):PAGE33
  AJ13    GND @T6G_MB_LIB.T6G(SCH_1):GND     I4 @T6G_MB_LIB.T6G(SCH_1):PAGE33
  AD31    GND @T6G_MB_LIB.T6G(SCH_1):GND     I4 @T6G_MB_LIB.T6G(SCH_1):PAGE33
  AA42    GND @T6G_MB_LIB.T6G(SCH_1):GND     I4 @T6G_MB_LIB.T6G(SCH_1):PAGE33
   V27    GND @T6G_MB_LIB.T6G(SCH_1):GND     I4 @T6G_MB_LIB.T6G(SCH_1):PAGE33
  CF46    GND @T6G_MB_LIB.T6G(SCH_1):GND     I4 @T6G_MB_LIB.T6G(SCH_1):PAGE33
  CC22    GND @T6G_MB_LIB.T6G(SCH_1):GND     I4 @T6G_MB_LIB.T6G(SCH_1):PAGE33
  AN20    GND @T6G_MB_LIB.T6G(SCH_1):GND     I4 @T6G_MB_LIB.T6G(SCH_1):PAGE33
   P68    GND @T6G_MB_LIB.T6G(SCH_1):GND     I4 @T6G_MB_LIB.T6G(SCH_1):PAGE33
   P25    GND @T6G_MB_LIB.T6G(SCH_1):GND     I4 @T6G_MB_LIB.T6G(SCH_1):PAGE33
  CU58    GND @T6G_MB_LIB.T6G(SCH_1):GND     I4 @T6G_MB_LIB.T6G(SCH_1):PAGE33
  BW25    GND @T6G_MB_LIB.T6G(SCH_1):GND     I4 @T6G_MB_LIB.T6G(SCH_1):PAGE33
  AH33    GND @T6G_MB_LIB.T6G(SCH_1):GND     I4 @T6G_MB_LIB.T6G(SCH_1):PAGE33
   AE4    GND @T6G_MB_LIB.T6G(SCH_1):GND     I4 @T6G_MB_LIB.T6G(SCH_1):PAGE33
  CG42    GND @T6G_MB_LIB.T6G(SCH_1):GND     I4 @T6G_MB_LIB.T6G(SCH_1):PAGE33
  DA56    GND @T6G_MB_LIB.T6G(SCH_1):GND     I4 @T6G_MB_LIB.T6G(SCH_1):PAGE33
   K59    GND @T6G_MB_LIB.T6G(SCH_1):GND     I4 @T6G_MB_LIB.T6G(SCH_1):PAGE33
  CM50    GND @T6G_MB_LIB.T6G(SCH_1):GND     I4 @T6G_MB_LIB.T6G(SCH_1):PAGE33
  CT52    GND @T6G_MB_LIB.T6G(SCH_1):GND     I4 @T6G_MB_LIB.T6G(SCH_1):PAGE33
  BV42    GND @T6G_MB_LIB.T6G(SCH_1):GND     I4 @T6G_MB_LIB.T6G(SCH_1):PAGE33
   V68    GND @T6G_MB_LIB.T6G(SCH_1):GND     I4 @T6G_MB_LIB.T6G(SCH_1):PAGE33

 U26 GENOA_SP5-SOCKET6096_13568-001,SMLF,IO,DGA^6000030
  AR74 M_A_CPU1_ALERT_R_N @T6G_MB_LIB.T6G(SCH_1):M_A_CPU1_ALERT_R_N   I167 @T6G_MB_LIB.T6G(SCH_1):PAGE37
  AT74 M_A_CPU1_RESET_N @T6G_MB_LIB.T6G(SCH_1):M_A_CPU1_RESET_N   I167 @T6G_MB_LIB.T6G(SCH_1):PAGE37
  CE73 M_A_CPU1_SB_DQS_DN<5> @T6G_MB_LIB.T6G(SCH_1):M_A_CPU1_SB_DQS_DN(5)   I167 @T6G_MB_LIB.T6G(SCH_1):PAGE37
  CK74 M_A_CPU1_SB_DQS_DP<1> @T6G_MB_LIB.T6G(SCH_1):M_A_CPU1_SB_DQS_DP(1)   I167 @T6G_MB_LIB.T6G(SCH_1):PAGE37
  DE73 M_A_CPU1_SB_DQ<29> @T6G_MB_LIB.T6G(SCH_1):M_A_CPU1_SB_DQ(29)   I167 @T6G_MB_LIB.T6G(SCH_1):PAGE37
  CR74 M_A_CPU1_SB_DQ<18> @T6G_MB_LIB.T6G(SCH_1):M_A_CPU1_SB_DQ(18)   I167 @T6G_MB_LIB.T6G(SCH_1):PAGE37
  CD72 M_A_CPU1_SB_DQ<3> @T6G_MB_LIB.T6G(SCH_1):M_A_CPU1_SB_DQ(3)   I167 @T6G_MB_LIB.T6G(SCH_1):PAGE37
  AA73 M_A_CPU1_SA_DQS_DP<7> @T6G_MB_LIB.T6G(SCH_1):M_A_CPU1_SA_DQS_DP(7)   I167 @T6G_MB_LIB.T6G(SCH_1):PAGE37
   J74 M_A_CPU1_SA_DQ<4> @T6G_MB_LIB.T6G(SCH_1):M_A_CPU1_SA_DQ(4)   I167 @T6G_MB_LIB.T6G(SCH_1):PAGE37
  AU74     NC     NC   I167 @T6G_MB_LIB.T6G(SCH_1):PAGE37
  AW73 M_A_CPU1_SA_CS_N<1> @T6G_MB_LIB.T6G(SCH_1):M_A_CPU1_SA_CS_N(1)   I167 @T6G_MB_LIB.T6G(SCH_1):PAGE37
  CL73 M_A_CPU1_SB_DQS_DN<6> @T6G_MB_LIB.T6G(SCH_1):M_A_CPU1_SB_DQS_DN(6)   I167 @T6G_MB_LIB.T6G(SCH_1):PAGE37
  CT74 M_A_CPU1_SB_DQS_DP<2> @T6G_MB_LIB.T6G(SCH_1):M_A_CPU1_SB_DQS_DP(2)   I167 @T6G_MB_LIB.T6G(SCH_1):PAGE37
  CT72 M_A_CPU1_SB_DQ<19> @T6G_MB_LIB.T6G(SCH_1):M_A_CPU1_SB_DQ(19)   I167 @T6G_MB_LIB.T6G(SCH_1):PAGE37
  CF74 M_A_CPU1_SB_DQ<4> @T6G_MB_LIB.T6G(SCH_1):M_A_CPU1_SB_DQ(4)   I167 @T6G_MB_LIB.T6G(SCH_1):PAGE37
  AG73 M_A_CPU1_SA_DQS_DP<8> @T6G_MB_LIB.T6G(SCH_1):M_A_CPU1_SA_DQS_DP(8)   I167 @T6G_MB_LIB.T6G(SCH_1):PAGE37
  AH74 M_A_CPU1_SA_DQ<30> @T6G_MB_LIB.T6G(SCH_1):M_A_CPU1_SA_DQ(30)   I167 @T6G_MB_LIB.T6G(SCH_1):PAGE37
   K72 M_A_CPU1_SA_DQ<5> @T6G_MB_LIB.T6G(SCH_1):M_A_CPU1_SA_DQ(5)   I167 @T6G_MB_LIB.T6G(SCH_1):PAGE37
  AV72     NC     NC   I167 @T6G_MB_LIB.T6G(SCH_1):PAGE37
  CU73 M_A_CPU1_SB_DQS_DN<7> @T6G_MB_LIB.T6G(SCH_1):M_A_CPU1_SB_DQS_DN(7)   I167 @T6G_MB_LIB.T6G(SCH_1):PAGE37
  DB74 M_A_CPU1_SB_DQS_DP<3> @T6G_MB_LIB.T6G(SCH_1):M_A_CPU1_SB_DQS_DP(3)   I167 @T6G_MB_LIB.T6G(SCH_1):PAGE37
  CG73 M_A_CPU1_SB_DQ<5> @T6G_MB_LIB.T6G(SCH_1):M_A_CPU1_SB_DQ(5)   I167 @T6G_MB_LIB.T6G(SCH_1):PAGE37
  AN73 M_A_CPU1_SA_DQS_DP<9> @T6G_MB_LIB.T6G(SCH_1):M_A_CPU1_SA_DQS_DP(9)   I167 @T6G_MB_LIB.T6G(SCH_1):PAGE37
  AJ73 M_A_CPU1_SA_DQ<31> @T6G_MB_LIB.T6G(SCH_1):M_A_CPU1_SA_DQ(31)   I167 @T6G_MB_LIB.T6G(SCH_1):PAGE37
  AA74 M_A_CPU1_SA_DQ<20> @T6G_MB_LIB.T6G(SCH_1):M_A_CPU1_SA_DQ(20)   I167 @T6G_MB_LIB.T6G(SCH_1):PAGE37
   K74 M_A_CPU1_SA_DQ<6> @T6G_MB_LIB.T6G(SCH_1):M_A_CPU1_SA_DQ(6)   I167 @T6G_MB_LIB.T6G(SCH_1):PAGE37
  AJ74 M_A_CPU1_SA_CB<0> @T6G_MB_LIB.T6G(SCH_1):M_A_CPU1_SA_CB(0)   I167 @T6G_MB_LIB.T6G(SCH_1):PAGE37
  DC73 M_A_CPU1_SB_DQS_DN<8> @T6G_MB_LIB.T6G(SCH_1):M_A_CPU1_SB_DQS_DN(8)   I167 @T6G_MB_LIB.T6G(SCH_1):PAGE37
  BY72 M_A_CPU1_SB_DQS_DP<4> @T6G_MB_LIB.T6G(SCH_1):M_A_CPU1_SB_DQS_DP(4)   I167 @T6G_MB_LIB.T6G(SCH_1):PAGE37
  CG74 M_A_CPU1_SB_DQ<6> @T6G_MB_LIB.T6G(SCH_1):M_A_CPU1_SB_DQ(6)   I167 @T6G_MB_LIB.T6G(SCH_1):PAGE37
  AB72 M_A_CPU1_SA_DQ<21> @T6G_MB_LIB.T6G(SCH_1):M_A_CPU1_SA_DQ(21)   I167 @T6G_MB_LIB.T6G(SCH_1):PAGE37
   M74 M_A_CPU1_SA_DQ<10> @T6G_MB_LIB.T6G(SCH_1):M_A_CPU1_SA_DQ(10)   I167 @T6G_MB_LIB.T6G(SCH_1):PAGE37
   L73 M_A_CPU1_SA_DQ<7> @T6G_MB_LIB.T6G(SCH_1):M_A_CPU1_SA_DQ(7)   I167 @T6G_MB_LIB.T6G(SCH_1):PAGE37
  AK72 M_A_CPU1_SA_CB<1> @T6G_MB_LIB.T6G(SCH_1):M_A_CPU1_SA_CB(1)   I167 @T6G_MB_LIB.T6G(SCH_1):PAGE37
  BW74 M_A_CPU1_SB_DQS_DN<9> @T6G_MB_LIB.T6G(SCH_1):M_A_CPU1_SB_DQS_DN(9)   I167 @T6G_MB_LIB.T6G(SCH_1):PAGE37
  CF72 M_A_CPU1_SB_DQS_DP<5> @T6G_MB_LIB.T6G(SCH_1):M_A_CPU1_SB_DQS_DP(5)   I167 @T6G_MB_LIB.T6G(SCH_1):PAGE37
  CH72 M_A_CPU1_SB_DQ<7> @T6G_MB_LIB.T6G(SCH_1):M_A_CPU1_SB_DQ(7)   I167 @T6G_MB_LIB.T6G(SCH_1):PAGE37
  AB74 M_A_CPU1_SA_DQ<22> @T6G_MB_LIB.T6G(SCH_1):M_A_CPU1_SA_DQ(22)   I167 @T6G_MB_LIB.T6G(SCH_1):PAGE37
   N73 M_A_CPU1_SA_DQ<11> @T6G_MB_LIB.T6G(SCH_1):M_A_CPU1_SA_DQ(11)   I167 @T6G_MB_LIB.T6G(SCH_1):PAGE37
   L74 M_A_CPU1_SA_DQ<8> @T6G_MB_LIB.T6G(SCH_1):M_A_CPU1_SA_DQ(8)   I167 @T6G_MB_LIB.T6G(SCH_1):PAGE37
  AK74 M_A_CPU1_SA_CB<2> @T6G_MB_LIB.T6G(SCH_1):M_A_CPU1_SA_CB(2)   I167 @T6G_MB_LIB.T6G(SCH_1):PAGE37
  CM72 M_A_CPU1_SB_DQS_DP<6> @T6G_MB_LIB.T6G(SCH_1):M_A_CPU1_SB_DQS_DP(6)   I167 @T6G_MB_LIB.T6G(SCH_1):PAGE37
  CH74 M_A_CPU1_SB_DQ<8> @T6G_MB_LIB.T6G(SCH_1):M_A_CPU1_SB_DQ(8)   I167 @T6G_MB_LIB.T6G(SCH_1):PAGE37
  BM72 M_A_CPU1_SB_CS_N<0> @T6G_MB_LIB.T6G(SCH_1):M_A_CPU1_SB_CS_N(0)   I167 @T6G_MB_LIB.T6G(SCH_1):PAGE37
  AC73 M_A_CPU1_SA_DQ<23> @T6G_MB_LIB.T6G(SCH_1):M_A_CPU1_SA_DQ(23)   I167 @T6G_MB_LIB.T6G(SCH_1):PAGE37
   R74 M_A_CPU1_SA_DQ<12> @T6G_MB_LIB.T6G(SCH_1):M_A_CPU1_SA_DQ(12)   I167 @T6G_MB_LIB.T6G(SCH_1):PAGE37
   M72 M_A_CPU1_SA_DQ<9> @T6G_MB_LIB.T6G(SCH_1):M_A_CPU1_SA_DQ(9)   I167 @T6G_MB_LIB.T6G(SCH_1):PAGE37
  AL73 M_A_CPU1_SA_CB<3> @T6G_MB_LIB.T6G(SCH_1):M_A_CPU1_SA_CB(3)   I167 @T6G_MB_LIB.T6G(SCH_1):PAGE37
  CV72 M_A_CPU1_SB_DQS_DP<7> @T6G_MB_LIB.T6G(SCH_1):M_A_CPU1_SB_DQS_DP(7)   I167 @T6G_MB_LIB.T6G(SCH_1):PAGE37
  CJ73 M_A_CPU1_SB_DQ<9> @T6G_MB_LIB.T6G(SCH_1):M_A_CPU1_SB_DQ(9)   I167 @T6G_MB_LIB.T6G(SCH_1):PAGE37
  BL73     NC     NC   I167 @T6G_MB_LIB.T6G(SCH_1):PAGE37
  BN74 M_A_CPU1_SB_CS_N<1> @T6G_MB_LIB.T6G(SCH_1):M_A_CPU1_SB_CS_N(1)   I167 @T6G_MB_LIB.T6G(SCH_1):PAGE37
   H74 M_A_CPU1_SA_DQS_DN<0> @T6G_MB_LIB.T6G(SCH_1):M_A_CPU1_SA_DQS_DN(0)   I167 @T6G_MB_LIB.T6G(SCH_1):PAGE37
  AC74 M_A_CPU1_SA_DQ<24> @T6G_MB_LIB.T6G(SCH_1):M_A_CPU1_SA_DQ(24)   I167 @T6G_MB_LIB.T6G(SCH_1):PAGE37
   T72 M_A_CPU1_SA_DQ<13> @T6G_MB_LIB.T6G(SCH_1):M_A_CPU1_SA_DQ(13)   I167 @T6G_MB_LIB.T6G(SCH_1):PAGE37
  AN74 M_A_CPU1_SA_CB<4> @T6G_MB_LIB.T6G(SCH_1):M_A_CPU1_SA_CB(4)   I167 @T6G_MB_LIB.T6G(SCH_1):PAGE37
  DD72 M_A_CPU1_SB_DQS_DP<8> @T6G_MB_LIB.T6G(SCH_1):M_A_CPU1_SB_DQS_DP(8)   I167 @T6G_MB_LIB.T6G(SCH_1):PAGE37
  DE74 M_A_CPU1_SB_DQ<30> @T6G_MB_LIB.T6G(SCH_1):M_A_CPU1_SB_DQ(30)   I167 @T6G_MB_LIB.T6G(SCH_1):PAGE37
  BM74     NC     NC   I167 @T6G_MB_LIB.T6G(SCH_1):PAGE37
   P74 M_A_CPU1_SA_DQS_DN<1> @T6G_MB_LIB.T6G(SCH_1):M_A_CPU1_SA_DQS_DN(1)   I167 @T6G_MB_LIB.T6G(SCH_1):PAGE37
  AD72 M_A_CPU1_SA_DQ<25> @T6G_MB_LIB.T6G(SCH_1):M_A_CPU1_SA_DQ(25)   I167 @T6G_MB_LIB.T6G(SCH_1):PAGE37
   T74 M_A_CPU1_SA_DQ<14> @T6G_MB_LIB.T6G(SCH_1):M_A_CPU1_SA_DQ(14)   I167 @T6G_MB_LIB.T6G(SCH_1):PAGE37
  AP72 M_A_CPU1_SA_CB<5> @T6G_MB_LIB.T6G(SCH_1):M_A_CPU1_SA_CB(5)   I167 @T6G_MB_LIB.T6G(SCH_1):PAGE37
  DF74 M_A_CPU1_SB_DQ<31> @T6G_MB_LIB.T6G(SCH_1):M_A_CPU1_SB_DQ(31)   I167 @T6G_MB_LIB.T6G(SCH_1):PAGE37
  CV74 M_A_CPU1_SB_DQ<20> @T6G_MB_LIB.T6G(SCH_1):M_A_CPU1_SB_DQ(20)   I167 @T6G_MB_LIB.T6G(SCH_1):PAGE37
  BY74 M_A_CPU1_SB_CB<0> @T6G_MB_LIB.T6G(SCH_1):M_A_CPU1_SB_CB(0)   I167 @T6G_MB_LIB.T6G(SCH_1):PAGE37
   Y74 M_A_CPU1_SA_DQS_DN<2> @T6G_MB_LIB.T6G(SCH_1):M_A_CPU1_SA_DQS_DN(2)   I167 @T6G_MB_LIB.T6G(SCH_1):PAGE37
  AD74 M_A_CPU1_SA_DQ<26> @T6G_MB_LIB.T6G(SCH_1):M_A_CPU1_SA_DQ(26)   I167 @T6G_MB_LIB.T6G(SCH_1):PAGE37
   U73 M_A_CPU1_SA_DQ<15> @T6G_MB_LIB.T6G(SCH_1):M_A_CPU1_SA_DQ(15)   I167 @T6G_MB_LIB.T6G(SCH_1):PAGE37
  AP74 M_A_CPU1_SA_CB<6> @T6G_MB_LIB.T6G(SCH_1):M_A_CPU1_SA_CB(6)   I167 @T6G_MB_LIB.T6G(SCH_1):PAGE37
  BN73 M_A_CPU1_SA_RSP<0> @T6G_MB_LIB.T6G(SCH_1):M_A_CPU1_SA_RSP(0)   I167 @T6G_MB_LIB.T6G(SCH_1):PAGE37
  CW73 M_A_CPU1_SB_DQ<21> @T6G_MB_LIB.T6G(SCH_1):M_A_CPU1_SB_DQ(21)   I167 @T6G_MB_LIB.T6G(SCH_1):PAGE37
  CJ74 M_A_CPU1_SB_DQ<10> @T6G_MB_LIB.T6G(SCH_1):M_A_CPU1_SB_DQ(10)   I167 @T6G_MB_LIB.T6G(SCH_1):PAGE37
  CA73 M_A_CPU1_SB_CB<1> @T6G_MB_LIB.T6G(SCH_1):M_A_CPU1_SB_CB(1)   I167 @T6G_MB_LIB.T6G(SCH_1):PAGE37
  AF74 M_A_CPU1_SA_DQS_DN<3> @T6G_MB_LIB.T6G(SCH_1):M_A_CPU1_SA_DQS_DN(3)   I167 @T6G_MB_LIB.T6G(SCH_1):PAGE37
  AE73 M_A_CPU1_SA_DQ<27> @T6G_MB_LIB.T6G(SCH_1):M_A_CPU1_SA_DQ(27)   I167 @T6G_MB_LIB.T6G(SCH_1):PAGE37
   U74 M_A_CPU1_SA_DQ<16> @T6G_MB_LIB.T6G(SCH_1):M_A_CPU1_SA_DQ(16)   I167 @T6G_MB_LIB.T6G(SCH_1):PAGE37
  AR73 M_A_CPU1_SA_CB<7> @T6G_MB_LIB.T6G(SCH_1):M_A_CPU1_SA_CB(7)   I167 @T6G_MB_LIB.T6G(SCH_1):PAGE37
  AW74 M_A_CPU1_SA_CA<0> @T6G_MB_LIB.T6G(SCH_1):M_A_CPU1_SA_CA(0)   I167 @T6G_MB_LIB.T6G(SCH_1):PAGE37
  BP72     NC     NC   I167 @T6G_MB_LIB.T6G(SCH_1):PAGE37
  CW74 M_A_CPU1_SB_DQ<22> @T6G_MB_LIB.T6G(SCH_1):M_A_CPU1_SB_DQ(22)   I167 @T6G_MB_LIB.T6G(SCH_1):PAGE37
  CK72 M_A_CPU1_SB_DQ<11> @T6G_MB_LIB.T6G(SCH_1):M_A_CPU1_SB_DQ(11)   I167 @T6G_MB_LIB.T6G(SCH_1):PAGE37
  CA74 M_A_CPU1_SB_CB<2> @T6G_MB_LIB.T6G(SCH_1):M_A_CPU1_SB_CB(2)   I167 @T6G_MB_LIB.T6G(SCH_1):PAGE37
  BG73 M_A_CPU1_SB_CA<0> @T6G_MB_LIB.T6G(SCH_1):M_A_CPU1_SB_CA(0)   I167 @T6G_MB_LIB.T6G(SCH_1):PAGE37
  AM74 M_A_CPU1_SA_DQS_DN<4> @T6G_MB_LIB.T6G(SCH_1):M_A_CPU1_SA_DQS_DN(4)   I167 @T6G_MB_LIB.T6G(SCH_1):PAGE37
   G74 M_A_CPU1_SA_DQS_DP<0> @T6G_MB_LIB.T6G(SCH_1):M_A_CPU1_SA_DQS_DP(0)   I167 @T6G_MB_LIB.T6G(SCH_1):PAGE37
  AG74 M_A_CPU1_SA_DQ<28> @T6G_MB_LIB.T6G(SCH_1):M_A_CPU1_SA_DQ(28)   I167 @T6G_MB_LIB.T6G(SCH_1):PAGE37
   V72 M_A_CPU1_SA_DQ<17> @T6G_MB_LIB.T6G(SCH_1):M_A_CPU1_SA_DQ(17)   I167 @T6G_MB_LIB.T6G(SCH_1):PAGE37
  AY74 M_A_CPU1_SA_CA<1> @T6G_MB_LIB.T6G(SCH_1):M_A_CPU1_SA_CA(1)   I167 @T6G_MB_LIB.T6G(SCH_1):PAGE37
  CY72 M_A_CPU1_SB_DQ<23> @T6G_MB_LIB.T6G(SCH_1):M_A_CPU1_SB_DQ(23)   I167 @T6G_MB_LIB.T6G(SCH_1):PAGE37
  CM74 M_A_CPU1_SB_DQ<12> @T6G_MB_LIB.T6G(SCH_1):M_A_CPU1_SB_DQ(12)   I167 @T6G_MB_LIB.T6G(SCH_1):PAGE37
  CB72 M_A_CPU1_SB_CB<3> @T6G_MB_LIB.T6G(SCH_1):M_A_CPU1_SB_CB(3)   I167 @T6G_MB_LIB.T6G(SCH_1):PAGE37
  BH72 M_A_CPU1_SB_CA<1> @T6G_MB_LIB.T6G(SCH_1):M_A_CPU1_SB_CA(1)   I167 @T6G_MB_LIB.T6G(SCH_1):PAGE37
   H72 M_A_CPU1_SA_DQS_DN<5> @T6G_MB_LIB.T6G(SCH_1):M_A_CPU1_SA_DQS_DN(5)   I167 @T6G_MB_LIB.T6G(SCH_1):PAGE37
   N74 M_A_CPU1_SA_DQS_DP<1> @T6G_MB_LIB.T6G(SCH_1):M_A_CPU1_SA_DQS_DP(1)   I167 @T6G_MB_LIB.T6G(SCH_1):PAGE37
  AH72 M_A_CPU1_SA_DQ<29> @T6G_MB_LIB.T6G(SCH_1):M_A_CPU1_SA_DQ(29)   I167 @T6G_MB_LIB.T6G(SCH_1):PAGE37
   V74 M_A_CPU1_SA_DQ<18> @T6G_MB_LIB.T6G(SCH_1):M_A_CPU1_SA_DQ(18)   I167 @T6G_MB_LIB.T6G(SCH_1):PAGE37
  AY72 M_A_CPU1_SA_CA<2> @T6G_MB_LIB.T6G(SCH_1):M_A_CPU1_SA_CA(2)   I167 @T6G_MB_LIB.T6G(SCH_1):PAGE37
  CE74 M_A_CPU1_SB_DQS_DN<0> @T6G_MB_LIB.T6G(SCH_1):M_A_CPU1_SB_DQS_DN(0)   I167 @T6G_MB_LIB.T6G(SCH_1):PAGE37
  CY74 M_A_CPU1_SB_DQ<24> @T6G_MB_LIB.T6G(SCH_1):M_A_CPU1_SB_DQ(24)   I167 @T6G_MB_LIB.T6G(SCH_1):PAGE37
  CN73 M_A_CPU1_SB_DQ<13> @T6G_MB_LIB.T6G(SCH_1):M_A_CPU1_SB_DQ(13)   I167 @T6G_MB_LIB.T6G(SCH_1):PAGE37
  BT74 M_A_CPU1_SB_CB<4> @T6G_MB_LIB.T6G(SCH_1):M_A_CPU1_SB_CB(4)   I167 @T6G_MB_LIB.T6G(SCH_1):PAGE37
  BH74 M_A_CPU1_SB_CA<2> @T6G_MB_LIB.T6G(SCH_1):M_A_CPU1_SB_CA(2)   I167 @T6G_MB_LIB.T6G(SCH_1):PAGE37
   P72 M_A_CPU1_SA_DQS_DN<6> @T6G_MB_LIB.T6G(SCH_1):M_A_CPU1_SA_DQS_DN(6)   I167 @T6G_MB_LIB.T6G(SCH_1):PAGE37
   W74 M_A_CPU1_SA_DQS_DP<2> @T6G_MB_LIB.T6G(SCH_1):M_A_CPU1_SA_DQS_DP(2)   I167 @T6G_MB_LIB.T6G(SCH_1):PAGE37
   W73 M_A_CPU1_SA_DQ<19> @T6G_MB_LIB.T6G(SCH_1):M_A_CPU1_SA_DQ(19)   I167 @T6G_MB_LIB.T6G(SCH_1):PAGE37
  BA73 M_A_CPU1_SA_CA<3> @T6G_MB_LIB.T6G(SCH_1):M_A_CPU1_SA_CA(3)   I167 @T6G_MB_LIB.T6G(SCH_1):PAGE37
  CL74 M_A_CPU1_SB_DQS_DN<1> @T6G_MB_LIB.T6G(SCH_1):M_A_CPU1_SB_DQS_DN(1)   I167 @T6G_MB_LIB.T6G(SCH_1):PAGE37
  DA73 M_A_CPU1_SB_DQ<25> @T6G_MB_LIB.T6G(SCH_1):M_A_CPU1_SB_DQ(25)   I167 @T6G_MB_LIB.T6G(SCH_1):PAGE37
  CN74 M_A_CPU1_SB_DQ<14> @T6G_MB_LIB.T6G(SCH_1):M_A_CPU1_SB_DQ(14)   I167 @T6G_MB_LIB.T6G(SCH_1):PAGE37
  BU73 M_A_CPU1_SB_CB<5> @T6G_MB_LIB.T6G(SCH_1):M_A_CPU1_SB_CB(5)   I167 @T6G_MB_LIB.T6G(SCH_1):PAGE37
  BJ74 M_A_CPU1_SB_CA<3> @T6G_MB_LIB.T6G(SCH_1):M_A_CPU1_SB_CA(3)   I167 @T6G_MB_LIB.T6G(SCH_1):PAGE37
   Y72 M_A_CPU1_SA_DQS_DN<7> @T6G_MB_LIB.T6G(SCH_1):M_A_CPU1_SA_DQS_DN(7)   I167 @T6G_MB_LIB.T6G(SCH_1):PAGE37
  AE74 M_A_CPU1_SA_DQS_DP<3> @T6G_MB_LIB.T6G(SCH_1):M_A_CPU1_SA_DQS_DP(3)   I167 @T6G_MB_LIB.T6G(SCH_1):PAGE37
   E74 M_A_CPU1_SA_DQ<0> @T6G_MB_LIB.T6G(SCH_1):M_A_CPU1_SA_DQ(0)   I167 @T6G_MB_LIB.T6G(SCH_1):PAGE37
  BA74 M_A_CPU1_SA_CA<4> @T6G_MB_LIB.T6G(SCH_1):M_A_CPU1_SA_CA(4)   I167 @T6G_MB_LIB.T6G(SCH_1):PAGE37
  CU74 M_A_CPU1_SB_DQS_DN<2> @T6G_MB_LIB.T6G(SCH_1):M_A_CPU1_SB_DQS_DN(2)   I167 @T6G_MB_LIB.T6G(SCH_1):PAGE37
  DA74 M_A_CPU1_SB_DQ<26> @T6G_MB_LIB.T6G(SCH_1):M_A_CPU1_SB_DQ(26)   I167 @T6G_MB_LIB.T6G(SCH_1):PAGE37
  CP72 M_A_CPU1_SB_DQ<15> @T6G_MB_LIB.T6G(SCH_1):M_A_CPU1_SB_DQ(15)   I167 @T6G_MB_LIB.T6G(SCH_1):PAGE37
  CB74 M_A_CPU1_SB_DQ<0> @T6G_MB_LIB.T6G(SCH_1):M_A_CPU1_SB_DQ(0)   I167 @T6G_MB_LIB.T6G(SCH_1):PAGE37
  BU74 M_A_CPU1_SB_CB<6> @T6G_MB_LIB.T6G(SCH_1):M_A_CPU1_SB_CB(6)   I167 @T6G_MB_LIB.T6G(SCH_1):PAGE37
  BJ73 M_A_CPU1_SB_CA<4> @T6G_MB_LIB.T6G(SCH_1):M_A_CPU1_SB_CA(4)   I167 @T6G_MB_LIB.T6G(SCH_1):PAGE37
  BP74 M_A_CPU1_SB_RSP<0> @T6G_MB_LIB.T6G(SCH_1):M_A_CPU1_SB_RSP(0)   I167 @T6G_MB_LIB.T6G(SCH_1):PAGE37
  AF72 M_A_CPU1_SA_DQS_DN<8> @T6G_MB_LIB.T6G(SCH_1):M_A_CPU1_SA_DQS_DN(8)   I167 @T6G_MB_LIB.T6G(SCH_1):PAGE37
  AL74 M_A_CPU1_SA_DQS_DP<4> @T6G_MB_LIB.T6G(SCH_1):M_A_CPU1_SA_DQS_DP(4)   I167 @T6G_MB_LIB.T6G(SCH_1):PAGE37
   F72 M_A_CPU1_SA_DQ<1> @T6G_MB_LIB.T6G(SCH_1):M_A_CPU1_SA_DQ(1)   I167 @T6G_MB_LIB.T6G(SCH_1):PAGE37
  BB74 M_A_CPU1_SA_CA<5> @T6G_MB_LIB.T6G(SCH_1):M_A_CPU1_SA_CA(5)   I167 @T6G_MB_LIB.T6G(SCH_1):PAGE37
  DC74 M_A_CPU1_SB_DQS_DN<3> @T6G_MB_LIB.T6G(SCH_1):M_A_CPU1_SB_DQS_DN(3)   I167 @T6G_MB_LIB.T6G(SCH_1):PAGE37
  DB72 M_A_CPU1_SB_DQ<27> @T6G_MB_LIB.T6G(SCH_1):M_A_CPU1_SB_DQ(27)   I167 @T6G_MB_LIB.T6G(SCH_1):PAGE37
  CP74 M_A_CPU1_SB_DQ<16> @T6G_MB_LIB.T6G(SCH_1):M_A_CPU1_SB_DQ(16)   I167 @T6G_MB_LIB.T6G(SCH_1):PAGE37
  CC73 M_A_CPU1_SB_DQ<1> @T6G_MB_LIB.T6G(SCH_1):M_A_CPU1_SB_DQ(1)   I167 @T6G_MB_LIB.T6G(SCH_1):PAGE37
  BV72 M_A_CPU1_SB_CB<7> @T6G_MB_LIB.T6G(SCH_1):M_A_CPU1_SB_CB(7)   I167 @T6G_MB_LIB.T6G(SCH_1):PAGE37
  BK72 M_A_CPU1_SB_CA<5> @T6G_MB_LIB.T6G(SCH_1):M_A_CPU1_SB_CA(5)   I167 @T6G_MB_LIB.T6G(SCH_1):PAGE37
  BR74     NC     NC   I167 @T6G_MB_LIB.T6G(SCH_1):PAGE37
  AM72 M_A_CPU1_SA_DQS_DN<9> @T6G_MB_LIB.T6G(SCH_1):M_A_CPU1_SA_DQS_DN(9)   I167 @T6G_MB_LIB.T6G(SCH_1):PAGE37
   J73 M_A_CPU1_SA_DQS_DP<5> @T6G_MB_LIB.T6G(SCH_1):M_A_CPU1_SA_DQS_DP(5)   I167 @T6G_MB_LIB.T6G(SCH_1):PAGE37
   F74 M_A_CPU1_SA_DQ<2> @T6G_MB_LIB.T6G(SCH_1):M_A_CPU1_SA_DQ(2)   I167 @T6G_MB_LIB.T6G(SCH_1):PAGE37
  BB72 M_A_CPU1_SA_CA<6> @T6G_MB_LIB.T6G(SCH_1):M_A_CPU1_SA_CA(6)   I167 @T6G_MB_LIB.T6G(SCH_1):PAGE37
  BW73 M_A_CPU1_SB_DQS_DN<4> @T6G_MB_LIB.T6G(SCH_1):M_A_CPU1_SB_DQS_DN(4)   I167 @T6G_MB_LIB.T6G(SCH_1):PAGE37
  CD74 M_A_CPU1_SB_DQS_DP<0> @T6G_MB_LIB.T6G(SCH_1):M_A_CPU1_SB_DQS_DP(0)   I167 @T6G_MB_LIB.T6G(SCH_1):PAGE37
  DD74 M_A_CPU1_SB_DQ<28> @T6G_MB_LIB.T6G(SCH_1):M_A_CPU1_SB_DQ(28)   I167 @T6G_MB_LIB.T6G(SCH_1):PAGE37
  CR73 M_A_CPU1_SB_DQ<17> @T6G_MB_LIB.T6G(SCH_1):M_A_CPU1_SB_DQ(17)   I167 @T6G_MB_LIB.T6G(SCH_1):PAGE37
  CC74 M_A_CPU1_SB_DQ<2> @T6G_MB_LIB.T6G(SCH_1):M_A_CPU1_SB_DQ(2)   I167 @T6G_MB_LIB.T6G(SCH_1):PAGE37
  BK74 M_A_CPU1_SB_CA<6> @T6G_MB_LIB.T6G(SCH_1):M_A_CPU1_SB_CA(6)   I167 @T6G_MB_LIB.T6G(SCH_1):PAGE37
   R73 M_A_CPU1_SA_DQS_DP<6> @T6G_MB_LIB.T6G(SCH_1):M_A_CPU1_SA_DQS_DP(6)   I167 @T6G_MB_LIB.T6G(SCH_1):PAGE37
   G73 M_A_CPU1_SA_DQ<3> @T6G_MB_LIB.T6G(SCH_1):M_A_CPU1_SA_DQ(3)   I167 @T6G_MB_LIB.T6G(SCH_1):PAGE37
  AV74 M_A_CPU1_SA_CS_N<0> @T6G_MB_LIB.T6G(SCH_1):M_A_CPU1_SA_CS_N(0)   I167 @T6G_MB_LIB.T6G(SCH_1):PAGE37
  BC73 M_A_CPU1_SA_PAR @T6G_MB_LIB.T6G(SCH_1):M_A_CPU1_SA_PAR   I167 @T6G_MB_LIB.T6G(SCH_1):PAGE37
  BL74 M_A_CPU1_SB_PAR @T6G_MB_LIB.T6G(SCH_1):M_A_CPU1_SB_PAR   I167 @T6G_MB_LIB.T6G(SCH_1):PAGE37
  BC74 M_A_CPU1_CLK_DP<0> @T6G_MB_LIB.T6G(SCH_1):M_A_CPU1_CLK_DP(0)   I167 @T6G_MB_LIB.T6G(SCH_1):PAGE37
  BV74 M_A_CPU1_SB_DQS_DP<9> @T6G_MB_LIB.T6G(SCH_1):M_A_CPU1_SB_DQS_DP(9)   I167 @T6G_MB_LIB.T6G(SCH_1):PAGE37
  BF74     NC     NC   I167 @T6G_MB_LIB.T6G(SCH_1):PAGE37
  BD74 M_A_CPU1_CLK_DN<0> @T6G_MB_LIB.T6G(SCH_1):M_A_CPU1_CLK_DN(0)   I167 @T6G_MB_LIB.T6G(SCH_1):PAGE37
  BG74     NC     NC   I167 @T6G_MB_LIB.T6G(SCH_1):PAGE37
  BF72 TP_M_A_CPU1_SA_TEST39A @T6G_MB_LIB.T6G(SCH_1):TP_M_A_CPU1_SA_TEST39A   I167 @T6G_MB_LIB.T6G(SCH_1):PAGE37
   C60 TP_M_A_CPU1_SA_TEST40 @T6G_MB_LIB.T6G(SCH_1):TP_M_A_CPU1_SA_TEST40   I167 @T6G_MB_LIB.T6G(SCH_1):PAGE37
  AT62 M_B_CPU1_ALERT_R_N @T6G_MB_LIB.T6G(SCH_1):M_B_CPU1_ALERT_R_N   I159 @T6G_MB_LIB.T6G(SCH_1):PAGE38
  AU62 M_B_CPU1_RESET_N @T6G_MB_LIB.T6G(SCH_1):M_B_CPU1_RESET_N   I159 @T6G_MB_LIB.T6G(SCH_1):PAGE38
  BW64 M_B_CPU1_SB_DQS_DN<9> @T6G_MB_LIB.T6G(SCH_1):M_B_CPU1_SB_DQS_DN(9)   I159 @T6G_MB_LIB.T6G(SCH_1):PAGE38
  CF62 M_B_CPU1_SB_DQS_DP<5> @T6G_MB_LIB.T6G(SCH_1):M_B_CPU1_SB_DQS_DP(5)   I159 @T6G_MB_LIB.T6G(SCH_1):PAGE38
  AB63 M_B_CPU1_SA_DQ<22> @T6G_MB_LIB.T6G(SCH_1):M_B_CPU1_SA_DQ(22)   I159 @T6G_MB_LIB.T6G(SCH_1):PAGE38
   N62 M_B_CPU1_SA_DQ<11> @T6G_MB_LIB.T6G(SCH_1):M_B_CPU1_SA_DQ(11)   I159 @T6G_MB_LIB.T6G(SCH_1):PAGE38
  AK63 M_B_CPU1_SA_CB<2> @T6G_MB_LIB.T6G(SCH_1):M_B_CPU1_SA_CB(2)   I159 @T6G_MB_LIB.T6G(SCH_1):PAGE38
  CM62 M_B_CPU1_SB_DQS_DP<6> @T6G_MB_LIB.T6G(SCH_1):M_B_CPU1_SB_DQS_DP(6)   I159 @T6G_MB_LIB.T6G(SCH_1):PAGE38
  AC62 M_B_CPU1_SA_DQ<23> @T6G_MB_LIB.T6G(SCH_1):M_B_CPU1_SA_DQ(23)   I159 @T6G_MB_LIB.T6G(SCH_1):PAGE38
   R64 M_B_CPU1_SA_DQ<12> @T6G_MB_LIB.T6G(SCH_1):M_B_CPU1_SA_DQ(12)   I159 @T6G_MB_LIB.T6G(SCH_1):PAGE38
  AL62 M_B_CPU1_SA_CB<3> @T6G_MB_LIB.T6G(SCH_1):M_B_CPU1_SA_CB(3)   I159 @T6G_MB_LIB.T6G(SCH_1):PAGE38
  CV62 M_B_CPU1_SB_DQS_DP<7> @T6G_MB_LIB.T6G(SCH_1):M_B_CPU1_SB_DQS_DP(7)   I159 @T6G_MB_LIB.T6G(SCH_1):PAGE38
  BM62 M_B_CPU1_SB_CS_N<0> @T6G_MB_LIB.T6G(SCH_1):M_B_CPU1_SB_CS_N(0)   I159 @T6G_MB_LIB.T6G(SCH_1):PAGE38
   H63 M_B_CPU1_SA_DQS_DN<0> @T6G_MB_LIB.T6G(SCH_1):M_B_CPU1_SA_DQS_DN(0)   I159 @T6G_MB_LIB.T6G(SCH_1):PAGE38
   T62 M_B_CPU1_SA_DQ<13> @T6G_MB_LIB.T6G(SCH_1):M_B_CPU1_SA_DQ(13)   I159 @T6G_MB_LIB.T6G(SCH_1):PAGE38
   E64 M_B_CPU1_SA_DQ<0> @T6G_MB_LIB.T6G(SCH_1):M_B_CPU1_SA_DQ(0)   I159 @T6G_MB_LIB.T6G(SCH_1):PAGE38
  AN64 M_B_CPU1_SA_CB<4> @T6G_MB_LIB.T6G(SCH_1):M_B_CPU1_SA_CB(4)   I159 @T6G_MB_LIB.T6G(SCH_1):PAGE38
  DD62 M_B_CPU1_SB_DQS_DP<8> @T6G_MB_LIB.T6G(SCH_1):M_B_CPU1_SB_DQS_DP(8)   I159 @T6G_MB_LIB.T6G(SCH_1):PAGE38
  DE64 M_B_CPU1_SB_DQ<30> @T6G_MB_LIB.T6G(SCH_1):M_B_CPU1_SB_DQ(30)   I159 @T6G_MB_LIB.T6G(SCH_1):PAGE38
  CB63 M_B_CPU1_SB_DQ<0> @T6G_MB_LIB.T6G(SCH_1):M_B_CPU1_SB_DQ(0)   I159 @T6G_MB_LIB.T6G(SCH_1):PAGE38
  BL62     NC     NC   I159 @T6G_MB_LIB.T6G(SCH_1):PAGE38
  BN64 M_B_CPU1_SB_CS_N<1> @T6G_MB_LIB.T6G(SCH_1):M_B_CPU1_SB_CS_N(1)   I159 @T6G_MB_LIB.T6G(SCH_1):PAGE38
   P63 M_B_CPU1_SA_DQS_DN<1> @T6G_MB_LIB.T6G(SCH_1):M_B_CPU1_SA_DQS_DN(1)   I159 @T6G_MB_LIB.T6G(SCH_1):PAGE38
  AD62 M_B_CPU1_SA_DQ<25> @T6G_MB_LIB.T6G(SCH_1):M_B_CPU1_SA_DQ(25)   I159 @T6G_MB_LIB.T6G(SCH_1):PAGE38
   T63 M_B_CPU1_SA_DQ<14> @T6G_MB_LIB.T6G(SCH_1):M_B_CPU1_SA_DQ(14)   I159 @T6G_MB_LIB.T6G(SCH_1):PAGE38
   F62 M_B_CPU1_SA_DQ<1> @T6G_MB_LIB.T6G(SCH_1):M_B_CPU1_SA_DQ(1)   I159 @T6G_MB_LIB.T6G(SCH_1):PAGE38
  AP62 M_B_CPU1_SA_CB<5> @T6G_MB_LIB.T6G(SCH_1):M_B_CPU1_SA_CB(5)   I159 @T6G_MB_LIB.T6G(SCH_1):PAGE38
  DF62 M_B_CPU1_SB_DQ<31> @T6G_MB_LIB.T6G(SCH_1):M_B_CPU1_SB_DQ(31)   I159 @T6G_MB_LIB.T6G(SCH_1):PAGE38
  CC62 M_B_CPU1_SB_DQ<1> @T6G_MB_LIB.T6G(SCH_1):M_B_CPU1_SB_DQ(1)   I159 @T6G_MB_LIB.T6G(SCH_1):PAGE38
  BY63 M_B_CPU1_SB_CB<0> @T6G_MB_LIB.T6G(SCH_1):M_B_CPU1_SB_CB(0)   I159 @T6G_MB_LIB.T6G(SCH_1):PAGE38
  BM63     NC     NC   I159 @T6G_MB_LIB.T6G(SCH_1):PAGE38
   Y63 M_B_CPU1_SA_DQS_DN<2> @T6G_MB_LIB.T6G(SCH_1):M_B_CPU1_SA_DQS_DN(2)   I159 @T6G_MB_LIB.T6G(SCH_1):PAGE38
  AD63 M_B_CPU1_SA_DQ<26> @T6G_MB_LIB.T6G(SCH_1):M_B_CPU1_SA_DQ(26)   I159 @T6G_MB_LIB.T6G(SCH_1):PAGE38
   U62 M_B_CPU1_SA_DQ<15> @T6G_MB_LIB.T6G(SCH_1):M_B_CPU1_SA_DQ(15)   I159 @T6G_MB_LIB.T6G(SCH_1):PAGE38
   F63 M_B_CPU1_SA_DQ<2> @T6G_MB_LIB.T6G(SCH_1):M_B_CPU1_SA_DQ(2)   I159 @T6G_MB_LIB.T6G(SCH_1):PAGE38
  AP63 M_B_CPU1_SA_CB<6> @T6G_MB_LIB.T6G(SCH_1):M_B_CPU1_SA_CB(6)   I159 @T6G_MB_LIB.T6G(SCH_1):PAGE38
  CW62 M_B_CPU1_SB_DQ<21> @T6G_MB_LIB.T6G(SCH_1):M_B_CPU1_SB_DQ(21)   I159 @T6G_MB_LIB.T6G(SCH_1):PAGE38
  CJ64 M_B_CPU1_SB_DQ<10> @T6G_MB_LIB.T6G(SCH_1):M_B_CPU1_SB_DQ(10)   I159 @T6G_MB_LIB.T6G(SCH_1):PAGE38
  CC64 M_B_CPU1_SB_DQ<2> @T6G_MB_LIB.T6G(SCH_1):M_B_CPU1_SB_DQ(2)   I159 @T6G_MB_LIB.T6G(SCH_1):PAGE38
  CA62 M_B_CPU1_SB_CB<1> @T6G_MB_LIB.T6G(SCH_1):M_B_CPU1_SB_CB(1)   I159 @T6G_MB_LIB.T6G(SCH_1):PAGE38
  AF63 M_B_CPU1_SA_DQS_DN<3> @T6G_MB_LIB.T6G(SCH_1):M_B_CPU1_SA_DQS_DN(3)   I159 @T6G_MB_LIB.T6G(SCH_1):PAGE38
  AE62 M_B_CPU1_SA_DQ<27> @T6G_MB_LIB.T6G(SCH_1):M_B_CPU1_SA_DQ(27)   I159 @T6G_MB_LIB.T6G(SCH_1):PAGE38
   U64 M_B_CPU1_SA_DQ<16> @T6G_MB_LIB.T6G(SCH_1):M_B_CPU1_SA_DQ(16)   I159 @T6G_MB_LIB.T6G(SCH_1):PAGE38
   G62 M_B_CPU1_SA_DQ<3> @T6G_MB_LIB.T6G(SCH_1):M_B_CPU1_SA_DQ(3)   I159 @T6G_MB_LIB.T6G(SCH_1):PAGE38
  AR62 M_B_CPU1_SA_CB<7> @T6G_MB_LIB.T6G(SCH_1):M_B_CPU1_SA_CB(7)   I159 @T6G_MB_LIB.T6G(SCH_1):PAGE38
  BN62 M_B_CPU1_SA_RSP<0> @T6G_MB_LIB.T6G(SCH_1):M_B_CPU1_SA_RSP(0)   I159 @T6G_MB_LIB.T6G(SCH_1):PAGE38
  CW64 M_B_CPU1_SB_DQ<22> @T6G_MB_LIB.T6G(SCH_1):M_B_CPU1_SB_DQ(22)   I159 @T6G_MB_LIB.T6G(SCH_1):PAGE38
  CK62 M_B_CPU1_SB_DQ<11> @T6G_MB_LIB.T6G(SCH_1):M_B_CPU1_SB_DQ(11)   I159 @T6G_MB_LIB.T6G(SCH_1):PAGE38
  CD62 M_B_CPU1_SB_DQ<3> @T6G_MB_LIB.T6G(SCH_1):M_B_CPU1_SB_DQ(3)   I159 @T6G_MB_LIB.T6G(SCH_1):PAGE38
  CA64 M_B_CPU1_SB_CB<2> @T6G_MB_LIB.T6G(SCH_1):M_B_CPU1_SB_CB(2)   I159 @T6G_MB_LIB.T6G(SCH_1):PAGE38
  AM63 M_B_CPU1_SA_DQS_DN<4> @T6G_MB_LIB.T6G(SCH_1):M_B_CPU1_SA_DQS_DN(4)   I159 @T6G_MB_LIB.T6G(SCH_1):PAGE38
   G64 M_B_CPU1_SA_DQS_DP<0> @T6G_MB_LIB.T6G(SCH_1):M_B_CPU1_SA_DQS_DP(0)   I159 @T6G_MB_LIB.T6G(SCH_1):PAGE38
  AG64 M_B_CPU1_SA_DQ<28> @T6G_MB_LIB.T6G(SCH_1):M_B_CPU1_SA_DQ(28)   I159 @T6G_MB_LIB.T6G(SCH_1):PAGE38
   V62 M_B_CPU1_SA_DQ<17> @T6G_MB_LIB.T6G(SCH_1):M_B_CPU1_SA_DQ(17)   I159 @T6G_MB_LIB.T6G(SCH_1):PAGE38
   J64 M_B_CPU1_SA_DQ<4> @T6G_MB_LIB.T6G(SCH_1):M_B_CPU1_SA_DQ(4)   I159 @T6G_MB_LIB.T6G(SCH_1):PAGE38
  BP62     NC     NC   I159 @T6G_MB_LIB.T6G(SCH_1):PAGE38
  CY62 M_B_CPU1_SB_DQ<23> @T6G_MB_LIB.T6G(SCH_1):M_B_CPU1_SB_DQ(23)   I159 @T6G_MB_LIB.T6G(SCH_1):PAGE38
  CM63 M_B_CPU1_SB_DQ<12> @T6G_MB_LIB.T6G(SCH_1):M_B_CPU1_SB_DQ(12)   I159 @T6G_MB_LIB.T6G(SCH_1):PAGE38
  CF63 M_B_CPU1_SB_DQ<4> @T6G_MB_LIB.T6G(SCH_1):M_B_CPU1_SB_DQ(4)   I159 @T6G_MB_LIB.T6G(SCH_1):PAGE38
  CB62 M_B_CPU1_SB_CB<3> @T6G_MB_LIB.T6G(SCH_1):M_B_CPU1_SB_CB(3)   I159 @T6G_MB_LIB.T6G(SCH_1):PAGE38
   H62 M_B_CPU1_SA_DQS_DN<5> @T6G_MB_LIB.T6G(SCH_1):M_B_CPU1_SA_DQS_DN(5)   I159 @T6G_MB_LIB.T6G(SCH_1):PAGE38
   N64 M_B_CPU1_SA_DQS_DP<1> @T6G_MB_LIB.T6G(SCH_1):M_B_CPU1_SA_DQS_DP(1)   I159 @T6G_MB_LIB.T6G(SCH_1):PAGE38
  AH62 M_B_CPU1_SA_DQ<29> @T6G_MB_LIB.T6G(SCH_1):M_B_CPU1_SA_DQ(29)   I159 @T6G_MB_LIB.T6G(SCH_1):PAGE38
   V63 M_B_CPU1_SA_DQ<18> @T6G_MB_LIB.T6G(SCH_1):M_B_CPU1_SA_DQ(18)   I159 @T6G_MB_LIB.T6G(SCH_1):PAGE38
   K62 M_B_CPU1_SA_DQ<5> @T6G_MB_LIB.T6G(SCH_1):M_B_CPU1_SA_DQ(5)   I159 @T6G_MB_LIB.T6G(SCH_1):PAGE38
  CE64 M_B_CPU1_SB_DQS_DN<0> @T6G_MB_LIB.T6G(SCH_1):M_B_CPU1_SB_DQS_DN(0)   I159 @T6G_MB_LIB.T6G(SCH_1):PAGE38
  CY63 M_B_CPU1_SB_DQ<24> @T6G_MB_LIB.T6G(SCH_1):M_B_CPU1_SB_DQ(24)   I159 @T6G_MB_LIB.T6G(SCH_1):PAGE38
  CN62 M_B_CPU1_SB_DQ<13> @T6G_MB_LIB.T6G(SCH_1):M_B_CPU1_SB_DQ(13)   I159 @T6G_MB_LIB.T6G(SCH_1):PAGE38
  CG62 M_B_CPU1_SB_DQ<5> @T6G_MB_LIB.T6G(SCH_1):M_B_CPU1_SB_DQ(5)   I159 @T6G_MB_LIB.T6G(SCH_1):PAGE38
  BT63 M_B_CPU1_SB_CB<4> @T6G_MB_LIB.T6G(SCH_1):M_B_CPU1_SB_CB(4)   I159 @T6G_MB_LIB.T6G(SCH_1):PAGE38
   P62 M_B_CPU1_SA_DQS_DN<6> @T6G_MB_LIB.T6G(SCH_1):M_B_CPU1_SA_DQS_DN(6)   I159 @T6G_MB_LIB.T6G(SCH_1):PAGE38
   W64 M_B_CPU1_SA_DQS_DP<2> @T6G_MB_LIB.T6G(SCH_1):M_B_CPU1_SA_DQS_DP(2)   I159 @T6G_MB_LIB.T6G(SCH_1):PAGE38
   W62 M_B_CPU1_SA_DQ<19> @T6G_MB_LIB.T6G(SCH_1):M_B_CPU1_SA_DQ(19)   I159 @T6G_MB_LIB.T6G(SCH_1):PAGE38
   K63 M_B_CPU1_SA_DQ<6> @T6G_MB_LIB.T6G(SCH_1):M_B_CPU1_SA_DQ(6)   I159 @T6G_MB_LIB.T6G(SCH_1):PAGE38
  AW64 M_B_CPU1_SA_CA<0> @T6G_MB_LIB.T6G(SCH_1):M_B_CPU1_SA_CA(0)   I159 @T6G_MB_LIB.T6G(SCH_1):PAGE38
  CL64 M_B_CPU1_SB_DQS_DN<1> @T6G_MB_LIB.T6G(SCH_1):M_B_CPU1_SB_DQS_DN(1)   I159 @T6G_MB_LIB.T6G(SCH_1):PAGE38
  DA62 M_B_CPU1_SB_DQ<25> @T6G_MB_LIB.T6G(SCH_1):M_B_CPU1_SB_DQ(25)   I159 @T6G_MB_LIB.T6G(SCH_1):PAGE38
  CN64 M_B_CPU1_SB_DQ<14> @T6G_MB_LIB.T6G(SCH_1):M_B_CPU1_SB_DQ(14)   I159 @T6G_MB_LIB.T6G(SCH_1):PAGE38
  CG64 M_B_CPU1_SB_DQ<6> @T6G_MB_LIB.T6G(SCH_1):M_B_CPU1_SB_DQ(6)   I159 @T6G_MB_LIB.T6G(SCH_1):PAGE38
  BU62 M_B_CPU1_SB_CB<5> @T6G_MB_LIB.T6G(SCH_1):M_B_CPU1_SB_CB(5)   I159 @T6G_MB_LIB.T6G(SCH_1):PAGE38
  BG62 M_B_CPU1_SB_CA<0> @T6G_MB_LIB.T6G(SCH_1):M_B_CPU1_SB_CA(0)   I159 @T6G_MB_LIB.T6G(SCH_1):PAGE38
   Y62 M_B_CPU1_SA_DQS_DN<7> @T6G_MB_LIB.T6G(SCH_1):M_B_CPU1_SA_DQS_DN(7)   I159 @T6G_MB_LIB.T6G(SCH_1):PAGE38
  AE64 M_B_CPU1_SA_DQS_DP<3> @T6G_MB_LIB.T6G(SCH_1):M_B_CPU1_SA_DQS_DP(3)   I159 @T6G_MB_LIB.T6G(SCH_1):PAGE38
   L62 M_B_CPU1_SA_DQ<7> @T6G_MB_LIB.T6G(SCH_1):M_B_CPU1_SA_DQ(7)   I159 @T6G_MB_LIB.T6G(SCH_1):PAGE38
  AY63 M_B_CPU1_SA_CA<1> @T6G_MB_LIB.T6G(SCH_1):M_B_CPU1_SA_CA(1)   I159 @T6G_MB_LIB.T6G(SCH_1):PAGE38
  CU64 M_B_CPU1_SB_DQS_DN<2> @T6G_MB_LIB.T6G(SCH_1):M_B_CPU1_SB_DQS_DN(2)   I159 @T6G_MB_LIB.T6G(SCH_1):PAGE38
  DA64 M_B_CPU1_SB_DQ<26> @T6G_MB_LIB.T6G(SCH_1):M_B_CPU1_SB_DQ(26)   I159 @T6G_MB_LIB.T6G(SCH_1):PAGE38
  CP62 M_B_CPU1_SB_DQ<15> @T6G_MB_LIB.T6G(SCH_1):M_B_CPU1_SB_DQ(15)   I159 @T6G_MB_LIB.T6G(SCH_1):PAGE38
  CH62 M_B_CPU1_SB_DQ<7> @T6G_MB_LIB.T6G(SCH_1):M_B_CPU1_SB_DQ(7)   I159 @T6G_MB_LIB.T6G(SCH_1):PAGE38
  BU64 M_B_CPU1_SB_CB<6> @T6G_MB_LIB.T6G(SCH_1):M_B_CPU1_SB_CB(6)   I159 @T6G_MB_LIB.T6G(SCH_1):PAGE38
  BH62 M_B_CPU1_SB_CA<1> @T6G_MB_LIB.T6G(SCH_1):M_B_CPU1_SB_CA(1)   I159 @T6G_MB_LIB.T6G(SCH_1):PAGE38
  AF62 M_B_CPU1_SA_DQS_DN<8> @T6G_MB_LIB.T6G(SCH_1):M_B_CPU1_SA_DQS_DN(8)   I159 @T6G_MB_LIB.T6G(SCH_1):PAGE38
  AL64 M_B_CPU1_SA_DQS_DP<4> @T6G_MB_LIB.T6G(SCH_1):M_B_CPU1_SA_DQS_DP(4)   I159 @T6G_MB_LIB.T6G(SCH_1):PAGE38
   L64 M_B_CPU1_SA_DQ<8> @T6G_MB_LIB.T6G(SCH_1):M_B_CPU1_SA_DQ(8)   I159 @T6G_MB_LIB.T6G(SCH_1):PAGE38
  AY62 M_B_CPU1_SA_CA<2> @T6G_MB_LIB.T6G(SCH_1):M_B_CPU1_SA_CA(2)   I159 @T6G_MB_LIB.T6G(SCH_1):PAGE38
  DC64 M_B_CPU1_SB_DQS_DN<3> @T6G_MB_LIB.T6G(SCH_1):M_B_CPU1_SB_DQS_DN(3)   I159 @T6G_MB_LIB.T6G(SCH_1):PAGE38
  DB62 M_B_CPU1_SB_DQ<27> @T6G_MB_LIB.T6G(SCH_1):M_B_CPU1_SB_DQ(27)   I159 @T6G_MB_LIB.T6G(SCH_1):PAGE38
  CP63 M_B_CPU1_SB_DQ<16> @T6G_MB_LIB.T6G(SCH_1):M_B_CPU1_SB_DQ(16)   I159 @T6G_MB_LIB.T6G(SCH_1):PAGE38
  CH63 M_B_CPU1_SB_DQ<8> @T6G_MB_LIB.T6G(SCH_1):M_B_CPU1_SB_DQ(8)   I159 @T6G_MB_LIB.T6G(SCH_1):PAGE38
  BV62 M_B_CPU1_SB_CB<7> @T6G_MB_LIB.T6G(SCH_1):M_B_CPU1_SB_CB(7)   I159 @T6G_MB_LIB.T6G(SCH_1):PAGE38
  BH63 M_B_CPU1_SB_CA<2> @T6G_MB_LIB.T6G(SCH_1):M_B_CPU1_SB_CA(2)   I159 @T6G_MB_LIB.T6G(SCH_1):PAGE38
  BP63 M_B_CPU1_SB_RSP<0> @T6G_MB_LIB.T6G(SCH_1):M_B_CPU1_SB_RSP(0)   I159 @T6G_MB_LIB.T6G(SCH_1):PAGE38
  AM62 M_B_CPU1_SA_DQS_DN<9> @T6G_MB_LIB.T6G(SCH_1):M_B_CPU1_SA_DQS_DN(9)   I159 @T6G_MB_LIB.T6G(SCH_1):PAGE38
   J62 M_B_CPU1_SA_DQS_DP<5> @T6G_MB_LIB.T6G(SCH_1):M_B_CPU1_SA_DQS_DP(5)   I159 @T6G_MB_LIB.T6G(SCH_1):PAGE38
   M62 M_B_CPU1_SA_DQ<9> @T6G_MB_LIB.T6G(SCH_1):M_B_CPU1_SA_DQ(9)   I159 @T6G_MB_LIB.T6G(SCH_1):PAGE38
  BA62 M_B_CPU1_SA_CA<3> @T6G_MB_LIB.T6G(SCH_1):M_B_CPU1_SA_CA(3)   I159 @T6G_MB_LIB.T6G(SCH_1):PAGE38
  BW62 M_B_CPU1_SB_DQS_DN<4> @T6G_MB_LIB.T6G(SCH_1):M_B_CPU1_SB_DQS_DN(4)   I159 @T6G_MB_LIB.T6G(SCH_1):PAGE38
  CD63 M_B_CPU1_SB_DQS_DP<0> @T6G_MB_LIB.T6G(SCH_1):M_B_CPU1_SB_DQS_DP(0)   I159 @T6G_MB_LIB.T6G(SCH_1):PAGE38
  DD63 M_B_CPU1_SB_DQ<28> @T6G_MB_LIB.T6G(SCH_1):M_B_CPU1_SB_DQ(28)   I159 @T6G_MB_LIB.T6G(SCH_1):PAGE38
  CR62 M_B_CPU1_SB_DQ<17> @T6G_MB_LIB.T6G(SCH_1):M_B_CPU1_SB_DQ(17)   I159 @T6G_MB_LIB.T6G(SCH_1):PAGE38
  CJ62 M_B_CPU1_SB_DQ<9> @T6G_MB_LIB.T6G(SCH_1):M_B_CPU1_SB_DQ(9)   I159 @T6G_MB_LIB.T6G(SCH_1):PAGE38
  BJ64 M_B_CPU1_SB_CA<3> @T6G_MB_LIB.T6G(SCH_1):M_B_CPU1_SB_CA(3)   I159 @T6G_MB_LIB.T6G(SCH_1):PAGE38
  BR64     NC     NC   I159 @T6G_MB_LIB.T6G(SCH_1):PAGE38
   R62 M_B_CPU1_SA_DQS_DP<6> @T6G_MB_LIB.T6G(SCH_1):M_B_CPU1_SA_DQS_DP(6)   I159 @T6G_MB_LIB.T6G(SCH_1):PAGE38
  BA64 M_B_CPU1_SA_CA<4> @T6G_MB_LIB.T6G(SCH_1):M_B_CPU1_SA_CA(4)   I159 @T6G_MB_LIB.T6G(SCH_1):PAGE38
  CE62 M_B_CPU1_SB_DQS_DN<5> @T6G_MB_LIB.T6G(SCH_1):M_B_CPU1_SB_DQS_DN(5)   I159 @T6G_MB_LIB.T6G(SCH_1):PAGE38
  CK63 M_B_CPU1_SB_DQS_DP<1> @T6G_MB_LIB.T6G(SCH_1):M_B_CPU1_SB_DQS_DP(1)   I159 @T6G_MB_LIB.T6G(SCH_1):PAGE38
  DE62 M_B_CPU1_SB_DQ<29> @T6G_MB_LIB.T6G(SCH_1):M_B_CPU1_SB_DQ(29)   I159 @T6G_MB_LIB.T6G(SCH_1):PAGE38
  CR64 M_B_CPU1_SB_DQ<18> @T6G_MB_LIB.T6G(SCH_1):M_B_CPU1_SB_DQ(18)   I159 @T6G_MB_LIB.T6G(SCH_1):PAGE38
  BJ62 M_B_CPU1_SB_CA<4> @T6G_MB_LIB.T6G(SCH_1):M_B_CPU1_SB_CA(4)   I159 @T6G_MB_LIB.T6G(SCH_1):PAGE38
  AA62 M_B_CPU1_SA_DQS_DP<7> @T6G_MB_LIB.T6G(SCH_1):M_B_CPU1_SA_DQS_DP(7)   I159 @T6G_MB_LIB.T6G(SCH_1):PAGE38
  BB63 M_B_CPU1_SA_CA<5> @T6G_MB_LIB.T6G(SCH_1):M_B_CPU1_SA_CA(5)   I159 @T6G_MB_LIB.T6G(SCH_1):PAGE38
  AV63 M_B_CPU1_SA_CS_N<0> @T6G_MB_LIB.T6G(SCH_1):M_B_CPU1_SA_CS_N(0)   I159 @T6G_MB_LIB.T6G(SCH_1):PAGE38
  CL62 M_B_CPU1_SB_DQS_DN<6> @T6G_MB_LIB.T6G(SCH_1):M_B_CPU1_SB_DQS_DN(6)   I159 @T6G_MB_LIB.T6G(SCH_1):PAGE38
  CT63 M_B_CPU1_SB_DQS_DP<2> @T6G_MB_LIB.T6G(SCH_1):M_B_CPU1_SB_DQS_DP(2)   I159 @T6G_MB_LIB.T6G(SCH_1):PAGE38
  BK62 M_B_CPU1_SB_CA<5> @T6G_MB_LIB.T6G(SCH_1):M_B_CPU1_SB_CA(5)   I159 @T6G_MB_LIB.T6G(SCH_1):PAGE38
  AG62 M_B_CPU1_SA_DQS_DP<8> @T6G_MB_LIB.T6G(SCH_1):M_B_CPU1_SA_DQS_DP(8)   I159 @T6G_MB_LIB.T6G(SCH_1):PAGE38
  AH63 M_B_CPU1_SA_DQ<30> @T6G_MB_LIB.T6G(SCH_1):M_B_CPU1_SA_DQ(30)   I159 @T6G_MB_LIB.T6G(SCH_1):PAGE38
  BB62 M_B_CPU1_SA_CA<6> @T6G_MB_LIB.T6G(SCH_1):M_B_CPU1_SA_CA(6)   I159 @T6G_MB_LIB.T6G(SCH_1):PAGE38
  AU64     NC     NC   I159 @T6G_MB_LIB.T6G(SCH_1):PAGE38
  AW62 M_B_CPU1_SA_CS_N<1> @T6G_MB_LIB.T6G(SCH_1):M_B_CPU1_SA_CS_N(1)   I159 @T6G_MB_LIB.T6G(SCH_1):PAGE38
  CU62 M_B_CPU1_SB_DQS_DN<7> @T6G_MB_LIB.T6G(SCH_1):M_B_CPU1_SB_DQS_DN(7)   I159 @T6G_MB_LIB.T6G(SCH_1):PAGE38
  DB63 M_B_CPU1_SB_DQS_DP<3> @T6G_MB_LIB.T6G(SCH_1):M_B_CPU1_SB_DQS_DP(3)   I159 @T6G_MB_LIB.T6G(SCH_1):PAGE38
  BK63 M_B_CPU1_SB_CA<6> @T6G_MB_LIB.T6G(SCH_1):M_B_CPU1_SB_CA(6)   I159 @T6G_MB_LIB.T6G(SCH_1):PAGE38
  AN62 M_B_CPU1_SA_DQS_DP<9> @T6G_MB_LIB.T6G(SCH_1):M_B_CPU1_SA_DQS_DP(9)   I159 @T6G_MB_LIB.T6G(SCH_1):PAGE38
  AJ62 M_B_CPU1_SA_DQ<31> @T6G_MB_LIB.T6G(SCH_1):M_B_CPU1_SA_DQ(31)   I159 @T6G_MB_LIB.T6G(SCH_1):PAGE38
  AA64 M_B_CPU1_SA_DQ<20> @T6G_MB_LIB.T6G(SCH_1):M_B_CPU1_SA_DQ(20)   I159 @T6G_MB_LIB.T6G(SCH_1):PAGE38
  AJ64 M_B_CPU1_SA_CB<0> @T6G_MB_LIB.T6G(SCH_1):M_B_CPU1_SA_CB(0)   I159 @T6G_MB_LIB.T6G(SCH_1):PAGE38
  AV62     NC     NC   I159 @T6G_MB_LIB.T6G(SCH_1):PAGE38
  DC62 M_B_CPU1_SB_DQS_DN<8> @T6G_MB_LIB.T6G(SCH_1):M_B_CPU1_SB_DQS_DN(8)   I159 @T6G_MB_LIB.T6G(SCH_1):PAGE38
  BY62 M_B_CPU1_SB_DQS_DP<4> @T6G_MB_LIB.T6G(SCH_1):M_B_CPU1_SB_DQS_DP(4)   I159 @T6G_MB_LIB.T6G(SCH_1):PAGE38
  AB62 M_B_CPU1_SA_DQ<21> @T6G_MB_LIB.T6G(SCH_1):M_B_CPU1_SA_DQ(21)   I159 @T6G_MB_LIB.T6G(SCH_1):PAGE38
   M63 M_B_CPU1_SA_DQ<10> @T6G_MB_LIB.T6G(SCH_1):M_B_CPU1_SA_DQ(10)   I159 @T6G_MB_LIB.T6G(SCH_1):PAGE38
  AK62 M_B_CPU1_SA_CB<1> @T6G_MB_LIB.T6G(SCH_1):M_B_CPU1_SA_CB(1)   I159 @T6G_MB_LIB.T6G(SCH_1):PAGE38
  BV63 M_B_CPU1_SB_DQS_DP<9> @T6G_MB_LIB.T6G(SCH_1):M_B_CPU1_SB_DQS_DP(9)   I159 @T6G_MB_LIB.T6G(SCH_1):PAGE38
  BC62 M_B_CPU1_SA_PAR @T6G_MB_LIB.T6G(SCH_1):M_B_CPU1_SA_PAR   I159 @T6G_MB_LIB.T6G(SCH_1):PAGE38
  BL64 M_B_CPU1_SB_PAR @T6G_MB_LIB.T6G(SCH_1):M_B_CPU1_SB_PAR   I159 @T6G_MB_LIB.T6G(SCH_1):PAGE38
  BC64 M_B_CPU1_CLK_DP<0> @T6G_MB_LIB.T6G(SCH_1):M_B_CPU1_CLK_DP(0)   I159 @T6G_MB_LIB.T6G(SCH_1):PAGE38
  BD63 M_B_CPU1_CLK_DN<0> @T6G_MB_LIB.T6G(SCH_1):M_B_CPU1_CLK_DN(0)   I159 @T6G_MB_LIB.T6G(SCH_1):PAGE38
  BF63     NC     NC   I159 @T6G_MB_LIB.T6G(SCH_1):PAGE38
  BG64     NC     NC   I159 @T6G_MB_LIB.T6G(SCH_1):PAGE38
  CT62 M_B_CPU1_SB_DQ<19> @T6G_MB_LIB.T6G(SCH_1):M_B_CPU1_SB_DQ(19)   I159 @T6G_MB_LIB.T6G(SCH_1):PAGE38
  AC64 M_B_CPU1_SA_DQ<24> @T6G_MB_LIB.T6G(SCH_1):M_B_CPU1_SA_DQ(24)   I159 @T6G_MB_LIB.T6G(SCH_1):PAGE38
  CV63 M_B_CPU1_SB_DQ<20> @T6G_MB_LIB.T6G(SCH_1):M_B_CPU1_SB_DQ(20)   I159 @T6G_MB_LIB.T6G(SCH_1):PAGE38
  BF62 TP_M_B_CPU1_SA_TEST39B @T6G_MB_LIB.T6G(SCH_1):TP_M_B_CPU1_SA_TEST39B   I159 @T6G_MB_LIB.T6G(SCH_1):PAGE38
  AT55 M_C_CPU1_ALERT_R_N @T6G_MB_LIB.T6G(SCH_1):M_C_CPU1_ALERT_R_N   I159 @T6G_MB_LIB.T6G(SCH_1):PAGE39
  AU55 M_C_CPU1_RESET_N @T6G_MB_LIB.T6G(SCH_1):M_C_CPU1_RESET_N   I159 @T6G_MB_LIB.T6G(SCH_1):PAGE39
  DD55 M_C_CPU1_SB_DQS_DP<8> @T6G_MB_LIB.T6G(SCH_1):M_C_CPU1_SB_DQS_DP(8)   I159 @T6G_MB_LIB.T6G(SCH_1):PAGE39
  DE57 M_C_CPU1_SB_DQ<30> @T6G_MB_LIB.T6G(SCH_1):M_C_CPU1_SB_DQ(30)   I159 @T6G_MB_LIB.T6G(SCH_1):PAGE39
  CH56 M_C_CPU1_SB_DQ<8> @T6G_MB_LIB.T6G(SCH_1):M_C_CPU1_SB_DQ(8)   I159 @T6G_MB_LIB.T6G(SCH_1):PAGE39
  BM56     NC     NC   I159 @T6G_MB_LIB.T6G(SCH_1):PAGE39
  BN57 M_C_CPU1_SB_CS_N<1> @T6G_MB_LIB.T6G(SCH_1):M_C_CPU1_SB_CS_N(1)   I159 @T6G_MB_LIB.T6G(SCH_1):PAGE39
   P56 M_C_CPU1_SA_DQS_DN<1> @T6G_MB_LIB.T6G(SCH_1):M_C_CPU1_SA_DQS_DN(1)   I159 @T6G_MB_LIB.T6G(SCH_1):PAGE39
  AD55 M_C_CPU1_SA_DQ<25> @T6G_MB_LIB.T6G(SCH_1):M_C_CPU1_SA_DQ(25)   I159 @T6G_MB_LIB.T6G(SCH_1):PAGE39
   T56 M_C_CPU1_SA_DQ<14> @T6G_MB_LIB.T6G(SCH_1):M_C_CPU1_SA_DQ(14)   I159 @T6G_MB_LIB.T6G(SCH_1):PAGE39
   M55 M_C_CPU1_SA_DQ<9> @T6G_MB_LIB.T6G(SCH_1):M_C_CPU1_SA_DQ(9)   I159 @T6G_MB_LIB.T6G(SCH_1):PAGE39
  AP55 M_C_CPU1_SA_CB<5> @T6G_MB_LIB.T6G(SCH_1):M_C_CPU1_SA_CB(5)   I159 @T6G_MB_LIB.T6G(SCH_1):PAGE39
  DF55 M_C_CPU1_SB_DQ<31> @T6G_MB_LIB.T6G(SCH_1):M_C_CPU1_SB_DQ(31)   I159 @T6G_MB_LIB.T6G(SCH_1):PAGE39
  CV56 M_C_CPU1_SB_DQ<20> @T6G_MB_LIB.T6G(SCH_1):M_C_CPU1_SB_DQ(20)   I159 @T6G_MB_LIB.T6G(SCH_1):PAGE39
  CJ55 M_C_CPU1_SB_DQ<9> @T6G_MB_LIB.T6G(SCH_1):M_C_CPU1_SB_DQ(9)   I159 @T6G_MB_LIB.T6G(SCH_1):PAGE39
  BY56 M_C_CPU1_SB_CB<0> @T6G_MB_LIB.T6G(SCH_1):M_C_CPU1_SB_CB(0)   I159 @T6G_MB_LIB.T6G(SCH_1):PAGE39
   Y56 M_C_CPU1_SA_DQS_DN<2> @T6G_MB_LIB.T6G(SCH_1):M_C_CPU1_SA_DQS_DN(2)   I159 @T6G_MB_LIB.T6G(SCH_1):PAGE39
  AD56 M_C_CPU1_SA_DQ<26> @T6G_MB_LIB.T6G(SCH_1):M_C_CPU1_SA_DQ(26)   I159 @T6G_MB_LIB.T6G(SCH_1):PAGE39
   U55 M_C_CPU1_SA_DQ<15> @T6G_MB_LIB.T6G(SCH_1):M_C_CPU1_SA_DQ(15)   I159 @T6G_MB_LIB.T6G(SCH_1):PAGE39
  AP56 M_C_CPU1_SA_CB<6> @T6G_MB_LIB.T6G(SCH_1):M_C_CPU1_SA_CB(6)   I159 @T6G_MB_LIB.T6G(SCH_1):PAGE39
  BN55 M_C_CPU1_SA_RSP<0> @T6G_MB_LIB.T6G(SCH_1):M_C_CPU1_SA_RSP(0)   I159 @T6G_MB_LIB.T6G(SCH_1):PAGE39
  CW55 M_C_CPU1_SB_DQ<21> @T6G_MB_LIB.T6G(SCH_1):M_C_CPU1_SB_DQ(21)   I159 @T6G_MB_LIB.T6G(SCH_1):PAGE39
  CJ57 M_C_CPU1_SB_DQ<10> @T6G_MB_LIB.T6G(SCH_1):M_C_CPU1_SB_DQ(10)   I159 @T6G_MB_LIB.T6G(SCH_1):PAGE39
  CA55 M_C_CPU1_SB_CB<1> @T6G_MB_LIB.T6G(SCH_1):M_C_CPU1_SB_CB(1)   I159 @T6G_MB_LIB.T6G(SCH_1):PAGE39
  AF56 M_C_CPU1_SA_DQS_DN<3> @T6G_MB_LIB.T6G(SCH_1):M_C_CPU1_SA_DQS_DN(3)   I159 @T6G_MB_LIB.T6G(SCH_1):PAGE39
  AE55 M_C_CPU1_SA_DQ<27> @T6G_MB_LIB.T6G(SCH_1):M_C_CPU1_SA_DQ(27)   I159 @T6G_MB_LIB.T6G(SCH_1):PAGE39
   U57 M_C_CPU1_SA_DQ<16> @T6G_MB_LIB.T6G(SCH_1):M_C_CPU1_SA_DQ(16)   I159 @T6G_MB_LIB.T6G(SCH_1):PAGE39
  AR55 M_C_CPU1_SA_CB<7> @T6G_MB_LIB.T6G(SCH_1):M_C_CPU1_SA_CB(7)   I159 @T6G_MB_LIB.T6G(SCH_1):PAGE39
  BP55     NC     NC   I159 @T6G_MB_LIB.T6G(SCH_1):PAGE39
  CW57 M_C_CPU1_SB_DQ<22> @T6G_MB_LIB.T6G(SCH_1):M_C_CPU1_SB_DQ(22)   I159 @T6G_MB_LIB.T6G(SCH_1):PAGE39
  CK55 M_C_CPU1_SB_DQ<11> @T6G_MB_LIB.T6G(SCH_1):M_C_CPU1_SB_DQ(11)   I159 @T6G_MB_LIB.T6G(SCH_1):PAGE39
  CA57 M_C_CPU1_SB_CB<2> @T6G_MB_LIB.T6G(SCH_1):M_C_CPU1_SB_CB(2)   I159 @T6G_MB_LIB.T6G(SCH_1):PAGE39
  AM56 M_C_CPU1_SA_DQS_DN<4> @T6G_MB_LIB.T6G(SCH_1):M_C_CPU1_SA_DQS_DN(4)   I159 @T6G_MB_LIB.T6G(SCH_1):PAGE39
   G57 M_C_CPU1_SA_DQS_DP<0> @T6G_MB_LIB.T6G(SCH_1):M_C_CPU1_SA_DQS_DP(0)   I159 @T6G_MB_LIB.T6G(SCH_1):PAGE39
  AG57 M_C_CPU1_SA_DQ<28> @T6G_MB_LIB.T6G(SCH_1):M_C_CPU1_SA_DQ(28)   I159 @T6G_MB_LIB.T6G(SCH_1):PAGE39
   V55 M_C_CPU1_SA_DQ<17> @T6G_MB_LIB.T6G(SCH_1):M_C_CPU1_SA_DQ(17)   I159 @T6G_MB_LIB.T6G(SCH_1):PAGE39
  CY55 M_C_CPU1_SB_DQ<23> @T6G_MB_LIB.T6G(SCH_1):M_C_CPU1_SB_DQ(23)   I159 @T6G_MB_LIB.T6G(SCH_1):PAGE39
  CM56 M_C_CPU1_SB_DQ<12> @T6G_MB_LIB.T6G(SCH_1):M_C_CPU1_SB_DQ(12)   I159 @T6G_MB_LIB.T6G(SCH_1):PAGE39
  CB55 M_C_CPU1_SB_CB<3> @T6G_MB_LIB.T6G(SCH_1):M_C_CPU1_SB_CB(3)   I159 @T6G_MB_LIB.T6G(SCH_1):PAGE39
   H55 M_C_CPU1_SA_DQS_DN<5> @T6G_MB_LIB.T6G(SCH_1):M_C_CPU1_SA_DQS_DN(5)   I159 @T6G_MB_LIB.T6G(SCH_1):PAGE39
   N57 M_C_CPU1_SA_DQS_DP<1> @T6G_MB_LIB.T6G(SCH_1):M_C_CPU1_SA_DQS_DP(1)   I159 @T6G_MB_LIB.T6G(SCH_1):PAGE39
  AH55 M_C_CPU1_SA_DQ<29> @T6G_MB_LIB.T6G(SCH_1):M_C_CPU1_SA_DQ(29)   I159 @T6G_MB_LIB.T6G(SCH_1):PAGE39
   V56 M_C_CPU1_SA_DQ<18> @T6G_MB_LIB.T6G(SCH_1):M_C_CPU1_SA_DQ(18)   I159 @T6G_MB_LIB.T6G(SCH_1):PAGE39
  CE57 M_C_CPU1_SB_DQS_DN<0> @T6G_MB_LIB.T6G(SCH_1):M_C_CPU1_SB_DQS_DN(0)   I159 @T6G_MB_LIB.T6G(SCH_1):PAGE39
  CY56 M_C_CPU1_SB_DQ<24> @T6G_MB_LIB.T6G(SCH_1):M_C_CPU1_SB_DQ(24)   I159 @T6G_MB_LIB.T6G(SCH_1):PAGE39
  CN55 M_C_CPU1_SB_DQ<13> @T6G_MB_LIB.T6G(SCH_1):M_C_CPU1_SB_DQ(13)   I159 @T6G_MB_LIB.T6G(SCH_1):PAGE39
  BT56 M_C_CPU1_SB_CB<4> @T6G_MB_LIB.T6G(SCH_1):M_C_CPU1_SB_CB(4)   I159 @T6G_MB_LIB.T6G(SCH_1):PAGE39
   P55 M_C_CPU1_SA_DQS_DN<6> @T6G_MB_LIB.T6G(SCH_1):M_C_CPU1_SA_DQS_DN(6)   I159 @T6G_MB_LIB.T6G(SCH_1):PAGE39
   W57 M_C_CPU1_SA_DQS_DP<2> @T6G_MB_LIB.T6G(SCH_1):M_C_CPU1_SA_DQS_DP(2)   I159 @T6G_MB_LIB.T6G(SCH_1):PAGE39
   W55 M_C_CPU1_SA_DQ<19> @T6G_MB_LIB.T6G(SCH_1):M_C_CPU1_SA_DQ(19)   I159 @T6G_MB_LIB.T6G(SCH_1):PAGE39
  CL57 M_C_CPU1_SB_DQS_DN<1> @T6G_MB_LIB.T6G(SCH_1):M_C_CPU1_SB_DQS_DN(1)   I159 @T6G_MB_LIB.T6G(SCH_1):PAGE39
  DA55 M_C_CPU1_SB_DQ<25> @T6G_MB_LIB.T6G(SCH_1):M_C_CPU1_SB_DQ(25)   I159 @T6G_MB_LIB.T6G(SCH_1):PAGE39
  CN57 M_C_CPU1_SB_DQ<14> @T6G_MB_LIB.T6G(SCH_1):M_C_CPU1_SB_DQ(14)   I159 @T6G_MB_LIB.T6G(SCH_1):PAGE39
  BU55 M_C_CPU1_SB_CB<5> @T6G_MB_LIB.T6G(SCH_1):M_C_CPU1_SB_CB(5)   I159 @T6G_MB_LIB.T6G(SCH_1):PAGE39
   Y55 M_C_CPU1_SA_DQS_DN<7> @T6G_MB_LIB.T6G(SCH_1):M_C_CPU1_SA_DQS_DN(7)   I159 @T6G_MB_LIB.T6G(SCH_1):PAGE39
  AE57 M_C_CPU1_SA_DQS_DP<3> @T6G_MB_LIB.T6G(SCH_1):M_C_CPU1_SA_DQS_DP(3)   I159 @T6G_MB_LIB.T6G(SCH_1):PAGE39
  CU57 M_C_CPU1_SB_DQS_DN<2> @T6G_MB_LIB.T6G(SCH_1):M_C_CPU1_SB_DQS_DN(2)   I159 @T6G_MB_LIB.T6G(SCH_1):PAGE39
  DA57 M_C_CPU1_SB_DQ<26> @T6G_MB_LIB.T6G(SCH_1):M_C_CPU1_SB_DQ(26)   I159 @T6G_MB_LIB.T6G(SCH_1):PAGE39
  CP55 M_C_CPU1_SB_DQ<15> @T6G_MB_LIB.T6G(SCH_1):M_C_CPU1_SB_DQ(15)   I159 @T6G_MB_LIB.T6G(SCH_1):PAGE39
  BU57 M_C_CPU1_SB_CB<6> @T6G_MB_LIB.T6G(SCH_1):M_C_CPU1_SB_CB(6)   I159 @T6G_MB_LIB.T6G(SCH_1):PAGE39
  AF55 M_C_CPU1_SA_DQS_DN<8> @T6G_MB_LIB.T6G(SCH_1):M_C_CPU1_SA_DQS_DN(8)   I159 @T6G_MB_LIB.T6G(SCH_1):PAGE39
  AL57 M_C_CPU1_SA_DQS_DP<4> @T6G_MB_LIB.T6G(SCH_1):M_C_CPU1_SA_DQS_DP(4)   I159 @T6G_MB_LIB.T6G(SCH_1):PAGE39
  AW57 M_C_CPU1_SA_CA<0> @T6G_MB_LIB.T6G(SCH_1):M_C_CPU1_SA_CA(0)   I159 @T6G_MB_LIB.T6G(SCH_1):PAGE39
  DC57 M_C_CPU1_SB_DQS_DN<3> @T6G_MB_LIB.T6G(SCH_1):M_C_CPU1_SB_DQS_DN(3)   I159 @T6G_MB_LIB.T6G(SCH_1):PAGE39
  DB55 M_C_CPU1_SB_DQ<27> @T6G_MB_LIB.T6G(SCH_1):M_C_CPU1_SB_DQ(27)   I159 @T6G_MB_LIB.T6G(SCH_1):PAGE39
  CP56 M_C_CPU1_SB_DQ<16> @T6G_MB_LIB.T6G(SCH_1):M_C_CPU1_SB_DQ(16)   I159 @T6G_MB_LIB.T6G(SCH_1):PAGE39
  BV55 M_C_CPU1_SB_CB<7> @T6G_MB_LIB.T6G(SCH_1):M_C_CPU1_SB_CB(7)   I159 @T6G_MB_LIB.T6G(SCH_1):PAGE39
  BG55 M_C_CPU1_SB_CA<0> @T6G_MB_LIB.T6G(SCH_1):M_C_CPU1_SB_CA(0)   I159 @T6G_MB_LIB.T6G(SCH_1):PAGE39
  BR57     NC     NC   I159 @T6G_MB_LIB.T6G(SCH_1):PAGE39
  BP56 M_C_CPU1_SB_RSP<0> @T6G_MB_LIB.T6G(SCH_1):M_C_CPU1_SB_RSP(0)   I159 @T6G_MB_LIB.T6G(SCH_1):PAGE39
  AM55 M_C_CPU1_SA_DQS_DN<9> @T6G_MB_LIB.T6G(SCH_1):M_C_CPU1_SA_DQS_DN(9)   I159 @T6G_MB_LIB.T6G(SCH_1):PAGE39
   J55 M_C_CPU1_SA_DQS_DP<5> @T6G_MB_LIB.T6G(SCH_1):M_C_CPU1_SA_DQS_DP(5)   I159 @T6G_MB_LIB.T6G(SCH_1):PAGE39
   E57 M_C_CPU1_SA_DQ<0> @T6G_MB_LIB.T6G(SCH_1):M_C_CPU1_SA_DQ(0)   I159 @T6G_MB_LIB.T6G(SCH_1):PAGE39
  AY56 M_C_CPU1_SA_CA<1> @T6G_MB_LIB.T6G(SCH_1):M_C_CPU1_SA_CA(1)   I159 @T6G_MB_LIB.T6G(SCH_1):PAGE39
  BW55 M_C_CPU1_SB_DQS_DN<4> @T6G_MB_LIB.T6G(SCH_1):M_C_CPU1_SB_DQS_DN(4)   I159 @T6G_MB_LIB.T6G(SCH_1):PAGE39
  CD56 M_C_CPU1_SB_DQS_DP<0> @T6G_MB_LIB.T6G(SCH_1):M_C_CPU1_SB_DQS_DP(0)   I159 @T6G_MB_LIB.T6G(SCH_1):PAGE39
  DD56 M_C_CPU1_SB_DQ<28> @T6G_MB_LIB.T6G(SCH_1):M_C_CPU1_SB_DQ(28)   I159 @T6G_MB_LIB.T6G(SCH_1):PAGE39
  CR55 M_C_CPU1_SB_DQ<17> @T6G_MB_LIB.T6G(SCH_1):M_C_CPU1_SB_DQ(17)   I159 @T6G_MB_LIB.T6G(SCH_1):PAGE39
  CB56 M_C_CPU1_SB_DQ<0> @T6G_MB_LIB.T6G(SCH_1):M_C_CPU1_SB_DQ(0)   I159 @T6G_MB_LIB.T6G(SCH_1):PAGE39
  BH55 M_C_CPU1_SB_CA<1> @T6G_MB_LIB.T6G(SCH_1):M_C_CPU1_SB_CA(1)   I159 @T6G_MB_LIB.T6G(SCH_1):PAGE39
   R55 M_C_CPU1_SA_DQS_DP<6> @T6G_MB_LIB.T6G(SCH_1):M_C_CPU1_SA_DQS_DP(6)   I159 @T6G_MB_LIB.T6G(SCH_1):PAGE39
   F55 M_C_CPU1_SA_DQ<1> @T6G_MB_LIB.T6G(SCH_1):M_C_CPU1_SA_DQ(1)   I159 @T6G_MB_LIB.T6G(SCH_1):PAGE39
  AY55 M_C_CPU1_SA_CA<2> @T6G_MB_LIB.T6G(SCH_1):M_C_CPU1_SA_CA(2)   I159 @T6G_MB_LIB.T6G(SCH_1):PAGE39
  AV56 M_C_CPU1_SA_CS_N<0> @T6G_MB_LIB.T6G(SCH_1):M_C_CPU1_SA_CS_N(0)   I159 @T6G_MB_LIB.T6G(SCH_1):PAGE39
  CE55 M_C_CPU1_SB_DQS_DN<5> @T6G_MB_LIB.T6G(SCH_1):M_C_CPU1_SB_DQS_DN(5)   I159 @T6G_MB_LIB.T6G(SCH_1):PAGE39
  CK56 M_C_CPU1_SB_DQS_DP<1> @T6G_MB_LIB.T6G(SCH_1):M_C_CPU1_SB_DQS_DP(1)   I159 @T6G_MB_LIB.T6G(SCH_1):PAGE39
  DE55 M_C_CPU1_SB_DQ<29> @T6G_MB_LIB.T6G(SCH_1):M_C_CPU1_SB_DQ(29)   I159 @T6G_MB_LIB.T6G(SCH_1):PAGE39
  CR57 M_C_CPU1_SB_DQ<18> @T6G_MB_LIB.T6G(SCH_1):M_C_CPU1_SB_DQ(18)   I159 @T6G_MB_LIB.T6G(SCH_1):PAGE39
  CC55 M_C_CPU1_SB_DQ<1> @T6G_MB_LIB.T6G(SCH_1):M_C_CPU1_SB_DQ(1)   I159 @T6G_MB_LIB.T6G(SCH_1):PAGE39
  BH56 M_C_CPU1_SB_CA<2> @T6G_MB_LIB.T6G(SCH_1):M_C_CPU1_SB_CA(2)   I159 @T6G_MB_LIB.T6G(SCH_1):PAGE39
  AA55 M_C_CPU1_SA_DQS_DP<7> @T6G_MB_LIB.T6G(SCH_1):M_C_CPU1_SA_DQS_DP(7)   I159 @T6G_MB_LIB.T6G(SCH_1):PAGE39
   F56 M_C_CPU1_SA_DQ<2> @T6G_MB_LIB.T6G(SCH_1):M_C_CPU1_SA_DQ(2)   I159 @T6G_MB_LIB.T6G(SCH_1):PAGE39
  BA55 M_C_CPU1_SA_CA<3> @T6G_MB_LIB.T6G(SCH_1):M_C_CPU1_SA_CA(3)   I159 @T6G_MB_LIB.T6G(SCH_1):PAGE39
  AU57     NC     NC   I159 @T6G_MB_LIB.T6G(SCH_1):PAGE39
  AW55 M_C_CPU1_SA_CS_N<1> @T6G_MB_LIB.T6G(SCH_1):M_C_CPU1_SA_CS_N(1)   I159 @T6G_MB_LIB.T6G(SCH_1):PAGE39
  CL55 M_C_CPU1_SB_DQS_DN<6> @T6G_MB_LIB.T6G(SCH_1):M_C_CPU1_SB_DQS_DN(6)   I159 @T6G_MB_LIB.T6G(SCH_1):PAGE39
  CT56 M_C_CPU1_SB_DQS_DP<2> @T6G_MB_LIB.T6G(SCH_1):M_C_CPU1_SB_DQS_DP(2)   I159 @T6G_MB_LIB.T6G(SCH_1):PAGE39
  CT55 M_C_CPU1_SB_DQ<19> @T6G_MB_LIB.T6G(SCH_1):M_C_CPU1_SB_DQ(19)   I159 @T6G_MB_LIB.T6G(SCH_1):PAGE39
  CC57 M_C_CPU1_SB_DQ<2> @T6G_MB_LIB.T6G(SCH_1):M_C_CPU1_SB_DQ(2)   I159 @T6G_MB_LIB.T6G(SCH_1):PAGE39
  BJ57 M_C_CPU1_SB_CA<3> @T6G_MB_LIB.T6G(SCH_1):M_C_CPU1_SB_CA(3)   I159 @T6G_MB_LIB.T6G(SCH_1):PAGE39
  AG55 M_C_CPU1_SA_DQS_DP<8> @T6G_MB_LIB.T6G(SCH_1):M_C_CPU1_SA_DQS_DP(8)   I159 @T6G_MB_LIB.T6G(SCH_1):PAGE39
  AH56 M_C_CPU1_SA_DQ<30> @T6G_MB_LIB.T6G(SCH_1):M_C_CPU1_SA_DQ(30)   I159 @T6G_MB_LIB.T6G(SCH_1):PAGE39
   G55 M_C_CPU1_SA_DQ<3> @T6G_MB_LIB.T6G(SCH_1):M_C_CPU1_SA_DQ(3)   I159 @T6G_MB_LIB.T6G(SCH_1):PAGE39
  BA57 M_C_CPU1_SA_CA<4> @T6G_MB_LIB.T6G(SCH_1):M_C_CPU1_SA_CA(4)   I159 @T6G_MB_LIB.T6G(SCH_1):PAGE39
  AV55     NC     NC   I159 @T6G_MB_LIB.T6G(SCH_1):PAGE39
  CU55 M_C_CPU1_SB_DQS_DN<7> @T6G_MB_LIB.T6G(SCH_1):M_C_CPU1_SB_DQS_DN(7)   I159 @T6G_MB_LIB.T6G(SCH_1):PAGE39
  DB56 M_C_CPU1_SB_DQS_DP<3> @T6G_MB_LIB.T6G(SCH_1):M_C_CPU1_SB_DQS_DP(3)   I159 @T6G_MB_LIB.T6G(SCH_1):PAGE39
  CD55 M_C_CPU1_SB_DQ<3> @T6G_MB_LIB.T6G(SCH_1):M_C_CPU1_SB_DQ(3)   I159 @T6G_MB_LIB.T6G(SCH_1):PAGE39
  BJ55 M_C_CPU1_SB_CA<4> @T6G_MB_LIB.T6G(SCH_1):M_C_CPU1_SB_CA(4)   I159 @T6G_MB_LIB.T6G(SCH_1):PAGE39
  AN55 M_C_CPU1_SA_DQS_DP<9> @T6G_MB_LIB.T6G(SCH_1):M_C_CPU1_SA_DQS_DP(9)   I159 @T6G_MB_LIB.T6G(SCH_1):PAGE39
  AJ55 M_C_CPU1_SA_DQ<31> @T6G_MB_LIB.T6G(SCH_1):M_C_CPU1_SA_DQ(31)   I159 @T6G_MB_LIB.T6G(SCH_1):PAGE39
  AA57 M_C_CPU1_SA_DQ<20> @T6G_MB_LIB.T6G(SCH_1):M_C_CPU1_SA_DQ(20)   I159 @T6G_MB_LIB.T6G(SCH_1):PAGE39
   J57 M_C_CPU1_SA_DQ<4> @T6G_MB_LIB.T6G(SCH_1):M_C_CPU1_SA_DQ(4)   I159 @T6G_MB_LIB.T6G(SCH_1):PAGE39
  AJ57 M_C_CPU1_SA_CB<0> @T6G_MB_LIB.T6G(SCH_1):M_C_CPU1_SA_CB(0)   I159 @T6G_MB_LIB.T6G(SCH_1):PAGE39
  BB56 M_C_CPU1_SA_CA<5> @T6G_MB_LIB.T6G(SCH_1):M_C_CPU1_SA_CA(5)   I159 @T6G_MB_LIB.T6G(SCH_1):PAGE39
  DC55 M_C_CPU1_SB_DQS_DN<8> @T6G_MB_LIB.T6G(SCH_1):M_C_CPU1_SB_DQS_DN(8)   I159 @T6G_MB_LIB.T6G(SCH_1):PAGE39
  BY55 M_C_CPU1_SB_DQS_DP<4> @T6G_MB_LIB.T6G(SCH_1):M_C_CPU1_SB_DQS_DP(4)   I159 @T6G_MB_LIB.T6G(SCH_1):PAGE39
  CF56 M_C_CPU1_SB_DQ<4> @T6G_MB_LIB.T6G(SCH_1):M_C_CPU1_SB_DQ(4)   I159 @T6G_MB_LIB.T6G(SCH_1):PAGE39
  BK55 M_C_CPU1_SB_CA<5> @T6G_MB_LIB.T6G(SCH_1):M_C_CPU1_SB_CA(5)   I159 @T6G_MB_LIB.T6G(SCH_1):PAGE39
  AB55 M_C_CPU1_SA_DQ<21> @T6G_MB_LIB.T6G(SCH_1):M_C_CPU1_SA_DQ(21)   I159 @T6G_MB_LIB.T6G(SCH_1):PAGE39
   M56 M_C_CPU1_SA_DQ<10> @T6G_MB_LIB.T6G(SCH_1):M_C_CPU1_SA_DQ(10)   I159 @T6G_MB_LIB.T6G(SCH_1):PAGE39
   K55 M_C_CPU1_SA_DQ<5> @T6G_MB_LIB.T6G(SCH_1):M_C_CPU1_SA_DQ(5)   I159 @T6G_MB_LIB.T6G(SCH_1):PAGE39
  AK55 M_C_CPU1_SA_CB<1> @T6G_MB_LIB.T6G(SCH_1):M_C_CPU1_SA_CB(1)   I159 @T6G_MB_LIB.T6G(SCH_1):PAGE39
  BB55 M_C_CPU1_SA_CA<6> @T6G_MB_LIB.T6G(SCH_1):M_C_CPU1_SA_CA(6)   I159 @T6G_MB_LIB.T6G(SCH_1):PAGE39
  BW57 M_C_CPU1_SB_DQS_DN<9> @T6G_MB_LIB.T6G(SCH_1):M_C_CPU1_SB_DQS_DN(9)   I159 @T6G_MB_LIB.T6G(SCH_1):PAGE39
  CF55 M_C_CPU1_SB_DQS_DP<5> @T6G_MB_LIB.T6G(SCH_1):M_C_CPU1_SB_DQS_DP(5)   I159 @T6G_MB_LIB.T6G(SCH_1):PAGE39
  CG55 M_C_CPU1_SB_DQ<5> @T6G_MB_LIB.T6G(SCH_1):M_C_CPU1_SB_DQ(5)   I159 @T6G_MB_LIB.T6G(SCH_1):PAGE39
  BK56 M_C_CPU1_SB_CA<6> @T6G_MB_LIB.T6G(SCH_1):M_C_CPU1_SB_CA(6)   I159 @T6G_MB_LIB.T6G(SCH_1):PAGE39
  AB56 M_C_CPU1_SA_DQ<22> @T6G_MB_LIB.T6G(SCH_1):M_C_CPU1_SA_DQ(22)   I159 @T6G_MB_LIB.T6G(SCH_1):PAGE39
   N55 M_C_CPU1_SA_DQ<11> @T6G_MB_LIB.T6G(SCH_1):M_C_CPU1_SA_DQ(11)   I159 @T6G_MB_LIB.T6G(SCH_1):PAGE39
   K56 M_C_CPU1_SA_DQ<6> @T6G_MB_LIB.T6G(SCH_1):M_C_CPU1_SA_DQ(6)   I159 @T6G_MB_LIB.T6G(SCH_1):PAGE39
  AK56 M_C_CPU1_SA_CB<2> @T6G_MB_LIB.T6G(SCH_1):M_C_CPU1_SA_CB(2)   I159 @T6G_MB_LIB.T6G(SCH_1):PAGE39
  CM55 M_C_CPU1_SB_DQS_DP<6> @T6G_MB_LIB.T6G(SCH_1):M_C_CPU1_SB_DQS_DP(6)   I159 @T6G_MB_LIB.T6G(SCH_1):PAGE39
  CG57 M_C_CPU1_SB_DQ<6> @T6G_MB_LIB.T6G(SCH_1):M_C_CPU1_SB_DQ(6)   I159 @T6G_MB_LIB.T6G(SCH_1):PAGE39
  AC55 M_C_CPU1_SA_DQ<23> @T6G_MB_LIB.T6G(SCH_1):M_C_CPU1_SA_DQ(23)   I159 @T6G_MB_LIB.T6G(SCH_1):PAGE39
   R57 M_C_CPU1_SA_DQ<12> @T6G_MB_LIB.T6G(SCH_1):M_C_CPU1_SA_DQ(12)   I159 @T6G_MB_LIB.T6G(SCH_1):PAGE39
   L55 M_C_CPU1_SA_DQ<7> @T6G_MB_LIB.T6G(SCH_1):M_C_CPU1_SA_DQ(7)   I159 @T6G_MB_LIB.T6G(SCH_1):PAGE39
  AL55 M_C_CPU1_SA_CB<3> @T6G_MB_LIB.T6G(SCH_1):M_C_CPU1_SA_CB(3)   I159 @T6G_MB_LIB.T6G(SCH_1):PAGE39
  CV55 M_C_CPU1_SB_DQS_DP<7> @T6G_MB_LIB.T6G(SCH_1):M_C_CPU1_SB_DQS_DP(7)   I159 @T6G_MB_LIB.T6G(SCH_1):PAGE39
  CH55 M_C_CPU1_SB_DQ<7> @T6G_MB_LIB.T6G(SCH_1):M_C_CPU1_SB_DQ(7)   I159 @T6G_MB_LIB.T6G(SCH_1):PAGE39
  BL55     NC     NC   I159 @T6G_MB_LIB.T6G(SCH_1):PAGE39
  BM55 M_C_CPU1_SB_CS_N<0> @T6G_MB_LIB.T6G(SCH_1):M_C_CPU1_SB_CS_N(0)   I159 @T6G_MB_LIB.T6G(SCH_1):PAGE39
   H56 M_C_CPU1_SA_DQS_DN<0> @T6G_MB_LIB.T6G(SCH_1):M_C_CPU1_SA_DQS_DN(0)   I159 @T6G_MB_LIB.T6G(SCH_1):PAGE39
  AC57 M_C_CPU1_SA_DQ<24> @T6G_MB_LIB.T6G(SCH_1):M_C_CPU1_SA_DQ(24)   I159 @T6G_MB_LIB.T6G(SCH_1):PAGE39
   T55 M_C_CPU1_SA_DQ<13> @T6G_MB_LIB.T6G(SCH_1):M_C_CPU1_SA_DQ(13)   I159 @T6G_MB_LIB.T6G(SCH_1):PAGE39
   L57 M_C_CPU1_SA_DQ<8> @T6G_MB_LIB.T6G(SCH_1):M_C_CPU1_SA_DQ(8)   I159 @T6G_MB_LIB.T6G(SCH_1):PAGE39
  AN57 M_C_CPU1_SA_CB<4> @T6G_MB_LIB.T6G(SCH_1):M_C_CPU1_SA_CB(4)   I159 @T6G_MB_LIB.T6G(SCH_1):PAGE39
  BV56 M_C_CPU1_SB_DQS_DP<9> @T6G_MB_LIB.T6G(SCH_1):M_C_CPU1_SB_DQS_DP(9)   I159 @T6G_MB_LIB.T6G(SCH_1):PAGE39
  BC55 M_C_CPU1_SA_PAR @T6G_MB_LIB.T6G(SCH_1):M_C_CPU1_SA_PAR   I159 @T6G_MB_LIB.T6G(SCH_1):PAGE39
  BL57 M_C_CPU1_SB_PAR @T6G_MB_LIB.T6G(SCH_1):M_C_CPU1_SB_PAR   I159 @T6G_MB_LIB.T6G(SCH_1):PAGE39
  BC57 M_C_CPU1_CLK_DP<0> @T6G_MB_LIB.T6G(SCH_1):M_C_CPU1_CLK_DP(0)   I159 @T6G_MB_LIB.T6G(SCH_1):PAGE39
  BD56 M_C_CPU1_CLK_DN<0> @T6G_MB_LIB.T6G(SCH_1):M_C_CPU1_CLK_DN(0)   I159 @T6G_MB_LIB.T6G(SCH_1):PAGE39
  BF56     NC     NC   I159 @T6G_MB_LIB.T6G(SCH_1):PAGE39
  BG57     NC     NC   I159 @T6G_MB_LIB.T6G(SCH_1):PAGE39
  BF55 TP_M_C_CPU1_SA_TEST39C @T6G_MB_LIB.T6G(SCH_1):TP_M_C_CPU1_SA_TEST39C   I159 @T6G_MB_LIB.T6G(SCH_1):PAGE39
  AT58 M_D_CPU1_ALERT_R_N @T6G_MB_LIB.T6G(SCH_1):M_D_CPU1_ALERT_R_N   I159 @T6G_MB_LIB.T6G(SCH_1):PAGE40
  AU59 M_D_CPU1_RESET_N @T6G_MB_LIB.T6G(SCH_1):M_D_CPU1_RESET_N   I159 @T6G_MB_LIB.T6G(SCH_1):PAGE40
  CY58 M_D_CPU1_SB_DQ<23> @T6G_MB_LIB.T6G(SCH_1):M_D_CPU1_SB_DQ(23)   I159 @T6G_MB_LIB.T6G(SCH_1):PAGE40
  CM60 M_D_CPU1_SB_DQ<12> @T6G_MB_LIB.T6G(SCH_1):M_D_CPU1_SB_DQ(12)   I159 @T6G_MB_LIB.T6G(SCH_1):PAGE40
  CC60 M_D_CPU1_SB_DQ<2> @T6G_MB_LIB.T6G(SCH_1):M_D_CPU1_SB_DQ(2)   I159 @T6G_MB_LIB.T6G(SCH_1):PAGE40
  CB58 M_D_CPU1_SB_CB<3> @T6G_MB_LIB.T6G(SCH_1):M_D_CPU1_SB_CB(3)   I159 @T6G_MB_LIB.T6G(SCH_1):PAGE40
   H58 M_D_CPU1_SA_DQS_DN<5> @T6G_MB_LIB.T6G(SCH_1):M_D_CPU1_SA_DQS_DN(5)   I159 @T6G_MB_LIB.T6G(SCH_1):PAGE40
   N60 M_D_CPU1_SA_DQS_DP<1> @T6G_MB_LIB.T6G(SCH_1):M_D_CPU1_SA_DQS_DP(1)   I159 @T6G_MB_LIB.T6G(SCH_1):PAGE40
  AH58 M_D_CPU1_SA_DQ<29> @T6G_MB_LIB.T6G(SCH_1):M_D_CPU1_SA_DQ(29)   I159 @T6G_MB_LIB.T6G(SCH_1):PAGE40
   V60 M_D_CPU1_SA_DQ<18> @T6G_MB_LIB.T6G(SCH_1):M_D_CPU1_SA_DQ(18)   I159 @T6G_MB_LIB.T6G(SCH_1):PAGE40
   G59 M_D_CPU1_SA_DQ<3> @T6G_MB_LIB.T6G(SCH_1):M_D_CPU1_SA_DQ(3)   I159 @T6G_MB_LIB.T6G(SCH_1):PAGE40
  CE60 M_D_CPU1_SB_DQS_DN<0> @T6G_MB_LIB.T6G(SCH_1):M_D_CPU1_SB_DQS_DN(0)   I159 @T6G_MB_LIB.T6G(SCH_1):PAGE40
  CY60 M_D_CPU1_SB_DQ<24> @T6G_MB_LIB.T6G(SCH_1):M_D_CPU1_SB_DQ(24)   I159 @T6G_MB_LIB.T6G(SCH_1):PAGE40
  CN59 M_D_CPU1_SB_DQ<13> @T6G_MB_LIB.T6G(SCH_1):M_D_CPU1_SB_DQ(13)   I159 @T6G_MB_LIB.T6G(SCH_1):PAGE40
  CD58 M_D_CPU1_SB_DQ<3> @T6G_MB_LIB.T6G(SCH_1):M_D_CPU1_SB_DQ(3)   I159 @T6G_MB_LIB.T6G(SCH_1):PAGE40
  BT60 M_D_CPU1_SB_CB<4> @T6G_MB_LIB.T6G(SCH_1):M_D_CPU1_SB_CB(4)   I159 @T6G_MB_LIB.T6G(SCH_1):PAGE40
   P58 M_D_CPU1_SA_DQS_DN<6> @T6G_MB_LIB.T6G(SCH_1):M_D_CPU1_SA_DQS_DN(6)   I159 @T6G_MB_LIB.T6G(SCH_1):PAGE40
   W60 M_D_CPU1_SA_DQS_DP<2> @T6G_MB_LIB.T6G(SCH_1):M_D_CPU1_SA_DQS_DP(2)   I159 @T6G_MB_LIB.T6G(SCH_1):PAGE40
   W59 M_D_CPU1_SA_DQ<19> @T6G_MB_LIB.T6G(SCH_1):M_D_CPU1_SA_DQ(19)   I159 @T6G_MB_LIB.T6G(SCH_1):PAGE40
   J60 M_D_CPU1_SA_DQ<4> @T6G_MB_LIB.T6G(SCH_1):M_D_CPU1_SA_DQ(4)   I159 @T6G_MB_LIB.T6G(SCH_1):PAGE40
  CL60 M_D_CPU1_SB_DQS_DN<1> @T6G_MB_LIB.T6G(SCH_1):M_D_CPU1_SB_DQS_DN(1)   I159 @T6G_MB_LIB.T6G(SCH_1):PAGE40
  DA59 M_D_CPU1_SB_DQ<25> @T6G_MB_LIB.T6G(SCH_1):M_D_CPU1_SB_DQ(25)   I159 @T6G_MB_LIB.T6G(SCH_1):PAGE40
  CN60 M_D_CPU1_SB_DQ<14> @T6G_MB_LIB.T6G(SCH_1):M_D_CPU1_SB_DQ(14)   I159 @T6G_MB_LIB.T6G(SCH_1):PAGE40
  CF60 M_D_CPU1_SB_DQ<4> @T6G_MB_LIB.T6G(SCH_1):M_D_CPU1_SB_DQ(4)   I159 @T6G_MB_LIB.T6G(SCH_1):PAGE40
  BU59 M_D_CPU1_SB_CB<5> @T6G_MB_LIB.T6G(SCH_1):M_D_CPU1_SB_CB(5)   I159 @T6G_MB_LIB.T6G(SCH_1):PAGE40
   Y58 M_D_CPU1_SA_DQS_DN<7> @T6G_MB_LIB.T6G(SCH_1):M_D_CPU1_SA_DQS_DN(7)   I159 @T6G_MB_LIB.T6G(SCH_1):PAGE40
  AE60 M_D_CPU1_SA_DQS_DP<3> @T6G_MB_LIB.T6G(SCH_1):M_D_CPU1_SA_DQS_DP(3)   I159 @T6G_MB_LIB.T6G(SCH_1):PAGE40
   K58 M_D_CPU1_SA_DQ<5> @T6G_MB_LIB.T6G(SCH_1):M_D_CPU1_SA_DQ(5)   I159 @T6G_MB_LIB.T6G(SCH_1):PAGE40
  CU60 M_D_CPU1_SB_DQS_DN<2> @T6G_MB_LIB.T6G(SCH_1):M_D_CPU1_SB_DQS_DN(2)   I159 @T6G_MB_LIB.T6G(SCH_1):PAGE40
  DA60 M_D_CPU1_SB_DQ<26> @T6G_MB_LIB.T6G(SCH_1):M_D_CPU1_SB_DQ(26)   I159 @T6G_MB_LIB.T6G(SCH_1):PAGE40
  CP58 M_D_CPU1_SB_DQ<15> @T6G_MB_LIB.T6G(SCH_1):M_D_CPU1_SB_DQ(15)   I159 @T6G_MB_LIB.T6G(SCH_1):PAGE40
  CG59 M_D_CPU1_SB_DQ<5> @T6G_MB_LIB.T6G(SCH_1):M_D_CPU1_SB_DQ(5)   I159 @T6G_MB_LIB.T6G(SCH_1):PAGE40
  BU60 M_D_CPU1_SB_CB<6> @T6G_MB_LIB.T6G(SCH_1):M_D_CPU1_SB_CB(6)   I159 @T6G_MB_LIB.T6G(SCH_1):PAGE40
  AF58 M_D_CPU1_SA_DQS_DN<8> @T6G_MB_LIB.T6G(SCH_1):M_D_CPU1_SA_DQS_DN(8)   I159 @T6G_MB_LIB.T6G(SCH_1):PAGE40
  AL60 M_D_CPU1_SA_DQS_DP<4> @T6G_MB_LIB.T6G(SCH_1):M_D_CPU1_SA_DQS_DP(4)   I159 @T6G_MB_LIB.T6G(SCH_1):PAGE40
   K60 M_D_CPU1_SA_DQ<6> @T6G_MB_LIB.T6G(SCH_1):M_D_CPU1_SA_DQ(6)   I159 @T6G_MB_LIB.T6G(SCH_1):PAGE40
  DC60 M_D_CPU1_SB_DQS_DN<3> @T6G_MB_LIB.T6G(SCH_1):M_D_CPU1_SB_DQS_DN(3)   I159 @T6G_MB_LIB.T6G(SCH_1):PAGE40
  DB58 M_D_CPU1_SB_DQ<27> @T6G_MB_LIB.T6G(SCH_1):M_D_CPU1_SB_DQ(27)   I159 @T6G_MB_LIB.T6G(SCH_1):PAGE40
  CP60 M_D_CPU1_SB_DQ<16> @T6G_MB_LIB.T6G(SCH_1):M_D_CPU1_SB_DQ(16)   I159 @T6G_MB_LIB.T6G(SCH_1):PAGE40
  CG60 M_D_CPU1_SB_DQ<6> @T6G_MB_LIB.T6G(SCH_1):M_D_CPU1_SB_DQ(6)   I159 @T6G_MB_LIB.T6G(SCH_1):PAGE40
  BV58 M_D_CPU1_SB_CB<7> @T6G_MB_LIB.T6G(SCH_1):M_D_CPU1_SB_CB(7)   I159 @T6G_MB_LIB.T6G(SCH_1):PAGE40
  BP60 M_D_CPU1_SB_RSP<0> @T6G_MB_LIB.T6G(SCH_1):M_D_CPU1_SB_RSP(0)   I159 @T6G_MB_LIB.T6G(SCH_1):PAGE40
  AM58 M_D_CPU1_SA_DQS_DN<9> @T6G_MB_LIB.T6G(SCH_1):M_D_CPU1_SA_DQS_DN(9)   I159 @T6G_MB_LIB.T6G(SCH_1):PAGE40
   J59 M_D_CPU1_SA_DQS_DP<5> @T6G_MB_LIB.T6G(SCH_1):M_D_CPU1_SA_DQS_DP(5)   I159 @T6G_MB_LIB.T6G(SCH_1):PAGE40
   L59 M_D_CPU1_SA_DQ<7> @T6G_MB_LIB.T6G(SCH_1):M_D_CPU1_SA_DQ(7)   I159 @T6G_MB_LIB.T6G(SCH_1):PAGE40
  BW59 M_D_CPU1_SB_DQS_DN<4> @T6G_MB_LIB.T6G(SCH_1):M_D_CPU1_SB_DQS_DN(4)   I159 @T6G_MB_LIB.T6G(SCH_1):PAGE40
  CD60 M_D_CPU1_SB_DQS_DP<0> @T6G_MB_LIB.T6G(SCH_1):M_D_CPU1_SB_DQS_DP(0)   I159 @T6G_MB_LIB.T6G(SCH_1):PAGE40
  DD60 M_D_CPU1_SB_DQ<28> @T6G_MB_LIB.T6G(SCH_1):M_D_CPU1_SB_DQ(28)   I159 @T6G_MB_LIB.T6G(SCH_1):PAGE40
  CR59 M_D_CPU1_SB_DQ<17> @T6G_MB_LIB.T6G(SCH_1):M_D_CPU1_SB_DQ(17)   I159 @T6G_MB_LIB.T6G(SCH_1):PAGE40
  CH58 M_D_CPU1_SB_DQ<7> @T6G_MB_LIB.T6G(SCH_1):M_D_CPU1_SB_DQ(7)   I159 @T6G_MB_LIB.T6G(SCH_1):PAGE40
  BR60     NC     NC   I159 @T6G_MB_LIB.T6G(SCH_1):PAGE40
   R59 M_D_CPU1_SA_DQS_DP<6> @T6G_MB_LIB.T6G(SCH_1):M_D_CPU1_SA_DQS_DP(6)   I159 @T6G_MB_LIB.T6G(SCH_1):PAGE40
   L60 M_D_CPU1_SA_DQ<8> @T6G_MB_LIB.T6G(SCH_1):M_D_CPU1_SA_DQ(8)   I159 @T6G_MB_LIB.T6G(SCH_1):PAGE40
  CE59 M_D_CPU1_SB_DQS_DN<5> @T6G_MB_LIB.T6G(SCH_1):M_D_CPU1_SB_DQS_DN(5)   I159 @T6G_MB_LIB.T6G(SCH_1):PAGE40
  CK60 M_D_CPU1_SB_DQS_DP<1> @T6G_MB_LIB.T6G(SCH_1):M_D_CPU1_SB_DQS_DP(1)   I159 @T6G_MB_LIB.T6G(SCH_1):PAGE40
  DE59 M_D_CPU1_SB_DQ<29> @T6G_MB_LIB.T6G(SCH_1):M_D_CPU1_SB_DQ(29)   I159 @T6G_MB_LIB.T6G(SCH_1):PAGE40
  CR60 M_D_CPU1_SB_DQ<18> @T6G_MB_LIB.T6G(SCH_1):M_D_CPU1_SB_DQ(18)   I159 @T6G_MB_LIB.T6G(SCH_1):PAGE40
  CH60 M_D_CPU1_SB_DQ<8> @T6G_MB_LIB.T6G(SCH_1):M_D_CPU1_SB_DQ(8)   I159 @T6G_MB_LIB.T6G(SCH_1):PAGE40
  AA59 M_D_CPU1_SA_DQS_DP<7> @T6G_MB_LIB.T6G(SCH_1):M_D_CPU1_SA_DQS_DP(7)   I159 @T6G_MB_LIB.T6G(SCH_1):PAGE40
   M58 M_D_CPU1_SA_DQ<9> @T6G_MB_LIB.T6G(SCH_1):M_D_CPU1_SA_DQ(9)   I159 @T6G_MB_LIB.T6G(SCH_1):PAGE40
  AW60 M_D_CPU1_SA_CA<0> @T6G_MB_LIB.T6G(SCH_1):M_D_CPU1_SA_CA(0)   I159 @T6G_MB_LIB.T6G(SCH_1):PAGE40
  AV60 M_D_CPU1_SA_CS_N<0> @T6G_MB_LIB.T6G(SCH_1):M_D_CPU1_SA_CS_N(0)   I159 @T6G_MB_LIB.T6G(SCH_1):PAGE40
  CL59 M_D_CPU1_SB_DQS_DN<6> @T6G_MB_LIB.T6G(SCH_1):M_D_CPU1_SB_DQS_DN(6)   I159 @T6G_MB_LIB.T6G(SCH_1):PAGE40
  CT60 M_D_CPU1_SB_DQS_DP<2> @T6G_MB_LIB.T6G(SCH_1):M_D_CPU1_SB_DQS_DP(2)   I159 @T6G_MB_LIB.T6G(SCH_1):PAGE40
  CT58 M_D_CPU1_SB_DQ<19> @T6G_MB_LIB.T6G(SCH_1):M_D_CPU1_SB_DQ(19)   I159 @T6G_MB_LIB.T6G(SCH_1):PAGE40
  CJ59 M_D_CPU1_SB_DQ<9> @T6G_MB_LIB.T6G(SCH_1):M_D_CPU1_SB_DQ(9)   I159 @T6G_MB_LIB.T6G(SCH_1):PAGE40
  BG59 M_D_CPU1_SB_CA<0> @T6G_MB_LIB.T6G(SCH_1):M_D_CPU1_SB_CA(0)   I159 @T6G_MB_LIB.T6G(SCH_1):PAGE40
  AG59 M_D_CPU1_SA_DQS_DP<8> @T6G_MB_LIB.T6G(SCH_1):M_D_CPU1_SA_DQS_DP(8)   I159 @T6G_MB_LIB.T6G(SCH_1):PAGE40
  AH60 M_D_CPU1_SA_DQ<30> @T6G_MB_LIB.T6G(SCH_1):M_D_CPU1_SA_DQ(30)   I159 @T6G_MB_LIB.T6G(SCH_1):PAGE40
  AY60 M_D_CPU1_SA_CA<1> @T6G_MB_LIB.T6G(SCH_1):M_D_CPU1_SA_CA(1)   I159 @T6G_MB_LIB.T6G(SCH_1):PAGE40
  AU60     NC     NC   I159 @T6G_MB_LIB.T6G(SCH_1):PAGE40
  AW59 M_D_CPU1_SA_CS_N<1> @T6G_MB_LIB.T6G(SCH_1):M_D_CPU1_SA_CS_N(1)   I159 @T6G_MB_LIB.T6G(SCH_1):PAGE40
  CU59 M_D_CPU1_SB_DQS_DN<7> @T6G_MB_LIB.T6G(SCH_1):M_D_CPU1_SB_DQS_DN(7)   I159 @T6G_MB_LIB.T6G(SCH_1):PAGE40
  DB60 M_D_CPU1_SB_DQS_DP<3> @T6G_MB_LIB.T6G(SCH_1):M_D_CPU1_SB_DQS_DP(3)   I159 @T6G_MB_LIB.T6G(SCH_1):PAGE40
  BH58 M_D_CPU1_SB_CA<1> @T6G_MB_LIB.T6G(SCH_1):M_D_CPU1_SB_CA(1)   I159 @T6G_MB_LIB.T6G(SCH_1):PAGE40
  AN59 M_D_CPU1_SA_DQS_DP<9> @T6G_MB_LIB.T6G(SCH_1):M_D_CPU1_SA_DQS_DP(9)   I159 @T6G_MB_LIB.T6G(SCH_1):PAGE40
  AJ59 M_D_CPU1_SA_DQ<31> @T6G_MB_LIB.T6G(SCH_1):M_D_CPU1_SA_DQ(31)   I159 @T6G_MB_LIB.T6G(SCH_1):PAGE40
  AA60 M_D_CPU1_SA_DQ<20> @T6G_MB_LIB.T6G(SCH_1):M_D_CPU1_SA_DQ(20)   I159 @T6G_MB_LIB.T6G(SCH_1):PAGE40
  AJ60 M_D_CPU1_SA_CB<0> @T6G_MB_LIB.T6G(SCH_1):M_D_CPU1_SA_CB(0)   I159 @T6G_MB_LIB.T6G(SCH_1):PAGE40
  AY58 M_D_CPU1_SA_CA<2> @T6G_MB_LIB.T6G(SCH_1):M_D_CPU1_SA_CA(2)   I159 @T6G_MB_LIB.T6G(SCH_1):PAGE40
  AV58     NC     NC   I159 @T6G_MB_LIB.T6G(SCH_1):PAGE40
  DC59 M_D_CPU1_SB_DQS_DN<8> @T6G_MB_LIB.T6G(SCH_1):M_D_CPU1_SB_DQS_DN(8)   I159 @T6G_MB_LIB.T6G(SCH_1):PAGE40
  BY58 M_D_CPU1_SB_DQS_DP<4> @T6G_MB_LIB.T6G(SCH_1):M_D_CPU1_SB_DQS_DP(4)   I159 @T6G_MB_LIB.T6G(SCH_1):PAGE40
  BH60 M_D_CPU1_SB_CA<2> @T6G_MB_LIB.T6G(SCH_1):M_D_CPU1_SB_CA(2)   I159 @T6G_MB_LIB.T6G(SCH_1):PAGE40
  AB58 M_D_CPU1_SA_DQ<21> @T6G_MB_LIB.T6G(SCH_1):M_D_CPU1_SA_DQ(21)   I159 @T6G_MB_LIB.T6G(SCH_1):PAGE40
   M60 M_D_CPU1_SA_DQ<10> @T6G_MB_LIB.T6G(SCH_1):M_D_CPU1_SA_DQ(10)   I159 @T6G_MB_LIB.T6G(SCH_1):PAGE40
  AK58 M_D_CPU1_SA_CB<1> @T6G_MB_LIB.T6G(SCH_1):M_D_CPU1_SA_CB(1)   I159 @T6G_MB_LIB.T6G(SCH_1):PAGE40
  BA59 M_D_CPU1_SA_CA<3> @T6G_MB_LIB.T6G(SCH_1):M_D_CPU1_SA_CA(3)   I159 @T6G_MB_LIB.T6G(SCH_1):PAGE40
  BW60 M_D_CPU1_SB_DQS_DN<9> @T6G_MB_LIB.T6G(SCH_1):M_D_CPU1_SB_DQS_DN(9)   I159 @T6G_MB_LIB.T6G(SCH_1):PAGE40
  CF58 M_D_CPU1_SB_DQS_DP<5> @T6G_MB_LIB.T6G(SCH_1):M_D_CPU1_SB_DQS_DP(5)   I159 @T6G_MB_LIB.T6G(SCH_1):PAGE40
  AB60 M_D_CPU1_SA_DQ<22> @T6G_MB_LIB.T6G(SCH_1):M_D_CPU1_SA_DQ(22)   I159 @T6G_MB_LIB.T6G(SCH_1):PAGE40
   N59 M_D_CPU1_SA_DQ<11> @T6G_MB_LIB.T6G(SCH_1):M_D_CPU1_SA_DQ(11)   I159 @T6G_MB_LIB.T6G(SCH_1):PAGE40
  AK60 M_D_CPU1_SA_CB<2> @T6G_MB_LIB.T6G(SCH_1):M_D_CPU1_SA_CB(2)   I159 @T6G_MB_LIB.T6G(SCH_1):PAGE40
  BA60 M_D_CPU1_SA_CA<4> @T6G_MB_LIB.T6G(SCH_1):M_D_CPU1_SA_CA(4)   I159 @T6G_MB_LIB.T6G(SCH_1):PAGE40
  CM58 M_D_CPU1_SB_DQS_DP<6> @T6G_MB_LIB.T6G(SCH_1):M_D_CPU1_SB_DQS_DP(6)   I159 @T6G_MB_LIB.T6G(SCH_1):PAGE40
  BJ59 M_D_CPU1_SB_CA<4> @T6G_MB_LIB.T6G(SCH_1):M_D_CPU1_SB_CA(4)   I159 @T6G_MB_LIB.T6G(SCH_1):PAGE40
  AC59 M_D_CPU1_SA_DQ<23> @T6G_MB_LIB.T6G(SCH_1):M_D_CPU1_SA_DQ(23)   I159 @T6G_MB_LIB.T6G(SCH_1):PAGE40
   R60 M_D_CPU1_SA_DQ<12> @T6G_MB_LIB.T6G(SCH_1):M_D_CPU1_SA_DQ(12)   I159 @T6G_MB_LIB.T6G(SCH_1):PAGE40
  AL59 M_D_CPU1_SA_CB<3> @T6G_MB_LIB.T6G(SCH_1):M_D_CPU1_SA_CB(3)   I159 @T6G_MB_LIB.T6G(SCH_1):PAGE40
  BB60 M_D_CPU1_SA_CA<5> @T6G_MB_LIB.T6G(SCH_1):M_D_CPU1_SA_CA(5)   I159 @T6G_MB_LIB.T6G(SCH_1):PAGE40
  CV58 M_D_CPU1_SB_DQS_DP<7> @T6G_MB_LIB.T6G(SCH_1):M_D_CPU1_SB_DQS_DP(7)   I159 @T6G_MB_LIB.T6G(SCH_1):PAGE40
  BK58 M_D_CPU1_SB_CA<5> @T6G_MB_LIB.T6G(SCH_1):M_D_CPU1_SB_CA(5)   I159 @T6G_MB_LIB.T6G(SCH_1):PAGE40
  BM58 M_D_CPU1_SB_CS_N<0> @T6G_MB_LIB.T6G(SCH_1):M_D_CPU1_SB_CS_N(0)   I159 @T6G_MB_LIB.T6G(SCH_1):PAGE40
   H60 M_D_CPU1_SA_DQS_DN<0> @T6G_MB_LIB.T6G(SCH_1):M_D_CPU1_SA_DQS_DN(0)   I159 @T6G_MB_LIB.T6G(SCH_1):PAGE40
  AC60 M_D_CPU1_SA_DQ<24> @T6G_MB_LIB.T6G(SCH_1):M_D_CPU1_SA_DQ(24)   I159 @T6G_MB_LIB.T6G(SCH_1):PAGE40
   T58 M_D_CPU1_SA_DQ<13> @T6G_MB_LIB.T6G(SCH_1):M_D_CPU1_SA_DQ(13)   I159 @T6G_MB_LIB.T6G(SCH_1):PAGE40
  AN60 M_D_CPU1_SA_CB<4> @T6G_MB_LIB.T6G(SCH_1):M_D_CPU1_SA_CB(4)   I159 @T6G_MB_LIB.T6G(SCH_1):PAGE40
  BB58 M_D_CPU1_SA_CA<6> @T6G_MB_LIB.T6G(SCH_1):M_D_CPU1_SA_CA(6)   I159 @T6G_MB_LIB.T6G(SCH_1):PAGE40
  DD58 M_D_CPU1_SB_DQS_DP<8> @T6G_MB_LIB.T6G(SCH_1):M_D_CPU1_SB_DQS_DP(8)   I159 @T6G_MB_LIB.T6G(SCH_1):PAGE40
  DE60 M_D_CPU1_SB_DQ<30> @T6G_MB_LIB.T6G(SCH_1):M_D_CPU1_SB_DQ(30)   I159 @T6G_MB_LIB.T6G(SCH_1):PAGE40
  BK60 M_D_CPU1_SB_CA<6> @T6G_MB_LIB.T6G(SCH_1):M_D_CPU1_SB_CA(6)   I159 @T6G_MB_LIB.T6G(SCH_1):PAGE40
  BL59     NC     NC   I159 @T6G_MB_LIB.T6G(SCH_1):PAGE40
  BN60 M_D_CPU1_SB_CS_N<1> @T6G_MB_LIB.T6G(SCH_1):M_D_CPU1_SB_CS_N(1)   I159 @T6G_MB_LIB.T6G(SCH_1):PAGE40
   P60 M_D_CPU1_SA_DQS_DN<1> @T6G_MB_LIB.T6G(SCH_1):M_D_CPU1_SA_DQS_DN(1)   I159 @T6G_MB_LIB.T6G(SCH_1):PAGE40
  AD58 M_D_CPU1_SA_DQ<25> @T6G_MB_LIB.T6G(SCH_1):M_D_CPU1_SA_DQ(25)   I159 @T6G_MB_LIB.T6G(SCH_1):PAGE40
   T60 M_D_CPU1_SA_DQ<14> @T6G_MB_LIB.T6G(SCH_1):M_D_CPU1_SA_DQ(14)   I159 @T6G_MB_LIB.T6G(SCH_1):PAGE40
  AP58 M_D_CPU1_SA_CB<5> @T6G_MB_LIB.T6G(SCH_1):M_D_CPU1_SA_CB(5)   I159 @T6G_MB_LIB.T6G(SCH_1):PAGE40
  DF60 M_D_CPU1_SB_DQ<31> @T6G_MB_LIB.T6G(SCH_1):M_D_CPU1_SB_DQ(31)   I159 @T6G_MB_LIB.T6G(SCH_1):PAGE40
  CV60 M_D_CPU1_SB_DQ<20> @T6G_MB_LIB.T6G(SCH_1):M_D_CPU1_SB_DQ(20)   I159 @T6G_MB_LIB.T6G(SCH_1):PAGE40
  BY60 M_D_CPU1_SB_CB<0> @T6G_MB_LIB.T6G(SCH_1):M_D_CPU1_SB_CB(0)   I159 @T6G_MB_LIB.T6G(SCH_1):PAGE40
  BM60     NC     NC   I159 @T6G_MB_LIB.T6G(SCH_1):PAGE40
   Y60 M_D_CPU1_SA_DQS_DN<2> @T6G_MB_LIB.T6G(SCH_1):M_D_CPU1_SA_DQS_DN(2)   I159 @T6G_MB_LIB.T6G(SCH_1):PAGE40
  AD60 M_D_CPU1_SA_DQ<26> @T6G_MB_LIB.T6G(SCH_1):M_D_CPU1_SA_DQ(26)   I159 @T6G_MB_LIB.T6G(SCH_1):PAGE40
   U59 M_D_CPU1_SA_DQ<15> @T6G_MB_LIB.T6G(SCH_1):M_D_CPU1_SA_DQ(15)   I159 @T6G_MB_LIB.T6G(SCH_1):PAGE40
   E60 M_D_CPU1_SA_DQ<0> @T6G_MB_LIB.T6G(SCH_1):M_D_CPU1_SA_DQ(0)   I159 @T6G_MB_LIB.T6G(SCH_1):PAGE40
  AP60 M_D_CPU1_SA_CB<6> @T6G_MB_LIB.T6G(SCH_1):M_D_CPU1_SA_CB(6)   I159 @T6G_MB_LIB.T6G(SCH_1):PAGE40
  CW59 M_D_CPU1_SB_DQ<21> @T6G_MB_LIB.T6G(SCH_1):M_D_CPU1_SB_DQ(21)   I159 @T6G_MB_LIB.T6G(SCH_1):PAGE40
  CJ60 M_D_CPU1_SB_DQ<10> @T6G_MB_LIB.T6G(SCH_1):M_D_CPU1_SB_DQ(10)   I159 @T6G_MB_LIB.T6G(SCH_1):PAGE40
  CB60 M_D_CPU1_SB_DQ<0> @T6G_MB_LIB.T6G(SCH_1):M_D_CPU1_SB_DQ(0)   I159 @T6G_MB_LIB.T6G(SCH_1):PAGE40
  CA59 M_D_CPU1_SB_CB<1> @T6G_MB_LIB.T6G(SCH_1):M_D_CPU1_SB_CB(1)   I159 @T6G_MB_LIB.T6G(SCH_1):PAGE40
  AF60 M_D_CPU1_SA_DQS_DN<3> @T6G_MB_LIB.T6G(SCH_1):M_D_CPU1_SA_DQS_DN(3)   I159 @T6G_MB_LIB.T6G(SCH_1):PAGE40
  AE59 M_D_CPU1_SA_DQ<27> @T6G_MB_LIB.T6G(SCH_1):M_D_CPU1_SA_DQ(27)   I159 @T6G_MB_LIB.T6G(SCH_1):PAGE40
   U60 M_D_CPU1_SA_DQ<16> @T6G_MB_LIB.T6G(SCH_1):M_D_CPU1_SA_DQ(16)   I159 @T6G_MB_LIB.T6G(SCH_1):PAGE40
   F58 M_D_CPU1_SA_DQ<1> @T6G_MB_LIB.T6G(SCH_1):M_D_CPU1_SA_DQ(1)   I159 @T6G_MB_LIB.T6G(SCH_1):PAGE40
  AR59 M_D_CPU1_SA_CB<7> @T6G_MB_LIB.T6G(SCH_1):M_D_CPU1_SA_CB(7)   I159 @T6G_MB_LIB.T6G(SCH_1):PAGE40
  BN59 M_D_CPU1_SA_RSP<0> @T6G_MB_LIB.T6G(SCH_1):M_D_CPU1_SA_RSP(0)   I159 @T6G_MB_LIB.T6G(SCH_1):PAGE40
  CW60 M_D_CPU1_SB_DQ<22> @T6G_MB_LIB.T6G(SCH_1):M_D_CPU1_SB_DQ(22)   I159 @T6G_MB_LIB.T6G(SCH_1):PAGE40
  CK58 M_D_CPU1_SB_DQ<11> @T6G_MB_LIB.T6G(SCH_1):M_D_CPU1_SB_DQ(11)   I159 @T6G_MB_LIB.T6G(SCH_1):PAGE40
  CC59 M_D_CPU1_SB_DQ<1> @T6G_MB_LIB.T6G(SCH_1):M_D_CPU1_SB_DQ(1)   I159 @T6G_MB_LIB.T6G(SCH_1):PAGE40
  CA60 M_D_CPU1_SB_CB<2> @T6G_MB_LIB.T6G(SCH_1):M_D_CPU1_SB_CB(2)   I159 @T6G_MB_LIB.T6G(SCH_1):PAGE40
  AM60 M_D_CPU1_SA_DQS_DN<4> @T6G_MB_LIB.T6G(SCH_1):M_D_CPU1_SA_DQS_DN(4)   I159 @T6G_MB_LIB.T6G(SCH_1):PAGE40
   G60 M_D_CPU1_SA_DQS_DP<0> @T6G_MB_LIB.T6G(SCH_1):M_D_CPU1_SA_DQS_DP(0)   I159 @T6G_MB_LIB.T6G(SCH_1):PAGE40
  AG60 M_D_CPU1_SA_DQ<28> @T6G_MB_LIB.T6G(SCH_1):M_D_CPU1_SA_DQ(28)   I159 @T6G_MB_LIB.T6G(SCH_1):PAGE40
   V58 M_D_CPU1_SA_DQ<17> @T6G_MB_LIB.T6G(SCH_1):M_D_CPU1_SA_DQ(17)   I159 @T6G_MB_LIB.T6G(SCH_1):PAGE40
   F60 M_D_CPU1_SA_DQ<2> @T6G_MB_LIB.T6G(SCH_1):M_D_CPU1_SA_DQ(2)   I159 @T6G_MB_LIB.T6G(SCH_1):PAGE40
  BP58     NC     NC   I159 @T6G_MB_LIB.T6G(SCH_1):PAGE40
  BC59 M_D_CPU1_SA_PAR @T6G_MB_LIB.T6G(SCH_1):M_D_CPU1_SA_PAR   I159 @T6G_MB_LIB.T6G(SCH_1):PAGE40
  BL60 M_D_CPU1_SB_PAR @T6G_MB_LIB.T6G(SCH_1):M_D_CPU1_SB_PAR   I159 @T6G_MB_LIB.T6G(SCH_1):PAGE40
  BJ60 M_D_CPU1_SB_CA<3> @T6G_MB_LIB.T6G(SCH_1):M_D_CPU1_SB_CA(3)   I159 @T6G_MB_LIB.T6G(SCH_1):PAGE40
  BV60 M_D_CPU1_SB_DQS_DP<9> @T6G_MB_LIB.T6G(SCH_1):M_D_CPU1_SB_DQS_DP(9)   I159 @T6G_MB_LIB.T6G(SCH_1):PAGE40
  BC60 M_D_CPU1_CLK_DP<0> @T6G_MB_LIB.T6G(SCH_1):M_D_CPU1_CLK_DP(0)   I159 @T6G_MB_LIB.T6G(SCH_1):PAGE40
  BD60 M_D_CPU1_CLK_DN<0> @T6G_MB_LIB.T6G(SCH_1):M_D_CPU1_CLK_DN(0)   I159 @T6G_MB_LIB.T6G(SCH_1):PAGE40
  BF60     NC     NC   I159 @T6G_MB_LIB.T6G(SCH_1):PAGE40
  BG60     NC     NC   I159 @T6G_MB_LIB.T6G(SCH_1):PAGE40
  BF58 TP_M_D_CPU1_SA_TEST39D @T6G_MB_LIB.T6G(SCH_1):TP_M_D_CPU1_SA_TEST39D   I159 @T6G_MB_LIB.T6G(SCH_1):PAGE40
  AT69 M_E_CPU1_ALERT_R_N @T6G_MB_LIB.T6G(SCH_1):M_E_CPU1_ALERT_R_N   I159 @T6G_MB_LIB.T6G(SCH_1):PAGE41
  AU69 M_E_CPU1_RESET_N @T6G_MB_LIB.T6G(SCH_1):M_E_CPU1_RESET_N   I159 @T6G_MB_LIB.T6G(SCH_1):PAGE41
  CU71 M_E_CPU1_SB_DQS_DN<2> @T6G_MB_LIB.T6G(SCH_1):M_E_CPU1_SB_DQS_DN(2)   I159 @T6G_MB_LIB.T6G(SCH_1):PAGE41
  DA71 M_E_CPU1_SB_DQ<26> @T6G_MB_LIB.T6G(SCH_1):M_E_CPU1_SB_DQ(26)   I159 @T6G_MB_LIB.T6G(SCH_1):PAGE41
  CP69 M_E_CPU1_SB_DQ<15> @T6G_MB_LIB.T6G(SCH_1):M_E_CPU1_SB_DQ(15)   I159 @T6G_MB_LIB.T6G(SCH_1):PAGE41
  BU71 M_E_CPU1_SB_CB<6> @T6G_MB_LIB.T6G(SCH_1):M_E_CPU1_SB_CB(6)   I159 @T6G_MB_LIB.T6G(SCH_1):PAGE41
  AF69 M_E_CPU1_SA_DQS_DN<8> @T6G_MB_LIB.T6G(SCH_1):M_E_CPU1_SA_DQS_DN(8)   I159 @T6G_MB_LIB.T6G(SCH_1):PAGE41
  AL71 M_E_CPU1_SA_DQS_DP<4> @T6G_MB_LIB.T6G(SCH_1):M_E_CPU1_SA_DQS_DP(4)   I159 @T6G_MB_LIB.T6G(SCH_1):PAGE41
  DC71 M_E_CPU1_SB_DQS_DN<3> @T6G_MB_LIB.T6G(SCH_1):M_E_CPU1_SB_DQS_DN(3)   I159 @T6G_MB_LIB.T6G(SCH_1):PAGE41
  DB69 M_E_CPU1_SB_DQ<27> @T6G_MB_LIB.T6G(SCH_1):M_E_CPU1_SB_DQ(27)   I159 @T6G_MB_LIB.T6G(SCH_1):PAGE41
  CP70 M_E_CPU1_SB_DQ<16> @T6G_MB_LIB.T6G(SCH_1):M_E_CPU1_SB_DQ(16)   I159 @T6G_MB_LIB.T6G(SCH_1):PAGE41
  BV69 M_E_CPU1_SB_CB<7> @T6G_MB_LIB.T6G(SCH_1):M_E_CPU1_SB_CB(7)   I159 @T6G_MB_LIB.T6G(SCH_1):PAGE41
  BR71     NC     NC   I159 @T6G_MB_LIB.T6G(SCH_1):PAGE41
  BP70 M_E_CPU1_SB_RSP<0> @T6G_MB_LIB.T6G(SCH_1):M_E_CPU1_SB_RSP(0)   I159 @T6G_MB_LIB.T6G(SCH_1):PAGE41
  AM69 M_E_CPU1_SA_DQS_DN<9> @T6G_MB_LIB.T6G(SCH_1):M_E_CPU1_SA_DQS_DN(9)   I159 @T6G_MB_LIB.T6G(SCH_1):PAGE41
   J69 M_E_CPU1_SA_DQS_DP<5> @T6G_MB_LIB.T6G(SCH_1):M_E_CPU1_SA_DQS_DP(5)   I159 @T6G_MB_LIB.T6G(SCH_1):PAGE41
  BW69 M_E_CPU1_SB_DQS_DN<4> @T6G_MB_LIB.T6G(SCH_1):M_E_CPU1_SB_DQS_DN(4)   I159 @T6G_MB_LIB.T6G(SCH_1):PAGE41
  CD70 M_E_CPU1_SB_DQS_DP<0> @T6G_MB_LIB.T6G(SCH_1):M_E_CPU1_SB_DQS_DP(0)   I159 @T6G_MB_LIB.T6G(SCH_1):PAGE41
  DD70 M_E_CPU1_SB_DQ<28> @T6G_MB_LIB.T6G(SCH_1):M_E_CPU1_SB_DQ(28)   I159 @T6G_MB_LIB.T6G(SCH_1):PAGE41
  CR69 M_E_CPU1_SB_DQ<17> @T6G_MB_LIB.T6G(SCH_1):M_E_CPU1_SB_DQ(17)   I159 @T6G_MB_LIB.T6G(SCH_1):PAGE41
   R69 M_E_CPU1_SA_DQS_DP<6> @T6G_MB_LIB.T6G(SCH_1):M_E_CPU1_SA_DQS_DP(6)   I159 @T6G_MB_LIB.T6G(SCH_1):PAGE41
  CE69 M_E_CPU1_SB_DQS_DN<5> @T6G_MB_LIB.T6G(SCH_1):M_E_CPU1_SB_DQS_DN(5)   I159 @T6G_MB_LIB.T6G(SCH_1):PAGE41
  CK70 M_E_CPU1_SB_DQS_DP<1> @T6G_MB_LIB.T6G(SCH_1):M_E_CPU1_SB_DQS_DP(1)   I159 @T6G_MB_LIB.T6G(SCH_1):PAGE41
  DE69 M_E_CPU1_SB_DQ<29> @T6G_MB_LIB.T6G(SCH_1):M_E_CPU1_SB_DQ(29)   I159 @T6G_MB_LIB.T6G(SCH_1):PAGE41
  CR71 M_E_CPU1_SB_DQ<18> @T6G_MB_LIB.T6G(SCH_1):M_E_CPU1_SB_DQ(18)   I159 @T6G_MB_LIB.T6G(SCH_1):PAGE41
  AA69 M_E_CPU1_SA_DQS_DP<7> @T6G_MB_LIB.T6G(SCH_1):M_E_CPU1_SA_DQS_DP(7)   I159 @T6G_MB_LIB.T6G(SCH_1):PAGE41
   E71 M_E_CPU1_SA_DQ<0> @T6G_MB_LIB.T6G(SCH_1):M_E_CPU1_SA_DQ(0)   I159 @T6G_MB_LIB.T6G(SCH_1):PAGE41
  AU71     NC     NC   I159 @T6G_MB_LIB.T6G(SCH_1):PAGE41
  AV70 M_E_CPU1_SA_CS_N<0> @T6G_MB_LIB.T6G(SCH_1):M_E_CPU1_SA_CS_N(0)   I159 @T6G_MB_LIB.T6G(SCH_1):PAGE41
  CL69 M_E_CPU1_SB_DQS_DN<6> @T6G_MB_LIB.T6G(SCH_1):M_E_CPU1_SB_DQS_DN(6)   I159 @T6G_MB_LIB.T6G(SCH_1):PAGE41
  CT70 M_E_CPU1_SB_DQS_DP<2> @T6G_MB_LIB.T6G(SCH_1):M_E_CPU1_SB_DQS_DP(2)   I159 @T6G_MB_LIB.T6G(SCH_1):PAGE41
  CT69 M_E_CPU1_SB_DQ<19> @T6G_MB_LIB.T6G(SCH_1):M_E_CPU1_SB_DQ(19)   I159 @T6G_MB_LIB.T6G(SCH_1):PAGE41
  CB70 M_E_CPU1_SB_DQ<0> @T6G_MB_LIB.T6G(SCH_1):M_E_CPU1_SB_DQ(0)   I159 @T6G_MB_LIB.T6G(SCH_1):PAGE41
  AG69 M_E_CPU1_SA_DQS_DP<8> @T6G_MB_LIB.T6G(SCH_1):M_E_CPU1_SA_DQS_DP(8)   I159 @T6G_MB_LIB.T6G(SCH_1):PAGE41
  AH70 M_E_CPU1_SA_DQ<30> @T6G_MB_LIB.T6G(SCH_1):M_E_CPU1_SA_DQ(30)   I159 @T6G_MB_LIB.T6G(SCH_1):PAGE41
   F69 M_E_CPU1_SA_DQ<1> @T6G_MB_LIB.T6G(SCH_1):M_E_CPU1_SA_DQ(1)   I159 @T6G_MB_LIB.T6G(SCH_1):PAGE41
  AV69     NC     NC   I159 @T6G_MB_LIB.T6G(SCH_1):PAGE41
  AW69 M_E_CPU1_SA_CS_N<1> @T6G_MB_LIB.T6G(SCH_1):M_E_CPU1_SA_CS_N(1)   I159 @T6G_MB_LIB.T6G(SCH_1):PAGE41
  CU69 M_E_CPU1_SB_DQS_DN<7> @T6G_MB_LIB.T6G(SCH_1):M_E_CPU1_SB_DQS_DN(7)   I159 @T6G_MB_LIB.T6G(SCH_1):PAGE41
  DB70 M_E_CPU1_SB_DQS_DP<3> @T6G_MB_LIB.T6G(SCH_1):M_E_CPU1_SB_DQS_DP(3)   I159 @T6G_MB_LIB.T6G(SCH_1):PAGE41
  CC69 M_E_CPU1_SB_DQ<1> @T6G_MB_LIB.T6G(SCH_1):M_E_CPU1_SB_DQ(1)   I159 @T6G_MB_LIB.T6G(SCH_1):PAGE41
  AN69 M_E_CPU1_SA_DQS_DP<9> @T6G_MB_LIB.T6G(SCH_1):M_E_CPU1_SA_DQS_DP(9)   I159 @T6G_MB_LIB.T6G(SCH_1):PAGE41
  AJ69 M_E_CPU1_SA_DQ<31> @T6G_MB_LIB.T6G(SCH_1):M_E_CPU1_SA_DQ(31)   I159 @T6G_MB_LIB.T6G(SCH_1):PAGE41
  AA71 M_E_CPU1_SA_DQ<20> @T6G_MB_LIB.T6G(SCH_1):M_E_CPU1_SA_DQ(20)   I159 @T6G_MB_LIB.T6G(SCH_1):PAGE41
   F70 M_E_CPU1_SA_DQ<2> @T6G_MB_LIB.T6G(SCH_1):M_E_CPU1_SA_DQ(2)   I159 @T6G_MB_LIB.T6G(SCH_1):PAGE41
  AJ71 M_E_CPU1_SA_CB<0> @T6G_MB_LIB.T6G(SCH_1):M_E_CPU1_SA_CB(0)   I159 @T6G_MB_LIB.T6G(SCH_1):PAGE41
  AW71 M_E_CPU1_SA_CA<0> @T6G_MB_LIB.T6G(SCH_1):M_E_CPU1_SA_CA(0)   I159 @T6G_MB_LIB.T6G(SCH_1):PAGE41
  DC69 M_E_CPU1_SB_DQS_DN<8> @T6G_MB_LIB.T6G(SCH_1):M_E_CPU1_SB_DQS_DN(8)   I159 @T6G_MB_LIB.T6G(SCH_1):PAGE41
  BY69 M_E_CPU1_SB_DQS_DP<4> @T6G_MB_LIB.T6G(SCH_1):M_E_CPU1_SB_DQS_DP(4)   I159 @T6G_MB_LIB.T6G(SCH_1):PAGE41
  CC71 M_E_CPU1_SB_DQ<2> @T6G_MB_LIB.T6G(SCH_1):M_E_CPU1_SB_DQ(2)   I159 @T6G_MB_LIB.T6G(SCH_1):PAGE41
  BG69 M_E_CPU1_SB_CA<0> @T6G_MB_LIB.T6G(SCH_1):M_E_CPU1_SB_CA(0)   I159 @T6G_MB_LIB.T6G(SCH_1):PAGE41
  AB69 M_E_CPU1_SA_DQ<21> @T6G_MB_LIB.T6G(SCH_1):M_E_CPU1_SA_DQ(21)   I159 @T6G_MB_LIB.T6G(SCH_1):PAGE41
   M70 M_E_CPU1_SA_DQ<10> @T6G_MB_LIB.T6G(SCH_1):M_E_CPU1_SA_DQ(10)   I159 @T6G_MB_LIB.T6G(SCH_1):PAGE41
   G69 M_E_CPU1_SA_DQ<3> @T6G_MB_LIB.T6G(SCH_1):M_E_CPU1_SA_DQ(3)   I159 @T6G_MB_LIB.T6G(SCH_1):PAGE41
  AK69 M_E_CPU1_SA_CB<1> @T6G_MB_LIB.T6G(SCH_1):M_E_CPU1_SA_CB(1)   I159 @T6G_MB_LIB.T6G(SCH_1):PAGE41
  AY70 M_E_CPU1_SA_CA<1> @T6G_MB_LIB.T6G(SCH_1):M_E_CPU1_SA_CA(1)   I159 @T6G_MB_LIB.T6G(SCH_1):PAGE41
  BW71 M_E_CPU1_SB_DQS_DN<9> @T6G_MB_LIB.T6G(SCH_1):M_E_CPU1_SB_DQS_DN(9)   I159 @T6G_MB_LIB.T6G(SCH_1):PAGE41
  CF69 M_E_CPU1_SB_DQS_DP<5> @T6G_MB_LIB.T6G(SCH_1):M_E_CPU1_SB_DQS_DP(5)   I159 @T6G_MB_LIB.T6G(SCH_1):PAGE41
  CD69 M_E_CPU1_SB_DQ<3> @T6G_MB_LIB.T6G(SCH_1):M_E_CPU1_SB_DQ(3)   I159 @T6G_MB_LIB.T6G(SCH_1):PAGE41
  BH69 M_E_CPU1_SB_CA<1> @T6G_MB_LIB.T6G(SCH_1):M_E_CPU1_SB_CA(1)   I159 @T6G_MB_LIB.T6G(SCH_1):PAGE41
  AB70 M_E_CPU1_SA_DQ<22> @T6G_MB_LIB.T6G(SCH_1):M_E_CPU1_SA_DQ(22)   I159 @T6G_MB_LIB.T6G(SCH_1):PAGE41
   N69 M_E_CPU1_SA_DQ<11> @T6G_MB_LIB.T6G(SCH_1):M_E_CPU1_SA_DQ(11)   I159 @T6G_MB_LIB.T6G(SCH_1):PAGE41
   J71 M_E_CPU1_SA_DQ<4> @T6G_MB_LIB.T6G(SCH_1):M_E_CPU1_SA_DQ(4)   I159 @T6G_MB_LIB.T6G(SCH_1):PAGE41
  AK70 M_E_CPU1_SA_CB<2> @T6G_MB_LIB.T6G(SCH_1):M_E_CPU1_SA_CB(2)   I159 @T6G_MB_LIB.T6G(SCH_1):PAGE41
  AY69 M_E_CPU1_SA_CA<2> @T6G_MB_LIB.T6G(SCH_1):M_E_CPU1_SA_CA(2)   I159 @T6G_MB_LIB.T6G(SCH_1):PAGE41
  CM69 M_E_CPU1_SB_DQS_DP<6> @T6G_MB_LIB.T6G(SCH_1):M_E_CPU1_SB_DQS_DP(6)   I159 @T6G_MB_LIB.T6G(SCH_1):PAGE41
  CF70 M_E_CPU1_SB_DQ<4> @T6G_MB_LIB.T6G(SCH_1):M_E_CPU1_SB_DQ(4)   I159 @T6G_MB_LIB.T6G(SCH_1):PAGE41
  BH70 M_E_CPU1_SB_CA<2> @T6G_MB_LIB.T6G(SCH_1):M_E_CPU1_SB_CA(2)   I159 @T6G_MB_LIB.T6G(SCH_1):PAGE41
  AC69 M_E_CPU1_SA_DQ<23> @T6G_MB_LIB.T6G(SCH_1):M_E_CPU1_SA_DQ(23)   I159 @T6G_MB_LIB.T6G(SCH_1):PAGE41
   R71 M_E_CPU1_SA_DQ<12> @T6G_MB_LIB.T6G(SCH_1):M_E_CPU1_SA_DQ(12)   I159 @T6G_MB_LIB.T6G(SCH_1):PAGE41
   K69 M_E_CPU1_SA_DQ<5> @T6G_MB_LIB.T6G(SCH_1):M_E_CPU1_SA_DQ(5)   I159 @T6G_MB_LIB.T6G(SCH_1):PAGE41
  AL69 M_E_CPU1_SA_CB<3> @T6G_MB_LIB.T6G(SCH_1):M_E_CPU1_SA_CB(3)   I159 @T6G_MB_LIB.T6G(SCH_1):PAGE41
  BA69 M_E_CPU1_SA_CA<3> @T6G_MB_LIB.T6G(SCH_1):M_E_CPU1_SA_CA(3)   I159 @T6G_MB_LIB.T6G(SCH_1):PAGE41
  CV69 M_E_CPU1_SB_DQS_DP<7> @T6G_MB_LIB.T6G(SCH_1):M_E_CPU1_SB_DQS_DP(7)   I159 @T6G_MB_LIB.T6G(SCH_1):PAGE41
  CG69 M_E_CPU1_SB_DQ<5> @T6G_MB_LIB.T6G(SCH_1):M_E_CPU1_SB_DQ(5)   I159 @T6G_MB_LIB.T6G(SCH_1):PAGE41
  BJ71 M_E_CPU1_SB_CA<3> @T6G_MB_LIB.T6G(SCH_1):M_E_CPU1_SB_CA(3)   I159 @T6G_MB_LIB.T6G(SCH_1):PAGE41
  BL69     NC     NC   I159 @T6G_MB_LIB.T6G(SCH_1):PAGE41
  BM69 M_E_CPU1_SB_CS_N<0> @T6G_MB_LIB.T6G(SCH_1):M_E_CPU1_SB_CS_N(0)   I159 @T6G_MB_LIB.T6G(SCH_1):PAGE41
   H70 M_E_CPU1_SA_DQS_DN<0> @T6G_MB_LIB.T6G(SCH_1):M_E_CPU1_SA_DQS_DN(0)   I159 @T6G_MB_LIB.T6G(SCH_1):PAGE41
  AC71 M_E_CPU1_SA_DQ<24> @T6G_MB_LIB.T6G(SCH_1):M_E_CPU1_SA_DQ(24)   I159 @T6G_MB_LIB.T6G(SCH_1):PAGE41
   T69 M_E_CPU1_SA_DQ<13> @T6G_MB_LIB.T6G(SCH_1):M_E_CPU1_SA_DQ(13)   I159 @T6G_MB_LIB.T6G(SCH_1):PAGE41
   K70 M_E_CPU1_SA_DQ<6> @T6G_MB_LIB.T6G(SCH_1):M_E_CPU1_SA_DQ(6)   I159 @T6G_MB_LIB.T6G(SCH_1):PAGE41
  AN71 M_E_CPU1_SA_CB<4> @T6G_MB_LIB.T6G(SCH_1):M_E_CPU1_SA_CB(4)   I159 @T6G_MB_LIB.T6G(SCH_1):PAGE41
  BA71 M_E_CPU1_SA_CA<4> @T6G_MB_LIB.T6G(SCH_1):M_E_CPU1_SA_CA(4)   I159 @T6G_MB_LIB.T6G(SCH_1):PAGE41
  DD69 M_E_CPU1_SB_DQS_DP<8> @T6G_MB_LIB.T6G(SCH_1):M_E_CPU1_SB_DQS_DP(8)   I159 @T6G_MB_LIB.T6G(SCH_1):PAGE41
  DE71 M_E_CPU1_SB_DQ<30> @T6G_MB_LIB.T6G(SCH_1):M_E_CPU1_SB_DQ(30)   I159 @T6G_MB_LIB.T6G(SCH_1):PAGE41
  CG71 M_E_CPU1_SB_DQ<6> @T6G_MB_LIB.T6G(SCH_1):M_E_CPU1_SB_DQ(6)   I159 @T6G_MB_LIB.T6G(SCH_1):PAGE41
  BJ69 M_E_CPU1_SB_CA<4> @T6G_MB_LIB.T6G(SCH_1):M_E_CPU1_SB_CA(4)   I159 @T6G_MB_LIB.T6G(SCH_1):PAGE41
  BM70     NC     NC   I159 @T6G_MB_LIB.T6G(SCH_1):PAGE41
  BN71 M_E_CPU1_SB_CS_N<1> @T6G_MB_LIB.T6G(SCH_1):M_E_CPU1_SB_CS_N(1)   I159 @T6G_MB_LIB.T6G(SCH_1):PAGE41
   P70 M_E_CPU1_SA_DQS_DN<1> @T6G_MB_LIB.T6G(SCH_1):M_E_CPU1_SA_DQS_DN(1)   I159 @T6G_MB_LIB.T6G(SCH_1):PAGE41
  AD69 M_E_CPU1_SA_DQ<25> @T6G_MB_LIB.T6G(SCH_1):M_E_CPU1_SA_DQ(25)   I159 @T6G_MB_LIB.T6G(SCH_1):PAGE41
   T70 M_E_CPU1_SA_DQ<14> @T6G_MB_LIB.T6G(SCH_1):M_E_CPU1_SA_DQ(14)   I159 @T6G_MB_LIB.T6G(SCH_1):PAGE41
   L69 M_E_CPU1_SA_DQ<7> @T6G_MB_LIB.T6G(SCH_1):M_E_CPU1_SA_DQ(7)   I159 @T6G_MB_LIB.T6G(SCH_1):PAGE41
  AP69 M_E_CPU1_SA_CB<5> @T6G_MB_LIB.T6G(SCH_1):M_E_CPU1_SA_CB(5)   I159 @T6G_MB_LIB.T6G(SCH_1):PAGE41
  BB70 M_E_CPU1_SA_CA<5> @T6G_MB_LIB.T6G(SCH_1):M_E_CPU1_SA_CA(5)   I159 @T6G_MB_LIB.T6G(SCH_1):PAGE41
  DF69 M_E_CPU1_SB_DQ<31> @T6G_MB_LIB.T6G(SCH_1):M_E_CPU1_SB_DQ(31)   I159 @T6G_MB_LIB.T6G(SCH_1):PAGE41
  CV70 M_E_CPU1_SB_DQ<20> @T6G_MB_LIB.T6G(SCH_1):M_E_CPU1_SB_DQ(20)   I159 @T6G_MB_LIB.T6G(SCH_1):PAGE41
  CH69 M_E_CPU1_SB_DQ<7> @T6G_MB_LIB.T6G(SCH_1):M_E_CPU1_SB_DQ(7)   I159 @T6G_MB_LIB.T6G(SCH_1):PAGE41
  BY70 M_E_CPU1_SB_CB<0> @T6G_MB_LIB.T6G(SCH_1):M_E_CPU1_SB_CB(0)   I159 @T6G_MB_LIB.T6G(SCH_1):PAGE41
  BK69 M_E_CPU1_SB_CA<5> @T6G_MB_LIB.T6G(SCH_1):M_E_CPU1_SB_CA(5)   I159 @T6G_MB_LIB.T6G(SCH_1):PAGE41
   Y70 M_E_CPU1_SA_DQS_DN<2> @T6G_MB_LIB.T6G(SCH_1):M_E_CPU1_SA_DQS_DN(2)   I159 @T6G_MB_LIB.T6G(SCH_1):PAGE41
  AD70 M_E_CPU1_SA_DQ<26> @T6G_MB_LIB.T6G(SCH_1):M_E_CPU1_SA_DQ(26)   I159 @T6G_MB_LIB.T6G(SCH_1):PAGE41
   U69 M_E_CPU1_SA_DQ<15> @T6G_MB_LIB.T6G(SCH_1):M_E_CPU1_SA_DQ(15)   I159 @T6G_MB_LIB.T6G(SCH_1):PAGE41
   L71 M_E_CPU1_SA_DQ<8> @T6G_MB_LIB.T6G(SCH_1):M_E_CPU1_SA_DQ(8)   I159 @T6G_MB_LIB.T6G(SCH_1):PAGE41
  AP70 M_E_CPU1_SA_CB<6> @T6G_MB_LIB.T6G(SCH_1):M_E_CPU1_SA_CB(6)   I159 @T6G_MB_LIB.T6G(SCH_1):PAGE41
  BB69 M_E_CPU1_SA_CA<6> @T6G_MB_LIB.T6G(SCH_1):M_E_CPU1_SA_CA(6)   I159 @T6G_MB_LIB.T6G(SCH_1):PAGE41
  CW69 M_E_CPU1_SB_DQ<21> @T6G_MB_LIB.T6G(SCH_1):M_E_CPU1_SB_DQ(21)   I159 @T6G_MB_LIB.T6G(SCH_1):PAGE41
  CJ71 M_E_CPU1_SB_DQ<10> @T6G_MB_LIB.T6G(SCH_1):M_E_CPU1_SB_DQ(10)   I159 @T6G_MB_LIB.T6G(SCH_1):PAGE41
  CH70 M_E_CPU1_SB_DQ<8> @T6G_MB_LIB.T6G(SCH_1):M_E_CPU1_SB_DQ(8)   I159 @T6G_MB_LIB.T6G(SCH_1):PAGE41
  CA69 M_E_CPU1_SB_CB<1> @T6G_MB_LIB.T6G(SCH_1):M_E_CPU1_SB_CB(1)   I159 @T6G_MB_LIB.T6G(SCH_1):PAGE41
  BK70 M_E_CPU1_SB_CA<6> @T6G_MB_LIB.T6G(SCH_1):M_E_CPU1_SB_CA(6)   I159 @T6G_MB_LIB.T6G(SCH_1):PAGE41
  AF70 M_E_CPU1_SA_DQS_DN<3> @T6G_MB_LIB.T6G(SCH_1):M_E_CPU1_SA_DQS_DN(3)   I159 @T6G_MB_LIB.T6G(SCH_1):PAGE41
  AE69 M_E_CPU1_SA_DQ<27> @T6G_MB_LIB.T6G(SCH_1):M_E_CPU1_SA_DQ(27)   I159 @T6G_MB_LIB.T6G(SCH_1):PAGE41
   U71 M_E_CPU1_SA_DQ<16> @T6G_MB_LIB.T6G(SCH_1):M_E_CPU1_SA_DQ(16)   I159 @T6G_MB_LIB.T6G(SCH_1):PAGE41
   M69 M_E_CPU1_SA_DQ<9> @T6G_MB_LIB.T6G(SCH_1):M_E_CPU1_SA_DQ(9)   I159 @T6G_MB_LIB.T6G(SCH_1):PAGE41
  AR69 M_E_CPU1_SA_CB<7> @T6G_MB_LIB.T6G(SCH_1):M_E_CPU1_SA_CB(7)   I159 @T6G_MB_LIB.T6G(SCH_1):PAGE41
  BP69     NC     NC   I159 @T6G_MB_LIB.T6G(SCH_1):PAGE41
  BN69 M_E_CPU1_SA_RSP<0> @T6G_MB_LIB.T6G(SCH_1):M_E_CPU1_SA_RSP(0)   I159 @T6G_MB_LIB.T6G(SCH_1):PAGE41
  CW71 M_E_CPU1_SB_DQ<22> @T6G_MB_LIB.T6G(SCH_1):M_E_CPU1_SB_DQ(22)   I159 @T6G_MB_LIB.T6G(SCH_1):PAGE41
  CK69 M_E_CPU1_SB_DQ<11> @T6G_MB_LIB.T6G(SCH_1):M_E_CPU1_SB_DQ(11)   I159 @T6G_MB_LIB.T6G(SCH_1):PAGE41
  CJ69 M_E_CPU1_SB_DQ<9> @T6G_MB_LIB.T6G(SCH_1):M_E_CPU1_SB_DQ(9)   I159 @T6G_MB_LIB.T6G(SCH_1):PAGE41
  CA71 M_E_CPU1_SB_CB<2> @T6G_MB_LIB.T6G(SCH_1):M_E_CPU1_SB_CB(2)   I159 @T6G_MB_LIB.T6G(SCH_1):PAGE41
  AM70 M_E_CPU1_SA_DQS_DN<4> @T6G_MB_LIB.T6G(SCH_1):M_E_CPU1_SA_DQS_DN(4)   I159 @T6G_MB_LIB.T6G(SCH_1):PAGE41
   G71 M_E_CPU1_SA_DQS_DP<0> @T6G_MB_LIB.T6G(SCH_1):M_E_CPU1_SA_DQS_DP(0)   I159 @T6G_MB_LIB.T6G(SCH_1):PAGE41
  AG71 M_E_CPU1_SA_DQ<28> @T6G_MB_LIB.T6G(SCH_1):M_E_CPU1_SA_DQ(28)   I159 @T6G_MB_LIB.T6G(SCH_1):PAGE41
   V69 M_E_CPU1_SA_DQ<17> @T6G_MB_LIB.T6G(SCH_1):M_E_CPU1_SA_DQ(17)   I159 @T6G_MB_LIB.T6G(SCH_1):PAGE41
  CY69 M_E_CPU1_SB_DQ<23> @T6G_MB_LIB.T6G(SCH_1):M_E_CPU1_SB_DQ(23)   I159 @T6G_MB_LIB.T6G(SCH_1):PAGE41
  CM70 M_E_CPU1_SB_DQ<12> @T6G_MB_LIB.T6G(SCH_1):M_E_CPU1_SB_DQ(12)   I159 @T6G_MB_LIB.T6G(SCH_1):PAGE41
  CB69 M_E_CPU1_SB_CB<3> @T6G_MB_LIB.T6G(SCH_1):M_E_CPU1_SB_CB(3)   I159 @T6G_MB_LIB.T6G(SCH_1):PAGE41
   H69 M_E_CPU1_SA_DQS_DN<5> @T6G_MB_LIB.T6G(SCH_1):M_E_CPU1_SA_DQS_DN(5)   I159 @T6G_MB_LIB.T6G(SCH_1):PAGE41
   N71 M_E_CPU1_SA_DQS_DP<1> @T6G_MB_LIB.T6G(SCH_1):M_E_CPU1_SA_DQS_DP(1)   I159 @T6G_MB_LIB.T6G(SCH_1):PAGE41
  AH69 M_E_CPU1_SA_DQ<29> @T6G_MB_LIB.T6G(SCH_1):M_E_CPU1_SA_DQ(29)   I159 @T6G_MB_LIB.T6G(SCH_1):PAGE41
   V70 M_E_CPU1_SA_DQ<18> @T6G_MB_LIB.T6G(SCH_1):M_E_CPU1_SA_DQ(18)   I159 @T6G_MB_LIB.T6G(SCH_1):PAGE41
  CE71 M_E_CPU1_SB_DQS_DN<0> @T6G_MB_LIB.T6G(SCH_1):M_E_CPU1_SB_DQS_DN(0)   I159 @T6G_MB_LIB.T6G(SCH_1):PAGE41
  CY70 M_E_CPU1_SB_DQ<24> @T6G_MB_LIB.T6G(SCH_1):M_E_CPU1_SB_DQ(24)   I159 @T6G_MB_LIB.T6G(SCH_1):PAGE41
  CN69 M_E_CPU1_SB_DQ<13> @T6G_MB_LIB.T6G(SCH_1):M_E_CPU1_SB_DQ(13)   I159 @T6G_MB_LIB.T6G(SCH_1):PAGE41
  BT70 M_E_CPU1_SB_CB<4> @T6G_MB_LIB.T6G(SCH_1):M_E_CPU1_SB_CB(4)   I159 @T6G_MB_LIB.T6G(SCH_1):PAGE41
   P69 M_E_CPU1_SA_DQS_DN<6> @T6G_MB_LIB.T6G(SCH_1):M_E_CPU1_SA_DQS_DN(6)   I159 @T6G_MB_LIB.T6G(SCH_1):PAGE41
   W71 M_E_CPU1_SA_DQS_DP<2> @T6G_MB_LIB.T6G(SCH_1):M_E_CPU1_SA_DQS_DP(2)   I159 @T6G_MB_LIB.T6G(SCH_1):PAGE41
   W69 M_E_CPU1_SA_DQ<19> @T6G_MB_LIB.T6G(SCH_1):M_E_CPU1_SA_DQ(19)   I159 @T6G_MB_LIB.T6G(SCH_1):PAGE41
  CL71 M_E_CPU1_SB_DQS_DN<1> @T6G_MB_LIB.T6G(SCH_1):M_E_CPU1_SB_DQS_DN(1)   I159 @T6G_MB_LIB.T6G(SCH_1):PAGE41
  DA69 M_E_CPU1_SB_DQ<25> @T6G_MB_LIB.T6G(SCH_1):M_E_CPU1_SB_DQ(25)   I159 @T6G_MB_LIB.T6G(SCH_1):PAGE41
  CN71 M_E_CPU1_SB_DQ<14> @T6G_MB_LIB.T6G(SCH_1):M_E_CPU1_SB_DQ(14)   I159 @T6G_MB_LIB.T6G(SCH_1):PAGE41
  BU69 M_E_CPU1_SB_CB<5> @T6G_MB_LIB.T6G(SCH_1):M_E_CPU1_SB_CB(5)   I159 @T6G_MB_LIB.T6G(SCH_1):PAGE41
   Y69 M_E_CPU1_SA_DQS_DN<7> @T6G_MB_LIB.T6G(SCH_1):M_E_CPU1_SA_DQS_DN(7)   I159 @T6G_MB_LIB.T6G(SCH_1):PAGE41
  AE71 M_E_CPU1_SA_DQS_DP<3> @T6G_MB_LIB.T6G(SCH_1):M_E_CPU1_SA_DQS_DP(3)   I159 @T6G_MB_LIB.T6G(SCH_1):PAGE41
  BC69 M_E_CPU1_SA_PAR @T6G_MB_LIB.T6G(SCH_1):M_E_CPU1_SA_PAR   I159 @T6G_MB_LIB.T6G(SCH_1):PAGE41
  BL71 M_E_CPU1_SB_PAR @T6G_MB_LIB.T6G(SCH_1):M_E_CPU1_SB_PAR   I159 @T6G_MB_LIB.T6G(SCH_1):PAGE41
  BV70 M_E_CPU1_SB_DQS_DP<9> @T6G_MB_LIB.T6G(SCH_1):M_E_CPU1_SB_DQS_DP(9)   I159 @T6G_MB_LIB.T6G(SCH_1):PAGE41
  BC71 M_E_CPU1_CLK_DP<0> @T6G_MB_LIB.T6G(SCH_1):M_E_CPU1_CLK_DP(0)   I159 @T6G_MB_LIB.T6G(SCH_1):PAGE41
  BD70 M_E_CPU1_CLK_DN<0> @T6G_MB_LIB.T6G(SCH_1):M_E_CPU1_CLK_DN(0)   I159 @T6G_MB_LIB.T6G(SCH_1):PAGE41
  BF70     NC     NC   I159 @T6G_MB_LIB.T6G(SCH_1):PAGE41
  BG71     NC     NC   I159 @T6G_MB_LIB.T6G(SCH_1):PAGE41
  BF69 TP_M_E_CPU1_SA_TEST39E @T6G_MB_LIB.T6G(SCH_1):TP_M_E_CPU1_SA_TEST39E   I159 @T6G_MB_LIB.T6G(SCH_1):PAGE41
  AT65 M_F_CPU1_ALERT_R_N @T6G_MB_LIB.T6G(SCH_1):M_F_CPU1_ALERT_R_N   I159 @T6G_MB_LIB.T6G(SCH_1):PAGE42
  AU66 M_F_CPU1_RESET_N @T6G_MB_LIB.T6G(SCH_1):M_F_CPU1_RESET_N   I159 @T6G_MB_LIB.T6G(SCH_1):PAGE42
  CL66 M_F_CPU1_SB_DQS_DN<6> @T6G_MB_LIB.T6G(SCH_1):M_F_CPU1_SB_DQS_DN(6)   I159 @T6G_MB_LIB.T6G(SCH_1):PAGE42
  CT67 M_F_CPU1_SB_DQS_DP<2> @T6G_MB_LIB.T6G(SCH_1):M_F_CPU1_SB_DQS_DP(2)   I159 @T6G_MB_LIB.T6G(SCH_1):PAGE42
  CT65 M_F_CPU1_SB_DQ<19> @T6G_MB_LIB.T6G(SCH_1):M_F_CPU1_SB_DQ(19)   I159 @T6G_MB_LIB.T6G(SCH_1):PAGE42
  CH65 M_F_CPU1_SB_DQ<7> @T6G_MB_LIB.T6G(SCH_1):M_F_CPU1_SB_DQ(7)   I159 @T6G_MB_LIB.T6G(SCH_1):PAGE42
  AG66 M_F_CPU1_SA_DQS_DP<8> @T6G_MB_LIB.T6G(SCH_1):M_F_CPU1_SA_DQS_DP(8)   I159 @T6G_MB_LIB.T6G(SCH_1):PAGE42
  AH67 M_F_CPU1_SA_DQ<30> @T6G_MB_LIB.T6G(SCH_1):M_F_CPU1_SA_DQ(30)   I159 @T6G_MB_LIB.T6G(SCH_1):PAGE42
   L67 M_F_CPU1_SA_DQ<8> @T6G_MB_LIB.T6G(SCH_1):M_F_CPU1_SA_DQ(8)   I159 @T6G_MB_LIB.T6G(SCH_1):PAGE42
  AU67     NC     NC   I159 @T6G_MB_LIB.T6G(SCH_1):PAGE42
  AW66 M_F_CPU1_SA_CS_N<1> @T6G_MB_LIB.T6G(SCH_1):M_F_CPU1_SA_CS_N(1)   I159 @T6G_MB_LIB.T6G(SCH_1):PAGE42
  CU66 M_F_CPU1_SB_DQS_DN<7> @T6G_MB_LIB.T6G(SCH_1):M_F_CPU1_SB_DQS_DN(7)   I159 @T6G_MB_LIB.T6G(SCH_1):PAGE42
  DB67 M_F_CPU1_SB_DQS_DP<3> @T6G_MB_LIB.T6G(SCH_1):M_F_CPU1_SB_DQS_DP(3)   I159 @T6G_MB_LIB.T6G(SCH_1):PAGE42
  CH67 M_F_CPU1_SB_DQ<8> @T6G_MB_LIB.T6G(SCH_1):M_F_CPU1_SB_DQ(8)   I159 @T6G_MB_LIB.T6G(SCH_1):PAGE42
  AN66 M_F_CPU1_SA_DQS_DP<9> @T6G_MB_LIB.T6G(SCH_1):M_F_CPU1_SA_DQS_DP(9)   I159 @T6G_MB_LIB.T6G(SCH_1):PAGE42
  AJ66 M_F_CPU1_SA_DQ<31> @T6G_MB_LIB.T6G(SCH_1):M_F_CPU1_SA_DQ(31)   I159 @T6G_MB_LIB.T6G(SCH_1):PAGE42
  AA67 M_F_CPU1_SA_DQ<20> @T6G_MB_LIB.T6G(SCH_1):M_F_CPU1_SA_DQ(20)   I159 @T6G_MB_LIB.T6G(SCH_1):PAGE42
   M65 M_F_CPU1_SA_DQ<9> @T6G_MB_LIB.T6G(SCH_1):M_F_CPU1_SA_DQ(9)   I159 @T6G_MB_LIB.T6G(SCH_1):PAGE42
  AJ67 M_F_CPU1_SA_CB<0> @T6G_MB_LIB.T6G(SCH_1):M_F_CPU1_SA_CB(0)   I159 @T6G_MB_LIB.T6G(SCH_1):PAGE42
  AV65     NC     NC   I159 @T6G_MB_LIB.T6G(SCH_1):PAGE42
  DC66 M_F_CPU1_SB_DQS_DN<8> @T6G_MB_LIB.T6G(SCH_1):M_F_CPU1_SB_DQS_DN(8)   I159 @T6G_MB_LIB.T6G(SCH_1):PAGE42
  BY65 M_F_CPU1_SB_DQS_DP<4> @T6G_MB_LIB.T6G(SCH_1):M_F_CPU1_SB_DQS_DP(4)   I159 @T6G_MB_LIB.T6G(SCH_1):PAGE42
  CJ66 M_F_CPU1_SB_DQ<9> @T6G_MB_LIB.T6G(SCH_1):M_F_CPU1_SB_DQ(9)   I159 @T6G_MB_LIB.T6G(SCH_1):PAGE42
  AB65 M_F_CPU1_SA_DQ<21> @T6G_MB_LIB.T6G(SCH_1):M_F_CPU1_SA_DQ(21)   I159 @T6G_MB_LIB.T6G(SCH_1):PAGE42
   M67 M_F_CPU1_SA_DQ<10> @T6G_MB_LIB.T6G(SCH_1):M_F_CPU1_SA_DQ(10)   I159 @T6G_MB_LIB.T6G(SCH_1):PAGE42
  AK65 M_F_CPU1_SA_CB<1> @T6G_MB_LIB.T6G(SCH_1):M_F_CPU1_SA_CB(1)   I159 @T6G_MB_LIB.T6G(SCH_1):PAGE42
  BW67 M_F_CPU1_SB_DQS_DN<9> @T6G_MB_LIB.T6G(SCH_1):M_F_CPU1_SB_DQS_DN(9)   I159 @T6G_MB_LIB.T6G(SCH_1):PAGE42
  CF65 M_F_CPU1_SB_DQS_DP<5> @T6G_MB_LIB.T6G(SCH_1):M_F_CPU1_SB_DQS_DP(5)   I159 @T6G_MB_LIB.T6G(SCH_1):PAGE42
  AB67 M_F_CPU1_SA_DQ<22> @T6G_MB_LIB.T6G(SCH_1):M_F_CPU1_SA_DQ(22)   I159 @T6G_MB_LIB.T6G(SCH_1):PAGE42
   N66 M_F_CPU1_SA_DQ<11> @T6G_MB_LIB.T6G(SCH_1):M_F_CPU1_SA_DQ(11)   I159 @T6G_MB_LIB.T6G(SCH_1):PAGE42
  AK67 M_F_CPU1_SA_CB<2> @T6G_MB_LIB.T6G(SCH_1):M_F_CPU1_SA_CB(2)   I159 @T6G_MB_LIB.T6G(SCH_1):PAGE42
  CM65 M_F_CPU1_SB_DQS_DP<6> @T6G_MB_LIB.T6G(SCH_1):M_F_CPU1_SB_DQS_DP(6)   I159 @T6G_MB_LIB.T6G(SCH_1):PAGE42
  AC66 M_F_CPU1_SA_DQ<23> @T6G_MB_LIB.T6G(SCH_1):M_F_CPU1_SA_DQ(23)   I159 @T6G_MB_LIB.T6G(SCH_1):PAGE42
   R67 M_F_CPU1_SA_DQ<12> @T6G_MB_LIB.T6G(SCH_1):M_F_CPU1_SA_DQ(12)   I159 @T6G_MB_LIB.T6G(SCH_1):PAGE42
  AL66 M_F_CPU1_SA_CB<3> @T6G_MB_LIB.T6G(SCH_1):M_F_CPU1_SA_CB(3)   I159 @T6G_MB_LIB.T6G(SCH_1):PAGE42
  AW67 M_F_CPU1_SA_CA<0> @T6G_MB_LIB.T6G(SCH_1):M_F_CPU1_SA_CA(0)   I159 @T6G_MB_LIB.T6G(SCH_1):PAGE42
  CV65 M_F_CPU1_SB_DQS_DP<7> @T6G_MB_LIB.T6G(SCH_1):M_F_CPU1_SB_DQS_DP(7)   I159 @T6G_MB_LIB.T6G(SCH_1):PAGE42
  BG66 M_F_CPU1_SB_CA<0> @T6G_MB_LIB.T6G(SCH_1):M_F_CPU1_SB_CA(0)   I159 @T6G_MB_LIB.T6G(SCH_1):PAGE42
  BM65 M_F_CPU1_SB_CS_N<0> @T6G_MB_LIB.T6G(SCH_1):M_F_CPU1_SB_CS_N(0)   I159 @T6G_MB_LIB.T6G(SCH_1):PAGE42
   H67 M_F_CPU1_SA_DQS_DN<0> @T6G_MB_LIB.T6G(SCH_1):M_F_CPU1_SA_DQS_DN(0)   I159 @T6G_MB_LIB.T6G(SCH_1):PAGE42
  AC67 M_F_CPU1_SA_DQ<24> @T6G_MB_LIB.T6G(SCH_1):M_F_CPU1_SA_DQ(24)   I159 @T6G_MB_LIB.T6G(SCH_1):PAGE42
   T65 M_F_CPU1_SA_DQ<13> @T6G_MB_LIB.T6G(SCH_1):M_F_CPU1_SA_DQ(13)   I159 @T6G_MB_LIB.T6G(SCH_1):PAGE42
  AN67 M_F_CPU1_SA_CB<4> @T6G_MB_LIB.T6G(SCH_1):M_F_CPU1_SA_CB(4)   I159 @T6G_MB_LIB.T6G(SCH_1):PAGE42
  AY67 M_F_CPU1_SA_CA<1> @T6G_MB_LIB.T6G(SCH_1):M_F_CPU1_SA_CA(1)   I159 @T6G_MB_LIB.T6G(SCH_1):PAGE42
  DD65 M_F_CPU1_SB_DQS_DP<8> @T6G_MB_LIB.T6G(SCH_1):M_F_CPU1_SB_DQS_DP(8)   I159 @T6G_MB_LIB.T6G(SCH_1):PAGE42
  DE67 M_F_CPU1_SB_DQ<30> @T6G_MB_LIB.T6G(SCH_1):M_F_CPU1_SB_DQ(30)   I159 @T6G_MB_LIB.T6G(SCH_1):PAGE42
  BH65 M_F_CPU1_SB_CA<1> @T6G_MB_LIB.T6G(SCH_1):M_F_CPU1_SB_CA(1)   I159 @T6G_MB_LIB.T6G(SCH_1):PAGE42
  BL66     NC     NC   I159 @T6G_MB_LIB.T6G(SCH_1):PAGE42
  BN67 M_F_CPU1_SB_CS_N<1> @T6G_MB_LIB.T6G(SCH_1):M_F_CPU1_SB_CS_N(1)   I159 @T6G_MB_LIB.T6G(SCH_1):PAGE42
   P67 M_F_CPU1_SA_DQS_DN<1> @T6G_MB_LIB.T6G(SCH_1):M_F_CPU1_SA_DQS_DN(1)   I159 @T6G_MB_LIB.T6G(SCH_1):PAGE42
  AD65 M_F_CPU1_SA_DQ<25> @T6G_MB_LIB.T6G(SCH_1):M_F_CPU1_SA_DQ(25)   I159 @T6G_MB_LIB.T6G(SCH_1):PAGE42
   T67 M_F_CPU1_SA_DQ<14> @T6G_MB_LIB.T6G(SCH_1):M_F_CPU1_SA_DQ(14)   I159 @T6G_MB_LIB.T6G(SCH_1):PAGE42
  AP65 M_F_CPU1_SA_CB<5> @T6G_MB_LIB.T6G(SCH_1):M_F_CPU1_SA_CB(5)   I159 @T6G_MB_LIB.T6G(SCH_1):PAGE42
  AY65 M_F_CPU1_SA_CA<2> @T6G_MB_LIB.T6G(SCH_1):M_F_CPU1_SA_CA(2)   I159 @T6G_MB_LIB.T6G(SCH_1):PAGE42
  DF67 M_F_CPU1_SB_DQ<31> @T6G_MB_LIB.T6G(SCH_1):M_F_CPU1_SB_DQ(31)   I159 @T6G_MB_LIB.T6G(SCH_1):PAGE42
  CV67 M_F_CPU1_SB_DQ<20> @T6G_MB_LIB.T6G(SCH_1):M_F_CPU1_SB_DQ(20)   I159 @T6G_MB_LIB.T6G(SCH_1):PAGE42
  BY67 M_F_CPU1_SB_CB<0> @T6G_MB_LIB.T6G(SCH_1):M_F_CPU1_SB_CB(0)   I159 @T6G_MB_LIB.T6G(SCH_1):PAGE42
  BH67 M_F_CPU1_SB_CA<2> @T6G_MB_LIB.T6G(SCH_1):M_F_CPU1_SB_CA(2)   I159 @T6G_MB_LIB.T6G(SCH_1):PAGE42
  BM67     NC     NC   I159 @T6G_MB_LIB.T6G(SCH_1):PAGE42
   Y67 M_F_CPU1_SA_DQS_DN<2> @T6G_MB_LIB.T6G(SCH_1):M_F_CPU1_SA_DQS_DN(2)   I159 @T6G_MB_LIB.T6G(SCH_1):PAGE42
  AD67 M_F_CPU1_SA_DQ<26> @T6G_MB_LIB.T6G(SCH_1):M_F_CPU1_SA_DQ(26)   I159 @T6G_MB_LIB.T6G(SCH_1):PAGE42
   U66 M_F_CPU1_SA_DQ<15> @T6G_MB_LIB.T6G(SCH_1):M_F_CPU1_SA_DQ(15)   I159 @T6G_MB_LIB.T6G(SCH_1):PAGE42
  AP67 M_F_CPU1_SA_CB<6> @T6G_MB_LIB.T6G(SCH_1):M_F_CPU1_SA_CB(6)   I159 @T6G_MB_LIB.T6G(SCH_1):PAGE42
  BA66 M_F_CPU1_SA_CA<3> @T6G_MB_LIB.T6G(SCH_1):M_F_CPU1_SA_CA(3)   I159 @T6G_MB_LIB.T6G(SCH_1):PAGE42
  CW66 M_F_CPU1_SB_DQ<21> @T6G_MB_LIB.T6G(SCH_1):M_F_CPU1_SB_DQ(21)   I159 @T6G_MB_LIB.T6G(SCH_1):PAGE42
  CJ67 M_F_CPU1_SB_DQ<10> @T6G_MB_LIB.T6G(SCH_1):M_F_CPU1_SB_DQ(10)   I159 @T6G_MB_LIB.T6G(SCH_1):PAGE42
  CA66 M_F_CPU1_SB_CB<1> @T6G_MB_LIB.T6G(SCH_1):M_F_CPU1_SB_CB(1)   I159 @T6G_MB_LIB.T6G(SCH_1):PAGE42
  BJ67 M_F_CPU1_SB_CA<3> @T6G_MB_LIB.T6G(SCH_1):M_F_CPU1_SB_CA(3)   I159 @T6G_MB_LIB.T6G(SCH_1):PAGE42
  AF67 M_F_CPU1_SA_DQS_DN<3> @T6G_MB_LIB.T6G(SCH_1):M_F_CPU1_SA_DQS_DN(3)   I159 @T6G_MB_LIB.T6G(SCH_1):PAGE42
  AE66 M_F_CPU1_SA_DQ<27> @T6G_MB_LIB.T6G(SCH_1):M_F_CPU1_SA_DQ(27)   I159 @T6G_MB_LIB.T6G(SCH_1):PAGE42
   U67 M_F_CPU1_SA_DQ<16> @T6G_MB_LIB.T6G(SCH_1):M_F_CPU1_SA_DQ(16)   I159 @T6G_MB_LIB.T6G(SCH_1):PAGE42
  AR66 M_F_CPU1_SA_CB<7> @T6G_MB_LIB.T6G(SCH_1):M_F_CPU1_SA_CB(7)   I159 @T6G_MB_LIB.T6G(SCH_1):PAGE42
  BA67 M_F_CPU1_SA_CA<4> @T6G_MB_LIB.T6G(SCH_1):M_F_CPU1_SA_CA(4)   I159 @T6G_MB_LIB.T6G(SCH_1):PAGE42
  BN66 M_F_CPU1_SA_RSP<0> @T6G_MB_LIB.T6G(SCH_1):M_F_CPU1_SA_RSP(0)   I159 @T6G_MB_LIB.T6G(SCH_1):PAGE42
  CW67 M_F_CPU1_SB_DQ<22> @T6G_MB_LIB.T6G(SCH_1):M_F_CPU1_SB_DQ(22)   I159 @T6G_MB_LIB.T6G(SCH_1):PAGE42
  CK65 M_F_CPU1_SB_DQ<11> @T6G_MB_LIB.T6G(SCH_1):M_F_CPU1_SB_DQ(11)   I159 @T6G_MB_LIB.T6G(SCH_1):PAGE42
  CA67 M_F_CPU1_SB_CB<2> @T6G_MB_LIB.T6G(SCH_1):M_F_CPU1_SB_CB(2)   I159 @T6G_MB_LIB.T6G(SCH_1):PAGE42
  BJ66 M_F_CPU1_SB_CA<4> @T6G_MB_LIB.T6G(SCH_1):M_F_CPU1_SB_CA(4)   I159 @T6G_MB_LIB.T6G(SCH_1):PAGE42
  AM67 M_F_CPU1_SA_DQS_DN<4> @T6G_MB_LIB.T6G(SCH_1):M_F_CPU1_SA_DQS_DN(4)   I159 @T6G_MB_LIB.T6G(SCH_1):PAGE42
   G67 M_F_CPU1_SA_DQS_DP<0> @T6G_MB_LIB.T6G(SCH_1):M_F_CPU1_SA_DQS_DP(0)   I159 @T6G_MB_LIB.T6G(SCH_1):PAGE42
  AG67 M_F_CPU1_SA_DQ<28> @T6G_MB_LIB.T6G(SCH_1):M_F_CPU1_SA_DQ(28)   I159 @T6G_MB_LIB.T6G(SCH_1):PAGE42
   V65 M_F_CPU1_SA_DQ<17> @T6G_MB_LIB.T6G(SCH_1):M_F_CPU1_SA_DQ(17)   I159 @T6G_MB_LIB.T6G(SCH_1):PAGE42
   E67 M_F_CPU1_SA_DQ<0> @T6G_MB_LIB.T6G(SCH_1):M_F_CPU1_SA_DQ(0)   I159 @T6G_MB_LIB.T6G(SCH_1):PAGE42
  BB67 M_F_CPU1_SA_CA<5> @T6G_MB_LIB.T6G(SCH_1):M_F_CPU1_SA_CA(5)   I159 @T6G_MB_LIB.T6G(SCH_1):PAGE42
  BP65     NC     NC   I159 @T6G_MB_LIB.T6G(SCH_1):PAGE42
  CY65 M_F_CPU1_SB_DQ<23> @T6G_MB_LIB.T6G(SCH_1):M_F_CPU1_SB_DQ(23)   I159 @T6G_MB_LIB.T6G(SCH_1):PAGE42
  CM67 M_F_CPU1_SB_DQ<12> @T6G_MB_LIB.T6G(SCH_1):M_F_CPU1_SB_DQ(12)   I159 @T6G_MB_LIB.T6G(SCH_1):PAGE42
  CB67 M_F_CPU1_SB_DQ<0> @T6G_MB_LIB.T6G(SCH_1):M_F_CPU1_SB_DQ(0)   I159 @T6G_MB_LIB.T6G(SCH_1):PAGE42
  CB65 M_F_CPU1_SB_CB<3> @T6G_MB_LIB.T6G(SCH_1):M_F_CPU1_SB_CB(3)   I159 @T6G_MB_LIB.T6G(SCH_1):PAGE42
  BK65 M_F_CPU1_SB_CA<5> @T6G_MB_LIB.T6G(SCH_1):M_F_CPU1_SB_CA(5)   I159 @T6G_MB_LIB.T6G(SCH_1):PAGE42
   H65 M_F_CPU1_SA_DQS_DN<5> @T6G_MB_LIB.T6G(SCH_1):M_F_CPU1_SA_DQS_DN(5)   I159 @T6G_MB_LIB.T6G(SCH_1):PAGE42
   N67 M_F_CPU1_SA_DQS_DP<1> @T6G_MB_LIB.T6G(SCH_1):M_F_CPU1_SA_DQS_DP(1)   I159 @T6G_MB_LIB.T6G(SCH_1):PAGE42
  AH65 M_F_CPU1_SA_DQ<29> @T6G_MB_LIB.T6G(SCH_1):M_F_CPU1_SA_DQ(29)   I159 @T6G_MB_LIB.T6G(SCH_1):PAGE42
   V67 M_F_CPU1_SA_DQ<18> @T6G_MB_LIB.T6G(SCH_1):M_F_CPU1_SA_DQ(18)   I159 @T6G_MB_LIB.T6G(SCH_1):PAGE42
   F65 M_F_CPU1_SA_DQ<1> @T6G_MB_LIB.T6G(SCH_1):M_F_CPU1_SA_DQ(1)   I159 @T6G_MB_LIB.T6G(SCH_1):PAGE42
  BB65 M_F_CPU1_SA_CA<6> @T6G_MB_LIB.T6G(SCH_1):M_F_CPU1_SA_CA(6)   I159 @T6G_MB_LIB.T6G(SCH_1):PAGE42
  CE67 M_F_CPU1_SB_DQS_DN<0> @T6G_MB_LIB.T6G(SCH_1):M_F_CPU1_SB_DQS_DN(0)   I159 @T6G_MB_LIB.T6G(SCH_1):PAGE42
  CY67 M_F_CPU1_SB_DQ<24> @T6G_MB_LIB.T6G(SCH_1):M_F_CPU1_SB_DQ(24)   I159 @T6G_MB_LIB.T6G(SCH_1):PAGE42
  CN66 M_F_CPU1_SB_DQ<13> @T6G_MB_LIB.T6G(SCH_1):M_F_CPU1_SB_DQ(13)   I159 @T6G_MB_LIB.T6G(SCH_1):PAGE42
  CC66 M_F_CPU1_SB_DQ<1> @T6G_MB_LIB.T6G(SCH_1):M_F_CPU1_SB_DQ(1)   I159 @T6G_MB_LIB.T6G(SCH_1):PAGE42
  BT67 M_F_CPU1_SB_CB<4> @T6G_MB_LIB.T6G(SCH_1):M_F_CPU1_SB_CB(4)   I159 @T6G_MB_LIB.T6G(SCH_1):PAGE42
  BK67 M_F_CPU1_SB_CA<6> @T6G_MB_LIB.T6G(SCH_1):M_F_CPU1_SB_CA(6)   I159 @T6G_MB_LIB.T6G(SCH_1):PAGE42
   P65 M_F_CPU1_SA_DQS_DN<6> @T6G_MB_LIB.T6G(SCH_1):M_F_CPU1_SA_DQS_DN(6)   I159 @T6G_MB_LIB.T6G(SCH_1):PAGE42
   W67 M_F_CPU1_SA_DQS_DP<2> @T6G_MB_LIB.T6G(SCH_1):M_F_CPU1_SA_DQS_DP(2)   I159 @T6G_MB_LIB.T6G(SCH_1):PAGE42
   W66 M_F_CPU1_SA_DQ<19> @T6G_MB_LIB.T6G(SCH_1):M_F_CPU1_SA_DQ(19)   I159 @T6G_MB_LIB.T6G(SCH_1):PAGE42
   F67 M_F_CPU1_SA_DQ<2> @T6G_MB_LIB.T6G(SCH_1):M_F_CPU1_SA_DQ(2)   I159 @T6G_MB_LIB.T6G(SCH_1):PAGE42
  CL67 M_F_CPU1_SB_DQS_DN<1> @T6G_MB_LIB.T6G(SCH_1):M_F_CPU1_SB_DQS_DN(1)   I159 @T6G_MB_LIB.T6G(SCH_1):PAGE42
  DA66 M_F_CPU1_SB_DQ<25> @T6G_MB_LIB.T6G(SCH_1):M_F_CPU1_SB_DQ(25)   I159 @T6G_MB_LIB.T6G(SCH_1):PAGE42
  CN67 M_F_CPU1_SB_DQ<14> @T6G_MB_LIB.T6G(SCH_1):M_F_CPU1_SB_DQ(14)   I159 @T6G_MB_LIB.T6G(SCH_1):PAGE42
  CC67 M_F_CPU1_SB_DQ<2> @T6G_MB_LIB.T6G(SCH_1):M_F_CPU1_SB_DQ(2)   I159 @T6G_MB_LIB.T6G(SCH_1):PAGE42
  BU66 M_F_CPU1_SB_CB<5> @T6G_MB_LIB.T6G(SCH_1):M_F_CPU1_SB_CB(5)   I159 @T6G_MB_LIB.T6G(SCH_1):PAGE42
   Y65 M_F_CPU1_SA_DQS_DN<7> @T6G_MB_LIB.T6G(SCH_1):M_F_CPU1_SA_DQS_DN(7)   I159 @T6G_MB_LIB.T6G(SCH_1):PAGE42
  AE67 M_F_CPU1_SA_DQS_DP<3> @T6G_MB_LIB.T6G(SCH_1):M_F_CPU1_SA_DQS_DP(3)   I159 @T6G_MB_LIB.T6G(SCH_1):PAGE42
   G66 M_F_CPU1_SA_DQ<3> @T6G_MB_LIB.T6G(SCH_1):M_F_CPU1_SA_DQ(3)   I159 @T6G_MB_LIB.T6G(SCH_1):PAGE42
  CU67 M_F_CPU1_SB_DQS_DN<2> @T6G_MB_LIB.T6G(SCH_1):M_F_CPU1_SB_DQS_DN(2)   I159 @T6G_MB_LIB.T6G(SCH_1):PAGE42
  DA67 M_F_CPU1_SB_DQ<26> @T6G_MB_LIB.T6G(SCH_1):M_F_CPU1_SB_DQ(26)   I159 @T6G_MB_LIB.T6G(SCH_1):PAGE42
  CP65 M_F_CPU1_SB_DQ<15> @T6G_MB_LIB.T6G(SCH_1):M_F_CPU1_SB_DQ(15)   I159 @T6G_MB_LIB.T6G(SCH_1):PAGE42
  CD65 M_F_CPU1_SB_DQ<3> @T6G_MB_LIB.T6G(SCH_1):M_F_CPU1_SB_DQ(3)   I159 @T6G_MB_LIB.T6G(SCH_1):PAGE42
  BU67 M_F_CPU1_SB_CB<6> @T6G_MB_LIB.T6G(SCH_1):M_F_CPU1_SB_CB(6)   I159 @T6G_MB_LIB.T6G(SCH_1):PAGE42
  AF65 M_F_CPU1_SA_DQS_DN<8> @T6G_MB_LIB.T6G(SCH_1):M_F_CPU1_SA_DQS_DN(8)   I159 @T6G_MB_LIB.T6G(SCH_1):PAGE42
  AL67 M_F_CPU1_SA_DQS_DP<4> @T6G_MB_LIB.T6G(SCH_1):M_F_CPU1_SA_DQS_DP(4)   I159 @T6G_MB_LIB.T6G(SCH_1):PAGE42
   J67 M_F_CPU1_SA_DQ<4> @T6G_MB_LIB.T6G(SCH_1):M_F_CPU1_SA_DQ(4)   I159 @T6G_MB_LIB.T6G(SCH_1):PAGE42
  DC67 M_F_CPU1_SB_DQS_DN<3> @T6G_MB_LIB.T6G(SCH_1):M_F_CPU1_SB_DQS_DN(3)   I159 @T6G_MB_LIB.T6G(SCH_1):PAGE42
  DB65 M_F_CPU1_SB_DQ<27> @T6G_MB_LIB.T6G(SCH_1):M_F_CPU1_SB_DQ(27)   I159 @T6G_MB_LIB.T6G(SCH_1):PAGE42
  CP67 M_F_CPU1_SB_DQ<16> @T6G_MB_LIB.T6G(SCH_1):M_F_CPU1_SB_DQ(16)   I159 @T6G_MB_LIB.T6G(SCH_1):PAGE42
  CF67 M_F_CPU1_SB_DQ<4> @T6G_MB_LIB.T6G(SCH_1):M_F_CPU1_SB_DQ(4)   I159 @T6G_MB_LIB.T6G(SCH_1):PAGE42
  BV65 M_F_CPU1_SB_CB<7> @T6G_MB_LIB.T6G(SCH_1):M_F_CPU1_SB_CB(7)   I159 @T6G_MB_LIB.T6G(SCH_1):PAGE42
  BP67 M_F_CPU1_SB_RSP<0> @T6G_MB_LIB.T6G(SCH_1):M_F_CPU1_SB_RSP(0)   I159 @T6G_MB_LIB.T6G(SCH_1):PAGE42
  AM65 M_F_CPU1_SA_DQS_DN<9> @T6G_MB_LIB.T6G(SCH_1):M_F_CPU1_SA_DQS_DN(9)   I159 @T6G_MB_LIB.T6G(SCH_1):PAGE42
   J66 M_F_CPU1_SA_DQS_DP<5> @T6G_MB_LIB.T6G(SCH_1):M_F_CPU1_SA_DQS_DP(5)   I159 @T6G_MB_LIB.T6G(SCH_1):PAGE42
   K65 M_F_CPU1_SA_DQ<5> @T6G_MB_LIB.T6G(SCH_1):M_F_CPU1_SA_DQ(5)   I159 @T6G_MB_LIB.T6G(SCH_1):PAGE42
  BW66 M_F_CPU1_SB_DQS_DN<4> @T6G_MB_LIB.T6G(SCH_1):M_F_CPU1_SB_DQS_DN(4)   I159 @T6G_MB_LIB.T6G(SCH_1):PAGE42
  CD67 M_F_CPU1_SB_DQS_DP<0> @T6G_MB_LIB.T6G(SCH_1):M_F_CPU1_SB_DQS_DP(0)   I159 @T6G_MB_LIB.T6G(SCH_1):PAGE42
  DD67 M_F_CPU1_SB_DQ<28> @T6G_MB_LIB.T6G(SCH_1):M_F_CPU1_SB_DQ(28)   I159 @T6G_MB_LIB.T6G(SCH_1):PAGE42
  CR66 M_F_CPU1_SB_DQ<17> @T6G_MB_LIB.T6G(SCH_1):M_F_CPU1_SB_DQ(17)   I159 @T6G_MB_LIB.T6G(SCH_1):PAGE42
  CG66 M_F_CPU1_SB_DQ<5> @T6G_MB_LIB.T6G(SCH_1):M_F_CPU1_SB_DQ(5)   I159 @T6G_MB_LIB.T6G(SCH_1):PAGE42
  BR67     NC     NC   I159 @T6G_MB_LIB.T6G(SCH_1):PAGE42
   R66 M_F_CPU1_SA_DQS_DP<6> @T6G_MB_LIB.T6G(SCH_1):M_F_CPU1_SA_DQS_DP(6)   I159 @T6G_MB_LIB.T6G(SCH_1):PAGE42
   K67 M_F_CPU1_SA_DQ<6> @T6G_MB_LIB.T6G(SCH_1):M_F_CPU1_SA_DQ(6)   I159 @T6G_MB_LIB.T6G(SCH_1):PAGE42
  CE66 M_F_CPU1_SB_DQS_DN<5> @T6G_MB_LIB.T6G(SCH_1):M_F_CPU1_SB_DQS_DN(5)   I159 @T6G_MB_LIB.T6G(SCH_1):PAGE42
  CK67 M_F_CPU1_SB_DQS_DP<1> @T6G_MB_LIB.T6G(SCH_1):M_F_CPU1_SB_DQS_DP(1)   I159 @T6G_MB_LIB.T6G(SCH_1):PAGE42
  DE66 M_F_CPU1_SB_DQ<29> @T6G_MB_LIB.T6G(SCH_1):M_F_CPU1_SB_DQ(29)   I159 @T6G_MB_LIB.T6G(SCH_1):PAGE42
  CR67 M_F_CPU1_SB_DQ<18> @T6G_MB_LIB.T6G(SCH_1):M_F_CPU1_SB_DQ(18)   I159 @T6G_MB_LIB.T6G(SCH_1):PAGE42
  CG67 M_F_CPU1_SB_DQ<6> @T6G_MB_LIB.T6G(SCH_1):M_F_CPU1_SB_DQ(6)   I159 @T6G_MB_LIB.T6G(SCH_1):PAGE42
  AA66 M_F_CPU1_SA_DQS_DP<7> @T6G_MB_LIB.T6G(SCH_1):M_F_CPU1_SA_DQS_DP(7)   I159 @T6G_MB_LIB.T6G(SCH_1):PAGE42
   L66 M_F_CPU1_SA_DQ<7> @T6G_MB_LIB.T6G(SCH_1):M_F_CPU1_SA_DQ(7)   I159 @T6G_MB_LIB.T6G(SCH_1):PAGE42
  AV67 M_F_CPU1_SA_CS_N<0> @T6G_MB_LIB.T6G(SCH_1):M_F_CPU1_SA_CS_N(0)   I159 @T6G_MB_LIB.T6G(SCH_1):PAGE42
  BC66 M_F_CPU1_SA_PAR @T6G_MB_LIB.T6G(SCH_1):M_F_CPU1_SA_PAR   I159 @T6G_MB_LIB.T6G(SCH_1):PAGE42
  BL67 M_F_CPU1_SB_PAR @T6G_MB_LIB.T6G(SCH_1):M_F_CPU1_SB_PAR   I159 @T6G_MB_LIB.T6G(SCH_1):PAGE42
  BV67 M_F_CPU1_SB_DQS_DP<9> @T6G_MB_LIB.T6G(SCH_1):M_F_CPU1_SB_DQS_DP(9)   I159 @T6G_MB_LIB.T6G(SCH_1):PAGE42
  BC67 M_F_CPU1_CLK_DP<0> @T6G_MB_LIB.T6G(SCH_1):M_F_CPU1_CLK_DP(0)   I159 @T6G_MB_LIB.T6G(SCH_1):PAGE42
  BD67 M_F_CPU1_CLK_DN<0> @T6G_MB_LIB.T6G(SCH_1):M_F_CPU1_CLK_DN(0)   I159 @T6G_MB_LIB.T6G(SCH_1):PAGE42
  BF67     NC     NC   I159 @T6G_MB_LIB.T6G(SCH_1):PAGE42
  BG67     NC     NC   I159 @T6G_MB_LIB.T6G(SCH_1):PAGE42
  BF65 TP_M_F_CPU1_SA_TEST39F @T6G_MB_LIB.T6G(SCH_1):TP_M_F_CPU1_SA_TEST39F   I159 @T6G_MB_LIB.T6G(SCH_1):PAGE42
   AR2 M_G_CPU1_ALERT_R_N @T6G_MB_LIB.T6G(SCH_1):M_G_CPU1_ALERT_R_N   I167 @T6G_MB_LIB.T6G(SCH_1):PAGE43
   AT2 M_G_CPU1_RESET_N @T6G_MB_LIB.T6G(SCH_1):M_G_CPU1_RESET_N   I167 @T6G_MB_LIB.T6G(SCH_1):PAGE43
   BW2 M_G_CPU1_SB_DQS_DN<9> @T6G_MB_LIB.T6G(SCH_1):M_G_CPU1_SB_DQS_DN(9)   I167 @T6G_MB_LIB.T6G(SCH_1):PAGE43
   CF4 M_G_CPU1_SB_DQS_DP<5> @T6G_MB_LIB.T6G(SCH_1):M_G_CPU1_SB_DQS_DP(5)   I167 @T6G_MB_LIB.T6G(SCH_1):PAGE43
   CC3 M_G_CPU1_SB_DQ<1> @T6G_MB_LIB.T6G(SCH_1):M_G_CPU1_SB_DQ(1)   I167 @T6G_MB_LIB.T6G(SCH_1):PAGE43
   AB2 M_G_CPU1_SA_DQ<22> @T6G_MB_LIB.T6G(SCH_1):M_G_CPU1_SA_DQ(22)   I167 @T6G_MB_LIB.T6G(SCH_1):PAGE43
    N3 M_G_CPU1_SA_DQ<11> @T6G_MB_LIB.T6G(SCH_1):M_G_CPU1_SA_DQ(11)   I167 @T6G_MB_LIB.T6G(SCH_1):PAGE43
    F4 M_G_CPU1_SA_DQ<1> @T6G_MB_LIB.T6G(SCH_1):M_G_CPU1_SA_DQ(1)   I167 @T6G_MB_LIB.T6G(SCH_1):PAGE43
   AK2 M_G_CPU1_SA_CB<2> @T6G_MB_LIB.T6G(SCH_1):M_G_CPU1_SA_CB(2)   I167 @T6G_MB_LIB.T6G(SCH_1):PAGE43
   CM4 M_G_CPU1_SB_DQS_DP<6> @T6G_MB_LIB.T6G(SCH_1):M_G_CPU1_SB_DQS_DP(6)   I167 @T6G_MB_LIB.T6G(SCH_1):PAGE43
   CC2 M_G_CPU1_SB_DQ<2> @T6G_MB_LIB.T6G(SCH_1):M_G_CPU1_SB_DQ(2)   I167 @T6G_MB_LIB.T6G(SCH_1):PAGE43
   AC3 M_G_CPU1_SA_DQ<23> @T6G_MB_LIB.T6G(SCH_1):M_G_CPU1_SA_DQ(23)   I167 @T6G_MB_LIB.T6G(SCH_1):PAGE43
    R2 M_G_CPU1_SA_DQ<12> @T6G_MB_LIB.T6G(SCH_1):M_G_CPU1_SA_DQ(12)   I167 @T6G_MB_LIB.T6G(SCH_1):PAGE43
    F2 M_G_CPU1_SA_DQ<2> @T6G_MB_LIB.T6G(SCH_1):M_G_CPU1_SA_DQ(2)   I167 @T6G_MB_LIB.T6G(SCH_1):PAGE43
   AL3 M_G_CPU1_SA_CB<3> @T6G_MB_LIB.T6G(SCH_1):M_G_CPU1_SA_CB(3)   I167 @T6G_MB_LIB.T6G(SCH_1):PAGE43
   CV4 M_G_CPU1_SB_DQS_DP<7> @T6G_MB_LIB.T6G(SCH_1):M_G_CPU1_SB_DQS_DP(7)   I167 @T6G_MB_LIB.T6G(SCH_1):PAGE43
   CD4 M_G_CPU1_SB_DQ<3> @T6G_MB_LIB.T6G(SCH_1):M_G_CPU1_SB_DQ(3)   I167 @T6G_MB_LIB.T6G(SCH_1):PAGE43
   BL2     NC     NC   I167 @T6G_MB_LIB.T6G(SCH_1):PAGE43
   BM4 M_G_CPU1_SB_CS_N<0> @T6G_MB_LIB.T6G(SCH_1):M_G_CPU1_SB_CS_N(0)   I167 @T6G_MB_LIB.T6G(SCH_1):PAGE43
    H2 M_G_CPU1_SA_DQS_DN<0> @T6G_MB_LIB.T6G(SCH_1):M_G_CPU1_SA_DQS_DN(0)   I167 @T6G_MB_LIB.T6G(SCH_1):PAGE43
   AC2 M_G_CPU1_SA_DQ<24> @T6G_MB_LIB.T6G(SCH_1):M_G_CPU1_SA_DQ(24)   I167 @T6G_MB_LIB.T6G(SCH_1):PAGE43
    T4 M_G_CPU1_SA_DQ<13> @T6G_MB_LIB.T6G(SCH_1):M_G_CPU1_SA_DQ(13)   I167 @T6G_MB_LIB.T6G(SCH_1):PAGE43
    G3 M_G_CPU1_SA_DQ<3> @T6G_MB_LIB.T6G(SCH_1):M_G_CPU1_SA_DQ(3)   I167 @T6G_MB_LIB.T6G(SCH_1):PAGE43
   AN2 M_G_CPU1_SA_CB<4> @T6G_MB_LIB.T6G(SCH_1):M_G_CPU1_SA_CB(4)   I167 @T6G_MB_LIB.T6G(SCH_1):PAGE43
   DD4 M_G_CPU1_SB_DQS_DP<8> @T6G_MB_LIB.T6G(SCH_1):M_G_CPU1_SB_DQS_DP(8)   I167 @T6G_MB_LIB.T6G(SCH_1):PAGE43
   DE2 M_G_CPU1_SB_DQ<30> @T6G_MB_LIB.T6G(SCH_1):M_G_CPU1_SB_DQ(30)   I167 @T6G_MB_LIB.T6G(SCH_1):PAGE43
   CF2 M_G_CPU1_SB_DQ<4> @T6G_MB_LIB.T6G(SCH_1):M_G_CPU1_SB_DQ(4)   I167 @T6G_MB_LIB.T6G(SCH_1):PAGE43
   BM2     NC     NC   I167 @T6G_MB_LIB.T6G(SCH_1):PAGE43
   BN2 M_G_CPU1_SB_CS_N<1> @T6G_MB_LIB.T6G(SCH_1):M_G_CPU1_SB_CS_N(1)   I167 @T6G_MB_LIB.T6G(SCH_1):PAGE43
    P2 M_G_CPU1_SA_DQS_DN<1> @T6G_MB_LIB.T6G(SCH_1):M_G_CPU1_SA_DQS_DN(1)   I167 @T6G_MB_LIB.T6G(SCH_1):PAGE43
   AD4 M_G_CPU1_SA_DQ<25> @T6G_MB_LIB.T6G(SCH_1):M_G_CPU1_SA_DQ(25)   I167 @T6G_MB_LIB.T6G(SCH_1):PAGE43
    T2 M_G_CPU1_SA_DQ<14> @T6G_MB_LIB.T6G(SCH_1):M_G_CPU1_SA_DQ(14)   I167 @T6G_MB_LIB.T6G(SCH_1):PAGE43
    J2 M_G_CPU1_SA_DQ<4> @T6G_MB_LIB.T6G(SCH_1):M_G_CPU1_SA_DQ(4)   I167 @T6G_MB_LIB.T6G(SCH_1):PAGE43
   AP4 M_G_CPU1_SA_CB<5> @T6G_MB_LIB.T6G(SCH_1):M_G_CPU1_SA_CB(5)   I167 @T6G_MB_LIB.T6G(SCH_1):PAGE43
   AW2 M_G_CPU1_SA_CA<0> @T6G_MB_LIB.T6G(SCH_1):M_G_CPU1_SA_CA(0)   I167 @T6G_MB_LIB.T6G(SCH_1):PAGE43
   DF2 M_G_CPU1_SB_DQ<31> @T6G_MB_LIB.T6G(SCH_1):M_G_CPU1_SB_DQ(31)   I167 @T6G_MB_LIB.T6G(SCH_1):PAGE43
   CV2 M_G_CPU1_SB_DQ<20> @T6G_MB_LIB.T6G(SCH_1):M_G_CPU1_SB_DQ(20)   I167 @T6G_MB_LIB.T6G(SCH_1):PAGE43
   CG3 M_G_CPU1_SB_DQ<5> @T6G_MB_LIB.T6G(SCH_1):M_G_CPU1_SB_DQ(5)   I167 @T6G_MB_LIB.T6G(SCH_1):PAGE43
   BY2 M_G_CPU1_SB_CB<0> @T6G_MB_LIB.T6G(SCH_1):M_G_CPU1_SB_CB(0)   I167 @T6G_MB_LIB.T6G(SCH_1):PAGE43
   BG3 M_G_CPU1_SB_CA<0> @T6G_MB_LIB.T6G(SCH_1):M_G_CPU1_SB_CA(0)   I167 @T6G_MB_LIB.T6G(SCH_1):PAGE43
    Y2 M_G_CPU1_SA_DQS_DN<2> @T6G_MB_LIB.T6G(SCH_1):M_G_CPU1_SA_DQS_DN(2)   I167 @T6G_MB_LIB.T6G(SCH_1):PAGE43
   AD2 M_G_CPU1_SA_DQ<26> @T6G_MB_LIB.T6G(SCH_1):M_G_CPU1_SA_DQ(26)   I167 @T6G_MB_LIB.T6G(SCH_1):PAGE43
    U3 M_G_CPU1_SA_DQ<15> @T6G_MB_LIB.T6G(SCH_1):M_G_CPU1_SA_DQ(15)   I167 @T6G_MB_LIB.T6G(SCH_1):PAGE43
    K4 M_G_CPU1_SA_DQ<5> @T6G_MB_LIB.T6G(SCH_1):M_G_CPU1_SA_DQ(5)   I167 @T6G_MB_LIB.T6G(SCH_1):PAGE43
   AP2 M_G_CPU1_SA_CB<6> @T6G_MB_LIB.T6G(SCH_1):M_G_CPU1_SA_CB(6)   I167 @T6G_MB_LIB.T6G(SCH_1):PAGE43
   AY2 M_G_CPU1_SA_CA<1> @T6G_MB_LIB.T6G(SCH_1):M_G_CPU1_SA_CA(1)   I167 @T6G_MB_LIB.T6G(SCH_1):PAGE43
   CW3 M_G_CPU1_SB_DQ<21> @T6G_MB_LIB.T6G(SCH_1):M_G_CPU1_SB_DQ(21)   I167 @T6G_MB_LIB.T6G(SCH_1):PAGE43
   CJ2 M_G_CPU1_SB_DQ<10> @T6G_MB_LIB.T6G(SCH_1):M_G_CPU1_SB_DQ(10)   I167 @T6G_MB_LIB.T6G(SCH_1):PAGE43
   CG2 M_G_CPU1_SB_DQ<6> @T6G_MB_LIB.T6G(SCH_1):M_G_CPU1_SB_DQ(6)   I167 @T6G_MB_LIB.T6G(SCH_1):PAGE43
   CA3 M_G_CPU1_SB_CB<1> @T6G_MB_LIB.T6G(SCH_1):M_G_CPU1_SB_CB(1)   I167 @T6G_MB_LIB.T6G(SCH_1):PAGE43
   BH4 M_G_CPU1_SB_CA<1> @T6G_MB_LIB.T6G(SCH_1):M_G_CPU1_SB_CA(1)   I167 @T6G_MB_LIB.T6G(SCH_1):PAGE43
   AF2 M_G_CPU1_SA_DQS_DN<3> @T6G_MB_LIB.T6G(SCH_1):M_G_CPU1_SA_DQS_DN(3)   I167 @T6G_MB_LIB.T6G(SCH_1):PAGE43
   AE3 M_G_CPU1_SA_DQ<27> @T6G_MB_LIB.T6G(SCH_1):M_G_CPU1_SA_DQ(27)   I167 @T6G_MB_LIB.T6G(SCH_1):PAGE43
    U2 M_G_CPU1_SA_DQ<16> @T6G_MB_LIB.T6G(SCH_1):M_G_CPU1_SA_DQ(16)   I167 @T6G_MB_LIB.T6G(SCH_1):PAGE43
    K2 M_G_CPU1_SA_DQ<6> @T6G_MB_LIB.T6G(SCH_1):M_G_CPU1_SA_DQ(6)   I167 @T6G_MB_LIB.T6G(SCH_1):PAGE43
   AR3 M_G_CPU1_SA_CB<7> @T6G_MB_LIB.T6G(SCH_1):M_G_CPU1_SA_CB(7)   I167 @T6G_MB_LIB.T6G(SCH_1):PAGE43
   AY4 M_G_CPU1_SA_CA<2> @T6G_MB_LIB.T6G(SCH_1):M_G_CPU1_SA_CA(2)   I167 @T6G_MB_LIB.T6G(SCH_1):PAGE43
   BP4     NC     NC   I167 @T6G_MB_LIB.T6G(SCH_1):PAGE43
   BN3 M_G_CPU1_SA_RSP<0> @T6G_MB_LIB.T6G(SCH_1):M_G_CPU1_SA_RSP(0)   I167 @T6G_MB_LIB.T6G(SCH_1):PAGE43
   CW2 M_G_CPU1_SB_DQ<22> @T6G_MB_LIB.T6G(SCH_1):M_G_CPU1_SB_DQ(22)   I167 @T6G_MB_LIB.T6G(SCH_1):PAGE43
   CK4 M_G_CPU1_SB_DQ<11> @T6G_MB_LIB.T6G(SCH_1):M_G_CPU1_SB_DQ(11)   I167 @T6G_MB_LIB.T6G(SCH_1):PAGE43
   CH4 M_G_CPU1_SB_DQ<7> @T6G_MB_LIB.T6G(SCH_1):M_G_CPU1_SB_DQ(7)   I167 @T6G_MB_LIB.T6G(SCH_1):PAGE43
   CA2 M_G_CPU1_SB_CB<2> @T6G_MB_LIB.T6G(SCH_1):M_G_CPU1_SB_CB(2)   I167 @T6G_MB_LIB.T6G(SCH_1):PAGE43
   BH2 M_G_CPU1_SB_CA<2> @T6G_MB_LIB.T6G(SCH_1):M_G_CPU1_SB_CA(2)   I167 @T6G_MB_LIB.T6G(SCH_1):PAGE43
   AM2 M_G_CPU1_SA_DQS_DN<4> @T6G_MB_LIB.T6G(SCH_1):M_G_CPU1_SA_DQS_DN(4)   I167 @T6G_MB_LIB.T6G(SCH_1):PAGE43
    G2 M_G_CPU1_SA_DQS_DP<0> @T6G_MB_LIB.T6G(SCH_1):M_G_CPU1_SA_DQS_DP(0)   I167 @T6G_MB_LIB.T6G(SCH_1):PAGE43
   AG2 M_G_CPU1_SA_DQ<28> @T6G_MB_LIB.T6G(SCH_1):M_G_CPU1_SA_DQ(28)   I167 @T6G_MB_LIB.T6G(SCH_1):PAGE43
    V4 M_G_CPU1_SA_DQ<17> @T6G_MB_LIB.T6G(SCH_1):M_G_CPU1_SA_DQ(17)   I167 @T6G_MB_LIB.T6G(SCH_1):PAGE43
    L3 M_G_CPU1_SA_DQ<7> @T6G_MB_LIB.T6G(SCH_1):M_G_CPU1_SA_DQ(7)   I167 @T6G_MB_LIB.T6G(SCH_1):PAGE43
   BA3 M_G_CPU1_SA_CA<3> @T6G_MB_LIB.T6G(SCH_1):M_G_CPU1_SA_CA(3)   I167 @T6G_MB_LIB.T6G(SCH_1):PAGE43
   CY4 M_G_CPU1_SB_DQ<23> @T6G_MB_LIB.T6G(SCH_1):M_G_CPU1_SB_DQ(23)   I167 @T6G_MB_LIB.T6G(SCH_1):PAGE43
   CM2 M_G_CPU1_SB_DQ<12> @T6G_MB_LIB.T6G(SCH_1):M_G_CPU1_SB_DQ(12)   I167 @T6G_MB_LIB.T6G(SCH_1):PAGE43
   CH2 M_G_CPU1_SB_DQ<8> @T6G_MB_LIB.T6G(SCH_1):M_G_CPU1_SB_DQ(8)   I167 @T6G_MB_LIB.T6G(SCH_1):PAGE43
   CB4 M_G_CPU1_SB_CB<3> @T6G_MB_LIB.T6G(SCH_1):M_G_CPU1_SB_CB(3)   I167 @T6G_MB_LIB.T6G(SCH_1):PAGE43
   BJ2 M_G_CPU1_SB_CA<3> @T6G_MB_LIB.T6G(SCH_1):M_G_CPU1_SB_CA(3)   I167 @T6G_MB_LIB.T6G(SCH_1):PAGE43
    H4 M_G_CPU1_SA_DQS_DN<5> @T6G_MB_LIB.T6G(SCH_1):M_G_CPU1_SA_DQS_DN(5)   I167 @T6G_MB_LIB.T6G(SCH_1):PAGE43
    N2 M_G_CPU1_SA_DQS_DP<1> @T6G_MB_LIB.T6G(SCH_1):M_G_CPU1_SA_DQS_DP(1)   I167 @T6G_MB_LIB.T6G(SCH_1):PAGE43
   AH4 M_G_CPU1_SA_DQ<29> @T6G_MB_LIB.T6G(SCH_1):M_G_CPU1_SA_DQ(29)   I167 @T6G_MB_LIB.T6G(SCH_1):PAGE43
    V2 M_G_CPU1_SA_DQ<18> @T6G_MB_LIB.T6G(SCH_1):M_G_CPU1_SA_DQ(18)   I167 @T6G_MB_LIB.T6G(SCH_1):PAGE43
    L2 M_G_CPU1_SA_DQ<8> @T6G_MB_LIB.T6G(SCH_1):M_G_CPU1_SA_DQ(8)   I167 @T6G_MB_LIB.T6G(SCH_1):PAGE43
   BA2 M_G_CPU1_SA_CA<4> @T6G_MB_LIB.T6G(SCH_1):M_G_CPU1_SA_CA(4)   I167 @T6G_MB_LIB.T6G(SCH_1):PAGE43
   CE2 M_G_CPU1_SB_DQS_DN<0> @T6G_MB_LIB.T6G(SCH_1):M_G_CPU1_SB_DQS_DN(0)   I167 @T6G_MB_LIB.T6G(SCH_1):PAGE43
   CY2 M_G_CPU1_SB_DQ<24> @T6G_MB_LIB.T6G(SCH_1):M_G_CPU1_SB_DQ(24)   I167 @T6G_MB_LIB.T6G(SCH_1):PAGE43
   CN3 M_G_CPU1_SB_DQ<13> @T6G_MB_LIB.T6G(SCH_1):M_G_CPU1_SB_DQ(13)   I167 @T6G_MB_LIB.T6G(SCH_1):PAGE43
   CJ3 M_G_CPU1_SB_DQ<9> @T6G_MB_LIB.T6G(SCH_1):M_G_CPU1_SB_DQ(9)   I167 @T6G_MB_LIB.T6G(SCH_1):PAGE43
   BT2 M_G_CPU1_SB_CB<4> @T6G_MB_LIB.T6G(SCH_1):M_G_CPU1_SB_CB(4)   I167 @T6G_MB_LIB.T6G(SCH_1):PAGE43
   BJ3 M_G_CPU1_SB_CA<4> @T6G_MB_LIB.T6G(SCH_1):M_G_CPU1_SB_CA(4)   I167 @T6G_MB_LIB.T6G(SCH_1):PAGE43
    P4 M_G_CPU1_SA_DQS_DN<6> @T6G_MB_LIB.T6G(SCH_1):M_G_CPU1_SA_DQS_DN(6)   I167 @T6G_MB_LIB.T6G(SCH_1):PAGE43
    W2 M_G_CPU1_SA_DQS_DP<2> @T6G_MB_LIB.T6G(SCH_1):M_G_CPU1_SA_DQS_DP(2)   I167 @T6G_MB_LIB.T6G(SCH_1):PAGE43
    W3 M_G_CPU1_SA_DQ<19> @T6G_MB_LIB.T6G(SCH_1):M_G_CPU1_SA_DQ(19)   I167 @T6G_MB_LIB.T6G(SCH_1):PAGE43
    M4 M_G_CPU1_SA_DQ<9> @T6G_MB_LIB.T6G(SCH_1):M_G_CPU1_SA_DQ(9)   I167 @T6G_MB_LIB.T6G(SCH_1):PAGE43
   BB2 M_G_CPU1_SA_CA<5> @T6G_MB_LIB.T6G(SCH_1):M_G_CPU1_SA_CA(5)   I167 @T6G_MB_LIB.T6G(SCH_1):PAGE43
   CL2 M_G_CPU1_SB_DQS_DN<1> @T6G_MB_LIB.T6G(SCH_1):M_G_CPU1_SB_DQS_DN(1)   I167 @T6G_MB_LIB.T6G(SCH_1):PAGE43
   DA3 M_G_CPU1_SB_DQ<25> @T6G_MB_LIB.T6G(SCH_1):M_G_CPU1_SB_DQ(25)   I167 @T6G_MB_LIB.T6G(SCH_1):PAGE43
   CN2 M_G_CPU1_SB_DQ<14> @T6G_MB_LIB.T6G(SCH_1):M_G_CPU1_SB_DQ(14)   I167 @T6G_MB_LIB.T6G(SCH_1):PAGE43
   BU3 M_G_CPU1_SB_CB<5> @T6G_MB_LIB.T6G(SCH_1):M_G_CPU1_SB_CB(5)   I167 @T6G_MB_LIB.T6G(SCH_1):PAGE43
   BK4 M_G_CPU1_SB_CA<5> @T6G_MB_LIB.T6G(SCH_1):M_G_CPU1_SB_CA(5)   I167 @T6G_MB_LIB.T6G(SCH_1):PAGE43
    Y4 M_G_CPU1_SA_DQS_DN<7> @T6G_MB_LIB.T6G(SCH_1):M_G_CPU1_SA_DQS_DN(7)   I167 @T6G_MB_LIB.T6G(SCH_1):PAGE43
   AE2 M_G_CPU1_SA_DQS_DP<3> @T6G_MB_LIB.T6G(SCH_1):M_G_CPU1_SA_DQS_DP(3)   I167 @T6G_MB_LIB.T6G(SCH_1):PAGE43
   BB4 M_G_CPU1_SA_CA<6> @T6G_MB_LIB.T6G(SCH_1):M_G_CPU1_SA_CA(6)   I167 @T6G_MB_LIB.T6G(SCH_1):PAGE43
   CU2 M_G_CPU1_SB_DQS_DN<2> @T6G_MB_LIB.T6G(SCH_1):M_G_CPU1_SB_DQS_DN(2)   I167 @T6G_MB_LIB.T6G(SCH_1):PAGE43
   DA2 M_G_CPU1_SB_DQ<26> @T6G_MB_LIB.T6G(SCH_1):M_G_CPU1_SB_DQ(26)   I167 @T6G_MB_LIB.T6G(SCH_1):PAGE43
   CP4 M_G_CPU1_SB_DQ<15> @T6G_MB_LIB.T6G(SCH_1):M_G_CPU1_SB_DQ(15)   I167 @T6G_MB_LIB.T6G(SCH_1):PAGE43
   BU2 M_G_CPU1_SB_CB<6> @T6G_MB_LIB.T6G(SCH_1):M_G_CPU1_SB_CB(6)   I167 @T6G_MB_LIB.T6G(SCH_1):PAGE43
   BK2 M_G_CPU1_SB_CA<6> @T6G_MB_LIB.T6G(SCH_1):M_G_CPU1_SB_CA(6)   I167 @T6G_MB_LIB.T6G(SCH_1):PAGE43
   AF4 M_G_CPU1_SA_DQS_DN<8> @T6G_MB_LIB.T6G(SCH_1):M_G_CPU1_SA_DQS_DN(8)   I167 @T6G_MB_LIB.T6G(SCH_1):PAGE43
   AL2 M_G_CPU1_SA_DQS_DP<4> @T6G_MB_LIB.T6G(SCH_1):M_G_CPU1_SA_DQS_DP(4)   I167 @T6G_MB_LIB.T6G(SCH_1):PAGE43
   DC2 M_G_CPU1_SB_DQS_DN<3> @T6G_MB_LIB.T6G(SCH_1):M_G_CPU1_SB_DQS_DN(3)   I167 @T6G_MB_LIB.T6G(SCH_1):PAGE43
   DB4 M_G_CPU1_SB_DQ<27> @T6G_MB_LIB.T6G(SCH_1):M_G_CPU1_SB_DQ(27)   I167 @T6G_MB_LIB.T6G(SCH_1):PAGE43
   CP2 M_G_CPU1_SB_DQ<16> @T6G_MB_LIB.T6G(SCH_1):M_G_CPU1_SB_DQ(16)   I167 @T6G_MB_LIB.T6G(SCH_1):PAGE43
   BV4 M_G_CPU1_SB_CB<7> @T6G_MB_LIB.T6G(SCH_1):M_G_CPU1_SB_CB(7)   I167 @T6G_MB_LIB.T6G(SCH_1):PAGE43
   BR2     NC     NC   I167 @T6G_MB_LIB.T6G(SCH_1):PAGE43
   BP2 M_G_CPU1_SB_RSP<0> @T6G_MB_LIB.T6G(SCH_1):M_G_CPU1_SB_RSP(0)   I167 @T6G_MB_LIB.T6G(SCH_1):PAGE43
   AM4 M_G_CPU1_SA_DQS_DN<9> @T6G_MB_LIB.T6G(SCH_1):M_G_CPU1_SA_DQS_DN(9)   I167 @T6G_MB_LIB.T6G(SCH_1):PAGE43
    J3 M_G_CPU1_SA_DQS_DP<5> @T6G_MB_LIB.T6G(SCH_1):M_G_CPU1_SA_DQS_DP(5)   I167 @T6G_MB_LIB.T6G(SCH_1):PAGE43
   BW3 M_G_CPU1_SB_DQS_DN<4> @T6G_MB_LIB.T6G(SCH_1):M_G_CPU1_SB_DQS_DN(4)   I167 @T6G_MB_LIB.T6G(SCH_1):PAGE43
   CD2 M_G_CPU1_SB_DQS_DP<0> @T6G_MB_LIB.T6G(SCH_1):M_G_CPU1_SB_DQS_DP(0)   I167 @T6G_MB_LIB.T6G(SCH_1):PAGE43
   DD2 M_G_CPU1_SB_DQ<28> @T6G_MB_LIB.T6G(SCH_1):M_G_CPU1_SB_DQ(28)   I167 @T6G_MB_LIB.T6G(SCH_1):PAGE43
   CR3 M_G_CPU1_SB_DQ<17> @T6G_MB_LIB.T6G(SCH_1):M_G_CPU1_SB_DQ(17)   I167 @T6G_MB_LIB.T6G(SCH_1):PAGE43
    R3 M_G_CPU1_SA_DQS_DP<6> @T6G_MB_LIB.T6G(SCH_1):M_G_CPU1_SA_DQS_DP(6)   I167 @T6G_MB_LIB.T6G(SCH_1):PAGE43
   CE3 M_G_CPU1_SB_DQS_DN<5> @T6G_MB_LIB.T6G(SCH_1):M_G_CPU1_SB_DQS_DN(5)   I167 @T6G_MB_LIB.T6G(SCH_1):PAGE43
   CK2 M_G_CPU1_SB_DQS_DP<1> @T6G_MB_LIB.T6G(SCH_1):M_G_CPU1_SB_DQS_DP(1)   I167 @T6G_MB_LIB.T6G(SCH_1):PAGE43
   DE3 M_G_CPU1_SB_DQ<29> @T6G_MB_LIB.T6G(SCH_1):M_G_CPU1_SB_DQ(29)   I167 @T6G_MB_LIB.T6G(SCH_1):PAGE43
   CR2 M_G_CPU1_SB_DQ<18> @T6G_MB_LIB.T6G(SCH_1):M_G_CPU1_SB_DQ(18)   I167 @T6G_MB_LIB.T6G(SCH_1):PAGE43
   AA3 M_G_CPU1_SA_DQS_DP<7> @T6G_MB_LIB.T6G(SCH_1):M_G_CPU1_SA_DQS_DP(7)   I167 @T6G_MB_LIB.T6G(SCH_1):PAGE43
   AV2     NC     NC   I167 @T6G_MB_LIB.T6G(SCH_1):PAGE43
   AU2 M_G_CPU1_SA_CS_N<0> @T6G_MB_LIB.T6G(SCH_1):M_G_CPU1_SA_CS_N(0)   I167 @T6G_MB_LIB.T6G(SCH_1):PAGE43
   CL3 M_G_CPU1_SB_DQS_DN<6> @T6G_MB_LIB.T6G(SCH_1):M_G_CPU1_SB_DQS_DN(6)   I167 @T6G_MB_LIB.T6G(SCH_1):PAGE43
   CT2 M_G_CPU1_SB_DQS_DP<2> @T6G_MB_LIB.T6G(SCH_1):M_G_CPU1_SB_DQS_DP(2)   I167 @T6G_MB_LIB.T6G(SCH_1):PAGE43
   CT4 M_G_CPU1_SB_DQ<19> @T6G_MB_LIB.T6G(SCH_1):M_G_CPU1_SB_DQ(19)   I167 @T6G_MB_LIB.T6G(SCH_1):PAGE43
   AG3 M_G_CPU1_SA_DQS_DP<8> @T6G_MB_LIB.T6G(SCH_1):M_G_CPU1_SA_DQS_DP(8)   I167 @T6G_MB_LIB.T6G(SCH_1):PAGE43
   AH2 M_G_CPU1_SA_DQ<30> @T6G_MB_LIB.T6G(SCH_1):M_G_CPU1_SA_DQ(30)   I167 @T6G_MB_LIB.T6G(SCH_1):PAGE43
   AW3     NC     NC   I167 @T6G_MB_LIB.T6G(SCH_1):PAGE43
   AV4 M_G_CPU1_SA_CS_N<1> @T6G_MB_LIB.T6G(SCH_1):M_G_CPU1_SA_CS_N(1)   I167 @T6G_MB_LIB.T6G(SCH_1):PAGE43
   CU3 M_G_CPU1_SB_DQS_DN<7> @T6G_MB_LIB.T6G(SCH_1):M_G_CPU1_SB_DQS_DN(7)   I167 @T6G_MB_LIB.T6G(SCH_1):PAGE43
   DB2 M_G_CPU1_SB_DQS_DP<3> @T6G_MB_LIB.T6G(SCH_1):M_G_CPU1_SB_DQS_DP(3)   I167 @T6G_MB_LIB.T6G(SCH_1):PAGE43
   AN3 M_G_CPU1_SA_DQS_DP<9> @T6G_MB_LIB.T6G(SCH_1):M_G_CPU1_SA_DQS_DP(9)   I167 @T6G_MB_LIB.T6G(SCH_1):PAGE43
   AJ3 M_G_CPU1_SA_DQ<31> @T6G_MB_LIB.T6G(SCH_1):M_G_CPU1_SA_DQ(31)   I167 @T6G_MB_LIB.T6G(SCH_1):PAGE43
   AA2 M_G_CPU1_SA_DQ<20> @T6G_MB_LIB.T6G(SCH_1):M_G_CPU1_SA_DQ(20)   I167 @T6G_MB_LIB.T6G(SCH_1):PAGE43
   AJ2 M_G_CPU1_SA_CB<0> @T6G_MB_LIB.T6G(SCH_1):M_G_CPU1_SA_CB(0)   I167 @T6G_MB_LIB.T6G(SCH_1):PAGE43
   DC3 M_G_CPU1_SB_DQS_DN<8> @T6G_MB_LIB.T6G(SCH_1):M_G_CPU1_SB_DQS_DN(8)   I167 @T6G_MB_LIB.T6G(SCH_1):PAGE43
   BY4 M_G_CPU1_SB_DQS_DP<4> @T6G_MB_LIB.T6G(SCH_1):M_G_CPU1_SB_DQS_DP(4)   I167 @T6G_MB_LIB.T6G(SCH_1):PAGE43
   CB2 M_G_CPU1_SB_DQ<0> @T6G_MB_LIB.T6G(SCH_1):M_G_CPU1_SB_DQ(0)   I167 @T6G_MB_LIB.T6G(SCH_1):PAGE43
   AB4 M_G_CPU1_SA_DQ<21> @T6G_MB_LIB.T6G(SCH_1):M_G_CPU1_SA_DQ(21)   I167 @T6G_MB_LIB.T6G(SCH_1):PAGE43
    M2 M_G_CPU1_SA_DQ<10> @T6G_MB_LIB.T6G(SCH_1):M_G_CPU1_SA_DQ(10)   I167 @T6G_MB_LIB.T6G(SCH_1):PAGE43
    E2 M_G_CPU1_SA_DQ<0> @T6G_MB_LIB.T6G(SCH_1):M_G_CPU1_SA_DQ(0)   I167 @T6G_MB_LIB.T6G(SCH_1):PAGE43
   AK4 M_G_CPU1_SA_CB<1> @T6G_MB_LIB.T6G(SCH_1):M_G_CPU1_SA_CB(1)   I167 @T6G_MB_LIB.T6G(SCH_1):PAGE43
   BL3 M_G_CPU1_SB_PAR @T6G_MB_LIB.T6G(SCH_1):M_G_CPU1_SB_PAR   I167 @T6G_MB_LIB.T6G(SCH_1):PAGE43
   BV2 M_G_CPU1_SB_DQS_DP<9> @T6G_MB_LIB.T6G(SCH_1):M_G_CPU1_SB_DQS_DP(9)   I167 @T6G_MB_LIB.T6G(SCH_1):PAGE43
   BC3 M_G_CPU1_SA_PAR @T6G_MB_LIB.T6G(SCH_1):M_G_CPU1_SA_PAR   I167 @T6G_MB_LIB.T6G(SCH_1):PAGE43
   BC2 M_G_CPU1_CLK_DP<0> @T6G_MB_LIB.T6G(SCH_1):M_G_CPU1_CLK_DP(0)   I167 @T6G_MB_LIB.T6G(SCH_1):PAGE43
   BD2 M_G_CPU1_CLK_DN<0> @T6G_MB_LIB.T6G(SCH_1):M_G_CPU1_CLK_DN(0)   I167 @T6G_MB_LIB.T6G(SCH_1):PAGE43
   BF2     NC     NC   I167 @T6G_MB_LIB.T6G(SCH_1):PAGE43
   BG2     NC     NC   I167 @T6G_MB_LIB.T6G(SCH_1):PAGE43
   BF4 TP_M_G_CPU1_SA_TEST39G @T6G_MB_LIB.T6G(SCH_1):TP_M_G_CPU1_SA_TEST39G   I167 @T6G_MB_LIB.T6G(SCH_1):PAGE43
  AT14 M_H_CPU1_ALERT_R_N @T6G_MB_LIB.T6G(SCH_1):M_H_CPU1_ALERT_R_N   I159 @T6G_MB_LIB.T6G(SCH_1):PAGE44
  AU14 M_H_CPU1_RESET_N @T6G_MB_LIB.T6G(SCH_1):M_H_CPU1_RESET_N   I159 @T6G_MB_LIB.T6G(SCH_1):PAGE44
  DF14 M_H_CPU1_SB_DQ<31> @T6G_MB_LIB.T6G(SCH_1):M_H_CPU1_SB_DQ(31)   I159 @T6G_MB_LIB.T6G(SCH_1):PAGE44
  CV13 M_H_CPU1_SB_DQ<20> @T6G_MB_LIB.T6G(SCH_1):M_H_CPU1_SB_DQ(20)   I159 @T6G_MB_LIB.T6G(SCH_1):PAGE44
  BY13 M_H_CPU1_SB_CB<0> @T6G_MB_LIB.T6G(SCH_1):M_H_CPU1_SB_CB(0)   I159 @T6G_MB_LIB.T6G(SCH_1):PAGE44
  BM13     NC     NC   I159 @T6G_MB_LIB.T6G(SCH_1):PAGE44
   Y13 M_H_CPU1_SA_DQS_DN<2> @T6G_MB_LIB.T6G(SCH_1):M_H_CPU1_SA_DQS_DN(2)   I159 @T6G_MB_LIB.T6G(SCH_1):PAGE44
  AD13 M_H_CPU1_SA_DQ<26> @T6G_MB_LIB.T6G(SCH_1):M_H_CPU1_SA_DQ(26)   I159 @T6G_MB_LIB.T6G(SCH_1):PAGE44
   U14 M_H_CPU1_SA_DQ<15> @T6G_MB_LIB.T6G(SCH_1):M_H_CPU1_SA_DQ(15)   I159 @T6G_MB_LIB.T6G(SCH_1):PAGE44
  AP13 M_H_CPU1_SA_CB<6> @T6G_MB_LIB.T6G(SCH_1):M_H_CPU1_SA_CB(6)   I159 @T6G_MB_LIB.T6G(SCH_1):PAGE44
  CW14 M_H_CPU1_SB_DQ<21> @T6G_MB_LIB.T6G(SCH_1):M_H_CPU1_SB_DQ(21)   I159 @T6G_MB_LIB.T6G(SCH_1):PAGE44
  CJ12 M_H_CPU1_SB_DQ<10> @T6G_MB_LIB.T6G(SCH_1):M_H_CPU1_SB_DQ(10)   I159 @T6G_MB_LIB.T6G(SCH_1):PAGE44
  CA14 M_H_CPU1_SB_CB<1> @T6G_MB_LIB.T6G(SCH_1):M_H_CPU1_SB_CB(1)   I159 @T6G_MB_LIB.T6G(SCH_1):PAGE44
  AF13 M_H_CPU1_SA_DQS_DN<3> @T6G_MB_LIB.T6G(SCH_1):M_H_CPU1_SA_DQS_DN(3)   I159 @T6G_MB_LIB.T6G(SCH_1):PAGE44
  AE14 M_H_CPU1_SA_DQ<27> @T6G_MB_LIB.T6G(SCH_1):M_H_CPU1_SA_DQ(27)   I159 @T6G_MB_LIB.T6G(SCH_1):PAGE44
   U12 M_H_CPU1_SA_DQ<16> @T6G_MB_LIB.T6G(SCH_1):M_H_CPU1_SA_DQ(16)   I159 @T6G_MB_LIB.T6G(SCH_1):PAGE44
  AR14 M_H_CPU1_SA_CB<7> @T6G_MB_LIB.T6G(SCH_1):M_H_CPU1_SA_CB(7)   I159 @T6G_MB_LIB.T6G(SCH_1):PAGE44
  BN14 M_H_CPU1_SA_RSP<0> @T6G_MB_LIB.T6G(SCH_1):M_H_CPU1_SA_RSP(0)   I159 @T6G_MB_LIB.T6G(SCH_1):PAGE44
  CW12 M_H_CPU1_SB_DQ<22> @T6G_MB_LIB.T6G(SCH_1):M_H_CPU1_SB_DQ(22)   I159 @T6G_MB_LIB.T6G(SCH_1):PAGE44
  CK14 M_H_CPU1_SB_DQ<11> @T6G_MB_LIB.T6G(SCH_1):M_H_CPU1_SB_DQ(11)   I159 @T6G_MB_LIB.T6G(SCH_1):PAGE44
  CA12 M_H_CPU1_SB_CB<2> @T6G_MB_LIB.T6G(SCH_1):M_H_CPU1_SB_CB(2)   I159 @T6G_MB_LIB.T6G(SCH_1):PAGE44
  AM13 M_H_CPU1_SA_DQS_DN<4> @T6G_MB_LIB.T6G(SCH_1):M_H_CPU1_SA_DQS_DN(4)   I159 @T6G_MB_LIB.T6G(SCH_1):PAGE44
   G12 M_H_CPU1_SA_DQS_DP<0> @T6G_MB_LIB.T6G(SCH_1):M_H_CPU1_SA_DQS_DP(0)   I159 @T6G_MB_LIB.T6G(SCH_1):PAGE44
  AG12 M_H_CPU1_SA_DQ<28> @T6G_MB_LIB.T6G(SCH_1):M_H_CPU1_SA_DQ(28)   I159 @T6G_MB_LIB.T6G(SCH_1):PAGE44
   V14 M_H_CPU1_SA_DQ<17> @T6G_MB_LIB.T6G(SCH_1):M_H_CPU1_SA_DQ(17)   I159 @T6G_MB_LIB.T6G(SCH_1):PAGE44
  AW12 M_H_CPU1_SA_CA<0> @T6G_MB_LIB.T6G(SCH_1):M_H_CPU1_SA_CA(0)   I159 @T6G_MB_LIB.T6G(SCH_1):PAGE44
  BP14     NC     NC   I159 @T6G_MB_LIB.T6G(SCH_1):PAGE44
  CY14 M_H_CPU1_SB_DQ<23> @T6G_MB_LIB.T6G(SCH_1):M_H_CPU1_SB_DQ(23)   I159 @T6G_MB_LIB.T6G(SCH_1):PAGE44
  CM13 M_H_CPU1_SB_DQ<12> @T6G_MB_LIB.T6G(SCH_1):M_H_CPU1_SB_DQ(12)   I159 @T6G_MB_LIB.T6G(SCH_1):PAGE44
  CB14 M_H_CPU1_SB_CB<3> @T6G_MB_LIB.T6G(SCH_1):M_H_CPU1_SB_CB(3)   I159 @T6G_MB_LIB.T6G(SCH_1):PAGE44
  BG14 M_H_CPU1_SB_CA<0> @T6G_MB_LIB.T6G(SCH_1):M_H_CPU1_SB_CA(0)   I159 @T6G_MB_LIB.T6G(SCH_1):PAGE44
   H14 M_H_CPU1_SA_DQS_DN<5> @T6G_MB_LIB.T6G(SCH_1):M_H_CPU1_SA_DQS_DN(5)   I159 @T6G_MB_LIB.T6G(SCH_1):PAGE44
   N12 M_H_CPU1_SA_DQS_DP<1> @T6G_MB_LIB.T6G(SCH_1):M_H_CPU1_SA_DQS_DP(1)   I159 @T6G_MB_LIB.T6G(SCH_1):PAGE44
  AH14 M_H_CPU1_SA_DQ<29> @T6G_MB_LIB.T6G(SCH_1):M_H_CPU1_SA_DQ(29)   I159 @T6G_MB_LIB.T6G(SCH_1):PAGE44
   V13 M_H_CPU1_SA_DQ<18> @T6G_MB_LIB.T6G(SCH_1):M_H_CPU1_SA_DQ(18)   I159 @T6G_MB_LIB.T6G(SCH_1):PAGE44
  AY13 M_H_CPU1_SA_CA<1> @T6G_MB_LIB.T6G(SCH_1):M_H_CPU1_SA_CA(1)   I159 @T6G_MB_LIB.T6G(SCH_1):PAGE44
  CE12 M_H_CPU1_SB_DQS_DN<0> @T6G_MB_LIB.T6G(SCH_1):M_H_CPU1_SB_DQS_DN(0)   I159 @T6G_MB_LIB.T6G(SCH_1):PAGE44
  CY13 M_H_CPU1_SB_DQ<24> @T6G_MB_LIB.T6G(SCH_1):M_H_CPU1_SB_DQ(24)   I159 @T6G_MB_LIB.T6G(SCH_1):PAGE44
  CN14 M_H_CPU1_SB_DQ<13> @T6G_MB_LIB.T6G(SCH_1):M_H_CPU1_SB_DQ(13)   I159 @T6G_MB_LIB.T6G(SCH_1):PAGE44
  BT13 M_H_CPU1_SB_CB<4> @T6G_MB_LIB.T6G(SCH_1):M_H_CPU1_SB_CB(4)   I159 @T6G_MB_LIB.T6G(SCH_1):PAGE44
  BH14 M_H_CPU1_SB_CA<1> @T6G_MB_LIB.T6G(SCH_1):M_H_CPU1_SB_CA(1)   I159 @T6G_MB_LIB.T6G(SCH_1):PAGE44
   P14 M_H_CPU1_SA_DQS_DN<6> @T6G_MB_LIB.T6G(SCH_1):M_H_CPU1_SA_DQS_DN(6)   I159 @T6G_MB_LIB.T6G(SCH_1):PAGE44
   W12 M_H_CPU1_SA_DQS_DP<2> @T6G_MB_LIB.T6G(SCH_1):M_H_CPU1_SA_DQS_DP(2)   I159 @T6G_MB_LIB.T6G(SCH_1):PAGE44
   W14 M_H_CPU1_SA_DQ<19> @T6G_MB_LIB.T6G(SCH_1):M_H_CPU1_SA_DQ(19)   I159 @T6G_MB_LIB.T6G(SCH_1):PAGE44
  AY14 M_H_CPU1_SA_CA<2> @T6G_MB_LIB.T6G(SCH_1):M_H_CPU1_SA_CA(2)   I159 @T6G_MB_LIB.T6G(SCH_1):PAGE44
  CL12 M_H_CPU1_SB_DQS_DN<1> @T6G_MB_LIB.T6G(SCH_1):M_H_CPU1_SB_DQS_DN(1)   I159 @T6G_MB_LIB.T6G(SCH_1):PAGE44
  DA14 M_H_CPU1_SB_DQ<25> @T6G_MB_LIB.T6G(SCH_1):M_H_CPU1_SB_DQ(25)   I159 @T6G_MB_LIB.T6G(SCH_1):PAGE44
  CN12 M_H_CPU1_SB_DQ<14> @T6G_MB_LIB.T6G(SCH_1):M_H_CPU1_SB_DQ(14)   I159 @T6G_MB_LIB.T6G(SCH_1):PAGE44
  CB13 M_H_CPU1_SB_DQ<0> @T6G_MB_LIB.T6G(SCH_1):M_H_CPU1_SB_DQ(0)   I159 @T6G_MB_LIB.T6G(SCH_1):PAGE44
  BU14 M_H_CPU1_SB_CB<5> @T6G_MB_LIB.T6G(SCH_1):M_H_CPU1_SB_CB(5)   I159 @T6G_MB_LIB.T6G(SCH_1):PAGE44
  BH13 M_H_CPU1_SB_CA<2> @T6G_MB_LIB.T6G(SCH_1):M_H_CPU1_SB_CA(2)   I159 @T6G_MB_LIB.T6G(SCH_1):PAGE44
   Y14 M_H_CPU1_SA_DQS_DN<7> @T6G_MB_LIB.T6G(SCH_1):M_H_CPU1_SA_DQS_DN(7)   I159 @T6G_MB_LIB.T6G(SCH_1):PAGE44
  AE12 M_H_CPU1_SA_DQS_DP<3> @T6G_MB_LIB.T6G(SCH_1):M_H_CPU1_SA_DQS_DP(3)   I159 @T6G_MB_LIB.T6G(SCH_1):PAGE44
   E12 M_H_CPU1_SA_DQ<0> @T6G_MB_LIB.T6G(SCH_1):M_H_CPU1_SA_DQ(0)   I159 @T6G_MB_LIB.T6G(SCH_1):PAGE44
  BA14 M_H_CPU1_SA_CA<3> @T6G_MB_LIB.T6G(SCH_1):M_H_CPU1_SA_CA(3)   I159 @T6G_MB_LIB.T6G(SCH_1):PAGE44
  CU12 M_H_CPU1_SB_DQS_DN<2> @T6G_MB_LIB.T6G(SCH_1):M_H_CPU1_SB_DQS_DN(2)   I159 @T6G_MB_LIB.T6G(SCH_1):PAGE44
  DA12 M_H_CPU1_SB_DQ<26> @T6G_MB_LIB.T6G(SCH_1):M_H_CPU1_SB_DQ(26)   I159 @T6G_MB_LIB.T6G(SCH_1):PAGE44
  CP14 M_H_CPU1_SB_DQ<15> @T6G_MB_LIB.T6G(SCH_1):M_H_CPU1_SB_DQ(15)   I159 @T6G_MB_LIB.T6G(SCH_1):PAGE44
  CC14 M_H_CPU1_SB_DQ<1> @T6G_MB_LIB.T6G(SCH_1):M_H_CPU1_SB_DQ(1)   I159 @T6G_MB_LIB.T6G(SCH_1):PAGE44
  BU12 M_H_CPU1_SB_CB<6> @T6G_MB_LIB.T6G(SCH_1):M_H_CPU1_SB_CB(6)   I159 @T6G_MB_LIB.T6G(SCH_1):PAGE44
  BJ12 M_H_CPU1_SB_CA<3> @T6G_MB_LIB.T6G(SCH_1):M_H_CPU1_SB_CA(3)   I159 @T6G_MB_LIB.T6G(SCH_1):PAGE44
  AF14 M_H_CPU1_SA_DQS_DN<8> @T6G_MB_LIB.T6G(SCH_1):M_H_CPU1_SA_DQS_DN(8)   I159 @T6G_MB_LIB.T6G(SCH_1):PAGE44
  AL12 M_H_CPU1_SA_DQS_DP<4> @T6G_MB_LIB.T6G(SCH_1):M_H_CPU1_SA_DQS_DP(4)   I159 @T6G_MB_LIB.T6G(SCH_1):PAGE44
   F14 M_H_CPU1_SA_DQ<1> @T6G_MB_LIB.T6G(SCH_1):M_H_CPU1_SA_DQ(1)   I159 @T6G_MB_LIB.T6G(SCH_1):PAGE44
  BA12 M_H_CPU1_SA_CA<4> @T6G_MB_LIB.T6G(SCH_1):M_H_CPU1_SA_CA(4)   I159 @T6G_MB_LIB.T6G(SCH_1):PAGE44
  DC12 M_H_CPU1_SB_DQS_DN<3> @T6G_MB_LIB.T6G(SCH_1):M_H_CPU1_SB_DQS_DN(3)   I159 @T6G_MB_LIB.T6G(SCH_1):PAGE44
  DB14 M_H_CPU1_SB_DQ<27> @T6G_MB_LIB.T6G(SCH_1):M_H_CPU1_SB_DQ(27)   I159 @T6G_MB_LIB.T6G(SCH_1):PAGE44
  CP13 M_H_CPU1_SB_DQ<16> @T6G_MB_LIB.T6G(SCH_1):M_H_CPU1_SB_DQ(16)   I159 @T6G_MB_LIB.T6G(SCH_1):PAGE44
  CC12 M_H_CPU1_SB_DQ<2> @T6G_MB_LIB.T6G(SCH_1):M_H_CPU1_SB_DQ(2)   I159 @T6G_MB_LIB.T6G(SCH_1):PAGE44
  BV14 M_H_CPU1_SB_CB<7> @T6G_MB_LIB.T6G(SCH_1):M_H_CPU1_SB_CB(7)   I159 @T6G_MB_LIB.T6G(SCH_1):PAGE44
  BJ14 M_H_CPU1_SB_CA<4> @T6G_MB_LIB.T6G(SCH_1):M_H_CPU1_SB_CA(4)   I159 @T6G_MB_LIB.T6G(SCH_1):PAGE44
  BP13 M_H_CPU1_SB_RSP<0> @T6G_MB_LIB.T6G(SCH_1):M_H_CPU1_SB_RSP(0)   I159 @T6G_MB_LIB.T6G(SCH_1):PAGE44
  AM14 M_H_CPU1_SA_DQS_DN<9> @T6G_MB_LIB.T6G(SCH_1):M_H_CPU1_SA_DQS_DN(9)   I159 @T6G_MB_LIB.T6G(SCH_1):PAGE44
   J14 M_H_CPU1_SA_DQS_DP<5> @T6G_MB_LIB.T6G(SCH_1):M_H_CPU1_SA_DQS_DP(5)   I159 @T6G_MB_LIB.T6G(SCH_1):PAGE44
   F13 M_H_CPU1_SA_DQ<2> @T6G_MB_LIB.T6G(SCH_1):M_H_CPU1_SA_DQ(2)   I159 @T6G_MB_LIB.T6G(SCH_1):PAGE44
  BB13 M_H_CPU1_SA_CA<5> @T6G_MB_LIB.T6G(SCH_1):M_H_CPU1_SA_CA(5)   I159 @T6G_MB_LIB.T6G(SCH_1):PAGE44
  BW14 M_H_CPU1_SB_DQS_DN<4> @T6G_MB_LIB.T6G(SCH_1):M_H_CPU1_SB_DQS_DN(4)   I159 @T6G_MB_LIB.T6G(SCH_1):PAGE44
  CD13 M_H_CPU1_SB_DQS_DP<0> @T6G_MB_LIB.T6G(SCH_1):M_H_CPU1_SB_DQS_DP(0)   I159 @T6G_MB_LIB.T6G(SCH_1):PAGE44
  DD13 M_H_CPU1_SB_DQ<28> @T6G_MB_LIB.T6G(SCH_1):M_H_CPU1_SB_DQ(28)   I159 @T6G_MB_LIB.T6G(SCH_1):PAGE44
  CR14 M_H_CPU1_SB_DQ<17> @T6G_MB_LIB.T6G(SCH_1):M_H_CPU1_SB_DQ(17)   I159 @T6G_MB_LIB.T6G(SCH_1):PAGE44
  CD14 M_H_CPU1_SB_DQ<3> @T6G_MB_LIB.T6G(SCH_1):M_H_CPU1_SB_DQ(3)   I159 @T6G_MB_LIB.T6G(SCH_1):PAGE44
  BK14 M_H_CPU1_SB_CA<5> @T6G_MB_LIB.T6G(SCH_1):M_H_CPU1_SB_CA(5)   I159 @T6G_MB_LIB.T6G(SCH_1):PAGE44
  BR12     NC     NC   I159 @T6G_MB_LIB.T6G(SCH_1):PAGE44
   R14 M_H_CPU1_SA_DQS_DP<6> @T6G_MB_LIB.T6G(SCH_1):M_H_CPU1_SA_DQS_DP(6)   I159 @T6G_MB_LIB.T6G(SCH_1):PAGE44
   G14 M_H_CPU1_SA_DQ<3> @T6G_MB_LIB.T6G(SCH_1):M_H_CPU1_SA_DQ(3)   I159 @T6G_MB_LIB.T6G(SCH_1):PAGE44
  BB14 M_H_CPU1_SA_CA<6> @T6G_MB_LIB.T6G(SCH_1):M_H_CPU1_SA_CA(6)   I159 @T6G_MB_LIB.T6G(SCH_1):PAGE44
  CE14 M_H_CPU1_SB_DQS_DN<5> @T6G_MB_LIB.T6G(SCH_1):M_H_CPU1_SB_DQS_DN(5)   I159 @T6G_MB_LIB.T6G(SCH_1):PAGE44
  CK13 M_H_CPU1_SB_DQS_DP<1> @T6G_MB_LIB.T6G(SCH_1):M_H_CPU1_SB_DQS_DP(1)   I159 @T6G_MB_LIB.T6G(SCH_1):PAGE44
  DE14 M_H_CPU1_SB_DQ<29> @T6G_MB_LIB.T6G(SCH_1):M_H_CPU1_SB_DQ(29)   I159 @T6G_MB_LIB.T6G(SCH_1):PAGE44
  CR12 M_H_CPU1_SB_DQ<18> @T6G_MB_LIB.T6G(SCH_1):M_H_CPU1_SB_DQ(18)   I159 @T6G_MB_LIB.T6G(SCH_1):PAGE44
  CF13 M_H_CPU1_SB_DQ<4> @T6G_MB_LIB.T6G(SCH_1):M_H_CPU1_SB_DQ(4)   I159 @T6G_MB_LIB.T6G(SCH_1):PAGE44
  BK13 M_H_CPU1_SB_CA<6> @T6G_MB_LIB.T6G(SCH_1):M_H_CPU1_SB_CA(6)   I159 @T6G_MB_LIB.T6G(SCH_1):PAGE44
  AA14 M_H_CPU1_SA_DQS_DP<7> @T6G_MB_LIB.T6G(SCH_1):M_H_CPU1_SA_DQS_DP(7)   I159 @T6G_MB_LIB.T6G(SCH_1):PAGE44
   J12 M_H_CPU1_SA_DQ<4> @T6G_MB_LIB.T6G(SCH_1):M_H_CPU1_SA_DQ(4)   I159 @T6G_MB_LIB.T6G(SCH_1):PAGE44
  AU12 M_H_CPU1_SA_CS_N<0> @T6G_MB_LIB.T6G(SCH_1):M_H_CPU1_SA_CS_N(0)   I159 @T6G_MB_LIB.T6G(SCH_1):PAGE44
  CL14 M_H_CPU1_SB_DQS_DN<6> @T6G_MB_LIB.T6G(SCH_1):M_H_CPU1_SB_DQS_DN(6)   I159 @T6G_MB_LIB.T6G(SCH_1):PAGE44
  CT13 M_H_CPU1_SB_DQS_DP<2> @T6G_MB_LIB.T6G(SCH_1):M_H_CPU1_SB_DQS_DP(2)   I159 @T6G_MB_LIB.T6G(SCH_1):PAGE44
  CT14 M_H_CPU1_SB_DQ<19> @T6G_MB_LIB.T6G(SCH_1):M_H_CPU1_SB_DQ(19)   I159 @T6G_MB_LIB.T6G(SCH_1):PAGE44
  CG14 M_H_CPU1_SB_DQ<5> @T6G_MB_LIB.T6G(SCH_1):M_H_CPU1_SB_DQ(5)   I159 @T6G_MB_LIB.T6G(SCH_1):PAGE44
  AG14 M_H_CPU1_SA_DQS_DP<8> @T6G_MB_LIB.T6G(SCH_1):M_H_CPU1_SA_DQS_DP(8)   I159 @T6G_MB_LIB.T6G(SCH_1):PAGE44
  AH13 M_H_CPU1_SA_DQ<30> @T6G_MB_LIB.T6G(SCH_1):M_H_CPU1_SA_DQ(30)   I159 @T6G_MB_LIB.T6G(SCH_1):PAGE44
   K14 M_H_CPU1_SA_DQ<5> @T6G_MB_LIB.T6G(SCH_1):M_H_CPU1_SA_DQ(5)   I159 @T6G_MB_LIB.T6G(SCH_1):PAGE44
  AV13     NC     NC   I159 @T6G_MB_LIB.T6G(SCH_1):PAGE44
  AV14 M_H_CPU1_SA_CS_N<1> @T6G_MB_LIB.T6G(SCH_1):M_H_CPU1_SA_CS_N(1)   I159 @T6G_MB_LIB.T6G(SCH_1):PAGE44
  CU14 M_H_CPU1_SB_DQS_DN<7> @T6G_MB_LIB.T6G(SCH_1):M_H_CPU1_SB_DQS_DN(7)   I159 @T6G_MB_LIB.T6G(SCH_1):PAGE44
  DB13 M_H_CPU1_SB_DQS_DP<3> @T6G_MB_LIB.T6G(SCH_1):M_H_CPU1_SB_DQS_DP(3)   I159 @T6G_MB_LIB.T6G(SCH_1):PAGE44
  CG12 M_H_CPU1_SB_DQ<6> @T6G_MB_LIB.T6G(SCH_1):M_H_CPU1_SB_DQ(6)   I159 @T6G_MB_LIB.T6G(SCH_1):PAGE44
  AN14 M_H_CPU1_SA_DQS_DP<9> @T6G_MB_LIB.T6G(SCH_1):M_H_CPU1_SA_DQS_DP(9)   I159 @T6G_MB_LIB.T6G(SCH_1):PAGE44
  AJ14 M_H_CPU1_SA_DQ<31> @T6G_MB_LIB.T6G(SCH_1):M_H_CPU1_SA_DQ(31)   I159 @T6G_MB_LIB.T6G(SCH_1):PAGE44
  AA12 M_H_CPU1_SA_DQ<20> @T6G_MB_LIB.T6G(SCH_1):M_H_CPU1_SA_DQ(20)   I159 @T6G_MB_LIB.T6G(SCH_1):PAGE44
   K13 M_H_CPU1_SA_DQ<6> @T6G_MB_LIB.T6G(SCH_1):M_H_CPU1_SA_DQ(6)   I159 @T6G_MB_LIB.T6G(SCH_1):PAGE44
  AJ12 M_H_CPU1_SA_CB<0> @T6G_MB_LIB.T6G(SCH_1):M_H_CPU1_SA_CB(0)   I159 @T6G_MB_LIB.T6G(SCH_1):PAGE44
  AW14     NC     NC   I159 @T6G_MB_LIB.T6G(SCH_1):PAGE44
  DC14 M_H_CPU1_SB_DQS_DN<8> @T6G_MB_LIB.T6G(SCH_1):M_H_CPU1_SB_DQS_DN(8)   I159 @T6G_MB_LIB.T6G(SCH_1):PAGE44
  BY14 M_H_CPU1_SB_DQS_DP<4> @T6G_MB_LIB.T6G(SCH_1):M_H_CPU1_SB_DQS_DP(4)   I159 @T6G_MB_LIB.T6G(SCH_1):PAGE44
  CH14 M_H_CPU1_SB_DQ<7> @T6G_MB_LIB.T6G(SCH_1):M_H_CPU1_SB_DQ(7)   I159 @T6G_MB_LIB.T6G(SCH_1):PAGE44
  AB14 M_H_CPU1_SA_DQ<21> @T6G_MB_LIB.T6G(SCH_1):M_H_CPU1_SA_DQ(21)   I159 @T6G_MB_LIB.T6G(SCH_1):PAGE44
   M13 M_H_CPU1_SA_DQ<10> @T6G_MB_LIB.T6G(SCH_1):M_H_CPU1_SA_DQ(10)   I159 @T6G_MB_LIB.T6G(SCH_1):PAGE44
   L14 M_H_CPU1_SA_DQ<7> @T6G_MB_LIB.T6G(SCH_1):M_H_CPU1_SA_DQ(7)   I159 @T6G_MB_LIB.T6G(SCH_1):PAGE44
  AK14 M_H_CPU1_SA_CB<1> @T6G_MB_LIB.T6G(SCH_1):M_H_CPU1_SA_CB(1)   I159 @T6G_MB_LIB.T6G(SCH_1):PAGE44
  BW12 M_H_CPU1_SB_DQS_DN<9> @T6G_MB_LIB.T6G(SCH_1):M_H_CPU1_SB_DQS_DN(9)   I159 @T6G_MB_LIB.T6G(SCH_1):PAGE44
  CF14 M_H_CPU1_SB_DQS_DP<5> @T6G_MB_LIB.T6G(SCH_1):M_H_CPU1_SB_DQS_DP(5)   I159 @T6G_MB_LIB.T6G(SCH_1):PAGE44
  CH13 M_H_CPU1_SB_DQ<8> @T6G_MB_LIB.T6G(SCH_1):M_H_CPU1_SB_DQ(8)   I159 @T6G_MB_LIB.T6G(SCH_1):PAGE44
  AB13 M_H_CPU1_SA_DQ<22> @T6G_MB_LIB.T6G(SCH_1):M_H_CPU1_SA_DQ(22)   I159 @T6G_MB_LIB.T6G(SCH_1):PAGE44
   N14 M_H_CPU1_SA_DQ<11> @T6G_MB_LIB.T6G(SCH_1):M_H_CPU1_SA_DQ(11)   I159 @T6G_MB_LIB.T6G(SCH_1):PAGE44
   L12 M_H_CPU1_SA_DQ<8> @T6G_MB_LIB.T6G(SCH_1):M_H_CPU1_SA_DQ(8)   I159 @T6G_MB_LIB.T6G(SCH_1):PAGE44
  AK13 M_H_CPU1_SA_CB<2> @T6G_MB_LIB.T6G(SCH_1):M_H_CPU1_SA_CB(2)   I159 @T6G_MB_LIB.T6G(SCH_1):PAGE44
  CM14 M_H_CPU1_SB_DQS_DP<6> @T6G_MB_LIB.T6G(SCH_1):M_H_CPU1_SB_DQS_DP(6)   I159 @T6G_MB_LIB.T6G(SCH_1):PAGE44
  CJ14 M_H_CPU1_SB_DQ<9> @T6G_MB_LIB.T6G(SCH_1):M_H_CPU1_SB_DQ(9)   I159 @T6G_MB_LIB.T6G(SCH_1):PAGE44
  AC14 M_H_CPU1_SA_DQ<23> @T6G_MB_LIB.T6G(SCH_1):M_H_CPU1_SA_DQ(23)   I159 @T6G_MB_LIB.T6G(SCH_1):PAGE44
   R12 M_H_CPU1_SA_DQ<12> @T6G_MB_LIB.T6G(SCH_1):M_H_CPU1_SA_DQ(12)   I159 @T6G_MB_LIB.T6G(SCH_1):PAGE44
   M14 M_H_CPU1_SA_DQ<9> @T6G_MB_LIB.T6G(SCH_1):M_H_CPU1_SA_DQ(9)   I159 @T6G_MB_LIB.T6G(SCH_1):PAGE44
  AL14 M_H_CPU1_SA_CB<3> @T6G_MB_LIB.T6G(SCH_1):M_H_CPU1_SA_CB(3)   I159 @T6G_MB_LIB.T6G(SCH_1):PAGE44
  CV14 M_H_CPU1_SB_DQS_DP<7> @T6G_MB_LIB.T6G(SCH_1):M_H_CPU1_SB_DQS_DP(7)   I159 @T6G_MB_LIB.T6G(SCH_1):PAGE44
  BM14 M_H_CPU1_SB_CS_N<0> @T6G_MB_LIB.T6G(SCH_1):M_H_CPU1_SB_CS_N(0)   I159 @T6G_MB_LIB.T6G(SCH_1):PAGE44
   H13 M_H_CPU1_SA_DQS_DN<0> @T6G_MB_LIB.T6G(SCH_1):M_H_CPU1_SA_DQS_DN(0)   I159 @T6G_MB_LIB.T6G(SCH_1):PAGE44
  AC12 M_H_CPU1_SA_DQ<24> @T6G_MB_LIB.T6G(SCH_1):M_H_CPU1_SA_DQ(24)   I159 @T6G_MB_LIB.T6G(SCH_1):PAGE44
   T14 M_H_CPU1_SA_DQ<13> @T6G_MB_LIB.T6G(SCH_1):M_H_CPU1_SA_DQ(13)   I159 @T6G_MB_LIB.T6G(SCH_1):PAGE44
  AN12 M_H_CPU1_SA_CB<4> @T6G_MB_LIB.T6G(SCH_1):M_H_CPU1_SA_CB(4)   I159 @T6G_MB_LIB.T6G(SCH_1):PAGE44
  DD14 M_H_CPU1_SB_DQS_DP<8> @T6G_MB_LIB.T6G(SCH_1):M_H_CPU1_SB_DQS_DP(8)   I159 @T6G_MB_LIB.T6G(SCH_1):PAGE44
  DE12 M_H_CPU1_SB_DQ<30> @T6G_MB_LIB.T6G(SCH_1):M_H_CPU1_SB_DQ(30)   I159 @T6G_MB_LIB.T6G(SCH_1):PAGE44
  BL12     NC     NC   I159 @T6G_MB_LIB.T6G(SCH_1):PAGE44
  BN12 M_H_CPU1_SB_CS_N<1> @T6G_MB_LIB.T6G(SCH_1):M_H_CPU1_SB_CS_N(1)   I159 @T6G_MB_LIB.T6G(SCH_1):PAGE44
   P13 M_H_CPU1_SA_DQS_DN<1> @T6G_MB_LIB.T6G(SCH_1):M_H_CPU1_SA_DQS_DN(1)   I159 @T6G_MB_LIB.T6G(SCH_1):PAGE44
  AD14 M_H_CPU1_SA_DQ<25> @T6G_MB_LIB.T6G(SCH_1):M_H_CPU1_SA_DQ(25)   I159 @T6G_MB_LIB.T6G(SCH_1):PAGE44
   T13 M_H_CPU1_SA_DQ<14> @T6G_MB_LIB.T6G(SCH_1):M_H_CPU1_SA_DQ(14)   I159 @T6G_MB_LIB.T6G(SCH_1):PAGE44
  AP14 M_H_CPU1_SA_CB<5> @T6G_MB_LIB.T6G(SCH_1):M_H_CPU1_SA_CB(5)   I159 @T6G_MB_LIB.T6G(SCH_1):PAGE44
  BV13 M_H_CPU1_SB_DQS_DP<9> @T6G_MB_LIB.T6G(SCH_1):M_H_CPU1_SB_DQS_DP(9)   I159 @T6G_MB_LIB.T6G(SCH_1):PAGE44
  BC14 M_H_CPU1_SA_PAR @T6G_MB_LIB.T6G(SCH_1):M_H_CPU1_SA_PAR   I159 @T6G_MB_LIB.T6G(SCH_1):PAGE44
  BL14 M_H_CPU1_SB_PAR @T6G_MB_LIB.T6G(SCH_1):M_H_CPU1_SB_PAR   I159 @T6G_MB_LIB.T6G(SCH_1):PAGE44
  BC12 M_H_CPU1_CLK_DP<0> @T6G_MB_LIB.T6G(SCH_1):M_H_CPU1_CLK_DP(0)   I159 @T6G_MB_LIB.T6G(SCH_1):PAGE44
  BD13 M_H_CPU1_CLK_DN<0> @T6G_MB_LIB.T6G(SCH_1):M_H_CPU1_CLK_DN(0)   I159 @T6G_MB_LIB.T6G(SCH_1):PAGE44
  BF13     NC     NC   I159 @T6G_MB_LIB.T6G(SCH_1):PAGE44
  BG12     NC     NC   I159 @T6G_MB_LIB.T6G(SCH_1):PAGE44
  BF14 TP_M_H_CPU1_SA_TEST39H @T6G_MB_LIB.T6G(SCH_1):TP_M_H_CPU1_SA_TEST39H   I159 @T6G_MB_LIB.T6G(SCH_1):PAGE44
  CY21 M_I_CPU1_SB_DQ<23> @T6G_MB_LIB.T6G(SCH_1):M_I_CPU1_SB_DQ(23)   I159 @T6G_MB_LIB.T6G(SCH_1):PAGE45
  CM20 M_I_CPU1_SB_DQ<12> @T6G_MB_LIB.T6G(SCH_1):M_I_CPU1_SB_DQ(12)   I159 @T6G_MB_LIB.T6G(SCH_1):PAGE45
  CG19 M_I_CPU1_SB_DQ<6> @T6G_MB_LIB.T6G(SCH_1):M_I_CPU1_SB_DQ(6)   I159 @T6G_MB_LIB.T6G(SCH_1):PAGE45
  CB21 M_I_CPU1_SB_CB<3> @T6G_MB_LIB.T6G(SCH_1):M_I_CPU1_SB_CB(3)   I159 @T6G_MB_LIB.T6G(SCH_1):PAGE45
   H21 M_I_CPU1_SA_DQS_DN<5> @T6G_MB_LIB.T6G(SCH_1):M_I_CPU1_SA_DQS_DN(5)   I159 @T6G_MB_LIB.T6G(SCH_1):PAGE45
   N19 M_I_CPU1_SA_DQS_DP<1> @T6G_MB_LIB.T6G(SCH_1):M_I_CPU1_SA_DQS_DP(1)   I159 @T6G_MB_LIB.T6G(SCH_1):PAGE45
  AH21 M_I_CPU1_SA_DQ<29> @T6G_MB_LIB.T6G(SCH_1):M_I_CPU1_SA_DQ(29)   I159 @T6G_MB_LIB.T6G(SCH_1):PAGE45
   V20 M_I_CPU1_SA_DQ<18> @T6G_MB_LIB.T6G(SCH_1):M_I_CPU1_SA_DQ(18)   I159 @T6G_MB_LIB.T6G(SCH_1):PAGE45
   K20 M_I_CPU1_SA_DQ<6> @T6G_MB_LIB.T6G(SCH_1):M_I_CPU1_SA_DQ(6)   I159 @T6G_MB_LIB.T6G(SCH_1):PAGE45
  CE19 M_I_CPU1_SB_DQS_DN<0> @T6G_MB_LIB.T6G(SCH_1):M_I_CPU1_SB_DQS_DN(0)   I159 @T6G_MB_LIB.T6G(SCH_1):PAGE45
  CY20 M_I_CPU1_SB_DQ<24> @T6G_MB_LIB.T6G(SCH_1):M_I_CPU1_SB_DQ(24)   I159 @T6G_MB_LIB.T6G(SCH_1):PAGE45
  CN21 M_I_CPU1_SB_DQ<13> @T6G_MB_LIB.T6G(SCH_1):M_I_CPU1_SB_DQ(13)   I159 @T6G_MB_LIB.T6G(SCH_1):PAGE45
  CH21 M_I_CPU1_SB_DQ<7> @T6G_MB_LIB.T6G(SCH_1):M_I_CPU1_SB_DQ(7)   I159 @T6G_MB_LIB.T6G(SCH_1):PAGE45
  BT20 M_I_CPU1_SB_CB<4> @T6G_MB_LIB.T6G(SCH_1):M_I_CPU1_SB_CB(4)   I159 @T6G_MB_LIB.T6G(SCH_1):PAGE45
   P21 M_I_CPU1_SA_DQS_DN<6> @T6G_MB_LIB.T6G(SCH_1):M_I_CPU1_SA_DQS_DN(6)   I159 @T6G_MB_LIB.T6G(SCH_1):PAGE45
   W19 M_I_CPU1_SA_DQS_DP<2> @T6G_MB_LIB.T6G(SCH_1):M_I_CPU1_SA_DQS_DP(2)   I159 @T6G_MB_LIB.T6G(SCH_1):PAGE45
   W21 M_I_CPU1_SA_DQ<19> @T6G_MB_LIB.T6G(SCH_1):M_I_CPU1_SA_DQ(19)   I159 @T6G_MB_LIB.T6G(SCH_1):PAGE45
   L21 M_I_CPU1_SA_DQ<7> @T6G_MB_LIB.T6G(SCH_1):M_I_CPU1_SA_DQ(7)   I159 @T6G_MB_LIB.T6G(SCH_1):PAGE45
  AW19 M_I_CPU1_SA_CA<0> @T6G_MB_LIB.T6G(SCH_1):M_I_CPU1_SA_CA(0)   I159 @T6G_MB_LIB.T6G(SCH_1):PAGE45
  CL19 M_I_CPU1_SB_DQS_DN<1> @T6G_MB_LIB.T6G(SCH_1):M_I_CPU1_SB_DQS_DN(1)   I159 @T6G_MB_LIB.T6G(SCH_1):PAGE45
  DA21 M_I_CPU1_SB_DQ<25> @T6G_MB_LIB.T6G(SCH_1):M_I_CPU1_SB_DQ(25)   I159 @T6G_MB_LIB.T6G(SCH_1):PAGE45
  CN19 M_I_CPU1_SB_DQ<14> @T6G_MB_LIB.T6G(SCH_1):M_I_CPU1_SB_DQ(14)   I159 @T6G_MB_LIB.T6G(SCH_1):PAGE45
  CH20 M_I_CPU1_SB_DQ<8> @T6G_MB_LIB.T6G(SCH_1):M_I_CPU1_SB_DQ(8)   I159 @T6G_MB_LIB.T6G(SCH_1):PAGE45
  BU21 M_I_CPU1_SB_CB<5> @T6G_MB_LIB.T6G(SCH_1):M_I_CPU1_SB_CB(5)   I159 @T6G_MB_LIB.T6G(SCH_1):PAGE45
  BG21 M_I_CPU1_SB_CA<0> @T6G_MB_LIB.T6G(SCH_1):M_I_CPU1_SB_CA(0)   I159 @T6G_MB_LIB.T6G(SCH_1):PAGE45
   Y21 M_I_CPU1_SA_DQS_DN<7> @T6G_MB_LIB.T6G(SCH_1):M_I_CPU1_SA_DQS_DN(7)   I159 @T6G_MB_LIB.T6G(SCH_1):PAGE45
  AE19 M_I_CPU1_SA_DQS_DP<3> @T6G_MB_LIB.T6G(SCH_1):M_I_CPU1_SA_DQS_DP(3)   I159 @T6G_MB_LIB.T6G(SCH_1):PAGE45
   L19 M_I_CPU1_SA_DQ<8> @T6G_MB_LIB.T6G(SCH_1):M_I_CPU1_SA_DQ(8)   I159 @T6G_MB_LIB.T6G(SCH_1):PAGE45
  AY20 M_I_CPU1_SA_CA<1> @T6G_MB_LIB.T6G(SCH_1):M_I_CPU1_SA_CA(1)   I159 @T6G_MB_LIB.T6G(SCH_1):PAGE45
  CU19 M_I_CPU1_SB_DQS_DN<2> @T6G_MB_LIB.T6G(SCH_1):M_I_CPU1_SB_DQS_DN(2)   I159 @T6G_MB_LIB.T6G(SCH_1):PAGE45
  DA19 M_I_CPU1_SB_DQ<26> @T6G_MB_LIB.T6G(SCH_1):M_I_CPU1_SB_DQ(26)   I159 @T6G_MB_LIB.T6G(SCH_1):PAGE45
  CP21 M_I_CPU1_SB_DQ<15> @T6G_MB_LIB.T6G(SCH_1):M_I_CPU1_SB_DQ(15)   I159 @T6G_MB_LIB.T6G(SCH_1):PAGE45
  CJ21 M_I_CPU1_SB_DQ<9> @T6G_MB_LIB.T6G(SCH_1):M_I_CPU1_SB_DQ(9)   I159 @T6G_MB_LIB.T6G(SCH_1):PAGE45
  BU19 M_I_CPU1_SB_CB<6> @T6G_MB_LIB.T6G(SCH_1):M_I_CPU1_SB_CB(6)   I159 @T6G_MB_LIB.T6G(SCH_1):PAGE45
  BH21 M_I_CPU1_SB_CA<1> @T6G_MB_LIB.T6G(SCH_1):M_I_CPU1_SB_CA(1)   I159 @T6G_MB_LIB.T6G(SCH_1):PAGE45
  AF21 M_I_CPU1_SA_DQS_DN<8> @T6G_MB_LIB.T6G(SCH_1):M_I_CPU1_SA_DQS_DN(8)   I159 @T6G_MB_LIB.T6G(SCH_1):PAGE45
  AL19 M_I_CPU1_SA_DQS_DP<4> @T6G_MB_LIB.T6G(SCH_1):M_I_CPU1_SA_DQS_DP(4)   I159 @T6G_MB_LIB.T6G(SCH_1):PAGE45
   M21 M_I_CPU1_SA_DQ<9> @T6G_MB_LIB.T6G(SCH_1):M_I_CPU1_SA_DQ(9)   I159 @T6G_MB_LIB.T6G(SCH_1):PAGE45
  AY21 M_I_CPU1_SA_CA<2> @T6G_MB_LIB.T6G(SCH_1):M_I_CPU1_SA_CA(2)   I159 @T6G_MB_LIB.T6G(SCH_1):PAGE45
  DC19 M_I_CPU1_SB_DQS_DN<3> @T6G_MB_LIB.T6G(SCH_1):M_I_CPU1_SB_DQS_DN(3)   I159 @T6G_MB_LIB.T6G(SCH_1):PAGE45
  DB21 M_I_CPU1_SB_DQ<27> @T6G_MB_LIB.T6G(SCH_1):M_I_CPU1_SB_DQ(27)   I159 @T6G_MB_LIB.T6G(SCH_1):PAGE45
  CP20 M_I_CPU1_SB_DQ<16> @T6G_MB_LIB.T6G(SCH_1):M_I_CPU1_SB_DQ(16)   I159 @T6G_MB_LIB.T6G(SCH_1):PAGE45
  BV21 M_I_CPU1_SB_CB<7> @T6G_MB_LIB.T6G(SCH_1):M_I_CPU1_SB_CB(7)   I159 @T6G_MB_LIB.T6G(SCH_1):PAGE45
  BH20 M_I_CPU1_SB_CA<2> @T6G_MB_LIB.T6G(SCH_1):M_I_CPU1_SB_CA(2)   I159 @T6G_MB_LIB.T6G(SCH_1):PAGE45
  BP20 M_I_CPU1_SB_RSP<0> @T6G_MB_LIB.T6G(SCH_1):M_I_CPU1_SB_RSP(0)   I159 @T6G_MB_LIB.T6G(SCH_1):PAGE45
  AM21 M_I_CPU1_SA_DQS_DN<9> @T6G_MB_LIB.T6G(SCH_1):M_I_CPU1_SA_DQS_DN(9)   I159 @T6G_MB_LIB.T6G(SCH_1):PAGE45
   J21 M_I_CPU1_SA_DQS_DP<5> @T6G_MB_LIB.T6G(SCH_1):M_I_CPU1_SA_DQS_DP(5)   I159 @T6G_MB_LIB.T6G(SCH_1):PAGE45
  BA21 M_I_CPU1_SA_CA<3> @T6G_MB_LIB.T6G(SCH_1):M_I_CPU1_SA_CA(3)   I159 @T6G_MB_LIB.T6G(SCH_1):PAGE45
  BW21 M_I_CPU1_SB_DQS_DN<4> @T6G_MB_LIB.T6G(SCH_1):M_I_CPU1_SB_DQS_DN(4)   I159 @T6G_MB_LIB.T6G(SCH_1):PAGE45
  CD20 M_I_CPU1_SB_DQS_DP<0> @T6G_MB_LIB.T6G(SCH_1):M_I_CPU1_SB_DQS_DP(0)   I159 @T6G_MB_LIB.T6G(SCH_1):PAGE45
  DD20 M_I_CPU1_SB_DQ<28> @T6G_MB_LIB.T6G(SCH_1):M_I_CPU1_SB_DQ(28)   I159 @T6G_MB_LIB.T6G(SCH_1):PAGE45
  CR21 M_I_CPU1_SB_DQ<17> @T6G_MB_LIB.T6G(SCH_1):M_I_CPU1_SB_DQ(17)   I159 @T6G_MB_LIB.T6G(SCH_1):PAGE45
  BJ19 M_I_CPU1_SB_CA<3> @T6G_MB_LIB.T6G(SCH_1):M_I_CPU1_SB_CA(3)   I159 @T6G_MB_LIB.T6G(SCH_1):PAGE45
  BR19     NC     NC   I159 @T6G_MB_LIB.T6G(SCH_1):PAGE45
   R21 M_I_CPU1_SA_DQS_DP<6> @T6G_MB_LIB.T6G(SCH_1):M_I_CPU1_SA_DQS_DP(6)   I159 @T6G_MB_LIB.T6G(SCH_1):PAGE45
  BA19 M_I_CPU1_SA_CA<4> @T6G_MB_LIB.T6G(SCH_1):M_I_CPU1_SA_CA(4)   I159 @T6G_MB_LIB.T6G(SCH_1):PAGE45
  CE21 M_I_CPU1_SB_DQS_DN<5> @T6G_MB_LIB.T6G(SCH_1):M_I_CPU1_SB_DQS_DN(5)   I159 @T6G_MB_LIB.T6G(SCH_1):PAGE45
  CK20 M_I_CPU1_SB_DQS_DP<1> @T6G_MB_LIB.T6G(SCH_1):M_I_CPU1_SB_DQS_DP(1)   I159 @T6G_MB_LIB.T6G(SCH_1):PAGE45
  DE21 M_I_CPU1_SB_DQ<29> @T6G_MB_LIB.T6G(SCH_1):M_I_CPU1_SB_DQ(29)   I159 @T6G_MB_LIB.T6G(SCH_1):PAGE45
  CR19 M_I_CPU1_SB_DQ<18> @T6G_MB_LIB.T6G(SCH_1):M_I_CPU1_SB_DQ(18)   I159 @T6G_MB_LIB.T6G(SCH_1):PAGE45
  BJ21 M_I_CPU1_SB_CA<4> @T6G_MB_LIB.T6G(SCH_1):M_I_CPU1_SB_CA(4)   I159 @T6G_MB_LIB.T6G(SCH_1):PAGE45
  AA21 M_I_CPU1_SA_DQS_DP<7> @T6G_MB_LIB.T6G(SCH_1):M_I_CPU1_SA_DQS_DP(7)   I159 @T6G_MB_LIB.T6G(SCH_1):PAGE45
  BB20 M_I_CPU1_SA_CA<5> @T6G_MB_LIB.T6G(SCH_1):M_I_CPU1_SA_CA(5)   I159 @T6G_MB_LIB.T6G(SCH_1):PAGE45
  AV20     NC     NC   I159 @T6G_MB_LIB.T6G(SCH_1):PAGE45
  AU19 M_I_CPU1_SA_CS_N<0> @T6G_MB_LIB.T6G(SCH_1):M_I_CPU1_SA_CS_N(0)   I159 @T6G_MB_LIB.T6G(SCH_1):PAGE45
  BF20     NC     NC   I159 @T6G_MB_LIB.T6G(SCH_1):PAGE45
  BC19 M_I_CPU1_CLK_DP<0> @T6G_MB_LIB.T6G(SCH_1):M_I_CPU1_CLK_DP(0)   I159 @T6G_MB_LIB.T6G(SCH_1):PAGE45
  CL21 M_I_CPU1_SB_DQS_DN<6> @T6G_MB_LIB.T6G(SCH_1):M_I_CPU1_SB_DQS_DN(6)   I159 @T6G_MB_LIB.T6G(SCH_1):PAGE45
  CT20 M_I_CPU1_SB_DQS_DP<2> @T6G_MB_LIB.T6G(SCH_1):M_I_CPU1_SB_DQS_DP(2)   I159 @T6G_MB_LIB.T6G(SCH_1):PAGE45
  CT21 M_I_CPU1_SB_DQ<19> @T6G_MB_LIB.T6G(SCH_1):M_I_CPU1_SB_DQ(19)   I159 @T6G_MB_LIB.T6G(SCH_1):PAGE45
  BK21 M_I_CPU1_SB_CA<5> @T6G_MB_LIB.T6G(SCH_1):M_I_CPU1_SB_CA(5)   I159 @T6G_MB_LIB.T6G(SCH_1):PAGE45
  AG21 M_I_CPU1_SA_DQS_DP<8> @T6G_MB_LIB.T6G(SCH_1):M_I_CPU1_SA_DQS_DP(8)   I159 @T6G_MB_LIB.T6G(SCH_1):PAGE45
  AH20 M_I_CPU1_SA_DQ<30> @T6G_MB_LIB.T6G(SCH_1):M_I_CPU1_SA_DQ(30)   I159 @T6G_MB_LIB.T6G(SCH_1):PAGE45
  BB21 M_I_CPU1_SA_CA<6> @T6G_MB_LIB.T6G(SCH_1):M_I_CPU1_SA_CA(6)   I159 @T6G_MB_LIB.T6G(SCH_1):PAGE45
  AW21     NC     NC   I159 @T6G_MB_LIB.T6G(SCH_1):PAGE45
  AV21 M_I_CPU1_SA_CS_N<1> @T6G_MB_LIB.T6G(SCH_1):M_I_CPU1_SA_CS_N(1)   I159 @T6G_MB_LIB.T6G(SCH_1):PAGE45
  CU21 M_I_CPU1_SB_DQS_DN<7> @T6G_MB_LIB.T6G(SCH_1):M_I_CPU1_SB_DQS_DN(7)   I159 @T6G_MB_LIB.T6G(SCH_1):PAGE45
  DB20 M_I_CPU1_SB_DQS_DP<3> @T6G_MB_LIB.T6G(SCH_1):M_I_CPU1_SB_DQS_DP(3)   I159 @T6G_MB_LIB.T6G(SCH_1):PAGE45
  BK20 M_I_CPU1_SB_CA<6> @T6G_MB_LIB.T6G(SCH_1):M_I_CPU1_SB_CA(6)   I159 @T6G_MB_LIB.T6G(SCH_1):PAGE45
  AN21 M_I_CPU1_SA_DQS_DP<9> @T6G_MB_LIB.T6G(SCH_1):M_I_CPU1_SA_DQS_DP(9)   I159 @T6G_MB_LIB.T6G(SCH_1):PAGE45
  AJ21 M_I_CPU1_SA_DQ<31> @T6G_MB_LIB.T6G(SCH_1):M_I_CPU1_SA_DQ(31)   I159 @T6G_MB_LIB.T6G(SCH_1):PAGE45
  AA19 M_I_CPU1_SA_DQ<20> @T6G_MB_LIB.T6G(SCH_1):M_I_CPU1_SA_DQ(20)   I159 @T6G_MB_LIB.T6G(SCH_1):PAGE45
  AJ19 M_I_CPU1_SA_CB<0> @T6G_MB_LIB.T6G(SCH_1):M_I_CPU1_SA_CB(0)   I159 @T6G_MB_LIB.T6G(SCH_1):PAGE45
  DC21 M_I_CPU1_SB_DQS_DN<8> @T6G_MB_LIB.T6G(SCH_1):M_I_CPU1_SB_DQS_DN(8)   I159 @T6G_MB_LIB.T6G(SCH_1):PAGE45
  BY21 M_I_CPU1_SB_DQS_DP<4> @T6G_MB_LIB.T6G(SCH_1):M_I_CPU1_SB_DQS_DP(4)   I159 @T6G_MB_LIB.T6G(SCH_1):PAGE45
  AB21 M_I_CPU1_SA_DQ<21> @T6G_MB_LIB.T6G(SCH_1):M_I_CPU1_SA_DQ(21)   I159 @T6G_MB_LIB.T6G(SCH_1):PAGE45
   M20 M_I_CPU1_SA_DQ<10> @T6G_MB_LIB.T6G(SCH_1):M_I_CPU1_SA_DQ(10)   I159 @T6G_MB_LIB.T6G(SCH_1):PAGE45
  AK21 M_I_CPU1_SA_CB<1> @T6G_MB_LIB.T6G(SCH_1):M_I_CPU1_SA_CB(1)   I159 @T6G_MB_LIB.T6G(SCH_1):PAGE45
  BW19 M_I_CPU1_SB_DQS_DN<9> @T6G_MB_LIB.T6G(SCH_1):M_I_CPU1_SB_DQS_DN(9)   I159 @T6G_MB_LIB.T6G(SCH_1):PAGE45
  CF21 M_I_CPU1_SB_DQS_DP<5> @T6G_MB_LIB.T6G(SCH_1):M_I_CPU1_SB_DQS_DP(5)   I159 @T6G_MB_LIB.T6G(SCH_1):PAGE45
  AB20 M_I_CPU1_SA_DQ<22> @T6G_MB_LIB.T6G(SCH_1):M_I_CPU1_SA_DQ(22)   I159 @T6G_MB_LIB.T6G(SCH_1):PAGE45
   N21 M_I_CPU1_SA_DQ<11> @T6G_MB_LIB.T6G(SCH_1):M_I_CPU1_SA_DQ(11)   I159 @T6G_MB_LIB.T6G(SCH_1):PAGE45
  AK20 M_I_CPU1_SA_CB<2> @T6G_MB_LIB.T6G(SCH_1):M_I_CPU1_SA_CB(2)   I159 @T6G_MB_LIB.T6G(SCH_1):PAGE45
  BG19     NC     NC   I159 @T6G_MB_LIB.T6G(SCH_1):PAGE45
  BD20 M_I_CPU1_CLK_DN<0> @T6G_MB_LIB.T6G(SCH_1):M_I_CPU1_CLK_DN(0)   I159 @T6G_MB_LIB.T6G(SCH_1):PAGE45
  AU21 M_I_CPU1_RESET_N @T6G_MB_LIB.T6G(SCH_1):M_I_CPU1_RESET_N   I159 @T6G_MB_LIB.T6G(SCH_1):PAGE45
  CM21 M_I_CPU1_SB_DQS_DP<6> @T6G_MB_LIB.T6G(SCH_1):M_I_CPU1_SB_DQS_DP(6)   I159 @T6G_MB_LIB.T6G(SCH_1):PAGE45
  CB20 M_I_CPU1_SB_DQ<0> @T6G_MB_LIB.T6G(SCH_1):M_I_CPU1_SB_DQ(0)   I159 @T6G_MB_LIB.T6G(SCH_1):PAGE45
  AC21 M_I_CPU1_SA_DQ<23> @T6G_MB_LIB.T6G(SCH_1):M_I_CPU1_SA_DQ(23)   I159 @T6G_MB_LIB.T6G(SCH_1):PAGE45
   R19 M_I_CPU1_SA_DQ<12> @T6G_MB_LIB.T6G(SCH_1):M_I_CPU1_SA_DQ(12)   I159 @T6G_MB_LIB.T6G(SCH_1):PAGE45
   E19 M_I_CPU1_SA_DQ<0> @T6G_MB_LIB.T6G(SCH_1):M_I_CPU1_SA_DQ(0)   I159 @T6G_MB_LIB.T6G(SCH_1):PAGE45
  AL21 M_I_CPU1_SA_CB<3> @T6G_MB_LIB.T6G(SCH_1):M_I_CPU1_SA_CB(3)   I159 @T6G_MB_LIB.T6G(SCH_1):PAGE45
  CV21 M_I_CPU1_SB_DQS_DP<7> @T6G_MB_LIB.T6G(SCH_1):M_I_CPU1_SB_DQS_DP(7)   I159 @T6G_MB_LIB.T6G(SCH_1):PAGE45
  CC21 M_I_CPU1_SB_DQ<1> @T6G_MB_LIB.T6G(SCH_1):M_I_CPU1_SB_DQ(1)   I159 @T6G_MB_LIB.T6G(SCH_1):PAGE45
  BM21 M_I_CPU1_SB_CS_N<0> @T6G_MB_LIB.T6G(SCH_1):M_I_CPU1_SB_CS_N(0)   I159 @T6G_MB_LIB.T6G(SCH_1):PAGE45
   H20 M_I_CPU1_SA_DQS_DN<0> @T6G_MB_LIB.T6G(SCH_1):M_I_CPU1_SA_DQS_DN(0)   I159 @T6G_MB_LIB.T6G(SCH_1):PAGE45
  AC19 M_I_CPU1_SA_DQ<24> @T6G_MB_LIB.T6G(SCH_1):M_I_CPU1_SA_DQ(24)   I159 @T6G_MB_LIB.T6G(SCH_1):PAGE45
   T21 M_I_CPU1_SA_DQ<13> @T6G_MB_LIB.T6G(SCH_1):M_I_CPU1_SA_DQ(13)   I159 @T6G_MB_LIB.T6G(SCH_1):PAGE45
   F21 M_I_CPU1_SA_DQ<1> @T6G_MB_LIB.T6G(SCH_1):M_I_CPU1_SA_DQ(1)   I159 @T6G_MB_LIB.T6G(SCH_1):PAGE45
  AN19 M_I_CPU1_SA_CB<4> @T6G_MB_LIB.T6G(SCH_1):M_I_CPU1_SA_CB(4)   I159 @T6G_MB_LIB.T6G(SCH_1):PAGE45
  DD21 M_I_CPU1_SB_DQS_DP<8> @T6G_MB_LIB.T6G(SCH_1):M_I_CPU1_SB_DQS_DP(8)   I159 @T6G_MB_LIB.T6G(SCH_1):PAGE45
  DE19 M_I_CPU1_SB_DQ<30> @T6G_MB_LIB.T6G(SCH_1):M_I_CPU1_SB_DQ(30)   I159 @T6G_MB_LIB.T6G(SCH_1):PAGE45
  CC19 M_I_CPU1_SB_DQ<2> @T6G_MB_LIB.T6G(SCH_1):M_I_CPU1_SB_DQ(2)   I159 @T6G_MB_LIB.T6G(SCH_1):PAGE45
  BL19     NC     NC   I159 @T6G_MB_LIB.T6G(SCH_1):PAGE45
  BN19 M_I_CPU1_SB_CS_N<1> @T6G_MB_LIB.T6G(SCH_1):M_I_CPU1_SB_CS_N(1)   I159 @T6G_MB_LIB.T6G(SCH_1):PAGE45
   P20 M_I_CPU1_SA_DQS_DN<1> @T6G_MB_LIB.T6G(SCH_1):M_I_CPU1_SA_DQS_DN(1)   I159 @T6G_MB_LIB.T6G(SCH_1):PAGE45
  AD21 M_I_CPU1_SA_DQ<25> @T6G_MB_LIB.T6G(SCH_1):M_I_CPU1_SA_DQ(25)   I159 @T6G_MB_LIB.T6G(SCH_1):PAGE45
   T20 M_I_CPU1_SA_DQ<14> @T6G_MB_LIB.T6G(SCH_1):M_I_CPU1_SA_DQ(14)   I159 @T6G_MB_LIB.T6G(SCH_1):PAGE45
   F20 M_I_CPU1_SA_DQ<2> @T6G_MB_LIB.T6G(SCH_1):M_I_CPU1_SA_DQ(2)   I159 @T6G_MB_LIB.T6G(SCH_1):PAGE45
  AP21 M_I_CPU1_SA_CB<5> @T6G_MB_LIB.T6G(SCH_1):M_I_CPU1_SA_CB(5)   I159 @T6G_MB_LIB.T6G(SCH_1):PAGE45
  BV20 M_I_CPU1_SB_DQS_DP<9> @T6G_MB_LIB.T6G(SCH_1):M_I_CPU1_SB_DQS_DP(9)   I159 @T6G_MB_LIB.T6G(SCH_1):PAGE45
  DF21 M_I_CPU1_SB_DQ<31> @T6G_MB_LIB.T6G(SCH_1):M_I_CPU1_SB_DQ(31)   I159 @T6G_MB_LIB.T6G(SCH_1):PAGE45
  CV20 M_I_CPU1_SB_DQ<20> @T6G_MB_LIB.T6G(SCH_1):M_I_CPU1_SB_DQ(20)   I159 @T6G_MB_LIB.T6G(SCH_1):PAGE45
  CD21 M_I_CPU1_SB_DQ<3> @T6G_MB_LIB.T6G(SCH_1):M_I_CPU1_SB_DQ(3)   I159 @T6G_MB_LIB.T6G(SCH_1):PAGE45
  BY20 M_I_CPU1_SB_CB<0> @T6G_MB_LIB.T6G(SCH_1):M_I_CPU1_SB_CB(0)   I159 @T6G_MB_LIB.T6G(SCH_1):PAGE45
  BM20     NC     NC   I159 @T6G_MB_LIB.T6G(SCH_1):PAGE45
  BC21 M_I_CPU1_SA_PAR @T6G_MB_LIB.T6G(SCH_1):M_I_CPU1_SA_PAR   I159 @T6G_MB_LIB.T6G(SCH_1):PAGE45
   Y20 M_I_CPU1_SA_DQS_DN<2> @T6G_MB_LIB.T6G(SCH_1):M_I_CPU1_SA_DQS_DN(2)   I159 @T6G_MB_LIB.T6G(SCH_1):PAGE45
  AD20 M_I_CPU1_SA_DQ<26> @T6G_MB_LIB.T6G(SCH_1):M_I_CPU1_SA_DQ(26)   I159 @T6G_MB_LIB.T6G(SCH_1):PAGE45
   U21 M_I_CPU1_SA_DQ<15> @T6G_MB_LIB.T6G(SCH_1):M_I_CPU1_SA_DQ(15)   I159 @T6G_MB_LIB.T6G(SCH_1):PAGE45
   G21 M_I_CPU1_SA_DQ<3> @T6G_MB_LIB.T6G(SCH_1):M_I_CPU1_SA_DQ(3)   I159 @T6G_MB_LIB.T6G(SCH_1):PAGE45
  AP20 M_I_CPU1_SA_CB<6> @T6G_MB_LIB.T6G(SCH_1):M_I_CPU1_SA_CB(6)   I159 @T6G_MB_LIB.T6G(SCH_1):PAGE45
  BL21 M_I_CPU1_SB_PAR @T6G_MB_LIB.T6G(SCH_1):M_I_CPU1_SB_PAR   I159 @T6G_MB_LIB.T6G(SCH_1):PAGE45
  CW21 M_I_CPU1_SB_DQ<21> @T6G_MB_LIB.T6G(SCH_1):M_I_CPU1_SB_DQ(21)   I159 @T6G_MB_LIB.T6G(SCH_1):PAGE45
  CJ19 M_I_CPU1_SB_DQ<10> @T6G_MB_LIB.T6G(SCH_1):M_I_CPU1_SB_DQ(10)   I159 @T6G_MB_LIB.T6G(SCH_1):PAGE45
  CF20 M_I_CPU1_SB_DQ<4> @T6G_MB_LIB.T6G(SCH_1):M_I_CPU1_SB_DQ(4)   I159 @T6G_MB_LIB.T6G(SCH_1):PAGE45
  CA21 M_I_CPU1_SB_CB<1> @T6G_MB_LIB.T6G(SCH_1):M_I_CPU1_SB_CB(1)   I159 @T6G_MB_LIB.T6G(SCH_1):PAGE45
  AF20 M_I_CPU1_SA_DQS_DN<3> @T6G_MB_LIB.T6G(SCH_1):M_I_CPU1_SA_DQS_DN(3)   I159 @T6G_MB_LIB.T6G(SCH_1):PAGE45
  AE21 M_I_CPU1_SA_DQ<27> @T6G_MB_LIB.T6G(SCH_1):M_I_CPU1_SA_DQ(27)   I159 @T6G_MB_LIB.T6G(SCH_1):PAGE45
   U19 M_I_CPU1_SA_DQ<16> @T6G_MB_LIB.T6G(SCH_1):M_I_CPU1_SA_DQ(16)   I159 @T6G_MB_LIB.T6G(SCH_1):PAGE45
   J19 M_I_CPU1_SA_DQ<4> @T6G_MB_LIB.T6G(SCH_1):M_I_CPU1_SA_DQ(4)   I159 @T6G_MB_LIB.T6G(SCH_1):PAGE45
  AR21 M_I_CPU1_SA_CB<7> @T6G_MB_LIB.T6G(SCH_1):M_I_CPU1_SA_CB(7)   I159 @T6G_MB_LIB.T6G(SCH_1):PAGE45
  BP21     NC     NC   I159 @T6G_MB_LIB.T6G(SCH_1):PAGE45
  BN21 M_I_CPU1_SA_RSP<0> @T6G_MB_LIB.T6G(SCH_1):M_I_CPU1_SA_RSP(0)   I159 @T6G_MB_LIB.T6G(SCH_1):PAGE45
  AT21 M_I_CPU1_ALERT_R_N @T6G_MB_LIB.T6G(SCH_1):M_I_CPU1_ALERT_R_N   I159 @T6G_MB_LIB.T6G(SCH_1):PAGE45
  CW19 M_I_CPU1_SB_DQ<22> @T6G_MB_LIB.T6G(SCH_1):M_I_CPU1_SB_DQ(22)   I159 @T6G_MB_LIB.T6G(SCH_1):PAGE45
  CK21 M_I_CPU1_SB_DQ<11> @T6G_MB_LIB.T6G(SCH_1):M_I_CPU1_SB_DQ(11)   I159 @T6G_MB_LIB.T6G(SCH_1):PAGE45
  CG21 M_I_CPU1_SB_DQ<5> @T6G_MB_LIB.T6G(SCH_1):M_I_CPU1_SB_DQ(5)   I159 @T6G_MB_LIB.T6G(SCH_1):PAGE45
  CA19 M_I_CPU1_SB_CB<2> @T6G_MB_LIB.T6G(SCH_1):M_I_CPU1_SB_CB(2)   I159 @T6G_MB_LIB.T6G(SCH_1):PAGE45
  AM20 M_I_CPU1_SA_DQS_DN<4> @T6G_MB_LIB.T6G(SCH_1):M_I_CPU1_SA_DQS_DN(4)   I159 @T6G_MB_LIB.T6G(SCH_1):PAGE45
   G19 M_I_CPU1_SA_DQS_DP<0> @T6G_MB_LIB.T6G(SCH_1):M_I_CPU1_SA_DQS_DP(0)   I159 @T6G_MB_LIB.T6G(SCH_1):PAGE45
  AG19 M_I_CPU1_SA_DQ<28> @T6G_MB_LIB.T6G(SCH_1):M_I_CPU1_SA_DQ(28)   I159 @T6G_MB_LIB.T6G(SCH_1):PAGE45
   V21 M_I_CPU1_SA_DQ<17> @T6G_MB_LIB.T6G(SCH_1):M_I_CPU1_SA_DQ(17)   I159 @T6G_MB_LIB.T6G(SCH_1):PAGE45
   K21 M_I_CPU1_SA_DQ<5> @T6G_MB_LIB.T6G(SCH_1):M_I_CPU1_SA_DQ(5)   I159 @T6G_MB_LIB.T6G(SCH_1):PAGE45
  BF21 TP_M_I_CPU1_SA_TEST39I @T6G_MB_LIB.T6G(SCH_1):TP_M_I_CPU1_SA_TEST39I   I159 @T6G_MB_LIB.T6G(SCH_1):PAGE45
  AU17 M_J_CPU1_RESET_N @T6G_MB_LIB.T6G(SCH_1):M_J_CPU1_RESET_N   I159 @T6G_MB_LIB.T6G(SCH_1):PAGE46
  AT18 M_J_CPU1_ALERT_R_N @T6G_MB_LIB.T6G(SCH_1):M_J_CPU1_ALERT_R_N   I159 @T6G_MB_LIB.T6G(SCH_1):PAGE46
  BL17 M_J_CPU1_SB_PAR @T6G_MB_LIB.T6G(SCH_1):M_J_CPU1_SB_PAR   I159 @T6G_MB_LIB.T6G(SCH_1):PAGE46
  BW16 M_J_CPU1_SB_DQS_DN<9> @T6G_MB_LIB.T6G(SCH_1):M_J_CPU1_SB_DQS_DN(9)   I159 @T6G_MB_LIB.T6G(SCH_1):PAGE46
  DC17 M_J_CPU1_SB_DQS_DN<8> @T6G_MB_LIB.T6G(SCH_1):M_J_CPU1_SB_DQS_DN(8)   I159 @T6G_MB_LIB.T6G(SCH_1):PAGE46
  CU17 M_J_CPU1_SB_DQS_DN<7> @T6G_MB_LIB.T6G(SCH_1):M_J_CPU1_SB_DQS_DN(7)   I159 @T6G_MB_LIB.T6G(SCH_1):PAGE46
  CL17 M_J_CPU1_SB_DQS_DN<6> @T6G_MB_LIB.T6G(SCH_1):M_J_CPU1_SB_DQS_DN(6)   I159 @T6G_MB_LIB.T6G(SCH_1):PAGE46
  CE17 M_J_CPU1_SB_DQS_DN<5> @T6G_MB_LIB.T6G(SCH_1):M_J_CPU1_SB_DQS_DN(5)   I159 @T6G_MB_LIB.T6G(SCH_1):PAGE46
  DC16 M_J_CPU1_SB_DQS_DN<3> @T6G_MB_LIB.T6G(SCH_1):M_J_CPU1_SB_DQS_DN(3)   I159 @T6G_MB_LIB.T6G(SCH_1):PAGE46
  CU16 M_J_CPU1_SB_DQS_DN<2> @T6G_MB_LIB.T6G(SCH_1):M_J_CPU1_SB_DQS_DN(2)   I159 @T6G_MB_LIB.T6G(SCH_1):PAGE46
  CL16 M_J_CPU1_SB_DQS_DN<1> @T6G_MB_LIB.T6G(SCH_1):M_J_CPU1_SB_DQS_DN(1)   I159 @T6G_MB_LIB.T6G(SCH_1):PAGE46
  BV16 M_J_CPU1_SB_DQS_DP<9> @T6G_MB_LIB.T6G(SCH_1):M_J_CPU1_SB_DQS_DP(9)   I159 @T6G_MB_LIB.T6G(SCH_1):PAGE46
  DD18 M_J_CPU1_SB_DQS_DP<8> @T6G_MB_LIB.T6G(SCH_1):M_J_CPU1_SB_DQS_DP(8)   I159 @T6G_MB_LIB.T6G(SCH_1):PAGE46
  CV18 M_J_CPU1_SB_DQS_DP<7> @T6G_MB_LIB.T6G(SCH_1):M_J_CPU1_SB_DQS_DP(7)   I159 @T6G_MB_LIB.T6G(SCH_1):PAGE46
  CM18 M_J_CPU1_SB_DQS_DP<6> @T6G_MB_LIB.T6G(SCH_1):M_J_CPU1_SB_DQS_DP(6)   I159 @T6G_MB_LIB.T6G(SCH_1):PAGE46
  BY18 M_J_CPU1_SB_DQS_DP<4> @T6G_MB_LIB.T6G(SCH_1):M_J_CPU1_SB_DQS_DP(4)   I159 @T6G_MB_LIB.T6G(SCH_1):PAGE46
  DB16 M_J_CPU1_SB_DQS_DP<3> @T6G_MB_LIB.T6G(SCH_1):M_J_CPU1_SB_DQS_DP(3)   I159 @T6G_MB_LIB.T6G(SCH_1):PAGE46
  CT16 M_J_CPU1_SB_DQS_DP<2> @T6G_MB_LIB.T6G(SCH_1):M_J_CPU1_SB_DQS_DP(2)   I159 @T6G_MB_LIB.T6G(SCH_1):PAGE46
  CK16 M_J_CPU1_SB_DQS_DP<1> @T6G_MB_LIB.T6G(SCH_1):M_J_CPU1_SB_DQS_DP(1)   I159 @T6G_MB_LIB.T6G(SCH_1):PAGE46
  CD16 M_J_CPU1_SB_DQS_DP<0> @T6G_MB_LIB.T6G(SCH_1):M_J_CPU1_SB_DQS_DP(0)   I159 @T6G_MB_LIB.T6G(SCH_1):PAGE46
  DF16 M_J_CPU1_SB_DQ<31> @T6G_MB_LIB.T6G(SCH_1):M_J_CPU1_SB_DQ(31)   I159 @T6G_MB_LIB.T6G(SCH_1):PAGE46
  DE16 M_J_CPU1_SB_DQ<30> @T6G_MB_LIB.T6G(SCH_1):M_J_CPU1_SB_DQ(30)   I159 @T6G_MB_LIB.T6G(SCH_1):PAGE46
  DE17 M_J_CPU1_SB_DQ<29> @T6G_MB_LIB.T6G(SCH_1):M_J_CPU1_SB_DQ(29)   I159 @T6G_MB_LIB.T6G(SCH_1):PAGE46
  DD16 M_J_CPU1_SB_DQ<28> @T6G_MB_LIB.T6G(SCH_1):M_J_CPU1_SB_DQ(28)   I159 @T6G_MB_LIB.T6G(SCH_1):PAGE46
  DB18 M_J_CPU1_SB_DQ<27> @T6G_MB_LIB.T6G(SCH_1):M_J_CPU1_SB_DQ(27)   I159 @T6G_MB_LIB.T6G(SCH_1):PAGE46
  DA16 M_J_CPU1_SB_DQ<26> @T6G_MB_LIB.T6G(SCH_1):M_J_CPU1_SB_DQ(26)   I159 @T6G_MB_LIB.T6G(SCH_1):PAGE46
  DA17 M_J_CPU1_SB_DQ<25> @T6G_MB_LIB.T6G(SCH_1):M_J_CPU1_SB_DQ(25)   I159 @T6G_MB_LIB.T6G(SCH_1):PAGE46
  CY16 M_J_CPU1_SB_DQ<24> @T6G_MB_LIB.T6G(SCH_1):M_J_CPU1_SB_DQ(24)   I159 @T6G_MB_LIB.T6G(SCH_1):PAGE46
  CY18 M_J_CPU1_SB_DQ<23> @T6G_MB_LIB.T6G(SCH_1):M_J_CPU1_SB_DQ(23)   I159 @T6G_MB_LIB.T6G(SCH_1):PAGE46
  CW16 M_J_CPU1_SB_DQ<22> @T6G_MB_LIB.T6G(SCH_1):M_J_CPU1_SB_DQ(22)   I159 @T6G_MB_LIB.T6G(SCH_1):PAGE46
  CW17 M_J_CPU1_SB_DQ<21> @T6G_MB_LIB.T6G(SCH_1):M_J_CPU1_SB_DQ(21)   I159 @T6G_MB_LIB.T6G(SCH_1):PAGE46
  CV16 M_J_CPU1_SB_DQ<20> @T6G_MB_LIB.T6G(SCH_1):M_J_CPU1_SB_DQ(20)   I159 @T6G_MB_LIB.T6G(SCH_1):PAGE46
  CT18 M_J_CPU1_SB_DQ<19> @T6G_MB_LIB.T6G(SCH_1):M_J_CPU1_SB_DQ(19)   I159 @T6G_MB_LIB.T6G(SCH_1):PAGE46
  CR16 M_J_CPU1_SB_DQ<18> @T6G_MB_LIB.T6G(SCH_1):M_J_CPU1_SB_DQ(18)   I159 @T6G_MB_LIB.T6G(SCH_1):PAGE46
  CR17 M_J_CPU1_SB_DQ<17> @T6G_MB_LIB.T6G(SCH_1):M_J_CPU1_SB_DQ(17)   I159 @T6G_MB_LIB.T6G(SCH_1):PAGE46
  CP16 M_J_CPU1_SB_DQ<16> @T6G_MB_LIB.T6G(SCH_1):M_J_CPU1_SB_DQ(16)   I159 @T6G_MB_LIB.T6G(SCH_1):PAGE46
  CP18 M_J_CPU1_SB_DQ<15> @T6G_MB_LIB.T6G(SCH_1):M_J_CPU1_SB_DQ(15)   I159 @T6G_MB_LIB.T6G(SCH_1):PAGE46
  CN16 M_J_CPU1_SB_DQ<14> @T6G_MB_LIB.T6G(SCH_1):M_J_CPU1_SB_DQ(14)   I159 @T6G_MB_LIB.T6G(SCH_1):PAGE46
  CN17 M_J_CPU1_SB_DQ<13> @T6G_MB_LIB.T6G(SCH_1):M_J_CPU1_SB_DQ(13)   I159 @T6G_MB_LIB.T6G(SCH_1):PAGE46
  CM16 M_J_CPU1_SB_DQ<12> @T6G_MB_LIB.T6G(SCH_1):M_J_CPU1_SB_DQ(12)   I159 @T6G_MB_LIB.T6G(SCH_1):PAGE46
  CK18 M_J_CPU1_SB_DQ<11> @T6G_MB_LIB.T6G(SCH_1):M_J_CPU1_SB_DQ(11)   I159 @T6G_MB_LIB.T6G(SCH_1):PAGE46
  CJ16 M_J_CPU1_SB_DQ<10> @T6G_MB_LIB.T6G(SCH_1):M_J_CPU1_SB_DQ(10)   I159 @T6G_MB_LIB.T6G(SCH_1):PAGE46
  CJ17 M_J_CPU1_SB_DQ<9> @T6G_MB_LIB.T6G(SCH_1):M_J_CPU1_SB_DQ(9)   I159 @T6G_MB_LIB.T6G(SCH_1):PAGE46
  CH16 M_J_CPU1_SB_DQ<8> @T6G_MB_LIB.T6G(SCH_1):M_J_CPU1_SB_DQ(8)   I159 @T6G_MB_LIB.T6G(SCH_1):PAGE46
  CC16 M_J_CPU1_SB_DQ<2> @T6G_MB_LIB.T6G(SCH_1):M_J_CPU1_SB_DQ(2)   I159 @T6G_MB_LIB.T6G(SCH_1):PAGE46
  CC17 M_J_CPU1_SB_DQ<1> @T6G_MB_LIB.T6G(SCH_1):M_J_CPU1_SB_DQ(1)   I159 @T6G_MB_LIB.T6G(SCH_1):PAGE46
  BV18 M_J_CPU1_SB_CB<7> @T6G_MB_LIB.T6G(SCH_1):M_J_CPU1_SB_CB(7)   I159 @T6G_MB_LIB.T6G(SCH_1):PAGE46
  BU16 M_J_CPU1_SB_CB<6> @T6G_MB_LIB.T6G(SCH_1):M_J_CPU1_SB_CB(6)   I159 @T6G_MB_LIB.T6G(SCH_1):PAGE46
  BU17 M_J_CPU1_SB_CB<5> @T6G_MB_LIB.T6G(SCH_1):M_J_CPU1_SB_CB(5)   I159 @T6G_MB_LIB.T6G(SCH_1):PAGE46
  BT16 M_J_CPU1_SB_CB<4> @T6G_MB_LIB.T6G(SCH_1):M_J_CPU1_SB_CB(4)   I159 @T6G_MB_LIB.T6G(SCH_1):PAGE46
  CB18 M_J_CPU1_SB_CB<3> @T6G_MB_LIB.T6G(SCH_1):M_J_CPU1_SB_CB(3)   I159 @T6G_MB_LIB.T6G(SCH_1):PAGE46
  CA16 M_J_CPU1_SB_CB<2> @T6G_MB_LIB.T6G(SCH_1):M_J_CPU1_SB_CB(2)   I159 @T6G_MB_LIB.T6G(SCH_1):PAGE46
  CA17 M_J_CPU1_SB_CB<1> @T6G_MB_LIB.T6G(SCH_1):M_J_CPU1_SB_CB(1)   I159 @T6G_MB_LIB.T6G(SCH_1):PAGE46
  BY16 M_J_CPU1_SB_CB<0> @T6G_MB_LIB.T6G(SCH_1):M_J_CPU1_SB_CB(0)   I159 @T6G_MB_LIB.T6G(SCH_1):PAGE46
  BK16 M_J_CPU1_SB_CA<6> @T6G_MB_LIB.T6G(SCH_1):M_J_CPU1_SB_CA(6)   I159 @T6G_MB_LIB.T6G(SCH_1):PAGE46
  BK18 M_J_CPU1_SB_CA<5> @T6G_MB_LIB.T6G(SCH_1):M_J_CPU1_SB_CA(5)   I159 @T6G_MB_LIB.T6G(SCH_1):PAGE46
  BJ17 M_J_CPU1_SB_CA<4> @T6G_MB_LIB.T6G(SCH_1):M_J_CPU1_SB_CA(4)   I159 @T6G_MB_LIB.T6G(SCH_1):PAGE46
  BJ16 M_J_CPU1_SB_CA<3> @T6G_MB_LIB.T6G(SCH_1):M_J_CPU1_SB_CA(3)   I159 @T6G_MB_LIB.T6G(SCH_1):PAGE46
  BH16 M_J_CPU1_SB_CA<2> @T6G_MB_LIB.T6G(SCH_1):M_J_CPU1_SB_CA(2)   I159 @T6G_MB_LIB.T6G(SCH_1):PAGE46
  BH18 M_J_CPU1_SB_CA<1> @T6G_MB_LIB.T6G(SCH_1):M_J_CPU1_SB_CA(1)   I159 @T6G_MB_LIB.T6G(SCH_1):PAGE46
  BG17 M_J_CPU1_SB_CA<0> @T6G_MB_LIB.T6G(SCH_1):M_J_CPU1_SB_CA(0)   I159 @T6G_MB_LIB.T6G(SCH_1):PAGE46
  BR16     NC     NC   I159 @T6G_MB_LIB.T6G(SCH_1):PAGE46
  BM16     NC     NC   I159 @T6G_MB_LIB.T6G(SCH_1):PAGE46
  BL16     NC     NC   I159 @T6G_MB_LIB.T6G(SCH_1):PAGE46
  BP16 M_J_CPU1_SB_RSP<0> @T6G_MB_LIB.T6G(SCH_1):M_J_CPU1_SB_RSP(0)   I159 @T6G_MB_LIB.T6G(SCH_1):PAGE46
  BN16 M_J_CPU1_SB_CS_N<1> @T6G_MB_LIB.T6G(SCH_1):M_J_CPU1_SB_CS_N(1)   I159 @T6G_MB_LIB.T6G(SCH_1):PAGE46
  BM18 M_J_CPU1_SB_CS_N<0> @T6G_MB_LIB.T6G(SCH_1):M_J_CPU1_SB_CS_N(0)   I159 @T6G_MB_LIB.T6G(SCH_1):PAGE46
  BC17 M_J_CPU1_SA_PAR @T6G_MB_LIB.T6G(SCH_1):M_J_CPU1_SA_PAR   I159 @T6G_MB_LIB.T6G(SCH_1):PAGE46
  AM18 M_J_CPU1_SA_DQS_DN<9> @T6G_MB_LIB.T6G(SCH_1):M_J_CPU1_SA_DQS_DN(9)   I159 @T6G_MB_LIB.T6G(SCH_1):PAGE46
  AF18 M_J_CPU1_SA_DQS_DN<8> @T6G_MB_LIB.T6G(SCH_1):M_J_CPU1_SA_DQS_DN(8)   I159 @T6G_MB_LIB.T6G(SCH_1):PAGE46
   P18 M_J_CPU1_SA_DQS_DN<6> @T6G_MB_LIB.T6G(SCH_1):M_J_CPU1_SA_DQS_DN(6)   I159 @T6G_MB_LIB.T6G(SCH_1):PAGE46
  AF16 M_J_CPU1_SA_DQS_DN<3> @T6G_MB_LIB.T6G(SCH_1):M_J_CPU1_SA_DQS_DN(3)   I159 @T6G_MB_LIB.T6G(SCH_1):PAGE46
   Y16 M_J_CPU1_SA_DQS_DN<2> @T6G_MB_LIB.T6G(SCH_1):M_J_CPU1_SA_DQS_DN(2)   I159 @T6G_MB_LIB.T6G(SCH_1):PAGE46
   P16 M_J_CPU1_SA_DQS_DN<1> @T6G_MB_LIB.T6G(SCH_1):M_J_CPU1_SA_DQS_DN(1)   I159 @T6G_MB_LIB.T6G(SCH_1):PAGE46
   H16 M_J_CPU1_SA_DQS_DN<0> @T6G_MB_LIB.T6G(SCH_1):M_J_CPU1_SA_DQS_DN(0)   I159 @T6G_MB_LIB.T6G(SCH_1):PAGE46
  AN17 M_J_CPU1_SA_DQS_DP<9> @T6G_MB_LIB.T6G(SCH_1):M_J_CPU1_SA_DQS_DP(9)   I159 @T6G_MB_LIB.T6G(SCH_1):PAGE46
  AA17 M_J_CPU1_SA_DQS_DP<7> @T6G_MB_LIB.T6G(SCH_1):M_J_CPU1_SA_DQS_DP(7)   I159 @T6G_MB_LIB.T6G(SCH_1):PAGE46
   R17 M_J_CPU1_SA_DQS_DP<6> @T6G_MB_LIB.T6G(SCH_1):M_J_CPU1_SA_DQS_DP(6)   I159 @T6G_MB_LIB.T6G(SCH_1):PAGE46
   J17 M_J_CPU1_SA_DQS_DP<5> @T6G_MB_LIB.T6G(SCH_1):M_J_CPU1_SA_DQS_DP(5)   I159 @T6G_MB_LIB.T6G(SCH_1):PAGE46
  AE16 M_J_CPU1_SA_DQS_DP<3> @T6G_MB_LIB.T6G(SCH_1):M_J_CPU1_SA_DQS_DP(3)   I159 @T6G_MB_LIB.T6G(SCH_1):PAGE46
   W16 M_J_CPU1_SA_DQS_DP<2> @T6G_MB_LIB.T6G(SCH_1):M_J_CPU1_SA_DQS_DP(2)   I159 @T6G_MB_LIB.T6G(SCH_1):PAGE46
   N16 M_J_CPU1_SA_DQS_DP<1> @T6G_MB_LIB.T6G(SCH_1):M_J_CPU1_SA_DQS_DP(1)   I159 @T6G_MB_LIB.T6G(SCH_1):PAGE46
   G16 M_J_CPU1_SA_DQS_DP<0> @T6G_MB_LIB.T6G(SCH_1):M_J_CPU1_SA_DQS_DP(0)   I159 @T6G_MB_LIB.T6G(SCH_1):PAGE46
  AH16 M_J_CPU1_SA_DQ<30> @T6G_MB_LIB.T6G(SCH_1):M_J_CPU1_SA_DQ(30)   I159 @T6G_MB_LIB.T6G(SCH_1):PAGE46
  AH18 M_J_CPU1_SA_DQ<29> @T6G_MB_LIB.T6G(SCH_1):M_J_CPU1_SA_DQ(29)   I159 @T6G_MB_LIB.T6G(SCH_1):PAGE46
  AG16 M_J_CPU1_SA_DQ<28> @T6G_MB_LIB.T6G(SCH_1):M_J_CPU1_SA_DQ(28)   I159 @T6G_MB_LIB.T6G(SCH_1):PAGE46
  AE17 M_J_CPU1_SA_DQ<27> @T6G_MB_LIB.T6G(SCH_1):M_J_CPU1_SA_DQ(27)   I159 @T6G_MB_LIB.T6G(SCH_1):PAGE46
  AD16 M_J_CPU1_SA_DQ<26> @T6G_MB_LIB.T6G(SCH_1):M_J_CPU1_SA_DQ(26)   I159 @T6G_MB_LIB.T6G(SCH_1):PAGE46
  AD18 M_J_CPU1_SA_DQ<25> @T6G_MB_LIB.T6G(SCH_1):M_J_CPU1_SA_DQ(25)   I159 @T6G_MB_LIB.T6G(SCH_1):PAGE46
  AC16 M_J_CPU1_SA_DQ<24> @T6G_MB_LIB.T6G(SCH_1):M_J_CPU1_SA_DQ(24)   I159 @T6G_MB_LIB.T6G(SCH_1):PAGE46
  AC17 M_J_CPU1_SA_DQ<23> @T6G_MB_LIB.T6G(SCH_1):M_J_CPU1_SA_DQ(23)   I159 @T6G_MB_LIB.T6G(SCH_1):PAGE46
  AB18 M_J_CPU1_SA_DQ<21> @T6G_MB_LIB.T6G(SCH_1):M_J_CPU1_SA_DQ(21)   I159 @T6G_MB_LIB.T6G(SCH_1):PAGE46
  AA16 M_J_CPU1_SA_DQ<20> @T6G_MB_LIB.T6G(SCH_1):M_J_CPU1_SA_DQ(20)   I159 @T6G_MB_LIB.T6G(SCH_1):PAGE46
   W17 M_J_CPU1_SA_DQ<19> @T6G_MB_LIB.T6G(SCH_1):M_J_CPU1_SA_DQ(19)   I159 @T6G_MB_LIB.T6G(SCH_1):PAGE46
   V16 M_J_CPU1_SA_DQ<18> @T6G_MB_LIB.T6G(SCH_1):M_J_CPU1_SA_DQ(18)   I159 @T6G_MB_LIB.T6G(SCH_1):PAGE46
   V18 M_J_CPU1_SA_DQ<17> @T6G_MB_LIB.T6G(SCH_1):M_J_CPU1_SA_DQ(17)   I159 @T6G_MB_LIB.T6G(SCH_1):PAGE46
   U16 M_J_CPU1_SA_DQ<16> @T6G_MB_LIB.T6G(SCH_1):M_J_CPU1_SA_DQ(16)   I159 @T6G_MB_LIB.T6G(SCH_1):PAGE46
   U17 M_J_CPU1_SA_DQ<15> @T6G_MB_LIB.T6G(SCH_1):M_J_CPU1_SA_DQ(15)   I159 @T6G_MB_LIB.T6G(SCH_1):PAGE46
   T16 M_J_CPU1_SA_DQ<14> @T6G_MB_LIB.T6G(SCH_1):M_J_CPU1_SA_DQ(14)   I159 @T6G_MB_LIB.T6G(SCH_1):PAGE46
   T18 M_J_CPU1_SA_DQ<13> @T6G_MB_LIB.T6G(SCH_1):M_J_CPU1_SA_DQ(13)   I159 @T6G_MB_LIB.T6G(SCH_1):PAGE46
   R16 M_J_CPU1_SA_DQ<12> @T6G_MB_LIB.T6G(SCH_1):M_J_CPU1_SA_DQ(12)   I159 @T6G_MB_LIB.T6G(SCH_1):PAGE46
   N17 M_J_CPU1_SA_DQ<11> @T6G_MB_LIB.T6G(SCH_1):M_J_CPU1_SA_DQ(11)   I159 @T6G_MB_LIB.T6G(SCH_1):PAGE46
   M16 M_J_CPU1_SA_DQ<10> @T6G_MB_LIB.T6G(SCH_1):M_J_CPU1_SA_DQ(10)   I159 @T6G_MB_LIB.T6G(SCH_1):PAGE46
   M18 M_J_CPU1_SA_DQ<9> @T6G_MB_LIB.T6G(SCH_1):M_J_CPU1_SA_DQ(9)   I159 @T6G_MB_LIB.T6G(SCH_1):PAGE46
   L16 M_J_CPU1_SA_DQ<8> @T6G_MB_LIB.T6G(SCH_1):M_J_CPU1_SA_DQ(8)   I159 @T6G_MB_LIB.T6G(SCH_1):PAGE46
   L17 M_J_CPU1_SA_DQ<7> @T6G_MB_LIB.T6G(SCH_1):M_J_CPU1_SA_DQ(7)   I159 @T6G_MB_LIB.T6G(SCH_1):PAGE46
   K16 M_J_CPU1_SA_DQ<6> @T6G_MB_LIB.T6G(SCH_1):M_J_CPU1_SA_DQ(6)   I159 @T6G_MB_LIB.T6G(SCH_1):PAGE46
   K18 M_J_CPU1_SA_DQ<5> @T6G_MB_LIB.T6G(SCH_1):M_J_CPU1_SA_DQ(5)   I159 @T6G_MB_LIB.T6G(SCH_1):PAGE46
   J16 M_J_CPU1_SA_DQ<4> @T6G_MB_LIB.T6G(SCH_1):M_J_CPU1_SA_DQ(4)   I159 @T6G_MB_LIB.T6G(SCH_1):PAGE46
   G17 M_J_CPU1_SA_DQ<3> @T6G_MB_LIB.T6G(SCH_1):M_J_CPU1_SA_DQ(3)   I159 @T6G_MB_LIB.T6G(SCH_1):PAGE46
   F16 M_J_CPU1_SA_DQ<2> @T6G_MB_LIB.T6G(SCH_1):M_J_CPU1_SA_DQ(2)   I159 @T6G_MB_LIB.T6G(SCH_1):PAGE46
   F18 M_J_CPU1_SA_DQ<1> @T6G_MB_LIB.T6G(SCH_1):M_J_CPU1_SA_DQ(1)   I159 @T6G_MB_LIB.T6G(SCH_1):PAGE46
   E16 M_J_CPU1_SA_DQ<0> @T6G_MB_LIB.T6G(SCH_1):M_J_CPU1_SA_DQ(0)   I159 @T6G_MB_LIB.T6G(SCH_1):PAGE46
  AR17 M_J_CPU1_SA_CB<7> @T6G_MB_LIB.T6G(SCH_1):M_J_CPU1_SA_CB(7)   I159 @T6G_MB_LIB.T6G(SCH_1):PAGE46
  AP16 M_J_CPU1_SA_CB<6> @T6G_MB_LIB.T6G(SCH_1):M_J_CPU1_SA_CB(6)   I159 @T6G_MB_LIB.T6G(SCH_1):PAGE46
  AP18 M_J_CPU1_SA_CB<5> @T6G_MB_LIB.T6G(SCH_1):M_J_CPU1_SA_CB(5)   I159 @T6G_MB_LIB.T6G(SCH_1):PAGE46
  AN16 M_J_CPU1_SA_CB<4> @T6G_MB_LIB.T6G(SCH_1):M_J_CPU1_SA_CB(4)   I159 @T6G_MB_LIB.T6G(SCH_1):PAGE46
  AL17 M_J_CPU1_SA_CB<3> @T6G_MB_LIB.T6G(SCH_1):M_J_CPU1_SA_CB(3)   I159 @T6G_MB_LIB.T6G(SCH_1):PAGE46
  AK16 M_J_CPU1_SA_CB<2> @T6G_MB_LIB.T6G(SCH_1):M_J_CPU1_SA_CB(2)   I159 @T6G_MB_LIB.T6G(SCH_1):PAGE46
  AK18 M_J_CPU1_SA_CB<1> @T6G_MB_LIB.T6G(SCH_1):M_J_CPU1_SA_CB(1)   I159 @T6G_MB_LIB.T6G(SCH_1):PAGE46
  AJ16 M_J_CPU1_SA_CB<0> @T6G_MB_LIB.T6G(SCH_1):M_J_CPU1_SA_CB(0)   I159 @T6G_MB_LIB.T6G(SCH_1):PAGE46
  BA16 M_J_CPU1_SA_CA<4> @T6G_MB_LIB.T6G(SCH_1):M_J_CPU1_SA_CA(4)   I159 @T6G_MB_LIB.T6G(SCH_1):PAGE46
  BA17 M_J_CPU1_SA_CA<3> @T6G_MB_LIB.T6G(SCH_1):M_J_CPU1_SA_CA(3)   I159 @T6G_MB_LIB.T6G(SCH_1):PAGE46
  AY18 M_J_CPU1_SA_CA<2> @T6G_MB_LIB.T6G(SCH_1):M_J_CPU1_SA_CA(2)   I159 @T6G_MB_LIB.T6G(SCH_1):PAGE46
  AY16 M_J_CPU1_SA_CA<1> @T6G_MB_LIB.T6G(SCH_1):M_J_CPU1_SA_CA(1)   I159 @T6G_MB_LIB.T6G(SCH_1):PAGE46
  AW16 M_J_CPU1_SA_CA<0> @T6G_MB_LIB.T6G(SCH_1):M_J_CPU1_SA_CA(0)   I159 @T6G_MB_LIB.T6G(SCH_1):PAGE46
  BP18     NC     NC   I159 @T6G_MB_LIB.T6G(SCH_1):PAGE46
  AW17     NC     NC   I159 @T6G_MB_LIB.T6G(SCH_1):PAGE46
  AV16     NC     NC   I159 @T6G_MB_LIB.T6G(SCH_1):PAGE46
  BN17 M_J_CPU1_SA_RSP<0> @T6G_MB_LIB.T6G(SCH_1):M_J_CPU1_SA_RSP(0)   I159 @T6G_MB_LIB.T6G(SCH_1):PAGE46
  AV18 M_J_CPU1_SA_CS_N<1> @T6G_MB_LIB.T6G(SCH_1):M_J_CPU1_SA_CS_N(1)   I159 @T6G_MB_LIB.T6G(SCH_1):PAGE46
  AU16 M_J_CPU1_SA_CS_N<0> @T6G_MB_LIB.T6G(SCH_1):M_J_CPU1_SA_CS_N(0)   I159 @T6G_MB_LIB.T6G(SCH_1):PAGE46
  BG16     NC     NC   I159 @T6G_MB_LIB.T6G(SCH_1):PAGE46
  BF16     NC     NC   I159 @T6G_MB_LIB.T6G(SCH_1):PAGE46
  BD16 M_J_CPU1_CLK_DN<0> @T6G_MB_LIB.T6G(SCH_1):M_J_CPU1_CLK_DN(0)   I159 @T6G_MB_LIB.T6G(SCH_1):PAGE46
  BC16 M_J_CPU1_CLK_DP<0> @T6G_MB_LIB.T6G(SCH_1):M_J_CPU1_CLK_DP(0)   I159 @T6G_MB_LIB.T6G(SCH_1):PAGE46
  BB18 M_J_CPU1_SA_CA<6> @T6G_MB_LIB.T6G(SCH_1):M_J_CPU1_SA_CA(6)   I159 @T6G_MB_LIB.T6G(SCH_1):PAGE46
  BB16 M_J_CPU1_SA_CA<5> @T6G_MB_LIB.T6G(SCH_1):M_J_CPU1_SA_CA(5)   I159 @T6G_MB_LIB.T6G(SCH_1):PAGE46
  AB16 M_J_CPU1_SA_DQ<22> @T6G_MB_LIB.T6G(SCH_1):M_J_CPU1_SA_DQ(22)   I159 @T6G_MB_LIB.T6G(SCH_1):PAGE46
   Y18 M_J_CPU1_SA_DQS_DN<7> @T6G_MB_LIB.T6G(SCH_1):M_J_CPU1_SA_DQS_DN(7)   I159 @T6G_MB_LIB.T6G(SCH_1):PAGE46
   H18 M_J_CPU1_SA_DQS_DN<5> @T6G_MB_LIB.T6G(SCH_1):M_J_CPU1_SA_DQS_DN(5)   I159 @T6G_MB_LIB.T6G(SCH_1):PAGE46
  AM16 M_J_CPU1_SA_DQS_DN<4> @T6G_MB_LIB.T6G(SCH_1):M_J_CPU1_SA_DQS_DN(4)   I159 @T6G_MB_LIB.T6G(SCH_1):PAGE46
  AG17 M_J_CPU1_SA_DQS_DP<8> @T6G_MB_LIB.T6G(SCH_1):M_J_CPU1_SA_DQS_DP(8)   I159 @T6G_MB_LIB.T6G(SCH_1):PAGE46
  AL16 M_J_CPU1_SA_DQS_DP<4> @T6G_MB_LIB.T6G(SCH_1):M_J_CPU1_SA_DQS_DP(4)   I159 @T6G_MB_LIB.T6G(SCH_1):PAGE46
  CF16 M_J_CPU1_SB_DQ<4> @T6G_MB_LIB.T6G(SCH_1):M_J_CPU1_SB_DQ(4)   I159 @T6G_MB_LIB.T6G(SCH_1):PAGE46
  CD18 M_J_CPU1_SB_DQ<3> @T6G_MB_LIB.T6G(SCH_1):M_J_CPU1_SB_DQ(3)   I159 @T6G_MB_LIB.T6G(SCH_1):PAGE46
  CB16 M_J_CPU1_SB_DQ<0> @T6G_MB_LIB.T6G(SCH_1):M_J_CPU1_SB_DQ(0)   I159 @T6G_MB_LIB.T6G(SCH_1):PAGE46
  AJ17 M_J_CPU1_SA_DQ<31> @T6G_MB_LIB.T6G(SCH_1):M_J_CPU1_SA_DQ(31)   I159 @T6G_MB_LIB.T6G(SCH_1):PAGE46
  CE16 M_J_CPU1_SB_DQS_DN<0> @T6G_MB_LIB.T6G(SCH_1):M_J_CPU1_SB_DQS_DN(0)   I159 @T6G_MB_LIB.T6G(SCH_1):PAGE46
  BW17 M_J_CPU1_SB_DQS_DN<4> @T6G_MB_LIB.T6G(SCH_1):M_J_CPU1_SB_DQS_DN(4)   I159 @T6G_MB_LIB.T6G(SCH_1):PAGE46
  CF18 M_J_CPU1_SB_DQS_DP<5> @T6G_MB_LIB.T6G(SCH_1):M_J_CPU1_SB_DQS_DP(5)   I159 @T6G_MB_LIB.T6G(SCH_1):PAGE46
  CG17 M_J_CPU1_SB_DQ<5> @T6G_MB_LIB.T6G(SCH_1):M_J_CPU1_SB_DQ(5)   I159 @T6G_MB_LIB.T6G(SCH_1):PAGE46
  CG16 M_J_CPU1_SB_DQ<6> @T6G_MB_LIB.T6G(SCH_1):M_J_CPU1_SB_DQ(6)   I159 @T6G_MB_LIB.T6G(SCH_1):PAGE46
  CH18 M_J_CPU1_SB_DQ<7> @T6G_MB_LIB.T6G(SCH_1):M_J_CPU1_SB_DQ(7)   I159 @T6G_MB_LIB.T6G(SCH_1):PAGE46
  BF18 TP_M_J_CPU1_SA_TEST39J @T6G_MB_LIB.T6G(SCH_1):TP_M_J_CPU1_SA_TEST39J   I159 @T6G_MB_LIB.T6G(SCH_1):PAGE46
   M40 GMI_CPU0_G2_CPU1_G0_TX_DN<15> @T6G_MB_LIB.T6G(SCH_1):GMI_CPU0_G2_CPU1_G0_TX_DN(15)   I213 @T6G_MB_LIB.T6G(SCH_1):PAGE49
   K40 GMI_CPU0_G2_CPU1_G0_TX_DN<14> @T6G_MB_LIB.T6G(SCH_1):GMI_CPU0_G2_CPU1_G0_TX_DN(14)   I213 @T6G_MB_LIB.T6G(SCH_1):PAGE49
   H40 GMI_CPU0_G2_CPU1_G0_TX_DN<13> @T6G_MB_LIB.T6G(SCH_1):GMI_CPU0_G2_CPU1_G0_TX_DN(13)   I213 @T6G_MB_LIB.T6G(SCH_1):PAGE49
   L43 GMI_CPU0_G2_CPU1_G0_TX_DN<12> @T6G_MB_LIB.T6G(SCH_1):GMI_CPU0_G2_CPU1_G0_TX_DN(12)   I213 @T6G_MB_LIB.T6G(SCH_1):PAGE49
   G43 GMI_CPU0_G2_CPU1_G0_TX_DN<11> @T6G_MB_LIB.T6G(SCH_1):GMI_CPU0_G2_CPU1_G0_TX_DN(11)   I213 @T6G_MB_LIB.T6G(SCH_1):PAGE49
   J43 GMI_CPU0_G2_CPU1_G0_TX_DN<10> @T6G_MB_LIB.T6G(SCH_1):GMI_CPU0_G2_CPU1_G0_TX_DN(10)   I213 @T6G_MB_LIB.T6G(SCH_1):PAGE49
   L46 GMI_CPU0_G2_CPU1_G0_TX_DN<9> @T6G_MB_LIB.T6G(SCH_1):GMI_CPU0_G2_CPU1_G0_TX_DN(9)   I213 @T6G_MB_LIB.T6G(SCH_1):PAGE49
   G46 GMI_CPU0_G2_CPU1_G0_TX_DN<8> @T6G_MB_LIB.T6G(SCH_1):GMI_CPU0_G2_CPU1_G0_TX_DN(8)   I213 @T6G_MB_LIB.T6G(SCH_1):PAGE49
   J46 GMI_CPU0_G2_CPU1_G0_TX_DN<7> @T6G_MB_LIB.T6G(SCH_1):GMI_CPU0_G2_CPU1_G0_TX_DN(7)   I213 @T6G_MB_LIB.T6G(SCH_1):PAGE49
   L49 GMI_CPU0_G2_CPU1_G0_TX_DN<6> @T6G_MB_LIB.T6G(SCH_1):GMI_CPU0_G2_CPU1_G0_TX_DN(6)   I213 @T6G_MB_LIB.T6G(SCH_1):PAGE49
   G49 GMI_CPU0_G2_CPU1_G0_TX_DN<5> @T6G_MB_LIB.T6G(SCH_1):GMI_CPU0_G2_CPU1_G0_TX_DN(5)   I213 @T6G_MB_LIB.T6G(SCH_1):PAGE49
   J49 GMI_CPU0_G2_CPU1_G0_TX_DN<4> @T6G_MB_LIB.T6G(SCH_1):GMI_CPU0_G2_CPU1_G0_TX_DN(4)   I213 @T6G_MB_LIB.T6G(SCH_1):PAGE49
   L52 GMI_CPU0_G2_CPU1_G0_TX_DN<3> @T6G_MB_LIB.T6G(SCH_1):GMI_CPU0_G2_CPU1_G0_TX_DN(3)   I213 @T6G_MB_LIB.T6G(SCH_1):PAGE49
   G52 GMI_CPU0_G2_CPU1_G0_TX_DN<2> @T6G_MB_LIB.T6G(SCH_1):GMI_CPU0_G2_CPU1_G0_TX_DN(2)   I213 @T6G_MB_LIB.T6G(SCH_1):PAGE49
   J52 GMI_CPU0_G2_CPU1_G0_TX_DN<1> @T6G_MB_LIB.T6G(SCH_1):GMI_CPU0_G2_CPU1_G0_TX_DN(1)   I213 @T6G_MB_LIB.T6G(SCH_1):PAGE49
   N52 GMI_CPU0_G2_CPU1_G0_TX_DN<0> @T6G_MB_LIB.T6G(SCH_1):GMI_CPU0_G2_CPU1_G0_TX_DN(0)   I213 @T6G_MB_LIB.T6G(SCH_1):PAGE49
   M41 GMI_CPU0_G2_CPU1_G0_TX_DP<15> @T6G_MB_LIB.T6G(SCH_1):GMI_CPU0_G2_CPU1_G0_TX_DP(15)   I213 @T6G_MB_LIB.T6G(SCH_1):PAGE49
   K41 GMI_CPU0_G2_CPU1_G0_TX_DP<14> @T6G_MB_LIB.T6G(SCH_1):GMI_CPU0_G2_CPU1_G0_TX_DP(14)   I213 @T6G_MB_LIB.T6G(SCH_1):PAGE49
   H41 GMI_CPU0_G2_CPU1_G0_TX_DP<13> @T6G_MB_LIB.T6G(SCH_1):GMI_CPU0_G2_CPU1_G0_TX_DP(13)   I213 @T6G_MB_LIB.T6G(SCH_1):PAGE49
   L44 GMI_CPU0_G2_CPU1_G0_TX_DP<12> @T6G_MB_LIB.T6G(SCH_1):GMI_CPU0_G2_CPU1_G0_TX_DP(12)   I213 @T6G_MB_LIB.T6G(SCH_1):PAGE49
   G44 GMI_CPU0_G2_CPU1_G0_TX_DP<11> @T6G_MB_LIB.T6G(SCH_1):GMI_CPU0_G2_CPU1_G0_TX_DP(11)   I213 @T6G_MB_LIB.T6G(SCH_1):PAGE49
   J44 GMI_CPU0_G2_CPU1_G0_TX_DP<10> @T6G_MB_LIB.T6G(SCH_1):GMI_CPU0_G2_CPU1_G0_TX_DP(10)   I213 @T6G_MB_LIB.T6G(SCH_1):PAGE49
   L47 GMI_CPU0_G2_CPU1_G0_TX_DP<9> @T6G_MB_LIB.T6G(SCH_1):GMI_CPU0_G2_CPU1_G0_TX_DP(9)   I213 @T6G_MB_LIB.T6G(SCH_1):PAGE49
   G47 GMI_CPU0_G2_CPU1_G0_TX_DP<8> @T6G_MB_LIB.T6G(SCH_1):GMI_CPU0_G2_CPU1_G0_TX_DP(8)   I213 @T6G_MB_LIB.T6G(SCH_1):PAGE49
   J47 GMI_CPU0_G2_CPU1_G0_TX_DP<7> @T6G_MB_LIB.T6G(SCH_1):GMI_CPU0_G2_CPU1_G0_TX_DP(7)   I213 @T6G_MB_LIB.T6G(SCH_1):PAGE49
   L50 GMI_CPU0_G2_CPU1_G0_TX_DP<6> @T6G_MB_LIB.T6G(SCH_1):GMI_CPU0_G2_CPU1_G0_TX_DP(6)   I213 @T6G_MB_LIB.T6G(SCH_1):PAGE49
   G50 GMI_CPU0_G2_CPU1_G0_TX_DP<5> @T6G_MB_LIB.T6G(SCH_1):GMI_CPU0_G2_CPU1_G0_TX_DP(5)   I213 @T6G_MB_LIB.T6G(SCH_1):PAGE49
   J50 GMI_CPU0_G2_CPU1_G0_TX_DP<4> @T6G_MB_LIB.T6G(SCH_1):GMI_CPU0_G2_CPU1_G0_TX_DP(4)   I213 @T6G_MB_LIB.T6G(SCH_1):PAGE49
   L53 GMI_CPU0_G2_CPU1_G0_TX_DP<3> @T6G_MB_LIB.T6G(SCH_1):GMI_CPU0_G2_CPU1_G0_TX_DP(3)   I213 @T6G_MB_LIB.T6G(SCH_1):PAGE49
   G53 GMI_CPU0_G2_CPU1_G0_TX_DP<2> @T6G_MB_LIB.T6G(SCH_1):GMI_CPU0_G2_CPU1_G0_TX_DP(2)   I213 @T6G_MB_LIB.T6G(SCH_1):PAGE49
   J53 GMI_CPU0_G2_CPU1_G0_TX_DP<1> @T6G_MB_LIB.T6G(SCH_1):GMI_CPU0_G2_CPU1_G0_TX_DP(1)   I213 @T6G_MB_LIB.T6G(SCH_1):PAGE49
   N53 GMI_CPU0_G2_CPU1_G0_TX_DP<0> @T6G_MB_LIB.T6G(SCH_1):GMI_CPU0_G2_CPU1_G0_TX_DP(0)   I213 @T6G_MB_LIB.T6G(SCH_1):PAGE49
  AF41 GMI_CPU1_G0_CPU0_G2_TX_DN<15> @T6G_MB_LIB.T6G(SCH_1):GMI_CPU1_G0_CPU0_G2_TX_DN(15)   I213 @T6G_MB_LIB.T6G(SCH_1):PAGE49
  AD41 GMI_CPU1_G0_CPU0_G2_TX_DN<14> @T6G_MB_LIB.T6G(SCH_1):GMI_CPU1_G0_CPU0_G2_TX_DN(14)   I213 @T6G_MB_LIB.T6G(SCH_1):PAGE49
  AB41 GMI_CPU1_G0_CPU0_G2_TX_DN<13> @T6G_MB_LIB.T6G(SCH_1):GMI_CPU1_G0_CPU0_G2_TX_DN(13)   I213 @T6G_MB_LIB.T6G(SCH_1):PAGE49
  AG44 GMI_CPU1_G0_CPU0_G2_TX_DN<12> @T6G_MB_LIB.T6G(SCH_1):GMI_CPU1_G0_CPU0_G2_TX_DN(12)   I213 @T6G_MB_LIB.T6G(SCH_1):PAGE49
  AA44 GMI_CPU1_G0_CPU0_G2_TX_DN<11> @T6G_MB_LIB.T6G(SCH_1):GMI_CPU1_G0_CPU0_G2_TX_DN(11)   I213 @T6G_MB_LIB.T6G(SCH_1):PAGE49
  AC44 GMI_CPU1_G0_CPU0_G2_TX_DN<10> @T6G_MB_LIB.T6G(SCH_1):GMI_CPU1_G0_CPU0_G2_TX_DN(10)   I213 @T6G_MB_LIB.T6G(SCH_1):PAGE49
  AE44 GMI_CPU1_G0_CPU0_G2_TX_DN<9> @T6G_MB_LIB.T6G(SCH_1):GMI_CPU1_G0_CPU0_G2_TX_DN(9)   I213 @T6G_MB_LIB.T6G(SCH_1):PAGE49
  AG47 GMI_CPU1_G0_CPU0_G2_TX_DN<8> @T6G_MB_LIB.T6G(SCH_1):GMI_CPU1_G0_CPU0_G2_TX_DN(8)   I213 @T6G_MB_LIB.T6G(SCH_1):PAGE49
  AC47 GMI_CPU1_G0_CPU0_G2_TX_DN<7> @T6G_MB_LIB.T6G(SCH_1):GMI_CPU1_G0_CPU0_G2_TX_DN(7)   I213 @T6G_MB_LIB.T6G(SCH_1):PAGE49
  AE47 GMI_CPU1_G0_CPU0_G2_TX_DN<6> @T6G_MB_LIB.T6G(SCH_1):GMI_CPU1_G0_CPU0_G2_TX_DN(6)   I213 @T6G_MB_LIB.T6G(SCH_1):PAGE49
  AG50 GMI_CPU1_G0_CPU0_G2_TX_DN<5> @T6G_MB_LIB.T6G(SCH_1):GMI_CPU1_G0_CPU0_G2_TX_DN(5)   I213 @T6G_MB_LIB.T6G(SCH_1):PAGE49
  AC50 GMI_CPU1_G0_CPU0_G2_TX_DN<4> @T6G_MB_LIB.T6G(SCH_1):GMI_CPU1_G0_CPU0_G2_TX_DN(4)   I213 @T6G_MB_LIB.T6G(SCH_1):PAGE49
  AE50 GMI_CPU1_G0_CPU0_G2_TX_DN<3> @T6G_MB_LIB.T6G(SCH_1):GMI_CPU1_G0_CPU0_G2_TX_DN(3)   I213 @T6G_MB_LIB.T6G(SCH_1):PAGE49
  AG53 GMI_CPU1_G0_CPU0_G2_TX_DN<2> @T6G_MB_LIB.T6G(SCH_1):GMI_CPU1_G0_CPU0_G2_TX_DN(2)   I213 @T6G_MB_LIB.T6G(SCH_1):PAGE49
  AC53 GMI_CPU1_G0_CPU0_G2_TX_DN<1> @T6G_MB_LIB.T6G(SCH_1):GMI_CPU1_G0_CPU0_G2_TX_DN(1)   I213 @T6G_MB_LIB.T6G(SCH_1):PAGE49
  AE53 GMI_CPU1_G0_CPU0_G2_TX_DN<0> @T6G_MB_LIB.T6G(SCH_1):GMI_CPU1_G0_CPU0_G2_TX_DN(0)   I213 @T6G_MB_LIB.T6G(SCH_1):PAGE49
  AF40 GMI_CPU1_G0_CPU0_G2_TX_DP<15> @T6G_MB_LIB.T6G(SCH_1):GMI_CPU1_G0_CPU0_G2_TX_DP(15)   I213 @T6G_MB_LIB.T6G(SCH_1):PAGE49
  AD40 GMI_CPU1_G0_CPU0_G2_TX_DP<14> @T6G_MB_LIB.T6G(SCH_1):GMI_CPU1_G0_CPU0_G2_TX_DP(14)   I213 @T6G_MB_LIB.T6G(SCH_1):PAGE49
  AB40 GMI_CPU1_G0_CPU0_G2_TX_DP<13> @T6G_MB_LIB.T6G(SCH_1):GMI_CPU1_G0_CPU0_G2_TX_DP(13)   I213 @T6G_MB_LIB.T6G(SCH_1):PAGE49
  AG43 GMI_CPU1_G0_CPU0_G2_TX_DP<12> @T6G_MB_LIB.T6G(SCH_1):GMI_CPU1_G0_CPU0_G2_TX_DP(12)   I213 @T6G_MB_LIB.T6G(SCH_1):PAGE49
  AA43 GMI_CPU1_G0_CPU0_G2_TX_DP<11> @T6G_MB_LIB.T6G(SCH_1):GMI_CPU1_G0_CPU0_G2_TX_DP(11)   I213 @T6G_MB_LIB.T6G(SCH_1):PAGE49
  AC43 GMI_CPU1_G0_CPU0_G2_TX_DP<10> @T6G_MB_LIB.T6G(SCH_1):GMI_CPU1_G0_CPU0_G2_TX_DP(10)   I213 @T6G_MB_LIB.T6G(SCH_1):PAGE49
  AE43 GMI_CPU1_G0_CPU0_G2_TX_DP<9> @T6G_MB_LIB.T6G(SCH_1):GMI_CPU1_G0_CPU0_G2_TX_DP(9)   I213 @T6G_MB_LIB.T6G(SCH_1):PAGE49
  AG46 GMI_CPU1_G0_CPU0_G2_TX_DP<8> @T6G_MB_LIB.T6G(SCH_1):GMI_CPU1_G0_CPU0_G2_TX_DP(8)   I213 @T6G_MB_LIB.T6G(SCH_1):PAGE49
  AC46 GMI_CPU1_G0_CPU0_G2_TX_DP<7> @T6G_MB_LIB.T6G(SCH_1):GMI_CPU1_G0_CPU0_G2_TX_DP(7)   I213 @T6G_MB_LIB.T6G(SCH_1):PAGE49
  AE46 GMI_CPU1_G0_CPU0_G2_TX_DP<6> @T6G_MB_LIB.T6G(SCH_1):GMI_CPU1_G0_CPU0_G2_TX_DP(6)   I213 @T6G_MB_LIB.T6G(SCH_1):PAGE49
  AG49 GMI_CPU1_G0_CPU0_G2_TX_DP<5> @T6G_MB_LIB.T6G(SCH_1):GMI_CPU1_G0_CPU0_G2_TX_DP(5)   I213 @T6G_MB_LIB.T6G(SCH_1):PAGE49
  AC49 GMI_CPU1_G0_CPU0_G2_TX_DP<4> @T6G_MB_LIB.T6G(SCH_1):GMI_CPU1_G0_CPU0_G2_TX_DP(4)   I213 @T6G_MB_LIB.T6G(SCH_1):PAGE49
  AE49 GMI_CPU1_G0_CPU0_G2_TX_DP<3> @T6G_MB_LIB.T6G(SCH_1):GMI_CPU1_G0_CPU0_G2_TX_DP(3)   I213 @T6G_MB_LIB.T6G(SCH_1):PAGE49
  AG52 GMI_CPU1_G0_CPU0_G2_TX_DP<2> @T6G_MB_LIB.T6G(SCH_1):GMI_CPU1_G0_CPU0_G2_TX_DP(2)   I213 @T6G_MB_LIB.T6G(SCH_1):PAGE49
  AC52 GMI_CPU1_G0_CPU0_G2_TX_DP<1> @T6G_MB_LIB.T6G(SCH_1):GMI_CPU1_G0_CPU0_G2_TX_DP(1)   I213 @T6G_MB_LIB.T6G(SCH_1):PAGE49
  AE52 GMI_CPU1_G0_CPU0_G2_TX_DP<0> @T6G_MB_LIB.T6G(SCH_1):GMI_CPU1_G0_CPU0_G2_TX_DP(0)   I213 @T6G_MB_LIB.T6G(SCH_1):PAGE49
  AL52 P5E_CPU1_G1_TX_DP<15> @T6G_MB_LIB.T6G(SCH_1):P5E_CPU1_G1_TX_DP(15)   I214 @T6G_MB_LIB.T6G(SCH_1):PAGE49
  AJ52 P5E_CPU1_G1_TX_DP<14> @T6G_MB_LIB.T6G(SCH_1):P5E_CPU1_G1_TX_DP(14)   I214 @T6G_MB_LIB.T6G(SCH_1):PAGE49
  AN52 P5E_CPU1_G1_TX_DP<13> @T6G_MB_LIB.T6G(SCH_1):P5E_CPU1_G1_TX_DP(13)   I214 @T6G_MB_LIB.T6G(SCH_1):PAGE49
  AL49 P5E_CPU1_G1_TX_DP<12> @T6G_MB_LIB.T6G(SCH_1):P5E_CPU1_G1_TX_DP(12)   I214 @T6G_MB_LIB.T6G(SCH_1):PAGE49
  AJ49 P5E_CPU1_G1_TX_DP<11> @T6G_MB_LIB.T6G(SCH_1):P5E_CPU1_G1_TX_DP(11)   I214 @T6G_MB_LIB.T6G(SCH_1):PAGE49
  AN49 P5E_CPU1_G1_TX_DP<10> @T6G_MB_LIB.T6G(SCH_1):P5E_CPU1_G1_TX_DP(10)   I214 @T6G_MB_LIB.T6G(SCH_1):PAGE49
  AL46 P5E_CPU1_G1_TX_DP<9> @T6G_MB_LIB.T6G(SCH_1):P5E_CPU1_G1_TX_DP(9)   I214 @T6G_MB_LIB.T6G(SCH_1):PAGE49
  AJ46 P5E_CPU1_G1_TX_DP<8> @T6G_MB_LIB.T6G(SCH_1):P5E_CPU1_G1_TX_DP(8)   I214 @T6G_MB_LIB.T6G(SCH_1):PAGE49
  AL53 P5E_CPU1_G1_TX_DN<15> @T6G_MB_LIB.T6G(SCH_1):P5E_CPU1_G1_TX_DN(15)   I214 @T6G_MB_LIB.T6G(SCH_1):PAGE49
  AJ53 P5E_CPU1_G1_TX_DN<14> @T6G_MB_LIB.T6G(SCH_1):P5E_CPU1_G1_TX_DN(14)   I214 @T6G_MB_LIB.T6G(SCH_1):PAGE49
  AN53 P5E_CPU1_G1_TX_DN<13> @T6G_MB_LIB.T6G(SCH_1):P5E_CPU1_G1_TX_DN(13)   I214 @T6G_MB_LIB.T6G(SCH_1):PAGE49
  AL50 P5E_CPU1_G1_TX_DN<12> @T6G_MB_LIB.T6G(SCH_1):P5E_CPU1_G1_TX_DN(12)   I214 @T6G_MB_LIB.T6G(SCH_1):PAGE49
  AJ50 P5E_CPU1_G1_TX_DN<11> @T6G_MB_LIB.T6G(SCH_1):P5E_CPU1_G1_TX_DN(11)   I214 @T6G_MB_LIB.T6G(SCH_1):PAGE49
  AN50 P5E_CPU1_G1_TX_DN<10> @T6G_MB_LIB.T6G(SCH_1):P5E_CPU1_G1_TX_DN(10)   I214 @T6G_MB_LIB.T6G(SCH_1):PAGE49
  AL47 P5E_CPU1_G1_TX_DN<9> @T6G_MB_LIB.T6G(SCH_1):P5E_CPU1_G1_TX_DN(9)   I214 @T6G_MB_LIB.T6G(SCH_1):PAGE49
  AJ47 P5E_CPU1_G1_TX_DN<8> @T6G_MB_LIB.T6G(SCH_1):P5E_CPU1_G1_TX_DN(8)   I214 @T6G_MB_LIB.T6G(SCH_1):PAGE49
   U53 P5E_CPU1_G1_RX_DP<15> @T6G_MB_LIB.T6G(SCH_1):P5E_CPU1_G1_RX_DP(15)   I214 @T6G_MB_LIB.T6G(SCH_1):PAGE49
   R53 P5E_CPU1_G1_RX_DP<14> @T6G_MB_LIB.T6G(SCH_1):P5E_CPU1_G1_RX_DP(14)   I214 @T6G_MB_LIB.T6G(SCH_1):PAGE49
   W53 P5E_CPU1_G1_RX_DP<13> @T6G_MB_LIB.T6G(SCH_1):P5E_CPU1_G1_RX_DP(13)   I214 @T6G_MB_LIB.T6G(SCH_1):PAGE49
   U50 P5E_CPU1_G1_RX_DP<12> @T6G_MB_LIB.T6G(SCH_1):P5E_CPU1_G1_RX_DP(12)   I214 @T6G_MB_LIB.T6G(SCH_1):PAGE49
   R50 P5E_CPU1_G1_RX_DP<11> @T6G_MB_LIB.T6G(SCH_1):P5E_CPU1_G1_RX_DP(11)   I214 @T6G_MB_LIB.T6G(SCH_1):PAGE49
   N50 P5E_CPU1_G1_RX_DP<10> @T6G_MB_LIB.T6G(SCH_1):P5E_CPU1_G1_RX_DP(10)   I214 @T6G_MB_LIB.T6G(SCH_1):PAGE49
   W50 P5E_CPU1_G1_RX_DP<9> @T6G_MB_LIB.T6G(SCH_1):P5E_CPU1_G1_RX_DP(9)   I214 @T6G_MB_LIB.T6G(SCH_1):PAGE49
   R47 P5E_CPU1_G1_RX_DP<8> @T6G_MB_LIB.T6G(SCH_1):P5E_CPU1_G1_RX_DP(8)   I214 @T6G_MB_LIB.T6G(SCH_1):PAGE49
   U52 P5E_CPU1_G1_RX_DN<15> @T6G_MB_LIB.T6G(SCH_1):P5E_CPU1_G1_RX_DN(15)   I214 @T6G_MB_LIB.T6G(SCH_1):PAGE49
   R52 P5E_CPU1_G1_RX_DN<14> @T6G_MB_LIB.T6G(SCH_1):P5E_CPU1_G1_RX_DN(14)   I214 @T6G_MB_LIB.T6G(SCH_1):PAGE49
   W52 P5E_CPU1_G1_RX_DN<13> @T6G_MB_LIB.T6G(SCH_1):P5E_CPU1_G1_RX_DN(13)   I214 @T6G_MB_LIB.T6G(SCH_1):PAGE49
   U49 P5E_CPU1_G1_RX_DN<12> @T6G_MB_LIB.T6G(SCH_1):P5E_CPU1_G1_RX_DN(12)   I214 @T6G_MB_LIB.T6G(SCH_1):PAGE49
   R49 P5E_CPU1_G1_RX_DN<11> @T6G_MB_LIB.T6G(SCH_1):P5E_CPU1_G1_RX_DN(11)   I214 @T6G_MB_LIB.T6G(SCH_1):PAGE49
   N49 P5E_CPU1_G1_RX_DN<10> @T6G_MB_LIB.T6G(SCH_1):P5E_CPU1_G1_RX_DN(10)   I214 @T6G_MB_LIB.T6G(SCH_1):PAGE49
   W49 P5E_CPU1_G1_RX_DN<9> @T6G_MB_LIB.T6G(SCH_1):P5E_CPU1_G1_RX_DN(9)   I214 @T6G_MB_LIB.T6G(SCH_1):PAGE49
   R46 P5E_CPU1_G1_RX_DN<8> @T6G_MB_LIB.T6G(SCH_1):P5E_CPU1_G1_RX_DN(8)   I214 @T6G_MB_LIB.T6G(SCH_1):PAGE49
  AP40 P5E_CPU1_G1_TX_DP<0> @T6G_MB_LIB.T6G(SCH_1):P5E_CPU1_G1_TX_DP(0)   I214 @T6G_MB_LIB.T6G(SCH_1):PAGE49
  AM40 P5E_CPU1_G1_TX_DP<1> @T6G_MB_LIB.T6G(SCH_1):P5E_CPU1_G1_TX_DP(1)   I214 @T6G_MB_LIB.T6G(SCH_1):PAGE49
  AH40 P5E_CPU1_G1_TX_DP<2> @T6G_MB_LIB.T6G(SCH_1):P5E_CPU1_G1_TX_DP(2)   I214 @T6G_MB_LIB.T6G(SCH_1):PAGE49
  AP41 P5E_CPU1_G1_TX_DN<0> @T6G_MB_LIB.T6G(SCH_1):P5E_CPU1_G1_TX_DN(0)   I214 @T6G_MB_LIB.T6G(SCH_1):PAGE49
   V41 P5E_CPU1_G1_RX_DP<0> @T6G_MB_LIB.T6G(SCH_1):P5E_CPU1_G1_RX_DP(0)   I214 @T6G_MB_LIB.T6G(SCH_1):PAGE49
  AK40 P5E_CPU1_G1_TX_DP<3> @T6G_MB_LIB.T6G(SCH_1):P5E_CPU1_G1_TX_DP(3)   I214 @T6G_MB_LIB.T6G(SCH_1):PAGE49
  AM41 P5E_CPU1_G1_TX_DN<1> @T6G_MB_LIB.T6G(SCH_1):P5E_CPU1_G1_TX_DN(1)   I214 @T6G_MB_LIB.T6G(SCH_1):PAGE49
   T41 P5E_CPU1_G1_RX_DP<1> @T6G_MB_LIB.T6G(SCH_1):P5E_CPU1_G1_RX_DP(1)   I214 @T6G_MB_LIB.T6G(SCH_1):PAGE49
  AN43 P5E_CPU1_G1_TX_DP<4> @T6G_MB_LIB.T6G(SCH_1):P5E_CPU1_G1_TX_DP(4)   I214 @T6G_MB_LIB.T6G(SCH_1):PAGE49
  AH41 P5E_CPU1_G1_TX_DN<2> @T6G_MB_LIB.T6G(SCH_1):P5E_CPU1_G1_TX_DN(2)   I214 @T6G_MB_LIB.T6G(SCH_1):PAGE49
   P41 P5E_CPU1_G1_RX_DP<2> @T6G_MB_LIB.T6G(SCH_1):P5E_CPU1_G1_RX_DP(2)   I214 @T6G_MB_LIB.T6G(SCH_1):PAGE49
   V40 P5E_CPU1_G1_RX_DN<0> @T6G_MB_LIB.T6G(SCH_1):P5E_CPU1_G1_RX_DN(0)   I214 @T6G_MB_LIB.T6G(SCH_1):PAGE49
  AJ43 P5E_CPU1_G1_TX_DP<5> @T6G_MB_LIB.T6G(SCH_1):P5E_CPU1_G1_TX_DP(5)   I214 @T6G_MB_LIB.T6G(SCH_1):PAGE49
  AK41 P5E_CPU1_G1_TX_DN<3> @T6G_MB_LIB.T6G(SCH_1):P5E_CPU1_G1_TX_DN(3)   I214 @T6G_MB_LIB.T6G(SCH_1):PAGE49
   U44 P5E_CPU1_G1_RX_DP<3> @T6G_MB_LIB.T6G(SCH_1):P5E_CPU1_G1_RX_DP(3)   I214 @T6G_MB_LIB.T6G(SCH_1):PAGE49
   T40 P5E_CPU1_G1_RX_DN<1> @T6G_MB_LIB.T6G(SCH_1):P5E_CPU1_G1_RX_DN(1)   I214 @T6G_MB_LIB.T6G(SCH_1):PAGE49
  AL43 P5E_CPU1_G1_TX_DP<6> @T6G_MB_LIB.T6G(SCH_1):P5E_CPU1_G1_TX_DP(6)   I214 @T6G_MB_LIB.T6G(SCH_1):PAGE49
  AN44 P5E_CPU1_G1_TX_DN<4> @T6G_MB_LIB.T6G(SCH_1):P5E_CPU1_G1_TX_DN(4)   I214 @T6G_MB_LIB.T6G(SCH_1):PAGE49
   N44 P5E_CPU1_G1_RX_DP<4> @T6G_MB_LIB.T6G(SCH_1):P5E_CPU1_G1_RX_DP(4)   I214 @T6G_MB_LIB.T6G(SCH_1):PAGE49
   P40 P5E_CPU1_G1_RX_DN<2> @T6G_MB_LIB.T6G(SCH_1):P5E_CPU1_G1_RX_DN(2)   I214 @T6G_MB_LIB.T6G(SCH_1):PAGE49
  AN46 P5E_CPU1_G1_TX_DP<7> @T6G_MB_LIB.T6G(SCH_1):P5E_CPU1_G1_TX_DP(7)   I214 @T6G_MB_LIB.T6G(SCH_1):PAGE49
  AJ44 P5E_CPU1_G1_TX_DN<5> @T6G_MB_LIB.T6G(SCH_1):P5E_CPU1_G1_TX_DN(5)   I214 @T6G_MB_LIB.T6G(SCH_1):PAGE49
   R44 P5E_CPU1_G1_RX_DP<5> @T6G_MB_LIB.T6G(SCH_1):P5E_CPU1_G1_RX_DP(5)   I214 @T6G_MB_LIB.T6G(SCH_1):PAGE49
   U43 P5E_CPU1_G1_RX_DN<3> @T6G_MB_LIB.T6G(SCH_1):P5E_CPU1_G1_RX_DN(3)   I214 @T6G_MB_LIB.T6G(SCH_1):PAGE49
  AL44 P5E_CPU1_G1_TX_DN<6> @T6G_MB_LIB.T6G(SCH_1):P5E_CPU1_G1_TX_DN(6)   I214 @T6G_MB_LIB.T6G(SCH_1):PAGE49
   U47 P5E_CPU1_G1_RX_DP<6> @T6G_MB_LIB.T6G(SCH_1):P5E_CPU1_G1_RX_DP(6)   I214 @T6G_MB_LIB.T6G(SCH_1):PAGE49
   N43 P5E_CPU1_G1_RX_DN<4> @T6G_MB_LIB.T6G(SCH_1):P5E_CPU1_G1_RX_DN(4)   I214 @T6G_MB_LIB.T6G(SCH_1):PAGE49
  AN47 P5E_CPU1_G1_TX_DN<7> @T6G_MB_LIB.T6G(SCH_1):P5E_CPU1_G1_TX_DN(7)   I214 @T6G_MB_LIB.T6G(SCH_1):PAGE49
   N47 P5E_CPU1_G1_RX_DP<7> @T6G_MB_LIB.T6G(SCH_1):P5E_CPU1_G1_RX_DP(7)   I214 @T6G_MB_LIB.T6G(SCH_1):PAGE49
   R43 P5E_CPU1_G1_RX_DN<5> @T6G_MB_LIB.T6G(SCH_1):P5E_CPU1_G1_RX_DN(5)   I214 @T6G_MB_LIB.T6G(SCH_1):PAGE49
   U46 P5E_CPU1_G1_RX_DN<6> @T6G_MB_LIB.T6G(SCH_1):P5E_CPU1_G1_RX_DN(6)   I214 @T6G_MB_LIB.T6G(SCH_1):PAGE49
   N46 P5E_CPU1_G1_RX_DN<7> @T6G_MB_LIB.T6G(SCH_1):P5E_CPU1_G1_RX_DN(7)   I214 @T6G_MB_LIB.T6G(SCH_1):PAGE49
   G29 GMI_CPU1_G2_CPU0_G0_TX_DP<7> @T6G_MB_LIB.T6G(SCH_1):GMI_CPU1_G2_CPU0_G0_TX_DP(7)   I143 @T6G_MB_LIB.T6G(SCH_1):PAGE50
   G30 GMI_CPU1_G2_CPU0_G0_TX_DN<7> @T6G_MB_LIB.T6G(SCH_1):GMI_CPU1_G2_CPU0_G0_TX_DN(7)   I143 @T6G_MB_LIB.T6G(SCH_1):PAGE50
   J32 GMI_CPU1_G2_CPU0_G0_TX_DP<5> @T6G_MB_LIB.T6G(SCH_1):GMI_CPU1_G2_CPU0_G0_TX_DP(5)   I143 @T6G_MB_LIB.T6G(SCH_1):PAGE50
   J33 GMI_CPU1_G2_CPU0_G0_TX_DN<5> @T6G_MB_LIB.T6G(SCH_1):GMI_CPU1_G2_CPU0_G0_TX_DN(5)   I143 @T6G_MB_LIB.T6G(SCH_1):PAGE50
   L32 GMI_CPU1_G2_CPU0_G0_TX_DP<3> @T6G_MB_LIB.T6G(SCH_1):GMI_CPU1_G2_CPU0_G0_TX_DP(3)   I143 @T6G_MB_LIB.T6G(SCH_1):PAGE50
   L33 GMI_CPU1_G2_CPU0_G0_TX_DN<3> @T6G_MB_LIB.T6G(SCH_1):GMI_CPU1_G2_CPU0_G0_TX_DN(3)   I143 @T6G_MB_LIB.T6G(SCH_1):PAGE50
   K35 GMI_CPU1_G2_CPU0_G0_TX_DP<1> @T6G_MB_LIB.T6G(SCH_1):GMI_CPU1_G2_CPU0_G0_TX_DP(1)   I143 @T6G_MB_LIB.T6G(SCH_1):PAGE50
   K36 GMI_CPU1_G2_CPU0_G0_TX_DN<1> @T6G_MB_LIB.T6G(SCH_1):GMI_CPU1_G2_CPU0_G0_TX_DN(1)   I143 @T6G_MB_LIB.T6G(SCH_1):PAGE50
   L29 GMI_CPU1_G2_CPU0_G0_TX_DP<6> @T6G_MB_LIB.T6G(SCH_1):GMI_CPU1_G2_CPU0_G0_TX_DP(6)   I143 @T6G_MB_LIB.T6G(SCH_1):PAGE50
   L30 GMI_CPU1_G2_CPU0_G0_TX_DN<6> @T6G_MB_LIB.T6G(SCH_1):GMI_CPU1_G2_CPU0_G0_TX_DN(6)   I143 @T6G_MB_LIB.T6G(SCH_1):PAGE50
   G32 GMI_CPU1_G2_CPU0_G0_TX_DP<4> @T6G_MB_LIB.T6G(SCH_1):GMI_CPU1_G2_CPU0_G0_TX_DP(4)   I143 @T6G_MB_LIB.T6G(SCH_1):PAGE50
   G33 GMI_CPU1_G2_CPU0_G0_TX_DN<4> @T6G_MB_LIB.T6G(SCH_1):GMI_CPU1_G2_CPU0_G0_TX_DN(4)   I143 @T6G_MB_LIB.T6G(SCH_1):PAGE50
   H35 GMI_CPU1_G2_CPU0_G0_TX_DP<2> @T6G_MB_LIB.T6G(SCH_1):GMI_CPU1_G2_CPU0_G0_TX_DP(2)   I143 @T6G_MB_LIB.T6G(SCH_1):PAGE50
   H36 GMI_CPU1_G2_CPU0_G0_TX_DN<2> @T6G_MB_LIB.T6G(SCH_1):GMI_CPU1_G2_CPU0_G0_TX_DN(2)   I143 @T6G_MB_LIB.T6G(SCH_1):PAGE50
   M35 GMI_CPU1_G2_CPU0_G0_TX_DP<0> @T6G_MB_LIB.T6G(SCH_1):GMI_CPU1_G2_CPU0_G0_TX_DP(0)   I143 @T6G_MB_LIB.T6G(SCH_1):PAGE50
   M36 GMI_CPU1_G2_CPU0_G0_TX_DN<0> @T6G_MB_LIB.T6G(SCH_1):GMI_CPU1_G2_CPU0_G0_TX_DN(0)   I143 @T6G_MB_LIB.T6G(SCH_1):PAGE50
  AG30 GMI_CPU0_G0_CPU1_G2_TX_DP<7> @T6G_MB_LIB.T6G(SCH_1):GMI_CPU0_G0_CPU1_G2_TX_DP(7)   I143 @T6G_MB_LIB.T6G(SCH_1):PAGE50
  AG29 GMI_CPU0_G0_CPU1_G2_TX_DN<7> @T6G_MB_LIB.T6G(SCH_1):GMI_CPU0_G0_CPU1_G2_TX_DN(7)   I143 @T6G_MB_LIB.T6G(SCH_1):PAGE50
  AC33 GMI_CPU0_G0_CPU1_G2_TX_DP<5> @T6G_MB_LIB.T6G(SCH_1):GMI_CPU0_G0_CPU1_G2_TX_DP(5)   I143 @T6G_MB_LIB.T6G(SCH_1):PAGE50
  AC32 GMI_CPU0_G0_CPU1_G2_TX_DN<5> @T6G_MB_LIB.T6G(SCH_1):GMI_CPU0_G0_CPU1_G2_TX_DN(5)   I143 @T6G_MB_LIB.T6G(SCH_1):PAGE50
  AG33 GMI_CPU0_G0_CPU1_G2_TX_DP<3> @T6G_MB_LIB.T6G(SCH_1):GMI_CPU0_G0_CPU1_G2_TX_DP(3)   I143 @T6G_MB_LIB.T6G(SCH_1):PAGE50
  AG32 GMI_CPU0_G0_CPU1_G2_TX_DN<3> @T6G_MB_LIB.T6G(SCH_1):GMI_CPU0_G0_CPU1_G2_TX_DN(3)   I143 @T6G_MB_LIB.T6G(SCH_1):PAGE50
  AD36 GMI_CPU0_G0_CPU1_G2_TX_DP<1> @T6G_MB_LIB.T6G(SCH_1):GMI_CPU0_G0_CPU1_G2_TX_DP(1)   I143 @T6G_MB_LIB.T6G(SCH_1):PAGE50
  AD35 GMI_CPU0_G0_CPU1_G2_TX_DN<1> @T6G_MB_LIB.T6G(SCH_1):GMI_CPU0_G0_CPU1_G2_TX_DN(1)   I143 @T6G_MB_LIB.T6G(SCH_1):PAGE50
  AE33 GMI_CPU0_G0_CPU1_G2_TX_DP<6> @T6G_MB_LIB.T6G(SCH_1):GMI_CPU0_G0_CPU1_G2_TX_DP(6)   I143 @T6G_MB_LIB.T6G(SCH_1):PAGE50
  AE32 GMI_CPU0_G0_CPU1_G2_TX_DN<6> @T6G_MB_LIB.T6G(SCH_1):GMI_CPU0_G0_CPU1_G2_TX_DN(6)   I143 @T6G_MB_LIB.T6G(SCH_1):PAGE50
  AA33 GMI_CPU0_G0_CPU1_G2_TX_DP<4> @T6G_MB_LIB.T6G(SCH_1):GMI_CPU0_G0_CPU1_G2_TX_DP(4)   I143 @T6G_MB_LIB.T6G(SCH_1):PAGE50
  AA32 GMI_CPU0_G0_CPU1_G2_TX_DN<4> @T6G_MB_LIB.T6G(SCH_1):GMI_CPU0_G0_CPU1_G2_TX_DN(4)   I143 @T6G_MB_LIB.T6G(SCH_1):PAGE50
  AB36 GMI_CPU0_G0_CPU1_G2_TX_DP<2> @T6G_MB_LIB.T6G(SCH_1):GMI_CPU0_G0_CPU1_G2_TX_DP(2)   I143 @T6G_MB_LIB.T6G(SCH_1):PAGE50
  AB35 GMI_CPU0_G0_CPU1_G2_TX_DN<2> @T6G_MB_LIB.T6G(SCH_1):GMI_CPU0_G0_CPU1_G2_TX_DN(2)   I143 @T6G_MB_LIB.T6G(SCH_1):PAGE50
  AF36 GMI_CPU0_G0_CPU1_G2_TX_DP<0> @T6G_MB_LIB.T6G(SCH_1):GMI_CPU0_G0_CPU1_G2_TX_DP(0)   I143 @T6G_MB_LIB.T6G(SCH_1):PAGE50
  AF35 GMI_CPU0_G0_CPU1_G2_TX_DN<0> @T6G_MB_LIB.T6G(SCH_1):GMI_CPU0_G0_CPU1_G2_TX_DN(0)   I143 @T6G_MB_LIB.T6G(SCH_1):PAGE50
   J23 GMI_CPU1_G2_CPU0_G0_TX_DP<14> @T6G_MB_LIB.T6G(SCH_1):GMI_CPU1_G2_CPU0_G0_TX_DP(14)   I143 @T6G_MB_LIB.T6G(SCH_1):PAGE50
   G23 GMI_CPU1_G2_CPU0_G0_TX_DP<13> @T6G_MB_LIB.T6G(SCH_1):GMI_CPU1_G2_CPU0_G0_TX_DP(13)   I143 @T6G_MB_LIB.T6G(SCH_1):PAGE50
   N24 GMI_CPU1_G2_CPU0_G0_TX_DN<15> @T6G_MB_LIB.T6G(SCH_1):GMI_CPU1_G2_CPU0_G0_TX_DN(15)   I143 @T6G_MB_LIB.T6G(SCH_1):PAGE50
  AE24 GMI_CPU0_G0_CPU1_G2_TX_DP<15> @T6G_MB_LIB.T6G(SCH_1):GMI_CPU0_G0_CPU1_G2_TX_DP(15)   I143 @T6G_MB_LIB.T6G(SCH_1):PAGE50
   L23 GMI_CPU1_G2_CPU0_G0_TX_DP<12> @T6G_MB_LIB.T6G(SCH_1):GMI_CPU1_G2_CPU0_G0_TX_DP(12)   I143 @T6G_MB_LIB.T6G(SCH_1):PAGE50
   J24 GMI_CPU1_G2_CPU0_G0_TX_DN<14> @T6G_MB_LIB.T6G(SCH_1):GMI_CPU1_G2_CPU0_G0_TX_DN(14)   I143 @T6G_MB_LIB.T6G(SCH_1):PAGE50
  AC24 GMI_CPU0_G0_CPU1_G2_TX_DP<14> @T6G_MB_LIB.T6G(SCH_1):GMI_CPU0_G0_CPU1_G2_TX_DP(14)   I143 @T6G_MB_LIB.T6G(SCH_1):PAGE50
   J26 GMI_CPU1_G2_CPU0_G0_TX_DP<11> @T6G_MB_LIB.T6G(SCH_1):GMI_CPU1_G2_CPU0_G0_TX_DP(11)   I143 @T6G_MB_LIB.T6G(SCH_1):PAGE50
   G24 GMI_CPU1_G2_CPU0_G0_TX_DN<13> @T6G_MB_LIB.T6G(SCH_1):GMI_CPU1_G2_CPU0_G0_TX_DN(13)   I143 @T6G_MB_LIB.T6G(SCH_1):PAGE50
  AG24 GMI_CPU0_G0_CPU1_G2_TX_DP<13> @T6G_MB_LIB.T6G(SCH_1):GMI_CPU0_G0_CPU1_G2_TX_DP(13)   I143 @T6G_MB_LIB.T6G(SCH_1):PAGE50
  AE23 GMI_CPU0_G0_CPU1_G2_TX_DN<15> @T6G_MB_LIB.T6G(SCH_1):GMI_CPU0_G0_CPU1_G2_TX_DN(15)   I143 @T6G_MB_LIB.T6G(SCH_1):PAGE50
   G26 GMI_CPU1_G2_CPU0_G0_TX_DP<10> @T6G_MB_LIB.T6G(SCH_1):GMI_CPU1_G2_CPU0_G0_TX_DP(10)   I143 @T6G_MB_LIB.T6G(SCH_1):PAGE50
   L24 GMI_CPU1_G2_CPU0_G0_TX_DN<12> @T6G_MB_LIB.T6G(SCH_1):GMI_CPU1_G2_CPU0_G0_TX_DN(12)   I143 @T6G_MB_LIB.T6G(SCH_1):PAGE50
  AE27 GMI_CPU0_G0_CPU1_G2_TX_DP<12> @T6G_MB_LIB.T6G(SCH_1):GMI_CPU0_G0_CPU1_G2_TX_DP(12)   I143 @T6G_MB_LIB.T6G(SCH_1):PAGE50
  AC23 GMI_CPU0_G0_CPU1_G2_TX_DN<14> @T6G_MB_LIB.T6G(SCH_1):GMI_CPU0_G0_CPU1_G2_TX_DN(14)   I143 @T6G_MB_LIB.T6G(SCH_1):PAGE50
   L26 GMI_CPU1_G2_CPU0_G0_TX_DP<9> @T6G_MB_LIB.T6G(SCH_1):GMI_CPU1_G2_CPU0_G0_TX_DP(9)   I143 @T6G_MB_LIB.T6G(SCH_1):PAGE50
   J27 GMI_CPU1_G2_CPU0_G0_TX_DN<11> @T6G_MB_LIB.T6G(SCH_1):GMI_CPU1_G2_CPU0_G0_TX_DN(11)   I143 @T6G_MB_LIB.T6G(SCH_1):PAGE50
  AC27 GMI_CPU0_G0_CPU1_G2_TX_DP<11> @T6G_MB_LIB.T6G(SCH_1):GMI_CPU0_G0_CPU1_G2_TX_DP(11)   I143 @T6G_MB_LIB.T6G(SCH_1):PAGE50
  AG23 GMI_CPU0_G0_CPU1_G2_TX_DN<13> @T6G_MB_LIB.T6G(SCH_1):GMI_CPU0_G0_CPU1_G2_TX_DN(13)   I143 @T6G_MB_LIB.T6G(SCH_1):PAGE50
   J29 GMI_CPU1_G2_CPU0_G0_TX_DP<8> @T6G_MB_LIB.T6G(SCH_1):GMI_CPU1_G2_CPU0_G0_TX_DP(8)   I143 @T6G_MB_LIB.T6G(SCH_1):PAGE50
   G27 GMI_CPU1_G2_CPU0_G0_TX_DN<10> @T6G_MB_LIB.T6G(SCH_1):GMI_CPU1_G2_CPU0_G0_TX_DN(10)   I143 @T6G_MB_LIB.T6G(SCH_1):PAGE50
  AG27 GMI_CPU0_G0_CPU1_G2_TX_DP<10> @T6G_MB_LIB.T6G(SCH_1):GMI_CPU0_G0_CPU1_G2_TX_DP(10)   I143 @T6G_MB_LIB.T6G(SCH_1):PAGE50
  AE26 GMI_CPU0_G0_CPU1_G2_TX_DN<12> @T6G_MB_LIB.T6G(SCH_1):GMI_CPU0_G0_CPU1_G2_TX_DN(12)   I143 @T6G_MB_LIB.T6G(SCH_1):PAGE50
   L27 GMI_CPU1_G2_CPU0_G0_TX_DN<9> @T6G_MB_LIB.T6G(SCH_1):GMI_CPU1_G2_CPU0_G0_TX_DN(9)   I143 @T6G_MB_LIB.T6G(SCH_1):PAGE50
  AE30 GMI_CPU0_G0_CPU1_G2_TX_DP<9> @T6G_MB_LIB.T6G(SCH_1):GMI_CPU0_G0_CPU1_G2_TX_DP(9)   I143 @T6G_MB_LIB.T6G(SCH_1):PAGE50
  AC26 GMI_CPU0_G0_CPU1_G2_TX_DN<11> @T6G_MB_LIB.T6G(SCH_1):GMI_CPU0_G0_CPU1_G2_TX_DN(11)   I143 @T6G_MB_LIB.T6G(SCH_1):PAGE50
   J30 GMI_CPU1_G2_CPU0_G0_TX_DN<8> @T6G_MB_LIB.T6G(SCH_1):GMI_CPU1_G2_CPU0_G0_TX_DN(8)   I143 @T6G_MB_LIB.T6G(SCH_1):PAGE50
  AC30 GMI_CPU0_G0_CPU1_G2_TX_DP<8> @T6G_MB_LIB.T6G(SCH_1):GMI_CPU0_G0_CPU1_G2_TX_DP(8)   I143 @T6G_MB_LIB.T6G(SCH_1):PAGE50
  AG26 GMI_CPU0_G0_CPU1_G2_TX_DN<10> @T6G_MB_LIB.T6G(SCH_1):GMI_CPU0_G0_CPU1_G2_TX_DN(10)   I143 @T6G_MB_LIB.T6G(SCH_1):PAGE50
  AE29 GMI_CPU0_G0_CPU1_G2_TX_DN<9> @T6G_MB_LIB.T6G(SCH_1):GMI_CPU0_G0_CPU1_G2_TX_DN(9)   I143 @T6G_MB_LIB.T6G(SCH_1):PAGE50
  AC29 GMI_CPU0_G0_CPU1_G2_TX_DN<8> @T6G_MB_LIB.T6G(SCH_1):GMI_CPU0_G0_CPU1_G2_TX_DN(8)   I143 @T6G_MB_LIB.T6G(SCH_1):PAGE50
   N23 GMI_CPU1_G2_CPU0_G0_TX_DP<15> @T6G_MB_LIB.T6G(SCH_1):GMI_CPU1_G2_CPU0_G0_TX_DP(15)   I143 @T6G_MB_LIB.T6G(SCH_1):PAGE50
   P35 GMI_CPU1_G3_CPU0_G1_TX_DP<2> @T6G_MB_LIB.T6G(SCH_1):GMI_CPU1_G3_CPU0_G1_TX_DP(2)   I144 @T6G_MB_LIB.T6G(SCH_1):PAGE50
   R32 GMI_CPU1_G3_CPU0_G1_TX_DP<5> @T6G_MB_LIB.T6G(SCH_1):GMI_CPU1_G3_CPU0_G1_TX_DP(5)   I144 @T6G_MB_LIB.T6G(SCH_1):PAGE50
  AN26 GMI_CPU0_G1_CPU1_G3_TX_DN<10> @T6G_MB_LIB.T6G(SCH_1):GMI_CPU0_G1_CPU1_G3_TX_DN(10)   I144 @T6G_MB_LIB.T6G(SCH_1):PAGE50
   W24 GMI_CPU1_G3_CPU0_G1_TX_DN<13> @T6G_MB_LIB.T6G(SCH_1):GMI_CPU1_G3_CPU0_G1_TX_DN(13)   I144 @T6G_MB_LIB.T6G(SCH_1):PAGE50
  AK36 GMI_CPU0_G1_CPU1_G3_TX_DP<3> @T6G_MB_LIB.T6G(SCH_1):GMI_CPU0_G1_CPU1_G3_TX_DP(3)   I144 @T6G_MB_LIB.T6G(SCH_1):PAGE50
  AL24 GMI_CPU0_G1_CPU1_G3_TX_DP<15> @T6G_MB_LIB.T6G(SCH_1):GMI_CPU0_G1_CPU1_G3_TX_DP(15)   I144 @T6G_MB_LIB.T6G(SCH_1):PAGE50
   T36 GMI_CPU1_G3_CPU0_G1_TX_DN<1> @T6G_MB_LIB.T6G(SCH_1):GMI_CPU1_G3_CPU0_G1_TX_DN(1)   I144 @T6G_MB_LIB.T6G(SCH_1):PAGE50
   N33 GMI_CPU1_G3_CPU0_G1_TX_DN<4> @T6G_MB_LIB.T6G(SCH_1):GMI_CPU1_G3_CPU0_G1_TX_DN(4)   I144 @T6G_MB_LIB.T6G(SCH_1):PAGE50
   N27 GMI_CPU1_G3_CPU0_G1_TX_DN<10> @T6G_MB_LIB.T6G(SCH_1):GMI_CPU1_G3_CPU0_G1_TX_DN(10)   I144 @T6G_MB_LIB.T6G(SCH_1):PAGE50
  AP36 GMI_CPU0_G1_CPU1_G3_TX_DP<0> @T6G_MB_LIB.T6G(SCH_1):GMI_CPU0_G1_CPU1_G3_TX_DP(0)   I144 @T6G_MB_LIB.T6G(SCH_1):PAGE50
  AL30 GMI_CPU0_G1_CPU1_G3_TX_DP<9> @T6G_MB_LIB.T6G(SCH_1):GMI_CPU0_G1_CPU1_G3_TX_DP(9)   I144 @T6G_MB_LIB.T6G(SCH_1):PAGE50
  AL27 GMI_CPU0_G1_CPU1_G3_TX_DP<12> @T6G_MB_LIB.T6G(SCH_1):GMI_CPU0_G1_CPU1_G3_TX_DP(12)   I144 @T6G_MB_LIB.T6G(SCH_1):PAGE50
   U26 GMI_CPU1_G3_CPU0_G1_TX_DP<12> @T6G_MB_LIB.T6G(SCH_1):GMI_CPU1_G3_CPU0_G1_TX_DP(12)   I144 @T6G_MB_LIB.T6G(SCH_1):PAGE50
   U23 GMI_CPU1_G3_CPU0_G1_TX_DP<15> @T6G_MB_LIB.T6G(SCH_1):GMI_CPU1_G3_CPU0_G1_TX_DP(15)   I144 @T6G_MB_LIB.T6G(SCH_1):PAGE50
  AJ32 GMI_CPU0_G1_CPU1_G3_TX_DN<5> @T6G_MB_LIB.T6G(SCH_1):GMI_CPU0_G1_CPU1_G3_TX_DN(5)   I144 @T6G_MB_LIB.T6G(SCH_1):PAGE50
   W26 GMI_CPU1_G3_CPU0_G1_TX_DP<9> @T6G_MB_LIB.T6G(SCH_1):GMI_CPU1_G3_CPU0_G1_TX_DP(9)   I144 @T6G_MB_LIB.T6G(SCH_1):PAGE50
  AH35 GMI_CPU0_G1_CPU1_G3_TX_DN<2> @T6G_MB_LIB.T6G(SCH_1):GMI_CPU0_G1_CPU1_G3_TX_DN(2)   I144 @T6G_MB_LIB.T6G(SCH_1):PAGE50
   N32 GMI_CPU1_G3_CPU0_G1_TX_DP<4> @T6G_MB_LIB.T6G(SCH_1):GMI_CPU1_G3_CPU0_G1_TX_DP(4)   I144 @T6G_MB_LIB.T6G(SCH_1):PAGE50
  AN30 GMI_CPU0_G1_CPU1_G3_TX_DP<7> @T6G_MB_LIB.T6G(SCH_1):GMI_CPU0_G1_CPU1_G3_TX_DP(7)   I144 @T6G_MB_LIB.T6G(SCH_1):PAGE50
  AL26 GMI_CPU0_G1_CPU1_G3_TX_DN<12> @T6G_MB_LIB.T6G(SCH_1):GMI_CPU0_G1_CPU1_G3_TX_DN(12)   I144 @T6G_MB_LIB.T6G(SCH_1):PAGE50
  AL23 GMI_CPU0_G1_CPU1_G3_TX_DN<15> @T6G_MB_LIB.T6G(SCH_1):GMI_CPU0_G1_CPU1_G3_TX_DN(15)   I144 @T6G_MB_LIB.T6G(SCH_1):PAGE50
   T35 GMI_CPU1_G3_CPU0_G1_TX_DP<1> @T6G_MB_LIB.T6G(SCH_1):GMI_CPU1_G3_CPU0_G1_TX_DP(1)   I144 @T6G_MB_LIB.T6G(SCH_1):PAGE50
   N29 GMI_CPU1_G3_CPU0_G1_TX_DP<7> @T6G_MB_LIB.T6G(SCH_1):GMI_CPU1_G3_CPU0_G1_TX_DP(7)   I144 @T6G_MB_LIB.T6G(SCH_1):PAGE50
   U24 GMI_CPU1_G3_CPU0_G1_TX_DN<15> @T6G_MB_LIB.T6G(SCH_1):GMI_CPU1_G3_CPU0_G1_TX_DN(15)   I144 @T6G_MB_LIB.T6G(SCH_1):PAGE50
  AL29 GMI_CPU0_G1_CPU1_G3_TX_DN<9> @T6G_MB_LIB.T6G(SCH_1):GMI_CPU0_G1_CPU1_G3_TX_DN(9)   I144 @T6G_MB_LIB.T6G(SCH_1):PAGE50
   W27 GMI_CPU1_G3_CPU0_G1_TX_DN<9> @T6G_MB_LIB.T6G(SCH_1):GMI_CPU1_G3_CPU0_G1_TX_DN(9)   I144 @T6G_MB_LIB.T6G(SCH_1):PAGE50
   U27 GMI_CPU1_G3_CPU0_G1_TX_DN<12> @T6G_MB_LIB.T6G(SCH_1):GMI_CPU1_G3_CPU0_G1_TX_DN(12)   I144 @T6G_MB_LIB.T6G(SCH_1):PAGE50
  AH36 GMI_CPU0_G1_CPU1_G3_TX_DP<2> @T6G_MB_LIB.T6G(SCH_1):GMI_CPU0_G1_CPU1_G3_TX_DP(2)   I144 @T6G_MB_LIB.T6G(SCH_1):PAGE50
  AJ33 GMI_CPU0_G1_CPU1_G3_TX_DP<5> @T6G_MB_LIB.T6G(SCH_1):GMI_CPU0_G1_CPU1_G3_TX_DP(5)   I144 @T6G_MB_LIB.T6G(SCH_1):PAGE50
  AJ27 GMI_CPU0_G1_CPU1_G3_TX_DP<11> @T6G_MB_LIB.T6G(SCH_1):GMI_CPU0_G1_CPU1_G3_TX_DP(11)   I144 @T6G_MB_LIB.T6G(SCH_1):PAGE50
  AJ24 GMI_CPU0_G1_CPU1_G3_TX_DP<14> @T6G_MB_LIB.T6G(SCH_1):GMI_CPU0_G1_CPU1_G3_TX_DP(14)   I144 @T6G_MB_LIB.T6G(SCH_1):PAGE50
   V36 GMI_CPU1_G3_CPU0_G1_TX_DN<0> @T6G_MB_LIB.T6G(SCH_1):GMI_CPU1_G3_CPU0_G1_TX_DN(0)   I144 @T6G_MB_LIB.T6G(SCH_1):PAGE50
   U33 GMI_CPU1_G3_CPU0_G1_TX_DN<3> @T6G_MB_LIB.T6G(SCH_1):GMI_CPU1_G3_CPU0_G1_TX_DN(3)   I144 @T6G_MB_LIB.T6G(SCH_1):PAGE50
  AN29 GMI_CPU0_G1_CPU1_G3_TX_DN<7> @T6G_MB_LIB.T6G(SCH_1):GMI_CPU0_G1_CPU1_G3_TX_DN(7)   I144 @T6G_MB_LIB.T6G(SCH_1):PAGE50
  AJ30 GMI_CPU0_G1_CPU1_G3_TX_DP<8> @T6G_MB_LIB.T6G(SCH_1):GMI_CPU0_G1_CPU1_G3_TX_DP(8)   I144 @T6G_MB_LIB.T6G(SCH_1):PAGE50
   R26 GMI_CPU1_G3_CPU0_G1_TX_DP<11> @T6G_MB_LIB.T6G(SCH_1):GMI_CPU1_G3_CPU0_G1_TX_DP(11)   I144 @T6G_MB_LIB.T6G(SCH_1):PAGE50
   R23 GMI_CPU1_G3_CPU0_G1_TX_DP<14> @T6G_MB_LIB.T6G(SCH_1):GMI_CPU1_G3_CPU0_G1_TX_DP(14)   I144 @T6G_MB_LIB.T6G(SCH_1):PAGE50
  AM35 GMI_CPU0_G1_CPU1_G3_TX_DN<1> @T6G_MB_LIB.T6G(SCH_1):GMI_CPU0_G1_CPU1_G3_TX_DN(1)   I144 @T6G_MB_LIB.T6G(SCH_1):PAGE50
  AN32 GMI_CPU0_G1_CPU1_G3_TX_DN<4> @T6G_MB_LIB.T6G(SCH_1):GMI_CPU0_G1_CPU1_G3_TX_DN(4)   I144 @T6G_MB_LIB.T6G(SCH_1):PAGE50
   N30 GMI_CPU1_G3_CPU0_G1_TX_DN<7> @T6G_MB_LIB.T6G(SCH_1):GMI_CPU1_G3_CPU0_G1_TX_DN(7)   I144 @T6G_MB_LIB.T6G(SCH_1):PAGE50
   R29 GMI_CPU1_G3_CPU0_G1_TX_DP<8> @T6G_MB_LIB.T6G(SCH_1):GMI_CPU1_G3_CPU0_G1_TX_DP(8)   I144 @T6G_MB_LIB.T6G(SCH_1):PAGE50
  AL33 GMI_CPU0_G1_CPU1_G3_TX_DP<6> @T6G_MB_LIB.T6G(SCH_1):GMI_CPU0_G1_CPU1_G3_TX_DP(6)   I144 @T6G_MB_LIB.T6G(SCH_1):PAGE50
   U32 GMI_CPU1_G3_CPU0_G1_TX_DP<3> @T6G_MB_LIB.T6G(SCH_1):GMI_CPU1_G3_CPU0_G1_TX_DP(3)   I144 @T6G_MB_LIB.T6G(SCH_1):PAGE50
  AJ29 GMI_CPU0_G1_CPU1_G3_TX_DN<8> @T6G_MB_LIB.T6G(SCH_1):GMI_CPU0_G1_CPU1_G3_TX_DN(8)   I144 @T6G_MB_LIB.T6G(SCH_1):PAGE50
  AJ26 GMI_CPU0_G1_CPU1_G3_TX_DN<11> @T6G_MB_LIB.T6G(SCH_1):GMI_CPU0_G1_CPU1_G3_TX_DN(11)   I144 @T6G_MB_LIB.T6G(SCH_1):PAGE50
  AJ23 GMI_CPU0_G1_CPU1_G3_TX_DN<14> @T6G_MB_LIB.T6G(SCH_1):GMI_CPU0_G1_CPU1_G3_TX_DN(14)   I144 @T6G_MB_LIB.T6G(SCH_1):PAGE50
   V35 GMI_CPU1_G3_CPU0_G1_TX_DP<0> @T6G_MB_LIB.T6G(SCH_1):GMI_CPU1_G3_CPU0_G1_TX_DP(0)   I144 @T6G_MB_LIB.T6G(SCH_1):PAGE50
   U29 GMI_CPU1_G3_CPU0_G1_TX_DP<6> @T6G_MB_LIB.T6G(SCH_1):GMI_CPU1_G3_CPU0_G1_TX_DP(6)   I144 @T6G_MB_LIB.T6G(SCH_1):PAGE50
   R24 GMI_CPU1_G3_CPU0_G1_TX_DN<14> @T6G_MB_LIB.T6G(SCH_1):GMI_CPU1_G3_CPU0_G1_TX_DN(14)   I144 @T6G_MB_LIB.T6G(SCH_1):PAGE50
  AN33 GMI_CPU0_G1_CPU1_G3_TX_DP<4> @T6G_MB_LIB.T6G(SCH_1):GMI_CPU0_G1_CPU1_G3_TX_DP(4)   I144 @T6G_MB_LIB.T6G(SCH_1):PAGE50
   P36 GMI_CPU1_G3_CPU0_G1_TX_DN<2> @T6G_MB_LIB.T6G(SCH_1):GMI_CPU1_G3_CPU0_G1_TX_DN(2)   I144 @T6G_MB_LIB.T6G(SCH_1):PAGE50
   R33 GMI_CPU1_G3_CPU0_G1_TX_DN<5> @T6G_MB_LIB.T6G(SCH_1):GMI_CPU1_G3_CPU0_G1_TX_DN(5)   I144 @T6G_MB_LIB.T6G(SCH_1):PAGE50
   R30 GMI_CPU1_G3_CPU0_G1_TX_DN<8> @T6G_MB_LIB.T6G(SCH_1):GMI_CPU1_G3_CPU0_G1_TX_DN(8)   I144 @T6G_MB_LIB.T6G(SCH_1):PAGE50
   R27 GMI_CPU1_G3_CPU0_G1_TX_DN<11> @T6G_MB_LIB.T6G(SCH_1):GMI_CPU1_G3_CPU0_G1_TX_DN(11)   I144 @T6G_MB_LIB.T6G(SCH_1):PAGE50
  AM36 GMI_CPU0_G1_CPU1_G3_TX_DP<1> @T6G_MB_LIB.T6G(SCH_1):GMI_CPU0_G1_CPU1_G3_TX_DP(1)   I144 @T6G_MB_LIB.T6G(SCH_1):PAGE50
  AN27 GMI_CPU0_G1_CPU1_G3_TX_DP<10> @T6G_MB_LIB.T6G(SCH_1):GMI_CPU0_G1_CPU1_G3_TX_DP(10)   I144 @T6G_MB_LIB.T6G(SCH_1):PAGE50
  AN24 GMI_CPU0_G1_CPU1_G3_TX_DP<13> @T6G_MB_LIB.T6G(SCH_1):GMI_CPU0_G1_CPU1_G3_TX_DP(13)   I144 @T6G_MB_LIB.T6G(SCH_1):PAGE50
   W23 GMI_CPU1_G3_CPU0_G1_TX_DP<13> @T6G_MB_LIB.T6G(SCH_1):GMI_CPU1_G3_CPU0_G1_TX_DP(13)   I144 @T6G_MB_LIB.T6G(SCH_1):PAGE50
  AL32 GMI_CPU0_G1_CPU1_G3_TX_DN<6> @T6G_MB_LIB.T6G(SCH_1):GMI_CPU0_G1_CPU1_G3_TX_DN(6)   I144 @T6G_MB_LIB.T6G(SCH_1):PAGE50
   N26 GMI_CPU1_G3_CPU0_G1_TX_DP<10> @T6G_MB_LIB.T6G(SCH_1):GMI_CPU1_G3_CPU0_G1_TX_DP(10)   I144 @T6G_MB_LIB.T6G(SCH_1):PAGE50
  AP35 GMI_CPU0_G1_CPU1_G3_TX_DN<0> @T6G_MB_LIB.T6G(SCH_1):GMI_CPU0_G1_CPU1_G3_TX_DN(0)   I144 @T6G_MB_LIB.T6G(SCH_1):PAGE50
  AK35 GMI_CPU0_G1_CPU1_G3_TX_DN<3> @T6G_MB_LIB.T6G(SCH_1):GMI_CPU0_G1_CPU1_G3_TX_DN(3)   I144 @T6G_MB_LIB.T6G(SCH_1):PAGE50
   U30 GMI_CPU1_G3_CPU0_G1_TX_DN<6> @T6G_MB_LIB.T6G(SCH_1):GMI_CPU1_G3_CPU0_G1_TX_DN(6)   I144 @T6G_MB_LIB.T6G(SCH_1):PAGE50
  AN23 GMI_CPU0_G1_CPU1_G3_TX_DN<13> @T6G_MB_LIB.T6G(SCH_1):GMI_CPU0_G1_CPU1_G3_TX_DN(13)   I144 @T6G_MB_LIB.T6G(SCH_1):PAGE50
  BW53 P5E_CPU1_P0_RX_DN<0> @T6G_MB_LIB.T6G(SCH_1):P5E_CPU1_P0_RX_DN(0)   I147 @T6G_MB_LIB.T6G(SCH_1):PAGE51
  BW47 P5E_CPU1_P0_RX_DN<6> @T6G_MB_LIB.T6G(SCH_1):P5E_CPU1_P0_RX_DN(6)   I147 @T6G_MB_LIB.T6G(SCH_1):PAGE51
  BW50 P5E_CPU1_P0_RX_DN<3> @T6G_MB_LIB.T6G(SCH_1):P5E_CPU1_P0_RX_DN(3)   I147 @T6G_MB_LIB.T6G(SCH_1):PAGE51
  CN49 P5E_CPU1_P0_TX_DN<3> @T6G_MB_LIB.T6G(SCH_1):P5E_CPU1_P0_TX_DN(3)   I147 @T6G_MB_LIB.T6G(SCH_1):PAGE51
  CN52 P5E_CPU1_P0_TX_DN<0> @T6G_MB_LIB.T6G(SCH_1):P5E_CPU1_P0_TX_DN(0)   I147 @T6G_MB_LIB.T6G(SCH_1):PAGE51
  CA52 P5E_CPU1_P0_RX_DP<1> @T6G_MB_LIB.T6G(SCH_1):P5E_CPU1_P0_RX_DP(1)   I147 @T6G_MB_LIB.T6G(SCH_1):PAGE51
  CL49 P5E_CPU1_P0_TX_DN<6> @T6G_MB_LIB.T6G(SCH_1):P5E_CPU1_P0_TX_DN(6)   I147 @T6G_MB_LIB.T6G(SCH_1):PAGE51
  CA46 P5E_CPU1_P0_RX_DP<7> @T6G_MB_LIB.T6G(SCH_1):P5E_CPU1_P0_RX_DP(7)   I147 @T6G_MB_LIB.T6G(SCH_1):PAGE51
  CA49 P5E_CPU1_P0_RX_DP<4> @T6G_MB_LIB.T6G(SCH_1):P5E_CPU1_P0_RX_DP(4)   I147 @T6G_MB_LIB.T6G(SCH_1):PAGE51
  CR50 P5E_CPU1_P0_TX_DP<4> @T6G_MB_LIB.T6G(SCH_1):P5E_CPU1_P0_TX_DP(4)   I147 @T6G_MB_LIB.T6G(SCH_1):PAGE51
  CR53 P5E_CPU1_P0_TX_DP<1> @T6G_MB_LIB.T6G(SCH_1):P5E_CPU1_P0_TX_DP(1)   I147 @T6G_MB_LIB.T6G(SCH_1):PAGE51
  CR47 P5E_CPU1_P0_TX_DP<7> @T6G_MB_LIB.T6G(SCH_1):P5E_CPU1_P0_TX_DP(7)   I147 @T6G_MB_LIB.T6G(SCH_1):PAGE51
  CA50 P5E_CPU1_P0_RX_DN<4> @T6G_MB_LIB.T6G(SCH_1):P5E_CPU1_P0_RX_DN(4)   I147 @T6G_MB_LIB.T6G(SCH_1):PAGE51
  CA53 P5E_CPU1_P0_RX_DN<1> @T6G_MB_LIB.T6G(SCH_1):P5E_CPU1_P0_RX_DN(1)   I147 @T6G_MB_LIB.T6G(SCH_1):PAGE51
  CA47 P5E_CPU1_P0_RX_DN<7> @T6G_MB_LIB.T6G(SCH_1):P5E_CPU1_P0_RX_DN(7)   I147 @T6G_MB_LIB.T6G(SCH_1):PAGE51
  CR49 P5E_CPU1_P0_TX_DN<4> @T6G_MB_LIB.T6G(SCH_1):P5E_CPU1_P0_TX_DN(4)   I147 @T6G_MB_LIB.T6G(SCH_1):PAGE51
  CR46 P5E_CPU1_P0_TX_DN<7> @T6G_MB_LIB.T6G(SCH_1):P5E_CPU1_P0_TX_DN(7)   I147 @T6G_MB_LIB.T6G(SCH_1):PAGE51
  CR52 P5E_CPU1_P0_TX_DN<1> @T6G_MB_LIB.T6G(SCH_1):P5E_CPU1_P0_TX_DN(1)   I147 @T6G_MB_LIB.T6G(SCH_1):PAGE51
  BU52 P5E_CPU1_P0_RX_DP<2> @T6G_MB_LIB.T6G(SCH_1):P5E_CPU1_P0_RX_DP(2)   I147 @T6G_MB_LIB.T6G(SCH_1):PAGE51
  BU49 P5E_CPU1_P0_RX_DP<5> @T6G_MB_LIB.T6G(SCH_1):P5E_CPU1_P0_RX_DP(5)   I147 @T6G_MB_LIB.T6G(SCH_1):PAGE51
  CU50 P5E_CPU1_P0_TX_DP<5> @T6G_MB_LIB.T6G(SCH_1):P5E_CPU1_P0_TX_DP(5)   I147 @T6G_MB_LIB.T6G(SCH_1):PAGE51
  CL53 P5E_CPU1_P0_TX_DP<2> @T6G_MB_LIB.T6G(SCH_1):P5E_CPU1_P0_TX_DP(2)   I147 @T6G_MB_LIB.T6G(SCH_1):PAGE51
  BU50 P5E_CPU1_P0_RX_DN<5> @T6G_MB_LIB.T6G(SCH_1):P5E_CPU1_P0_RX_DN(5)   I147 @T6G_MB_LIB.T6G(SCH_1):PAGE51
  BU53 P5E_CPU1_P0_RX_DN<2> @T6G_MB_LIB.T6G(SCH_1):P5E_CPU1_P0_RX_DN(2)   I147 @T6G_MB_LIB.T6G(SCH_1):PAGE51
  CL52 P5E_CPU1_P0_TX_DN<2> @T6G_MB_LIB.T6G(SCH_1):P5E_CPU1_P0_TX_DN(2)   I147 @T6G_MB_LIB.T6G(SCH_1):PAGE51
  BW52 P5E_CPU1_P0_RX_DP<0> @T6G_MB_LIB.T6G(SCH_1):P5E_CPU1_P0_RX_DP(0)   I147 @T6G_MB_LIB.T6G(SCH_1):PAGE51
  CU49 P5E_CPU1_P0_TX_DN<5> @T6G_MB_LIB.T6G(SCH_1):P5E_CPU1_P0_TX_DN(5)   I147 @T6G_MB_LIB.T6G(SCH_1):PAGE51
  BW46 P5E_CPU1_P0_RX_DP<6> @T6G_MB_LIB.T6G(SCH_1):P5E_CPU1_P0_RX_DP(6)   I147 @T6G_MB_LIB.T6G(SCH_1):PAGE51
  BW49 P5E_CPU1_P0_RX_DP<3> @T6G_MB_LIB.T6G(SCH_1):P5E_CPU1_P0_RX_DP(3)   I147 @T6G_MB_LIB.T6G(SCH_1):PAGE51
  CN53 P5E_CPU1_P0_TX_DP<0> @T6G_MB_LIB.T6G(SCH_1):P5E_CPU1_P0_TX_DP(0)   I147 @T6G_MB_LIB.T6G(SCH_1):PAGE51
  CL50 P5E_CPU1_P0_TX_DP<6> @T6G_MB_LIB.T6G(SCH_1):P5E_CPU1_P0_TX_DP(6)   I147 @T6G_MB_LIB.T6G(SCH_1):PAGE51
  CN50 P5E_CPU1_P0_TX_DP<3> @T6G_MB_LIB.T6G(SCH_1):P5E_CPU1_P0_TX_DP(3)   I147 @T6G_MB_LIB.T6G(SCH_1):PAGE51
  CT40 P5E_CPU1_P0_TX_DN<13> @T6G_MB_LIB.T6G(SCH_1):P5E_CPU1_P0_TX_DN(13)   I147 @T6G_MB_LIB.T6G(SCH_1):PAGE51
  CR43 P5E_CPU1_P0_TX_DN<10> @T6G_MB_LIB.T6G(SCH_1):P5E_CPU1_P0_TX_DN(10)   I147 @T6G_MB_LIB.T6G(SCH_1):PAGE51
  BV40 P5E_CPU1_P0_RX_DP<14> @T6G_MB_LIB.T6G(SCH_1):P5E_CPU1_P0_RX_DP(14)   I147 @T6G_MB_LIB.T6G(SCH_1):PAGE51
  BU46 P5E_CPU1_P0_RX_DP<8> @T6G_MB_LIB.T6G(SCH_1):P5E_CPU1_P0_RX_DP(8)   I147 @T6G_MB_LIB.T6G(SCH_1):PAGE51
  BY41 P5E_CPU1_P0_RX_DN<12> @T6G_MB_LIB.T6G(SCH_1):P5E_CPU1_P0_RX_DN(12)   I147 @T6G_MB_LIB.T6G(SCH_1):PAGE51
  CU47 P5E_CPU1_P0_TX_DP<8> @T6G_MB_LIB.T6G(SCH_1):P5E_CPU1_P0_TX_DP(8)   I147 @T6G_MB_LIB.T6G(SCH_1):PAGE51
  BT41 P5E_CPU1_P0_RX_DN<15> @T6G_MB_LIB.T6G(SCH_1):P5E_CPU1_P0_RX_DN(15)   I147 @T6G_MB_LIB.T6G(SCH_1):PAGE51
  CR44 P5E_CPU1_P0_TX_DP<10> @T6G_MB_LIB.T6G(SCH_1):P5E_CPU1_P0_TX_DP(10)   I147 @T6G_MB_LIB.T6G(SCH_1):PAGE51
  CT41 P5E_CPU1_P0_TX_DP<13> @T6G_MB_LIB.T6G(SCH_1):P5E_CPU1_P0_TX_DP(13)   I147 @T6G_MB_LIB.T6G(SCH_1):PAGE51
  BU47 P5E_CPU1_P0_RX_DN<8> @T6G_MB_LIB.T6G(SCH_1):P5E_CPU1_P0_RX_DN(8)   I147 @T6G_MB_LIB.T6G(SCH_1):PAGE51
  CU43 P5E_CPU1_P0_TX_DN<11> @T6G_MB_LIB.T6G(SCH_1):P5E_CPU1_P0_TX_DN(11)   I147 @T6G_MB_LIB.T6G(SCH_1):PAGE51
  CU46 P5E_CPU1_P0_TX_DN<8> @T6G_MB_LIB.T6G(SCH_1):P5E_CPU1_P0_TX_DN(8)   I147 @T6G_MB_LIB.T6G(SCH_1):PAGE51
  BT40 P5E_CPU1_P0_RX_DP<15> @T6G_MB_LIB.T6G(SCH_1):P5E_CPU1_P0_RX_DP(15)   I147 @T6G_MB_LIB.T6G(SCH_1):PAGE51
  BY40 P5E_CPU1_P0_RX_DP<12> @T6G_MB_LIB.T6G(SCH_1):P5E_CPU1_P0_RX_DP(12)   I147 @T6G_MB_LIB.T6G(SCH_1):PAGE51
  CP40 P5E_CPU1_P0_TX_DN<14> @T6G_MB_LIB.T6G(SCH_1):P5E_CPU1_P0_TX_DN(14)   I147 @T6G_MB_LIB.T6G(SCH_1):PAGE51
  BW43 P5E_CPU1_P0_RX_DP<9> @T6G_MB_LIB.T6G(SCH_1):P5E_CPU1_P0_RX_DP(9)   I147 @T6G_MB_LIB.T6G(SCH_1):PAGE51
  CN47 P5E_CPU1_P0_TX_DP<9> @T6G_MB_LIB.T6G(SCH_1):P5E_CPU1_P0_TX_DP(9)   I147 @T6G_MB_LIB.T6G(SCH_1):PAGE51
  CB41 P5E_CPU1_P0_RX_DN<13> @T6G_MB_LIB.T6G(SCH_1):P5E_CPU1_P0_RX_DN(13)   I147 @T6G_MB_LIB.T6G(SCH_1):PAGE51
  CA44 P5E_CPU1_P0_RX_DN<10> @T6G_MB_LIB.T6G(SCH_1):P5E_CPU1_P0_RX_DN(10)   I147 @T6G_MB_LIB.T6G(SCH_1):PAGE51
  CP41 P5E_CPU1_P0_TX_DP<14> @T6G_MB_LIB.T6G(SCH_1):P5E_CPU1_P0_TX_DP(14)   I147 @T6G_MB_LIB.T6G(SCH_1):PAGE51
  CU44 P5E_CPU1_P0_TX_DP<11> @T6G_MB_LIB.T6G(SCH_1):P5E_CPU1_P0_TX_DP(11)   I147 @T6G_MB_LIB.T6G(SCH_1):PAGE51
  BW44 P5E_CPU1_P0_RX_DN<9> @T6G_MB_LIB.T6G(SCH_1):P5E_CPU1_P0_RX_DN(9)   I147 @T6G_MB_LIB.T6G(SCH_1):PAGE51
  CA43 P5E_CPU1_P0_RX_DP<10> @T6G_MB_LIB.T6G(SCH_1):P5E_CPU1_P0_RX_DP(10)   I147 @T6G_MB_LIB.T6G(SCH_1):PAGE51
  CN43 P5E_CPU1_P0_TX_DN<12> @T6G_MB_LIB.T6G(SCH_1):P5E_CPU1_P0_TX_DN(12)   I147 @T6G_MB_LIB.T6G(SCH_1):PAGE51
  CN46 P5E_CPU1_P0_TX_DN<9> @T6G_MB_LIB.T6G(SCH_1):P5E_CPU1_P0_TX_DN(9)   I147 @T6G_MB_LIB.T6G(SCH_1):PAGE51
  CB40 P5E_CPU1_P0_RX_DP<13> @T6G_MB_LIB.T6G(SCH_1):P5E_CPU1_P0_RX_DP(13)   I147 @T6G_MB_LIB.T6G(SCH_1):PAGE51
  CM40 P5E_CPU1_P0_TX_DN<15> @T6G_MB_LIB.T6G(SCH_1):P5E_CPU1_P0_TX_DN(15)   I147 @T6G_MB_LIB.T6G(SCH_1):PAGE51
  BV41 P5E_CPU1_P0_RX_DN<14> @T6G_MB_LIB.T6G(SCH_1):P5E_CPU1_P0_RX_DN(14)   I147 @T6G_MB_LIB.T6G(SCH_1):PAGE51
  BU44 P5E_CPU1_P0_RX_DN<11> @T6G_MB_LIB.T6G(SCH_1):P5E_CPU1_P0_RX_DN(11)   I147 @T6G_MB_LIB.T6G(SCH_1):PAGE51
  CM41 P5E_CPU1_P0_TX_DP<15> @T6G_MB_LIB.T6G(SCH_1):P5E_CPU1_P0_TX_DP(15)   I147 @T6G_MB_LIB.T6G(SCH_1):PAGE51
  CN44 P5E_CPU1_P0_TX_DP<12> @T6G_MB_LIB.T6G(SCH_1):P5E_CPU1_P0_TX_DP(12)   I147 @T6G_MB_LIB.T6G(SCH_1):PAGE51
  BU43 P5E_CPU1_P0_RX_DP<11> @T6G_MB_LIB.T6G(SCH_1):P5E_CPU1_P0_RX_DP(11)   I147 @T6G_MB_LIB.T6G(SCH_1):PAGE51
  CC46 P5E_CPU1_P1_RX_DP<8> @T6G_MB_LIB.T6G(SCH_1):P5E_CPU1_P1_RX_DP(8)   I148 @T6G_MB_LIB.T6G(SCH_1):PAGE51
  CC47 P5E_CPU1_P1_RX_DN<8> @T6G_MB_LIB.T6G(SCH_1):P5E_CPU1_P1_RX_DN(8)   I148 @T6G_MB_LIB.T6G(SCH_1):PAGE51
  CE43 P5E_CPU1_P1_RX_DP<9> @T6G_MB_LIB.T6G(SCH_1):P5E_CPU1_P1_RX_DP(9)   I148 @T6G_MB_LIB.T6G(SCH_1):PAGE51
  CE44 P5E_CPU1_P1_RX_DN<9> @T6G_MB_LIB.T6G(SCH_1):P5E_CPU1_P1_RX_DN(9)   I148 @T6G_MB_LIB.T6G(SCH_1):PAGE51
  CG43 P5E_CPU1_P1_RX_DP<10> @T6G_MB_LIB.T6G(SCH_1):P5E_CPU1_P1_RX_DP(10)   I148 @T6G_MB_LIB.T6G(SCH_1):PAGE51
  CG44 P5E_CPU1_P1_RX_DN<10> @T6G_MB_LIB.T6G(SCH_1):P5E_CPU1_P1_RX_DN(10)   I148 @T6G_MB_LIB.T6G(SCH_1):PAGE51
  CJ43 P5E_CPU1_P1_RX_DP<11> @T6G_MB_LIB.T6G(SCH_1):P5E_CPU1_P1_RX_DP(11)   I148 @T6G_MB_LIB.T6G(SCH_1):PAGE51
  CJ44 P5E_CPU1_P1_RX_DN<11> @T6G_MB_LIB.T6G(SCH_1):P5E_CPU1_P1_RX_DN(11)   I148 @T6G_MB_LIB.T6G(SCH_1):PAGE51
  CC43 P5E_CPU1_P1_RX_DP<12> @T6G_MB_LIB.T6G(SCH_1):P5E_CPU1_P1_RX_DP(12)   I148 @T6G_MB_LIB.T6G(SCH_1):PAGE51
  CC44 P5E_CPU1_P1_RX_DN<12> @T6G_MB_LIB.T6G(SCH_1):P5E_CPU1_P1_RX_DN(12)   I148 @T6G_MB_LIB.T6G(SCH_1):PAGE51
  CH40 P5E_CPU1_P1_RX_DP<13> @T6G_MB_LIB.T6G(SCH_1):P5E_CPU1_P1_RX_DP(13)   I148 @T6G_MB_LIB.T6G(SCH_1):PAGE51
  CH41 P5E_CPU1_P1_RX_DN<13> @T6G_MB_LIB.T6G(SCH_1):P5E_CPU1_P1_RX_DN(13)   I148 @T6G_MB_LIB.T6G(SCH_1):PAGE51
  CF40 P5E_CPU1_P1_RX_DP<14> @T6G_MB_LIB.T6G(SCH_1):P5E_CPU1_P1_RX_DP(14)   I148 @T6G_MB_LIB.T6G(SCH_1):PAGE51
  CF41 P5E_CPU1_P1_RX_DN<14> @T6G_MB_LIB.T6G(SCH_1):P5E_CPU1_P1_RX_DN(14)   I148 @T6G_MB_LIB.T6G(SCH_1):PAGE51
  CD40 P5E_CPU1_P1_RX_DP<15> @T6G_MB_LIB.T6G(SCH_1):P5E_CPU1_P1_RX_DP(15)   I148 @T6G_MB_LIB.T6G(SCH_1):PAGE51
  CD41 P5E_CPU1_P1_RX_DN<15> @T6G_MB_LIB.T6G(SCH_1):P5E_CPU1_P1_RX_DN(15)   I148 @T6G_MB_LIB.T6G(SCH_1):PAGE51
  DC47 P5E_CPU1_P1_TX_DP<8> @T6G_MB_LIB.T6G(SCH_1):P5E_CPU1_P1_TX_DP(8)   I148 @T6G_MB_LIB.T6G(SCH_1):PAGE51
  DC46 P5E_CPU1_P1_TX_DN<8> @T6G_MB_LIB.T6G(SCH_1):P5E_CPU1_P1_TX_DN(8)   I148 @T6G_MB_LIB.T6G(SCH_1):PAGE51
  CW47 P5E_CPU1_P1_TX_DP<9> @T6G_MB_LIB.T6G(SCH_1):P5E_CPU1_P1_TX_DP(9)   I148 @T6G_MB_LIB.T6G(SCH_1):PAGE51
  CW46 P5E_CPU1_P1_TX_DN<9> @T6G_MB_LIB.T6G(SCH_1):P5E_CPU1_P1_TX_DN(9)   I148 @T6G_MB_LIB.T6G(SCH_1):PAGE51
  DA44 P5E_CPU1_P1_TX_DP<10> @T6G_MB_LIB.T6G(SCH_1):P5E_CPU1_P1_TX_DP(10)   I148 @T6G_MB_LIB.T6G(SCH_1):PAGE51
  DA43 P5E_CPU1_P1_TX_DN<10> @T6G_MB_LIB.T6G(SCH_1):P5E_CPU1_P1_TX_DN(10)   I148 @T6G_MB_LIB.T6G(SCH_1):PAGE51
  DC44 P5E_CPU1_P1_TX_DP<11> @T6G_MB_LIB.T6G(SCH_1):P5E_CPU1_P1_TX_DP(11)   I148 @T6G_MB_LIB.T6G(SCH_1):PAGE51
  DC43 P5E_CPU1_P1_TX_DN<11> @T6G_MB_LIB.T6G(SCH_1):P5E_CPU1_P1_TX_DN(11)   I148 @T6G_MB_LIB.T6G(SCH_1):PAGE51
  CW44 P5E_CPU1_P1_TX_DP<12> @T6G_MB_LIB.T6G(SCH_1):P5E_CPU1_P1_TX_DP(12)   I148 @T6G_MB_LIB.T6G(SCH_1):PAGE51
  CW43 P5E_CPU1_P1_TX_DN<12> @T6G_MB_LIB.T6G(SCH_1):P5E_CPU1_P1_TX_DN(12)   I148 @T6G_MB_LIB.T6G(SCH_1):PAGE51
  DB41 P5E_CPU1_P1_TX_DP<13> @T6G_MB_LIB.T6G(SCH_1):P5E_CPU1_P1_TX_DP(13)   I148 @T6G_MB_LIB.T6G(SCH_1):PAGE51
  DB40 P5E_CPU1_P1_TX_DN<13> @T6G_MB_LIB.T6G(SCH_1):P5E_CPU1_P1_TX_DN(13)   I148 @T6G_MB_LIB.T6G(SCH_1):PAGE51
  CY41 P5E_CPU1_P1_TX_DP<14> @T6G_MB_LIB.T6G(SCH_1):P5E_CPU1_P1_TX_DP(14)   I148 @T6G_MB_LIB.T6G(SCH_1):PAGE51
  CY40 P5E_CPU1_P1_TX_DN<14> @T6G_MB_LIB.T6G(SCH_1):P5E_CPU1_P1_TX_DN(14)   I148 @T6G_MB_LIB.T6G(SCH_1):PAGE51
  CV41 P5E_CPU1_P1_TX_DP<15> @T6G_MB_LIB.T6G(SCH_1):P5E_CPU1_P1_TX_DP(15)   I148 @T6G_MB_LIB.T6G(SCH_1):PAGE51
  CV40 P5E_CPU1_P1_TX_DN<15> @T6G_MB_LIB.T6G(SCH_1):P5E_CPU1_P1_TX_DN(15)   I148 @T6G_MB_LIB.T6G(SCH_1):PAGE51
  CG47 P5E_CPU1_P1_RX_DN<7> @T6G_MB_LIB.T6G(SCH_1):P5E_CPU1_P1_RX_DN(7)   I148 @T6G_MB_LIB.T6G(SCH_1):PAGE51
  CU53 P5E_CPU1_P1_TX_DP<0> @T6G_MB_LIB.T6G(SCH_1):P5E_CPU1_P1_TX_DP(0)   I148 @T6G_MB_LIB.T6G(SCH_1):PAGE51
  DA53 P5E_CPU1_P1_TX_DP<1> @T6G_MB_LIB.T6G(SCH_1):P5E_CPU1_P1_TX_DP(1)   I148 @T6G_MB_LIB.T6G(SCH_1):PAGE51
  DC53 P5E_CPU1_P1_TX_DP<2> @T6G_MB_LIB.T6G(SCH_1):P5E_CPU1_P1_TX_DP(2)   I148 @T6G_MB_LIB.T6G(SCH_1):PAGE51
  CU52 P5E_CPU1_P1_TX_DN<0> @T6G_MB_LIB.T6G(SCH_1):P5E_CPU1_P1_TX_DN(0)   I148 @T6G_MB_LIB.T6G(SCH_1):PAGE51
  CE52 P5E_CPU1_P1_RX_DP<0> @T6G_MB_LIB.T6G(SCH_1):P5E_CPU1_P1_RX_DP(0)   I148 @T6G_MB_LIB.T6G(SCH_1):PAGE51
  CW53 P5E_CPU1_P1_TX_DP<3> @T6G_MB_LIB.T6G(SCH_1):P5E_CPU1_P1_TX_DP(3)   I148 @T6G_MB_LIB.T6G(SCH_1):PAGE51
  DA52 P5E_CPU1_P1_TX_DN<1> @T6G_MB_LIB.T6G(SCH_1):P5E_CPU1_P1_TX_DN(1)   I148 @T6G_MB_LIB.T6G(SCH_1):PAGE51
  CG52 P5E_CPU1_P1_RX_DP<1> @T6G_MB_LIB.T6G(SCH_1):P5E_CPU1_P1_RX_DP(1)   I148 @T6G_MB_LIB.T6G(SCH_1):PAGE51
  DA50 P5E_CPU1_P1_TX_DP<4> @T6G_MB_LIB.T6G(SCH_1):P5E_CPU1_P1_TX_DP(4)   I148 @T6G_MB_LIB.T6G(SCH_1):PAGE51
  DC52 P5E_CPU1_P1_TX_DN<2> @T6G_MB_LIB.T6G(SCH_1):P5E_CPU1_P1_TX_DN(2)   I148 @T6G_MB_LIB.T6G(SCH_1):PAGE51
  CC52 P5E_CPU1_P1_RX_DP<2> @T6G_MB_LIB.T6G(SCH_1):P5E_CPU1_P1_RX_DP(2)   I148 @T6G_MB_LIB.T6G(SCH_1):PAGE51
  CE53 P5E_CPU1_P1_RX_DN<0> @T6G_MB_LIB.T6G(SCH_1):P5E_CPU1_P1_RX_DN(0)   I148 @T6G_MB_LIB.T6G(SCH_1):PAGE51
  DC50 P5E_CPU1_P1_TX_DP<5> @T6G_MB_LIB.T6G(SCH_1):P5E_CPU1_P1_TX_DP(5)   I148 @T6G_MB_LIB.T6G(SCH_1):PAGE51
  CW52 P5E_CPU1_P1_TX_DN<3> @T6G_MB_LIB.T6G(SCH_1):P5E_CPU1_P1_TX_DN(3)   I148 @T6G_MB_LIB.T6G(SCH_1):PAGE51
  CE49 P5E_CPU1_P1_RX_DP<3> @T6G_MB_LIB.T6G(SCH_1):P5E_CPU1_P1_RX_DP(3)   I148 @T6G_MB_LIB.T6G(SCH_1):PAGE51
  CG53 P5E_CPU1_P1_RX_DN<1> @T6G_MB_LIB.T6G(SCH_1):P5E_CPU1_P1_RX_DN(1)   I148 @T6G_MB_LIB.T6G(SCH_1):PAGE51
  CW50 P5E_CPU1_P1_TX_DP<6> @T6G_MB_LIB.T6G(SCH_1):P5E_CPU1_P1_TX_DP(6)   I148 @T6G_MB_LIB.T6G(SCH_1):PAGE51
  DA49 P5E_CPU1_P1_TX_DN<4> @T6G_MB_LIB.T6G(SCH_1):P5E_CPU1_P1_TX_DN(4)   I148 @T6G_MB_LIB.T6G(SCH_1):PAGE51
  CG49 P5E_CPU1_P1_RX_DP<4> @T6G_MB_LIB.T6G(SCH_1):P5E_CPU1_P1_RX_DP(4)   I148 @T6G_MB_LIB.T6G(SCH_1):PAGE51
  CC53 P5E_CPU1_P1_RX_DN<2> @T6G_MB_LIB.T6G(SCH_1):P5E_CPU1_P1_RX_DN(2)   I148 @T6G_MB_LIB.T6G(SCH_1):PAGE51
  DA47 P5E_CPU1_P1_TX_DP<7> @T6G_MB_LIB.T6G(SCH_1):P5E_CPU1_P1_TX_DP(7)   I148 @T6G_MB_LIB.T6G(SCH_1):PAGE51
  DC49 P5E_CPU1_P1_TX_DN<5> @T6G_MB_LIB.T6G(SCH_1):P5E_CPU1_P1_TX_DN(5)   I148 @T6G_MB_LIB.T6G(SCH_1):PAGE51
  CC49 P5E_CPU1_P1_RX_DP<5> @T6G_MB_LIB.T6G(SCH_1):P5E_CPU1_P1_RX_DP(5)   I148 @T6G_MB_LIB.T6G(SCH_1):PAGE51
  CE50 P5E_CPU1_P1_RX_DN<3> @T6G_MB_LIB.T6G(SCH_1):P5E_CPU1_P1_RX_DN(3)   I148 @T6G_MB_LIB.T6G(SCH_1):PAGE51
  CW49 P5E_CPU1_P1_TX_DN<6> @T6G_MB_LIB.T6G(SCH_1):P5E_CPU1_P1_TX_DN(6)   I148 @T6G_MB_LIB.T6G(SCH_1):PAGE51
  CE46 P5E_CPU1_P1_RX_DP<6> @T6G_MB_LIB.T6G(SCH_1):P5E_CPU1_P1_RX_DP(6)   I148 @T6G_MB_LIB.T6G(SCH_1):PAGE51
  CG50 P5E_CPU1_P1_RX_DN<4> @T6G_MB_LIB.T6G(SCH_1):P5E_CPU1_P1_RX_DN(4)   I148 @T6G_MB_LIB.T6G(SCH_1):PAGE51
  DA46 P5E_CPU1_P1_TX_DN<7> @T6G_MB_LIB.T6G(SCH_1):P5E_CPU1_P1_TX_DN(7)   I148 @T6G_MB_LIB.T6G(SCH_1):PAGE51
  CG46 P5E_CPU1_P1_RX_DP<7> @T6G_MB_LIB.T6G(SCH_1):P5E_CPU1_P1_RX_DP(7)   I148 @T6G_MB_LIB.T6G(SCH_1):PAGE51
  CC50 P5E_CPU1_P1_RX_DN<5> @T6G_MB_LIB.T6G(SCH_1):P5E_CPU1_P1_RX_DN(5)   I148 @T6G_MB_LIB.T6G(SCH_1):PAGE51
  CE47 P5E_CPU1_P1_RX_DN<6> @T6G_MB_LIB.T6G(SCH_1):P5E_CPU1_P1_RX_DN(6)   I148 @T6G_MB_LIB.T6G(SCH_1):PAGE51
  CR29 P5E_CPU1_P2_RX_DP<8> @T6G_MB_LIB.T6G(SCH_1):P5E_CPU1_P2_RX_DP(8)   I148 @T6G_MB_LIB.T6G(SCH_1):PAGE52
  CR30 P5E_CPU1_P2_RX_DN<8> @T6G_MB_LIB.T6G(SCH_1):P5E_CPU1_P2_RX_DN(8)   I148 @T6G_MB_LIB.T6G(SCH_1):PAGE52
  CL26 P5E_CPU1_P2_RX_DP<9> @T6G_MB_LIB.T6G(SCH_1):P5E_CPU1_P2_RX_DP(9)   I148 @T6G_MB_LIB.T6G(SCH_1):PAGE52
  CL27 P5E_CPU1_P2_RX_DN<9> @T6G_MB_LIB.T6G(SCH_1):P5E_CPU1_P2_RX_DN(9)   I148 @T6G_MB_LIB.T6G(SCH_1):PAGE52
  CU26 P5E_CPU1_P2_RX_DP<10> @T6G_MB_LIB.T6G(SCH_1):P5E_CPU1_P2_RX_DP(10)   I148 @T6G_MB_LIB.T6G(SCH_1):PAGE52
  CU27 P5E_CPU1_P2_RX_DN<10> @T6G_MB_LIB.T6G(SCH_1):P5E_CPU1_P2_RX_DN(10)   I148 @T6G_MB_LIB.T6G(SCH_1):PAGE52
  CR26 P5E_CPU1_P2_RX_DP<11> @T6G_MB_LIB.T6G(SCH_1):P5E_CPU1_P2_RX_DP(11)   I148 @T6G_MB_LIB.T6G(SCH_1):PAGE52
  CR27 P5E_CPU1_P2_RX_DN<11> @T6G_MB_LIB.T6G(SCH_1):P5E_CPU1_P2_RX_DN(11)   I148 @T6G_MB_LIB.T6G(SCH_1):PAGE52
  CN26 P5E_CPU1_P2_RX_DP<12> @T6G_MB_LIB.T6G(SCH_1):P5E_CPU1_P2_RX_DP(12)   I148 @T6G_MB_LIB.T6G(SCH_1):PAGE52
  CN27 P5E_CPU1_P2_RX_DN<12> @T6G_MB_LIB.T6G(SCH_1):P5E_CPU1_P2_RX_DN(12)   I148 @T6G_MB_LIB.T6G(SCH_1):PAGE52
  CL23 P5E_CPU1_P2_RX_DP<13> @T6G_MB_LIB.T6G(SCH_1):P5E_CPU1_P2_RX_DP(13)   I148 @T6G_MB_LIB.T6G(SCH_1):PAGE52
  CL24 P5E_CPU1_P2_RX_DN<13> @T6G_MB_LIB.T6G(SCH_1):P5E_CPU1_P2_RX_DN(13)   I148 @T6G_MB_LIB.T6G(SCH_1):PAGE52
  CR23 P5E_CPU1_P2_RX_DP<14> @T6G_MB_LIB.T6G(SCH_1):P5E_CPU1_P2_RX_DP(14)   I148 @T6G_MB_LIB.T6G(SCH_1):PAGE52
  CR24 P5E_CPU1_P2_RX_DN<14> @T6G_MB_LIB.T6G(SCH_1):P5E_CPU1_P2_RX_DN(14)   I148 @T6G_MB_LIB.T6G(SCH_1):PAGE52
  CN23 P5E_CPU1_P2_RX_DP<15> @T6G_MB_LIB.T6G(SCH_1):P5E_CPU1_P2_RX_DP(15)   I148 @T6G_MB_LIB.T6G(SCH_1):PAGE52
  CN24 P5E_CPU1_P2_RX_DN<15> @T6G_MB_LIB.T6G(SCH_1):P5E_CPU1_P2_RX_DN(15)   I148 @T6G_MB_LIB.T6G(SCH_1):PAGE52
  CA30 P5E_CPU1_P2_TX_DP<8> @T6G_MB_LIB.T6G(SCH_1):P5E_CPU1_P2_TX_DP(8)   I148 @T6G_MB_LIB.T6G(SCH_1):PAGE52
  CA29 P5E_CPU1_P2_TX_DN<8> @T6G_MB_LIB.T6G(SCH_1):P5E_CPU1_P2_TX_DN(8)   I148 @T6G_MB_LIB.T6G(SCH_1):PAGE52
  BW30 P5E_CPU1_P2_TX_DP<9> @T6G_MB_LIB.T6G(SCH_1):P5E_CPU1_P2_TX_DP(9)   I148 @T6G_MB_LIB.T6G(SCH_1):PAGE52
  BW29 P5E_CPU1_P2_TX_DN<9> @T6G_MB_LIB.T6G(SCH_1):P5E_CPU1_P2_TX_DN(9)   I148 @T6G_MB_LIB.T6G(SCH_1):PAGE52
  BU27 P5E_CPU1_P2_TX_DP<10> @T6G_MB_LIB.T6G(SCH_1):P5E_CPU1_P2_TX_DP(10)   I148 @T6G_MB_LIB.T6G(SCH_1):PAGE52
  BU26 P5E_CPU1_P2_TX_DN<10> @T6G_MB_LIB.T6G(SCH_1):P5E_CPU1_P2_TX_DN(10)   I148 @T6G_MB_LIB.T6G(SCH_1):PAGE52
  CA27 P5E_CPU1_P2_TX_DP<11> @T6G_MB_LIB.T6G(SCH_1):P5E_CPU1_P2_TX_DP(11)   I148 @T6G_MB_LIB.T6G(SCH_1):PAGE52
  CA26 P5E_CPU1_P2_TX_DN<11> @T6G_MB_LIB.T6G(SCH_1):P5E_CPU1_P2_TX_DN(11)   I148 @T6G_MB_LIB.T6G(SCH_1):PAGE52
  BW27 P5E_CPU1_P2_TX_DP<12> @T6G_MB_LIB.T6G(SCH_1):P5E_CPU1_P2_TX_DP(12)   I148 @T6G_MB_LIB.T6G(SCH_1):PAGE52
  BW26 P5E_CPU1_P2_TX_DN<12> @T6G_MB_LIB.T6G(SCH_1):P5E_CPU1_P2_TX_DN(12)   I148 @T6G_MB_LIB.T6G(SCH_1):PAGE52
  BU24 P5E_CPU1_P2_TX_DP<13> @T6G_MB_LIB.T6G(SCH_1):P5E_CPU1_P2_TX_DP(13)   I148 @T6G_MB_LIB.T6G(SCH_1):PAGE52
  BU23 P5E_CPU1_P2_TX_DN<13> @T6G_MB_LIB.T6G(SCH_1):P5E_CPU1_P2_TX_DN(13)   I148 @T6G_MB_LIB.T6G(SCH_1):PAGE52
  CA24 P5E_CPU1_P2_TX_DP<14> @T6G_MB_LIB.T6G(SCH_1):P5E_CPU1_P2_TX_DP(14)   I148 @T6G_MB_LIB.T6G(SCH_1):PAGE52
  CA23 P5E_CPU1_P2_TX_DN<14> @T6G_MB_LIB.T6G(SCH_1):P5E_CPU1_P2_TX_DN(14)   I148 @T6G_MB_LIB.T6G(SCH_1):PAGE52
  BW24 P5E_CPU1_P2_TX_DP<15> @T6G_MB_LIB.T6G(SCH_1):P5E_CPU1_P2_TX_DP(15)   I148 @T6G_MB_LIB.T6G(SCH_1):PAGE52
  BW23 P5E_CPU1_P2_TX_DN<15> @T6G_MB_LIB.T6G(SCH_1):P5E_CPU1_P2_TX_DN(15)   I148 @T6G_MB_LIB.T6G(SCH_1):PAGE52
  BT36 P5E_CPU1_P2_TX_DP<0> @T6G_MB_LIB.T6G(SCH_1):P5E_CPU1_P2_TX_DP(0)   I148 @T6G_MB_LIB.T6G(SCH_1):PAGE52
  BV36 P5E_CPU1_P2_TX_DP<1> @T6G_MB_LIB.T6G(SCH_1):P5E_CPU1_P2_TX_DP(1)   I148 @T6G_MB_LIB.T6G(SCH_1):PAGE52
  CB36 P5E_CPU1_P2_TX_DP<2> @T6G_MB_LIB.T6G(SCH_1):P5E_CPU1_P2_TX_DP(2)   I148 @T6G_MB_LIB.T6G(SCH_1):PAGE52
  BT35 P5E_CPU1_P2_TX_DN<0> @T6G_MB_LIB.T6G(SCH_1):P5E_CPU1_P2_TX_DN(0)   I148 @T6G_MB_LIB.T6G(SCH_1):PAGE52
  CM35 P5E_CPU1_P2_RX_DP<0> @T6G_MB_LIB.T6G(SCH_1):P5E_CPU1_P2_RX_DP(0)   I148 @T6G_MB_LIB.T6G(SCH_1):PAGE52
  BY36 P5E_CPU1_P2_TX_DP<3> @T6G_MB_LIB.T6G(SCH_1):P5E_CPU1_P2_TX_DP(3)   I148 @T6G_MB_LIB.T6G(SCH_1):PAGE52
  BV35 P5E_CPU1_P2_TX_DN<1> @T6G_MB_LIB.T6G(SCH_1):P5E_CPU1_P2_TX_DN(1)   I148 @T6G_MB_LIB.T6G(SCH_1):PAGE52
  CP35 P5E_CPU1_P2_RX_DP<1> @T6G_MB_LIB.T6G(SCH_1):P5E_CPU1_P2_RX_DP(1)   I148 @T6G_MB_LIB.T6G(SCH_1):PAGE52
  BU33 P5E_CPU1_P2_TX_DP<4> @T6G_MB_LIB.T6G(SCH_1):P5E_CPU1_P2_TX_DP(4)   I148 @T6G_MB_LIB.T6G(SCH_1):PAGE52
  CB35 P5E_CPU1_P2_TX_DN<2> @T6G_MB_LIB.T6G(SCH_1):P5E_CPU1_P2_TX_DN(2)   I148 @T6G_MB_LIB.T6G(SCH_1):PAGE52
  CT35 P5E_CPU1_P2_RX_DP<2> @T6G_MB_LIB.T6G(SCH_1):P5E_CPU1_P2_RX_DP(2)   I148 @T6G_MB_LIB.T6G(SCH_1):PAGE52
  CM36 P5E_CPU1_P2_RX_DN<0> @T6G_MB_LIB.T6G(SCH_1):P5E_CPU1_P2_RX_DN(0)   I148 @T6G_MB_LIB.T6G(SCH_1):PAGE52
  CA33 P5E_CPU1_P2_TX_DP<5> @T6G_MB_LIB.T6G(SCH_1):P5E_CPU1_P2_TX_DP(5)   I148 @T6G_MB_LIB.T6G(SCH_1):PAGE52
  BY35 P5E_CPU1_P2_TX_DN<3> @T6G_MB_LIB.T6G(SCH_1):P5E_CPU1_P2_TX_DN(3)   I148 @T6G_MB_LIB.T6G(SCH_1):PAGE52
  CN32 P5E_CPU1_P2_RX_DP<3> @T6G_MB_LIB.T6G(SCH_1):P5E_CPU1_P2_RX_DP(3)   I148 @T6G_MB_LIB.T6G(SCH_1):PAGE52
  CP36 P5E_CPU1_P2_RX_DN<1> @T6G_MB_LIB.T6G(SCH_1):P5E_CPU1_P2_RX_DN(1)   I148 @T6G_MB_LIB.T6G(SCH_1):PAGE52
  BW33 P5E_CPU1_P2_TX_DP<6> @T6G_MB_LIB.T6G(SCH_1):P5E_CPU1_P2_TX_DP(6)   I148 @T6G_MB_LIB.T6G(SCH_1):PAGE52
  BU32 P5E_CPU1_P2_TX_DN<4> @T6G_MB_LIB.T6G(SCH_1):P5E_CPU1_P2_TX_DN(4)   I148 @T6G_MB_LIB.T6G(SCH_1):PAGE52
  CU32 P5E_CPU1_P2_RX_DP<4> @T6G_MB_LIB.T6G(SCH_1):P5E_CPU1_P2_RX_DP(4)   I148 @T6G_MB_LIB.T6G(SCH_1):PAGE52
  CT36 P5E_CPU1_P2_RX_DN<2> @T6G_MB_LIB.T6G(SCH_1):P5E_CPU1_P2_RX_DN(2)   I148 @T6G_MB_LIB.T6G(SCH_1):PAGE52
  BU30 P5E_CPU1_P2_TX_DP<7> @T6G_MB_LIB.T6G(SCH_1):P5E_CPU1_P2_TX_DP(7)   I148 @T6G_MB_LIB.T6G(SCH_1):PAGE52
  CA32 P5E_CPU1_P2_TX_DN<5> @T6G_MB_LIB.T6G(SCH_1):P5E_CPU1_P2_TX_DN(5)   I148 @T6G_MB_LIB.T6G(SCH_1):PAGE52
  CR32 P5E_CPU1_P2_RX_DP<5> @T6G_MB_LIB.T6G(SCH_1):P5E_CPU1_P2_RX_DP(5)   I148 @T6G_MB_LIB.T6G(SCH_1):PAGE52
  CN33 P5E_CPU1_P2_RX_DN<3> @T6G_MB_LIB.T6G(SCH_1):P5E_CPU1_P2_RX_DN(3)   I148 @T6G_MB_LIB.T6G(SCH_1):PAGE52
  BW32 P5E_CPU1_P2_TX_DN<6> @T6G_MB_LIB.T6G(SCH_1):P5E_CPU1_P2_TX_DN(6)   I148 @T6G_MB_LIB.T6G(SCH_1):PAGE52
  CN29 P5E_CPU1_P2_RX_DP<6> @T6G_MB_LIB.T6G(SCH_1):P5E_CPU1_P2_RX_DP(6)   I148 @T6G_MB_LIB.T6G(SCH_1):PAGE52
  CU33 P5E_CPU1_P2_RX_DN<4> @T6G_MB_LIB.T6G(SCH_1):P5E_CPU1_P2_RX_DN(4)   I148 @T6G_MB_LIB.T6G(SCH_1):PAGE52
  BU29 P5E_CPU1_P2_TX_DN<7> @T6G_MB_LIB.T6G(SCH_1):P5E_CPU1_P2_TX_DN(7)   I148 @T6G_MB_LIB.T6G(SCH_1):PAGE52
  CU29 P5E_CPU1_P2_RX_DP<7> @T6G_MB_LIB.T6G(SCH_1):P5E_CPU1_P2_RX_DP(7)   I148 @T6G_MB_LIB.T6G(SCH_1):PAGE52
  CR33 P5E_CPU1_P2_RX_DN<5> @T6G_MB_LIB.T6G(SCH_1):P5E_CPU1_P2_RX_DN(5)   I148 @T6G_MB_LIB.T6G(SCH_1):PAGE52
  CN30 P5E_CPU1_P2_RX_DN<6> @T6G_MB_LIB.T6G(SCH_1):P5E_CPU1_P2_RX_DN(6)   I148 @T6G_MB_LIB.T6G(SCH_1):PAGE52
  CU30 P5E_CPU1_P2_RX_DN<7> @T6G_MB_LIB.T6G(SCH_1):P5E_CPU1_P2_RX_DN(7)   I148 @T6G_MB_LIB.T6G(SCH_1):PAGE52
  CV35 P5E_CPU1_P3_RX_DP<0> @T6G_MB_LIB.T6G(SCH_1):P5E_CPU1_P3_RX_DP(0)   I147 @T6G_MB_LIB.T6G(SCH_1):PAGE52
  CV36 P5E_CPU1_P3_RX_DN<0> @T6G_MB_LIB.T6G(SCH_1):P5E_CPU1_P3_RX_DN(0)   I147 @T6G_MB_LIB.T6G(SCH_1):PAGE52
  CY35 P5E_CPU1_P3_RX_DP<1> @T6G_MB_LIB.T6G(SCH_1):P5E_CPU1_P3_RX_DP(1)   I147 @T6G_MB_LIB.T6G(SCH_1):PAGE52
  CY36 P5E_CPU1_P3_RX_DN<1> @T6G_MB_LIB.T6G(SCH_1):P5E_CPU1_P3_RX_DN(1)   I147 @T6G_MB_LIB.T6G(SCH_1):PAGE52
  DB35 P5E_CPU1_P3_RX_DP<2> @T6G_MB_LIB.T6G(SCH_1):P5E_CPU1_P3_RX_DP(2)   I147 @T6G_MB_LIB.T6G(SCH_1):PAGE52
  DB36 P5E_CPU1_P3_RX_DN<2> @T6G_MB_LIB.T6G(SCH_1):P5E_CPU1_P3_RX_DN(2)   I147 @T6G_MB_LIB.T6G(SCH_1):PAGE52
  CW32 P5E_CPU1_P3_RX_DP<3> @T6G_MB_LIB.T6G(SCH_1):P5E_CPU1_P3_RX_DP(3)   I147 @T6G_MB_LIB.T6G(SCH_1):PAGE52
  CW33 P5E_CPU1_P3_RX_DN<3> @T6G_MB_LIB.T6G(SCH_1):P5E_CPU1_P3_RX_DN(3)   I147 @T6G_MB_LIB.T6G(SCH_1):PAGE52
  DC32 P5E_CPU1_P3_RX_DP<4> @T6G_MB_LIB.T6G(SCH_1):P5E_CPU1_P3_RX_DP(4)   I147 @T6G_MB_LIB.T6G(SCH_1):PAGE52
  DC33 P5E_CPU1_P3_RX_DN<4> @T6G_MB_LIB.T6G(SCH_1):P5E_CPU1_P3_RX_DN(4)   I147 @T6G_MB_LIB.T6G(SCH_1):PAGE52
  DA32 P5E_CPU1_P3_RX_DP<5> @T6G_MB_LIB.T6G(SCH_1):P5E_CPU1_P3_RX_DP(5)   I147 @T6G_MB_LIB.T6G(SCH_1):PAGE52
  DA33 P5E_CPU1_P3_RX_DN<5> @T6G_MB_LIB.T6G(SCH_1):P5E_CPU1_P3_RX_DN(5)   I147 @T6G_MB_LIB.T6G(SCH_1):PAGE52
  CW29 P5E_CPU1_P3_RX_DP<6> @T6G_MB_LIB.T6G(SCH_1):P5E_CPU1_P3_RX_DP(6)   I147 @T6G_MB_LIB.T6G(SCH_1):PAGE52
  CW30 P5E_CPU1_P3_RX_DN<6> @T6G_MB_LIB.T6G(SCH_1):P5E_CPU1_P3_RX_DN(6)   I147 @T6G_MB_LIB.T6G(SCH_1):PAGE52
  DC29 P5E_CPU1_P3_RX_DP<7> @T6G_MB_LIB.T6G(SCH_1):P5E_CPU1_P3_RX_DP(7)   I147 @T6G_MB_LIB.T6G(SCH_1):PAGE52
  DC30 P5E_CPU1_P3_RX_DN<7> @T6G_MB_LIB.T6G(SCH_1):P5E_CPU1_P3_RX_DN(7)   I147 @T6G_MB_LIB.T6G(SCH_1):PAGE52
  DA29 P5E_CPU1_P3_RX_DP<8> @T6G_MB_LIB.T6G(SCH_1):P5E_CPU1_P3_RX_DP(8)   I147 @T6G_MB_LIB.T6G(SCH_1):PAGE52
  DA30 P5E_CPU1_P3_RX_DN<8> @T6G_MB_LIB.T6G(SCH_1):P5E_CPU1_P3_RX_DN(8)   I147 @T6G_MB_LIB.T6G(SCH_1):PAGE52
  CW26 P5E_CPU1_P3_RX_DP<9> @T6G_MB_LIB.T6G(SCH_1):P5E_CPU1_P3_RX_DP(9)   I147 @T6G_MB_LIB.T6G(SCH_1):PAGE52
  CW27 P5E_CPU1_P3_RX_DN<9> @T6G_MB_LIB.T6G(SCH_1):P5E_CPU1_P3_RX_DN(9)   I147 @T6G_MB_LIB.T6G(SCH_1):PAGE52
  DC26 P5E_CPU1_P3_RX_DP<10> @T6G_MB_LIB.T6G(SCH_1):P5E_CPU1_P3_RX_DP(10)   I147 @T6G_MB_LIB.T6G(SCH_1):PAGE52
  DC27 P5E_CPU1_P3_RX_DN<10> @T6G_MB_LIB.T6G(SCH_1):P5E_CPU1_P3_RX_DN(10)   I147 @T6G_MB_LIB.T6G(SCH_1):PAGE52
  DA26 P5E_CPU1_P3_RX_DP<11> @T6G_MB_LIB.T6G(SCH_1):P5E_CPU1_P3_RX_DP(11)   I147 @T6G_MB_LIB.T6G(SCH_1):PAGE52
  DA27 P5E_CPU1_P3_RX_DN<11> @T6G_MB_LIB.T6G(SCH_1):P5E_CPU1_P3_RX_DN(11)   I147 @T6G_MB_LIB.T6G(SCH_1):PAGE52
  CW23 P5E_CPU1_P3_RX_DP<12> @T6G_MB_LIB.T6G(SCH_1):P5E_CPU1_P3_RX_DP(12)   I147 @T6G_MB_LIB.T6G(SCH_1):PAGE52
  CW24 P5E_CPU1_P3_RX_DN<12> @T6G_MB_LIB.T6G(SCH_1):P5E_CPU1_P3_RX_DN(12)   I147 @T6G_MB_LIB.T6G(SCH_1):PAGE52
  DC23 P5E_CPU1_P3_RX_DP<13> @T6G_MB_LIB.T6G(SCH_1):P5E_CPU1_P3_RX_DP(13)   I147 @T6G_MB_LIB.T6G(SCH_1):PAGE52
  DC24 P5E_CPU1_P3_RX_DN<13> @T6G_MB_LIB.T6G(SCH_1):P5E_CPU1_P3_RX_DN(13)   I147 @T6G_MB_LIB.T6G(SCH_1):PAGE52
  DA23 P5E_CPU1_P3_RX_DP<14> @T6G_MB_LIB.T6G(SCH_1):P5E_CPU1_P3_RX_DP(14)   I147 @T6G_MB_LIB.T6G(SCH_1):PAGE52
  DA24 P5E_CPU1_P3_RX_DN<14> @T6G_MB_LIB.T6G(SCH_1):P5E_CPU1_P3_RX_DN(14)   I147 @T6G_MB_LIB.T6G(SCH_1):PAGE52
  CU23 P5E_CPU1_P3_RX_DP<15> @T6G_MB_LIB.T6G(SCH_1):P5E_CPU1_P3_RX_DP(15)   I147 @T6G_MB_LIB.T6G(SCH_1):PAGE52
  CU24 P5E_CPU1_P3_RX_DN<15> @T6G_MB_LIB.T6G(SCH_1):P5E_CPU1_P3_RX_DN(15)   I147 @T6G_MB_LIB.T6G(SCH_1):PAGE52
  CD36 P5E_CPU1_P3_TX_DP<0> @T6G_MB_LIB.T6G(SCH_1):P5E_CPU1_P3_TX_DP(0)   I147 @T6G_MB_LIB.T6G(SCH_1):PAGE52
  CD35 P5E_CPU1_P3_TX_DN<0> @T6G_MB_LIB.T6G(SCH_1):P5E_CPU1_P3_TX_DN(0)   I147 @T6G_MB_LIB.T6G(SCH_1):PAGE52
  CF36 P5E_CPU1_P3_TX_DP<1> @T6G_MB_LIB.T6G(SCH_1):P5E_CPU1_P3_TX_DP(1)   I147 @T6G_MB_LIB.T6G(SCH_1):PAGE52
  CF35 P5E_CPU1_P3_TX_DN<1> @T6G_MB_LIB.T6G(SCH_1):P5E_CPU1_P3_TX_DN(1)   I147 @T6G_MB_LIB.T6G(SCH_1):PAGE52
  CH36 P5E_CPU1_P3_TX_DP<2> @T6G_MB_LIB.T6G(SCH_1):P5E_CPU1_P3_TX_DP(2)   I147 @T6G_MB_LIB.T6G(SCH_1):PAGE52
  CH35 P5E_CPU1_P3_TX_DN<2> @T6G_MB_LIB.T6G(SCH_1):P5E_CPU1_P3_TX_DN(2)   I147 @T6G_MB_LIB.T6G(SCH_1):PAGE52
  CC33 P5E_CPU1_P3_TX_DP<3> @T6G_MB_LIB.T6G(SCH_1):P5E_CPU1_P3_TX_DP(3)   I147 @T6G_MB_LIB.T6G(SCH_1):PAGE52
  CC32 P5E_CPU1_P3_TX_DN<3> @T6G_MB_LIB.T6G(SCH_1):P5E_CPU1_P3_TX_DN(3)   I147 @T6G_MB_LIB.T6G(SCH_1):PAGE52
  CJ33 P5E_CPU1_P3_TX_DP<4> @T6G_MB_LIB.T6G(SCH_1):P5E_CPU1_P3_TX_DP(4)   I147 @T6G_MB_LIB.T6G(SCH_1):PAGE52
  CJ32 P5E_CPU1_P3_TX_DN<4> @T6G_MB_LIB.T6G(SCH_1):P5E_CPU1_P3_TX_DN(4)   I147 @T6G_MB_LIB.T6G(SCH_1):PAGE52
  CG33 P5E_CPU1_P3_TX_DP<5> @T6G_MB_LIB.T6G(SCH_1):P5E_CPU1_P3_TX_DP(5)   I147 @T6G_MB_LIB.T6G(SCH_1):PAGE52
  CG32 P5E_CPU1_P3_TX_DN<5> @T6G_MB_LIB.T6G(SCH_1):P5E_CPU1_P3_TX_DN(5)   I147 @T6G_MB_LIB.T6G(SCH_1):PAGE52
  CE33 P5E_CPU1_P3_TX_DP<6> @T6G_MB_LIB.T6G(SCH_1):P5E_CPU1_P3_TX_DP(6)   I147 @T6G_MB_LIB.T6G(SCH_1):PAGE52
  CE32 P5E_CPU1_P3_TX_DN<6> @T6G_MB_LIB.T6G(SCH_1):P5E_CPU1_P3_TX_DN(6)   I147 @T6G_MB_LIB.T6G(SCH_1):PAGE52
  CC30 P5E_CPU1_P3_TX_DP<7> @T6G_MB_LIB.T6G(SCH_1):P5E_CPU1_P3_TX_DP(7)   I147 @T6G_MB_LIB.T6G(SCH_1):PAGE52
  CC29 P5E_CPU1_P3_TX_DN<7> @T6G_MB_LIB.T6G(SCH_1):P5E_CPU1_P3_TX_DN(7)   I147 @T6G_MB_LIB.T6G(SCH_1):PAGE52
  CG30 P5E_CPU1_P3_TX_DP<8> @T6G_MB_LIB.T6G(SCH_1):P5E_CPU1_P3_TX_DP(8)   I147 @T6G_MB_LIB.T6G(SCH_1):PAGE52
  CG29 P5E_CPU1_P3_TX_DN<8> @T6G_MB_LIB.T6G(SCH_1):P5E_CPU1_P3_TX_DN(8)   I147 @T6G_MB_LIB.T6G(SCH_1):PAGE52
  CE30 P5E_CPU1_P3_TX_DP<9> @T6G_MB_LIB.T6G(SCH_1):P5E_CPU1_P3_TX_DP(9)   I147 @T6G_MB_LIB.T6G(SCH_1):PAGE52
  CE29 P5E_CPU1_P3_TX_DN<9> @T6G_MB_LIB.T6G(SCH_1):P5E_CPU1_P3_TX_DN(9)   I147 @T6G_MB_LIB.T6G(SCH_1):PAGE52
  CC27 P5E_CPU1_P3_TX_DP<10> @T6G_MB_LIB.T6G(SCH_1):P5E_CPU1_P3_TX_DP(10)   I147 @T6G_MB_LIB.T6G(SCH_1):PAGE52
  CC26 P5E_CPU1_P3_TX_DN<10> @T6G_MB_LIB.T6G(SCH_1):P5E_CPU1_P3_TX_DN(10)   I147 @T6G_MB_LIB.T6G(SCH_1):PAGE52
  CG27 P5E_CPU1_P3_TX_DP<11> @T6G_MB_LIB.T6G(SCH_1):P5E_CPU1_P3_TX_DP(11)   I147 @T6G_MB_LIB.T6G(SCH_1):PAGE52
  CG26 P5E_CPU1_P3_TX_DN<11> @T6G_MB_LIB.T6G(SCH_1):P5E_CPU1_P3_TX_DN(11)   I147 @T6G_MB_LIB.T6G(SCH_1):PAGE52
  CE27 P5E_CPU1_P3_TX_DP<12> @T6G_MB_LIB.T6G(SCH_1):P5E_CPU1_P3_TX_DP(12)   I147 @T6G_MB_LIB.T6G(SCH_1):PAGE52
  CE26 P5E_CPU1_P3_TX_DN<12> @T6G_MB_LIB.T6G(SCH_1):P5E_CPU1_P3_TX_DN(12)   I147 @T6G_MB_LIB.T6G(SCH_1):PAGE52
  CC24 P5E_CPU1_P3_TX_DP<13> @T6G_MB_LIB.T6G(SCH_1):P5E_CPU1_P3_TX_DP(13)   I147 @T6G_MB_LIB.T6G(SCH_1):PAGE52
  CC23 P5E_CPU1_P3_TX_DN<13> @T6G_MB_LIB.T6G(SCH_1):P5E_CPU1_P3_TX_DN(13)   I147 @T6G_MB_LIB.T6G(SCH_1):PAGE52
  CG24 P5E_CPU1_P3_TX_DP<14> @T6G_MB_LIB.T6G(SCH_1):P5E_CPU1_P3_TX_DP(14)   I147 @T6G_MB_LIB.T6G(SCH_1):PAGE52
  CG23 P5E_CPU1_P3_TX_DN<14> @T6G_MB_LIB.T6G(SCH_1):P5E_CPU1_P3_TX_DN(14)   I147 @T6G_MB_LIB.T6G(SCH_1):PAGE52
  CE24 P5E_CPU1_P3_TX_DP<15> @T6G_MB_LIB.T6G(SCH_1):P5E_CPU1_P3_TX_DP(15)   I147 @T6G_MB_LIB.T6G(SCH_1):PAGE52
  CE23 P5E_CPU1_P3_TX_DN<15> @T6G_MB_LIB.T6G(SCH_1):P5E_CPU1_P3_TX_DN(15)   I147 @T6G_MB_LIB.T6G(SCH_1):PAGE52
  DG47 P3E_CPU1_P4_RX_DN<2> @T6G_MB_LIB.T6G(SCH_1):P3E_CPU1_P4_RX_DN(2)   I145 @T6G_MB_LIB.T6G(SCH_1):PAGE53
  DG44 P3E_CPU1_P4_RX_DN<3> @T6G_MB_LIB.T6G(SCH_1):P3E_CPU1_P4_RX_DN(3)   I145 @T6G_MB_LIB.T6G(SCH_1):PAGE53
  DG48 P3E_CPU1_P4_RX_DP<2> @T6G_MB_LIB.T6G(SCH_1):P3E_CPU1_P4_RX_DP(2)   I145 @T6G_MB_LIB.T6G(SCH_1):PAGE53
  DG45 P3E_CPU1_P4_RX_DP<3> @T6G_MB_LIB.T6G(SCH_1):P3E_CPU1_P4_RX_DP(3)   I145 @T6G_MB_LIB.T6G(SCH_1):PAGE53
  DE46 P3E_CPU1_P4_TX_DN<2> @T6G_MB_LIB.T6G(SCH_1):P3E_CPU1_P4_TX_DN(2)   I145 @T6G_MB_LIB.T6G(SCH_1):PAGE53
  DE43 P3E_CPU1_P4_TX_DN<3> @T6G_MB_LIB.T6G(SCH_1):P3E_CPU1_P4_TX_DN(3)   I145 @T6G_MB_LIB.T6G(SCH_1):PAGE53
  DE47 P3E_CPU1_P4_TX_DP<2> @T6G_MB_LIB.T6G(SCH_1):P3E_CPU1_P4_TX_DP(2)   I145 @T6G_MB_LIB.T6G(SCH_1):PAGE53
  DE44 P3E_CPU1_P4_TX_DP<3> @T6G_MB_LIB.T6G(SCH_1):P3E_CPU1_P4_TX_DP(3)   I145 @T6G_MB_LIB.T6G(SCH_1):PAGE53
   E44 P3E_CPU1_P5_RX_DP<0> @T6G_MB_LIB.T6G(SCH_1):P3E_CPU1_P5_RX_DP(0)   I145 @T6G_MB_LIB.T6G(SCH_1):PAGE53
   E41 P3E_CPU1_P5_RX_DP<1> @T6G_MB_LIB.T6G(SCH_1):P3E_CPU1_P5_RX_DP(1)   I145 @T6G_MB_LIB.T6G(SCH_1):PAGE53
   E43 P3E_CPU1_P5_RX_DN<0> @T6G_MB_LIB.T6G(SCH_1):P3E_CPU1_P5_RX_DN(0)   I145 @T6G_MB_LIB.T6G(SCH_1):PAGE53
   E40 P3E_CPU1_P5_RX_DN<1> @T6G_MB_LIB.T6G(SCH_1):P3E_CPU1_P5_RX_DN(1)   I145 @T6G_MB_LIB.T6G(SCH_1):PAGE53
   C45 P3E_CPU1_P5_TX_DN<0> @T6G_MB_LIB.T6G(SCH_1):P3E_CPU1_P5_TX_DN(0)   I145 @T6G_MB_LIB.T6G(SCH_1):PAGE53
   C42 P3E_CPU1_P5_TX_DN<1> @T6G_MB_LIB.T6G(SCH_1):P3E_CPU1_P5_TX_DN(1)   I145 @T6G_MB_LIB.T6G(SCH_1):PAGE53
   C44 P3E_CPU1_P5_TX_DP<0> @T6G_MB_LIB.T6G(SCH_1):P3E_CPU1_P5_TX_DP(0)   I145 @T6G_MB_LIB.T6G(SCH_1):PAGE53
   C41 P3E_CPU1_P5_TX_DP<1> @T6G_MB_LIB.T6G(SCH_1):P3E_CPU1_P5_TX_DP(1)   I145 @T6G_MB_LIB.T6G(SCH_1):PAGE53
  DE53 P3E_CPU1_P4_TX_DP<0> @T6G_MB_LIB.T6G(SCH_1):P3E_CPU1_P4_TX_DP(0)   I145 @T6G_MB_LIB.T6G(SCH_1):PAGE53
  DE50 P3E_CPU1_P4_TX_DP<1> @T6G_MB_LIB.T6G(SCH_1):P3E_CPU1_P4_TX_DP(1)   I145 @T6G_MB_LIB.T6G(SCH_1):PAGE53
  DE52 P3E_CPU1_P4_TX_DN<0> @T6G_MB_LIB.T6G(SCH_1):P3E_CPU1_P4_TX_DN(0)   I145 @T6G_MB_LIB.T6G(SCH_1):PAGE53
  DG54 P3E_CPU1_P4_RX_DP<0> @T6G_MB_LIB.T6G(SCH_1):P3E_CPU1_P4_RX_DP(0)   I145 @T6G_MB_LIB.T6G(SCH_1):PAGE53
  DE49 P3E_CPU1_P4_TX_DN<1> @T6G_MB_LIB.T6G(SCH_1):P3E_CPU1_P4_TX_DN(1)   I145 @T6G_MB_LIB.T6G(SCH_1):PAGE53
  DG51 P3E_CPU1_P4_RX_DP<1> @T6G_MB_LIB.T6G(SCH_1):P3E_CPU1_P4_RX_DP(1)   I145 @T6G_MB_LIB.T6G(SCH_1):PAGE53
  DG53 P3E_CPU1_P4_RX_DN<0> @T6G_MB_LIB.T6G(SCH_1):P3E_CPU1_P4_RX_DN(0)   I145 @T6G_MB_LIB.T6G(SCH_1):PAGE53
  DG50 P3E_CPU1_P4_RX_DN<1> @T6G_MB_LIB.T6G(SCH_1):P3E_CPU1_P4_RX_DN(1)   I145 @T6G_MB_LIB.T6G(SCH_1):PAGE53
   E50     NC     NC   I145 @T6G_MB_LIB.T6G(SCH_1):PAGE53
   E49     NC     NC   I145 @T6G_MB_LIB.T6G(SCH_1):PAGE53
   E47 WAFL_CPU0_TX0_CPU1_RX1_DN @T6G_MB_LIB.T6G(SCH_1):WAFL_CPU0_TX0_CPU1_RX1_DN   I145 @T6G_MB_LIB.T6G(SCH_1):PAGE53
   E46 WAFL_CPU0_TX0_CPU1_RX1_DP @T6G_MB_LIB.T6G(SCH_1):WAFL_CPU0_TX0_CPU1_RX1_DP   I145 @T6G_MB_LIB.T6G(SCH_1):PAGE53
   C51     NC     NC   I145 @T6G_MB_LIB.T6G(SCH_1):PAGE53
   C50     NC     NC   I145 @T6G_MB_LIB.T6G(SCH_1):PAGE53
   C48 WAFL_CPU1_TX1_CPU0_RX0_DN @T6G_MB_LIB.T6G(SCH_1):WAFL_CPU1_TX1_CPU0_RX0_DN   I145 @T6G_MB_LIB.T6G(SCH_1):PAGE53
   C47 WAFL_CPU1_TX1_CPU0_RX0_DP @T6G_MB_LIB.T6G(SCH_1):WAFL_CPU1_TX1_CPU0_RX0_DP   I145 @T6G_MB_LIB.T6G(SCH_1):PAGE53
   A68 APML_CPU1_ALERT_N @T6G_MB_LIB.T6G(SCH_1):APML_CPU1_ALERT_N   I190 @T6G_MB_LIB.T6G(SCH_1):PAGE54
   B66 PRSNT_CPU1_N @T6G_MB_LIB.T6G(SCH_1):PRSNT_CPU1_N   I190 @T6G_MB_LIB.T6G(SCH_1):PAGE54
   C16 JTAG_CPU1_DBREQ_N @T6G_MB_LIB.T6G(SCH_1):JTAG_CPU1_DBREQ_N   I190 @T6G_MB_LIB.T6G(SCH_1):PAGE54
   A69 CPU1_PROCHOT_N @T6G_MB_LIB.T6G(SCH_1):CPU1_PROCHOT_N   I190 @T6G_MB_LIB.T6G(SCH_1):PAGE54
  DJ55 CPU1_SA0 @T6G_MB_LIB.T6G(SCH_1):CPU1_SA0   I190 @T6G_MB_LIB.T6G(SCH_1):PAGE54
  DJ71 SMB_APML_CPU1_SCL @T6G_MB_LIB.T6G(SCH_1):SMB_APML_CPU1_SCL   I190 @T6G_MB_LIB.T6G(SCH_1):PAGE54
  DH71 SMB_APML_CPU1_SDA @T6G_MB_LIB.T6G(SCH_1):SMB_APML_CPU1_SDA   I190 @T6G_MB_LIB.T6G(SCH_1):PAGE54
   C17 JTAG_CPU1_TDI @T6G_MB_LIB.T6G(SCH_1):JTAG_CPU1_TDI   I190 @T6G_MB_LIB.T6G(SCH_1):PAGE54
   C18 JTAG_CPU1_R_TDO @T6G_MB_LIB.T6G(SCH_1):JTAG_CPU1_R_TDO   I190 @T6G_MB_LIB.T6G(SCH_1):PAGE54
   DJ9 CPU1_THERMTRIP_N @T6G_MB_LIB.T6G(SCH_1):CPU1_THERMTRIP_N   I190 @T6G_MB_LIB.T6G(SCH_1):PAGE54
   A16 JTAG_CPU1_TMS @T6G_MB_LIB.T6G(SCH_1):JTAG_CPU1_TMS   I190 @T6G_MB_LIB.T6G(SCH_1):PAGE54
   A17 JTAG_CPU1_TRST_N @T6G_MB_LIB.T6G(SCH_1):JTAG_CPU1_TRST_N   I190 @T6G_MB_LIB.T6G(SCH_1):PAGE54
   C66 CPU1_XTRIG_R2_L4 @T6G_MB_LIB.T6G(SCH_1):CPU1_XTRIG_R2_L4   I190 @T6G_MB_LIB.T6G(SCH_1):PAGE54
   C65 CPU1_XTRIG_R2_L5 @T6G_MB_LIB.T6G(SCH_1):CPU1_XTRIG_R2_L5   I190 @T6G_MB_LIB.T6G(SCH_1):PAGE54
   A66 CPU1_XTRIG_R2_L6 @T6G_MB_LIB.T6G(SCH_1):CPU1_XTRIG_R2_L6   I190 @T6G_MB_LIB.T6G(SCH_1):PAGE54
   A65 CPU1_XTRIG_R2_L7 @T6G_MB_LIB.T6G(SCH_1):CPU1_XTRIG_R2_L7   I190 @T6G_MB_LIB.T6G(SCH_1):PAGE54
  DJ56 CPU1_SA1 @T6G_MB_LIB.T6G(SCH_1):CPU1_SA1   I190 @T6G_MB_LIB.T6G(SCH_1):PAGE54
   C70 CPU1_CORETYPE0 @T6G_MB_LIB.T6G(SCH_1):CPU1_CORETYPE0   I190 @T6G_MB_LIB.T6G(SCH_1):PAGE54
   B69 CPU1_CORETYPE1 @T6G_MB_LIB.T6G(SCH_1):CPU1_CORETYPE1   I190 @T6G_MB_LIB.T6G(SCH_1):PAGE54
   C68 CPU1_SP5R2 @T6G_MB_LIB.T6G(SCH_1):CPU1_SP5R2   I190 @T6G_MB_LIB.T6G(SCH_1):PAGE54
  DH73 CPU1_SP5R3 @T6G_MB_LIB.T6G(SCH_1):CPU1_SP5R3   I190 @T6G_MB_LIB.T6G(SCH_1):PAGE54
  DH10 CPU1_SP5R4 @T6G_MB_LIB.T6G(SCH_1):CPU1_SP5R4   I190 @T6G_MB_LIB.T6G(SCH_1):PAGE54
   C22 FM_P1_PCC0_N @T6G_MB_LIB.T6G(SCH_1):FM_P1_PCC0_N   I190 @T6G_MB_LIB.T6G(SCH_1):PAGE54
  DG72 FM_P1_PCC1_N @T6G_MB_LIB.T6G(SCH_1):FM_P1_PCC1_N   I190 @T6G_MB_LIB.T6G(SCH_1):PAGE54
   C32 NC_CPU1_AZ_BITCLK @T6G_MB_LIB.T6G(SCH_1):NC_CPU1_AZ_BITCLK   I190 @T6G_MB_LIB.T6G(SCH_1):PAGE54
   D32 NC_CPU1_AZ_SYNC @T6G_MB_LIB.T6G(SCH_1):NC_CPU1_AZ_SYNC   I190 @T6G_MB_LIB.T6G(SCH_1):PAGE54
   A22 SVID_PVDDCR_CPU0_P1_SVD @T6G_MB_LIB.T6G(SCH_1):SVID_PVDDCR_CPU0_P1_SVD   I190 @T6G_MB_LIB.T6G(SCH_1):PAGE54
   B21 SVID_PVDDCR_CPU0_P1_SVTO @T6G_MB_LIB.T6G(SCH_1):SVID_PVDDCR_CPU0_P1_SVTO   I190 @T6G_MB_LIB.T6G(SCH_1):PAGE54
  DH72 SVID_PVDDCR_CPU1_P1_SVD @T6G_MB_LIB.T6G(SCH_1):SVID_PVDDCR_CPU1_P1_SVD   I190 @T6G_MB_LIB.T6G(SCH_1):PAGE54
   A23 SVID_PVDDCR_CPU0_P1_SVC @T6G_MB_LIB.T6G(SCH_1):SVID_PVDDCR_CPU0_P1_SVC   I190 @T6G_MB_LIB.T6G(SCH_1):PAGE54
  DG73 SVID_PVDDCR_CPU1_P1_SVTO @T6G_MB_LIB.T6G(SCH_1):SVID_PVDDCR_CPU1_P1_SVTO   I190 @T6G_MB_LIB.T6G(SCH_1):PAGE54
  DJ72 SVID_PVDDCR_CPU1_P1_SVC @T6G_MB_LIB.T6G(SCH_1):SVID_PVDDCR_CPU1_P1_SVC   I190 @T6G_MB_LIB.T6G(SCH_1):PAGE54
  DG35 TP_CPU1_UART0_RX @T6G_MB_LIB.T6G(SCH_1):TP_CPU1_UART0_RX   I190 @T6G_MB_LIB.T6G(SCH_1):PAGE54
  DF34 TP_CPU1_UART0_RTS_N @T6G_MB_LIB.T6G(SCH_1):TP_CPU1_UART0_RTS_N   I190 @T6G_MB_LIB.T6G(SCH_1):PAGE54
  DG34 TP_CPU1_UART0_INTR @T6G_MB_LIB.T6G(SCH_1):TP_CPU1_UART0_INTR   I190 @T6G_MB_LIB.T6G(SCH_1):PAGE54
  DJ34 TP_CPU1_UART0_TX @T6G_MB_LIB.T6G(SCH_1):TP_CPU1_UART0_TX   I190 @T6G_MB_LIB.T6G(SCH_1):PAGE54
  DJ33 TP_CPU1_UART0_CTS_N @T6G_MB_LIB.T6G(SCH_1):TP_CPU1_UART0_CTS_N   I190 @T6G_MB_LIB.T6G(SCH_1):PAGE54
   A33 NC_CPU1_AZ_SDIN2 @T6G_MB_LIB.T6G(SCH_1):NC_CPU1_AZ_SDIN2   I190 @T6G_MB_LIB.T6G(SCH_1):PAGE54
   A32 NC_CPU1_AZ_SDOUT @T6G_MB_LIB.T6G(SCH_1):NC_CPU1_AZ_SDOUT   I190 @T6G_MB_LIB.T6G(SCH_1):PAGE54
   A34 NC_CPU1_AZ_RST_N @T6G_MB_LIB.T6G(SCH_1):NC_CPU1_AZ_RST_N   I190 @T6G_MB_LIB.T6G(SCH_1):PAGE54
   C33 NC_CPU1_AZ_SDIN0 @T6G_MB_LIB.T6G(SCH_1):NC_CPU1_AZ_SDIN0   I190 @T6G_MB_LIB.T6G(SCH_1):PAGE54
   D33 NC_CPU1_AZ_SDIN1 @T6G_MB_LIB.T6G(SCH_1):NC_CPU1_AZ_SDIN1   I190 @T6G_MB_LIB.T6G(SCH_1):PAGE54
   C19 CPU1_SP5R1 @T6G_MB_LIB.T6G(SCH_1):CPU1_SP5R1   I190 @T6G_MB_LIB.T6G(SCH_1):PAGE54
   B17 JTAG_CPU1_TCK @T6G_MB_LIB.T6G(SCH_1):JTAG_CPU1_TCK   I190 @T6G_MB_LIB.T6G(SCH_1):PAGE54
   DH8    GND @T6G_MB_LIB.T6G(SCH_1):GND   I190 @T6G_MB_LIB.T6G(SCH_1):PAGE54
  DH33 TP_CPU1_UART1_RX @T6G_MB_LIB.T6G(SCH_1):TP_CPU1_UART1_RX   I190 @T6G_MB_LIB.T6G(SCH_1):PAGE54
  DJ32     NC     NC   I190 @T6G_MB_LIB.T6G(SCH_1):PAGE54
    C3 VSENSE_VSS_SENSE_A_P1 @T6G_MB_LIB.T6G(SCH_1):VSENSE_VSS_SENSE_A_P1   I190 @T6G_MB_LIB.T6G(SCH_1):PAGE54
  BR54 VSENSE_VSS_SENSE_B_P1 @T6G_MB_LIB.T6G(SCH_1):VSENSE_VSS_SENSE_B_P1   I190 @T6G_MB_LIB.T6G(SCH_1):PAGE54
   DJ3 VSENSE_VSS_SENSE_C_P1 @T6G_MB_LIB.T6G(SCH_1):VSENSE_VSS_SENSE_C_P1   I190 @T6G_MB_LIB.T6G(SCH_1):PAGE54
   B73 VSENSE_PVDD18_S5_P1_DN @T6G_MB_LIB.T6G(SCH_1):VSENSE_PVDD18_S5_P1_DN   I190 @T6G_MB_LIB.T6G(SCH_1):PAGE54
  BR53 VSENSE_PVDDIO_P1_DP @T6G_MB_LIB.T6G(SCH_1):VSENSE_PVDDIO_P1_DP   I190 @T6G_MB_LIB.T6G(SCH_1):PAGE54
   DH3 VSENSE_PVDD11_S3_P1_DP @T6G_MB_LIB.T6G(SCH_1):VSENSE_PVDD11_S3_P1_DP   I190 @T6G_MB_LIB.T6G(SCH_1):PAGE54
   C74 VSENSE_PVDD18_S5_P1_DP @T6G_MB_LIB.T6G(SCH_1):VSENSE_PVDD18_S5_P1_DP   I190 @T6G_MB_LIB.T6G(SCH_1):PAGE54
  BP53 TP_VSENSE_PVDD33_S5_P1 @T6G_MB_LIB.T6G(SCH_1):TP_VSENSE_PVDD33_S5_P1   I190 @T6G_MB_LIB.T6G(SCH_1):PAGE54
    B3 VSENSE_PVDDCR_SOC_P1_DP @T6G_MB_LIB.T6G(SCH_1):VSENSE_PVDDCR_SOC_P1_DP   I190 @T6G_MB_LIB.T6G(SCH_1):PAGE54
   DG3 VSENSE_PVDDCR_CPU1_P1_DP @T6G_MB_LIB.T6G(SCH_1):VSENSE_PVDDCR_CPU1_P1_DP   I190 @T6G_MB_LIB.T6G(SCH_1):PAGE54
    C2 VSENSE_PVDDCR_CPU0_P1_DP @T6G_MB_LIB.T6G(SCH_1):VSENSE_PVDDCR_CPU0_P1_DP   I190 @T6G_MB_LIB.T6G(SCH_1):PAGE54
  AA23 TP_CPU1_TEST6_X3D4 @T6G_MB_LIB.T6G(SCH_1):TP_CPU1_TEST6_X3D4   I190 @T6G_MB_LIB.T6G(SCH_1):PAGE54
  CJ30 TP_CPU1_TEST6_CCD1 @T6G_MB_LIB.T6G(SCH_1):TP_CPU1_TEST6_CCD1   I190 @T6G_MB_LIB.T6G(SCH_1):PAGE54
  AA51 TP_CPU1_TEST5_CCD0 @T6G_MB_LIB.T6G(SCH_1):TP_CPU1_TEST5_CCD0   I190 @T6G_MB_LIB.T6G(SCH_1):PAGE54
  CJ53 TP_CPU1_TEST6_X3D5 @T6G_MB_LIB.T6G(SCH_1):TP_CPU1_TEST6_X3D5   I190 @T6G_MB_LIB.T6G(SCH_1):PAGE54
  CJ46 TP_CPU1_TEST6_CCD2 @T6G_MB_LIB.T6G(SCH_1):TP_CPU1_TEST6_CCD2   I190 @T6G_MB_LIB.T6G(SCH_1):PAGE54
  CJ27 TP_CPU1_TEST5_CCD1 @T6G_MB_LIB.T6G(SCH_1):TP_CPU1_TEST5_CCD1   I190 @T6G_MB_LIB.T6G(SCH_1):PAGE54
  AA50 TP_CPU1_TEST4_CCD0 @T6G_MB_LIB.T6G(SCH_1):TP_CPU1_TEST4_CCD0   I190 @T6G_MB_LIB.T6G(SCH_1):PAGE54
   Y46 TP_CPU1_TEST6_CCD3 @T6G_MB_LIB.T6G(SCH_1):TP_CPU1_TEST6_CCD3   I190 @T6G_MB_LIB.T6G(SCH_1):PAGE54
  CJ49 TP_CPU1_TEST5_CCD2 @T6G_MB_LIB.T6G(SCH_1):TP_CPU1_TEST5_CCD2   I190 @T6G_MB_LIB.T6G(SCH_1):PAGE54
  CJ28 TP_CPU1_TEST4_CCD1 @T6G_MB_LIB.T6G(SCH_1):TP_CPU1_TEST4_CCD1   I190 @T6G_MB_LIB.T6G(SCH_1):PAGE54
   Y30 TP_CPU1_TEST5_CCD3 @T6G_MB_LIB.T6G(SCH_1):TP_CPU1_TEST5_CCD3   I190 @T6G_MB_LIB.T6G(SCH_1):PAGE54
  AA25 TP_CPU1_TEST4_IOD @T6G_MB_LIB.T6G(SCH_1):TP_CPU1_TEST4_IOD   I190 @T6G_MB_LIB.T6G(SCH_1):PAGE54
  CJ48 TP_CPU1_TEST4_CCD2 @T6G_MB_LIB.T6G(SCH_1):TP_CPU1_TEST4_CCD2   I190 @T6G_MB_LIB.T6G(SCH_1):PAGE54
  AA24 TP_CPU1_TEST5_IOD @T6G_MB_LIB.T6G(SCH_1):TP_CPU1_TEST5_IOD   I190 @T6G_MB_LIB.T6G(SCH_1):PAGE54
  AA53 TP_CPU1_TEST5_CCD4 @T6G_MB_LIB.T6G(SCH_1):TP_CPU1_TEST5_CCD4   I190 @T6G_MB_LIB.T6G(SCH_1):PAGE54
  AA30 TP_CPU1_TEST4_CCD3 @T6G_MB_LIB.T6G(SCH_1):TP_CPU1_TEST4_CCD3   I190 @T6G_MB_LIB.T6G(SCH_1):PAGE54
  AA49 TP_CPU1_TEST6_IOD @T6G_MB_LIB.T6G(SCH_1):TP_CPU1_TEST6_IOD   I190 @T6G_MB_LIB.T6G(SCH_1):PAGE54
  CJ25 TP_CPU1_TEST5_CCD5 @T6G_MB_LIB.T6G(SCH_1):TP_CPU1_TEST5_CCD5   I190 @T6G_MB_LIB.T6G(SCH_1):PAGE54
  AA52 TP_CPU1_TEST4_CCD4 @T6G_MB_LIB.T6G(SCH_1):TP_CPU1_TEST4_CCD4   I190 @T6G_MB_LIB.T6G(SCH_1):PAGE54
  CJ51 TP_CPU1_TEST5_CCD6 @T6G_MB_LIB.T6G(SCH_1):TP_CPU1_TEST5_CCD6   I190 @T6G_MB_LIB.T6G(SCH_1):PAGE54
  CJ26 TP_CPU1_TEST4_CCD5 @T6G_MB_LIB.T6G(SCH_1):TP_CPU1_TEST4_CCD5   I190 @T6G_MB_LIB.T6G(SCH_1):PAGE54
  AA26 TP_CPU1_TEST5_CCD7 @T6G_MB_LIB.T6G(SCH_1):TP_CPU1_TEST5_CCD7   I190 @T6G_MB_LIB.T6G(SCH_1):PAGE54
  CJ50 TP_CPU1_TEST4_CCD6 @T6G_MB_LIB.T6G(SCH_1):TP_CPU1_TEST4_CCD6   I190 @T6G_MB_LIB.T6G(SCH_1):PAGE54
   B60 TP_CPU1_TEST47_CCD0 @T6G_MB_LIB.T6G(SCH_1):TP_CPU1_TEST47_CCD0   I190 @T6G_MB_LIB.T6G(SCH_1):PAGE54
   Y47 TP_CPU1_TEST5_CCD8 @T6G_MB_LIB.T6G(SCH_1):TP_CPU1_TEST5_CCD8   I190 @T6G_MB_LIB.T6G(SCH_1):PAGE54
   B61 TP_CPU1_TEST50_IOD @T6G_MB_LIB.T6G(SCH_1):TP_CPU1_TEST50_IOD   I190 @T6G_MB_LIB.T6G(SCH_1):PAGE54
  AA27 TP_CPU1_TEST4_CCD7 @T6G_MB_LIB.T6G(SCH_1):TP_CPU1_TEST4_CCD7   I190 @T6G_MB_LIB.T6G(SCH_1):PAGE54
  CJ24 TP_CPU1_TEST47_CCD1 @T6G_MB_LIB.T6G(SCH_1):TP_CPU1_TEST47_CCD1   I190 @T6G_MB_LIB.T6G(SCH_1):PAGE54
  CK29 TP_CPU1_TEST5_CCD9 @T6G_MB_LIB.T6G(SCH_1):TP_CPU1_TEST5_CCD9   I190 @T6G_MB_LIB.T6G(SCH_1):PAGE54
  AA48 TP_CPU1_TEST4_CCD8 @T6G_MB_LIB.T6G(SCH_1):TP_CPU1_TEST4_CCD8   I190 @T6G_MB_LIB.T6G(SCH_1):PAGE54
  CK46 TP_CPU1_TEST47_CCD2 @T6G_MB_LIB.T6G(SCH_1):TP_CPU1_TEST47_CCD2   I190 @T6G_MB_LIB.T6G(SCH_1):PAGE54
  CJ47 TP_CPU1_TEST4_CCD10 @T6G_MB_LIB.T6G(SCH_1):TP_CPU1_TEST4_CCD10   I190 @T6G_MB_LIB.T6G(SCH_1):PAGE54
  CK30 TP_CPU1_TEST4_CCD9 @T6G_MB_LIB.T6G(SCH_1):TP_CPU1_TEST4_CCD9   I190 @T6G_MB_LIB.T6G(SCH_1):PAGE54
  CK47 TP_CPU1_TEST5_CCD10 @T6G_MB_LIB.T6G(SCH_1):TP_CPU1_TEST5_CCD10   I190 @T6G_MB_LIB.T6G(SCH_1):PAGE54
  AA28 TP_CPU1_TEST4_CCD11 @T6G_MB_LIB.T6G(SCH_1):TP_CPU1_TEST4_CCD11   I190 @T6G_MB_LIB.T6G(SCH_1):PAGE54
   Y29 TP_CPU1_TEST5_CCD11 @T6G_MB_LIB.T6G(SCH_1):TP_CPU1_TEST5_CCD11   I190 @T6G_MB_LIB.T6G(SCH_1):PAGE54
  AA47 TP_CPU1_TEST6_X3D0 @T6G_MB_LIB.T6G(SCH_1):TP_CPU1_TEST6_X3D0   I190 @T6G_MB_LIB.T6G(SCH_1):PAGE54
   B58 TP_CPU1_TEST47_IOD0 @T6G_MB_LIB.T6G(SCH_1):TP_CPU1_TEST47_IOD0   I190 @T6G_MB_LIB.T6G(SCH_1):PAGE54
  CJ29 TP_CPU1_TEST6_X3D1 @T6G_MB_LIB.T6G(SCH_1):TP_CPU1_TEST6_X3D1   I190 @T6G_MB_LIB.T6G(SCH_1):PAGE54
    D7 TP_CPU1_TEST47_IOD1 @T6G_MB_LIB.T6G(SCH_1):TP_CPU1_TEST47_IOD1   I190 @T6G_MB_LIB.T6G(SCH_1):PAGE54
  AA29 TP_CPU1_TEST6_X3D2 @T6G_MB_LIB.T6G(SCH_1):TP_CPU1_TEST6_X3D2   I190 @T6G_MB_LIB.T6G(SCH_1):PAGE54
  CJ52 TP_CPU1_TEST6_X3D3 @T6G_MB_LIB.T6G(SCH_1):TP_CPU1_TEST6_X3D3   I190 @T6G_MB_LIB.T6G(SCH_1):PAGE54
  AA46 TP_CPU1_TEST6_CCD0 @T6G_MB_LIB.T6G(SCH_1):TP_CPU1_TEST6_CCD0   I190 @T6G_MB_LIB.T6G(SCH_1):PAGE54
   E32 TP_CPU1_TEST47_CCD3 @T6G_MB_LIB.T6G(SCH_1):TP_CPU1_TEST47_CCD3   I190 @T6G_MB_LIB.T6G(SCH_1):PAGE54
   W31 TP_CPU1_TEST41_IOD @T6G_MB_LIB.T6G(SCH_1):TP_CPU1_TEST41_IOD   I190 @T6G_MB_LIB.T6G(SCH_1):PAGE54
   C63 CPU1_BP0 @T6G_MB_LIB.T6G(SCH_1):CPU1_BP0   I190 @T6G_MB_LIB.T6G(SCH_1):PAGE54
   C62 CPU1_BP1 @T6G_MB_LIB.T6G(SCH_1):CPU1_BP1   I190 @T6G_MB_LIB.T6G(SCH_1):PAGE54
   A63 CPU1_BP2 @T6G_MB_LIB.T6G(SCH_1):CPU1_BP2   I190 @T6G_MB_LIB.T6G(SCH_1):PAGE54
   A62 CPU1_BP3 @T6G_MB_LIB.T6G(SCH_1):CPU1_BP3   I190 @T6G_MB_LIB.T6G(SCH_1):PAGE54
   D68 CPU1_CORETYPE2 @T6G_MB_LIB.T6G(SCH_1):CPU1_CORETYPE2   I190 @T6G_MB_LIB.T6G(SCH_1):PAGE54
   DJ8 CPU1_PWR_GD_IN @T6G_MB_LIB.T6G(SCH_1):CPU1_PWR_GD_IN   I182 @T6G_MB_LIB.T6G(SCH_1):PAGE55
  DG10 RST_CPU1_RSMRST_N @T6G_MB_LIB.T6G(SCH_1):RST_CPU1_RSMRST_N   I182 @T6G_MB_LIB.T6G(SCH_1):PAGE55
   DJ5 CPU1_SLP_S3_N @T6G_MB_LIB.T6G(SCH_1):CPU1_SLP_S3_N   I182 @T6G_MB_LIB.T6G(SCH_1):PAGE55
   DG4 CPU1_SLP_S5_N @T6G_MB_LIB.T6G(SCH_1):CPU1_SLP_S5_N   I182 @T6G_MB_LIB.T6G(SCH_1):PAGE55
   DH6 RST_CPU1_SYS_N @T6G_MB_LIB.T6G(SCH_1):RST_CPU1_SYS_N   I182 @T6G_MB_LIB.T6G(SCH_1):PAGE55
  DJ10 IRQ_WAKE_N @T6G_MB_LIB.T6G(SCH_1):IRQ_WAKE_N   I182 @T6G_MB_LIB.T6G(SCH_1):PAGE55
  DJ14 XTAL_CPU1_X32K_X1 @T6G_MB_LIB.T6G(SCH_1):XTAL_CPU1_X32K_X1   I182 @T6G_MB_LIB.T6G(SCH_1):PAGE55
  DJ13 XTAL_CPU1_X32K_X2 @T6G_MB_LIB.T6G(SCH_1):XTAL_CPU1_X32K_X2   I182 @T6G_MB_LIB.T6G(SCH_1):PAGE55
  DJ17 XTAL_CPU1_X48M_X1 @T6G_MB_LIB.T6G(SCH_1):XTAL_CPU1_X48M_X1   I182 @T6G_MB_LIB.T6G(SCH_1):PAGE55
  DJ16 XTAL_CPU1_X48M_X2 @T6G_MB_LIB.T6G(SCH_1):XTAL_CPU1_X48M_X2   I182 @T6G_MB_LIB.T6G(SCH_1):PAGE55
   DH7 NC_CPU1_PWR_BTN_N @T6G_MB_LIB.T6G(SCH_1):NC_CPU1_PWR_BTN_N   I182 @T6G_MB_LIB.T6G(SCH_1):PAGE55
   B64 CPU1_NV_SAVE_N @T6G_MB_LIB.T6G(SCH_1):CPU1_NV_SAVE_N   I182 @T6G_MB_LIB.T6G(SCH_1):PAGE55
   B63 CPU1_FORCE_SELFREFRESH @T6G_MB_LIB.T6G(SCH_1):CPU1_FORCE_SELFREFRESH   I182 @T6G_MB_LIB.T6G(SCH_1):PAGE55
   DH9 CLK_CPU1_RTCCLK @T6G_MB_LIB.T6G(SCH_1):CLK_CPU1_RTCCLK   I182 @T6G_MB_LIB.T6G(SCH_1):PAGE55
    C9 CLK_100M_CPU1_CLK05_R_DN @T6G_MB_LIB.T6G(SCH_1):CLK_100M_CPU1_CLK05_R_DN   I182 @T6G_MB_LIB.T6G(SCH_1):PAGE55
  DJ50     NC     NC   I182 @T6G_MB_LIB.T6G(SCH_1):PAGE55
   C12 CLK_100M_CPU1_CLK04_R_DN @T6G_MB_LIB.T6G(SCH_1):CLK_100M_CPU1_CLK04_R_DN   I182 @T6G_MB_LIB.T6G(SCH_1):PAGE55
  DJ47     NC     NC   I182 @T6G_MB_LIB.T6G(SCH_1):PAGE55
    B9 CLK_100M_CPU1_CLK05_R_DP @T6G_MB_LIB.T6G(SCH_1):CLK_100M_CPU1_CLK05_R_DP   I182 @T6G_MB_LIB.T6G(SCH_1):PAGE55
   A11 CLK_100M_CPU1_CLK03_R_DN @T6G_MB_LIB.T6G(SCH_1):CLK_100M_CPU1_CLK03_R_DN   I182 @T6G_MB_LIB.T6G(SCH_1):PAGE55
  DJ51     NC     NC   I182 @T6G_MB_LIB.T6G(SCH_1):PAGE55
  DJ54 CLK_100M_CPU1_CLK13_R_DN @T6G_MB_LIB.T6G(SCH_1):CLK_100M_CPU1_CLK13_R_DN   I182 @T6G_MB_LIB.T6G(SCH_1):PAGE55
   B12 CLK_100M_CPU1_CLK04_R_DP @T6G_MB_LIB.T6G(SCH_1):CLK_100M_CPU1_CLK04_R_DP   I182 @T6G_MB_LIB.T6G(SCH_1):PAGE55
    C6 CLK_100M_CPU1_CLK02_R_DN @T6G_MB_LIB.T6G(SCH_1):CLK_100M_CPU1_CLK02_R_DN   I182 @T6G_MB_LIB.T6G(SCH_1):PAGE55
  DJ48     NC     NC   I182 @T6G_MB_LIB.T6G(SCH_1):PAGE55
  DJ44 CLK_100M_CPU1_CLK12_R_DN @T6G_MB_LIB.T6G(SCH_1):CLK_100M_CPU1_CLK12_R_DN   I182 @T6G_MB_LIB.T6G(SCH_1):PAGE55
   A10 CLK_100M_CPU1_CLK03_R_DP @T6G_MB_LIB.T6G(SCH_1):CLK_100M_CPU1_CLK03_R_DP   I182 @T6G_MB_LIB.T6G(SCH_1):PAGE55
    A7 CLK_100M_CPU1_CLK01_R_DN @T6G_MB_LIB.T6G(SCH_1):CLK_100M_CPU1_CLK01_R_DN   I182 @T6G_MB_LIB.T6G(SCH_1):PAGE55
  DJ53 CLK_100M_CPU1_CLK13_R_DP @T6G_MB_LIB.T6G(SCH_1):CLK_100M_CPU1_CLK13_R_DP   I182 @T6G_MB_LIB.T6G(SCH_1):PAGE55
  DJ42 CLK_100M_CPU1_CLK11_R_DN @T6G_MB_LIB.T6G(SCH_1):CLK_100M_CPU1_CLK11_R_DN   I182 @T6G_MB_LIB.T6G(SCH_1):PAGE55
    B6 CLK_100M_CPU1_CLK02_R_DP @T6G_MB_LIB.T6G(SCH_1):CLK_100M_CPU1_CLK02_R_DP   I182 @T6G_MB_LIB.T6G(SCH_1):PAGE55
  DJ45 CLK_100M_CPU1_CLK12_R_DP @T6G_MB_LIB.T6G(SCH_1):CLK_100M_CPU1_CLK12_R_DP   I182 @T6G_MB_LIB.T6G(SCH_1):PAGE55
    A8 CLK_100M_CPU1_CLK01_R_DP @T6G_MB_LIB.T6G(SCH_1):CLK_100M_CPU1_CLK01_R_DP   I182 @T6G_MB_LIB.T6G(SCH_1):PAGE55
  DJ41 CLK_100M_CPU1_CLK11_R_DP @T6G_MB_LIB.T6G(SCH_1):CLK_100M_CPU1_CLK11_R_DP   I182 @T6G_MB_LIB.T6G(SCH_1):PAGE55
  DF36     NC     NC   I182 @T6G_MB_LIB.T6G(SCH_1):PAGE55
  DE36 CPU1_SPD_HOST_CTRL_R_N @T6G_MB_LIB.T6G(SCH_1):CPU1_SPD_HOST_CTRL_R_N   I182 @T6G_MB_LIB.T6G(SCH_1):PAGE55
  DG36 RST_CPU1_PERST1_N @T6G_MB_LIB.T6G(SCH_1):RST_CPU1_PERST1_N   I182 @T6G_MB_LIB.T6G(SCH_1):PAGE55
   B15     NC     NC   I182 @T6G_MB_LIB.T6G(SCH_1):PAGE55
   B72     NC     NC   I182 @T6G_MB_LIB.T6G(SCH_1):PAGE55
   D15     NC     NC   I182 @T6G_MB_LIB.T6G(SCH_1):PAGE55
    B4     NC     NC   I182 @T6G_MB_LIB.T6G(SCH_1):PAGE55
   A13     NC     NC   I182 @T6G_MB_LIB.T6G(SCH_1):PAGE55
   A14     NC     NC   I182 @T6G_MB_LIB.T6G(SCH_1):PAGE55
   D18 RST_CPU1_PERST0_N @T6G_MB_LIB.T6G(SCH_1):RST_CPU1_PERST0_N   I182 @T6G_MB_LIB.T6G(SCH_1):PAGE55
  DH16 FM_BMC_TPM_PRES_N @T6G_MB_LIB.T6G(SCH_1):FM_BMC_TPM_PRES_N   I182 @T6G_MB_LIB.T6G(SCH_1):PAGE55
   B71 I3C_0_SPD_DDRAF_CPU1_R_SDA @T6G_MB_LIB.T6G(SCH_1):I3C_0_SPD_DDRAF_CPU1_R_SDA   I182 @T6G_MB_LIB.T6G(SCH_1):PAGE55
    C7 I3C_1_SPD_DDRGL_CPU1_R_SCL @T6G_MB_LIB.T6G(SCH_1):I3C_1_SPD_DDRGL_CPU1_R_SCL   I182 @T6G_MB_LIB.T6G(SCH_1):PAGE55
   C72     NC     NC   I182 @T6G_MB_LIB.T6G(SCH_1):PAGE55
   A71 I3C_0_SPD_DDRAF_CPU1_R_SCL @T6G_MB_LIB.T6G(SCH_1):I3C_0_SPD_DDRAF_CPU1_R_SCL   I182 @T6G_MB_LIB.T6G(SCH_1):PAGE55
   B16     NC     NC   I182 @T6G_MB_LIB.T6G(SCH_1):PAGE55
  DH36 CPU1_PWRGD_OUT @T6G_MB_LIB.T6G(SCH_1):CPU1_PWRGD_OUT   I182 @T6G_MB_LIB.T6G(SCH_1):PAGE55
  DH15 FM_CPU1_BMC_RST_N @T6G_MB_LIB.T6G(SCH_1):FM_CPU1_BMC_RST_N   I182 @T6G_MB_LIB.T6G(SCH_1):PAGE55
    A5 I3C_1_SPD_DDRGL_CPU1_R_SDA @T6G_MB_LIB.T6G(SCH_1):I3C_1_SPD_DDRGL_CPU1_R_SDA   I182 @T6G_MB_LIB.T6G(SCH_1):PAGE55
    A4     NC     NC   I182 @T6G_MB_LIB.T6G(SCH_1):PAGE55
  DG12     NC     NC   I182 @T6G_MB_LIB.T6G(SCH_1):PAGE55
  DH12     NC     NC   I182 @T6G_MB_LIB.T6G(SCH_1):PAGE55
  DJ21     NC     NC   I182 @T6G_MB_LIB.T6G(SCH_1):PAGE55
  DJ20     NC     NC   I182 @T6G_MB_LIB.T6G(SCH_1):PAGE55
  DJ11 CPU1_SMERR_N @T6G_MB_LIB.T6G(SCH_1):CPU1_SMERR_N   I182 @T6G_MB_LIB.T6G(SCH_1):PAGE55
   A19 CLK_100M_REF_IN_DP @T6G_MB_LIB.T6G(SCH_1):CLK_100M_REF_IN_DP   I182 @T6G_MB_LIB.T6G(SCH_1):PAGE55
   A20 CLK_100M_REF_IN_DN @T6G_MB_LIB.T6G(SCH_1):CLK_100M_REF_IN_DN   I182 @T6G_MB_LIB.T6G(SCH_1):PAGE55
   B67 RST_CPU1_RESETL_N @T6G_MB_LIB.T6G(SCH_1):RST_CPU1_RESETL_N   I182 @T6G_MB_LIB.T6G(SCH_1):PAGE55
  DH30     NC     NC   I182 @T6G_MB_LIB.T6G(SCH_1):PAGE55
  DE30     NC     NC   I182 @T6G_MB_LIB.T6G(SCH_1):PAGE55
  DF31     NC     NC   I182 @T6G_MB_LIB.T6G(SCH_1):PAGE55
  DG31     NC     NC   I182 @T6G_MB_LIB.T6G(SCH_1):PAGE55
  DG32     NC     NC   I182 @T6G_MB_LIB.T6G(SCH_1):PAGE55
  DG11     NC     NC   I182 @T6G_MB_LIB.T6G(SCH_1):PAGE55
  DF33 TP_SLOT2_BUF_SKU_ID0 @T6G_MB_LIB.T6G(SCH_1):TP_SLOT2_BUF_SKU_ID0   I182 @T6G_MB_LIB.T6G(SCH_1):PAGE55
  DJ29     NC     NC   I182 @T6G_MB_LIB.T6G(SCH_1):PAGE55
  DE32 TP_SLOT2_BUF_SKU_ID1 @T6G_MB_LIB.T6G(SCH_1):TP_SLOT2_BUF_SKU_ID1   I182 @T6G_MB_LIB.T6G(SCH_1):PAGE55
  DJ35 INT_CPU1_HP_UBM_N @T6G_MB_LIB.T6G(SCH_1):INT_CPU1_HP_UBM_N   I182 @T6G_MB_LIB.T6G(SCH_1):PAGE55
  DF40 IRQ_CPU_BMC_NMI_N @T6G_MB_LIB.T6G(SCH_1):IRQ_CPU_BMC_NMI_N   I182 @T6G_MB_LIB.T6G(SCH_1):PAGE55
  DE40 FM_BMC_READY_N @T6G_MB_LIB.T6G(SCH_1):FM_BMC_READY_N   I182 @T6G_MB_LIB.T6G(SCH_1):PAGE55
   D69 PWRGD_CPU1_PWROK @T6G_MB_LIB.T6G(SCH_1):PWRGD_CPU1_PWROK   I182 @T6G_MB_LIB.T6G(SCH_1):PAGE55
   C14     NC     NC   I182 @T6G_MB_LIB.T6G(SCH_1):PAGE55
   D14 SMB_CPU1_SEC_SDA @T6G_MB_LIB.T6G(SCH_1):SMB_CPU1_SEC_SDA   I182 @T6G_MB_LIB.T6G(SCH_1):PAGE55
   B14 SMB_CPU1_SEC_SCL @T6G_MB_LIB.T6G(SCH_1):SMB_CPU1_SEC_SCL   I182 @T6G_MB_LIB.T6G(SCH_1):PAGE55
  DJ31 CPU1_NMI_SYNC_FLOOD_N @T6G_MB_LIB.T6G(SCH_1):CPU1_NMI_SYNC_FLOOD_N   I182 @T6G_MB_LIB.T6G(SCH_1):PAGE55
   DH4     NC     NC   I182 @T6G_MB_LIB.T6G(SCH_1):PAGE55
   A25 NC_CPU1_USB2_USB00_DN @T6G_MB_LIB.T6G(SCH_1):NC_CPU1_USB2_USB00_DN     I8 @T6G_MB_LIB.T6G(SCH_1):PAGE56
   A26 NC_CPU1_USB2_USB00_DP @T6G_MB_LIB.T6G(SCH_1):NC_CPU1_USB2_USB00_DP     I8 @T6G_MB_LIB.T6G(SCH_1):PAGE56
   E26 NC_CPU1_USB3_USB00_RXN @T6G_MB_LIB.T6G(SCH_1):NC_CPU1_USB3_USB00_RXN     I8 @T6G_MB_LIB.T6G(SCH_1):PAGE56
   E27 NC_CPU1_USB3_USB00_RXP @T6G_MB_LIB.T6G(SCH_1):NC_CPU1_USB3_USB00_RXP     I8 @T6G_MB_LIB.T6G(SCH_1):PAGE56
   C26 NC_CPU1_USB3_USB00_TXP @T6G_MB_LIB.T6G(SCH_1):NC_CPU1_USB3_USB00_TXP     I8 @T6G_MB_LIB.T6G(SCH_1):PAGE56
   C25 NC_CPU1_USB3_USB00_TXN @T6G_MB_LIB.T6G(SCH_1):NC_CPU1_USB3_USB00_TXN     I8 @T6G_MB_LIB.T6G(SCH_1):PAGE56
   A29 NC_CPU1_USB2_USB01_DN @T6G_MB_LIB.T6G(SCH_1):NC_CPU1_USB2_USB01_DN     I8 @T6G_MB_LIB.T6G(SCH_1):PAGE56
   A28 NC_CPU1_USB2_USB01_DP @T6G_MB_LIB.T6G(SCH_1):NC_CPU1_USB2_USB01_DP     I8 @T6G_MB_LIB.T6G(SCH_1):PAGE56
   C28 NC_CPU1_USB3_USB01_RXN @T6G_MB_LIB.T6G(SCH_1):NC_CPU1_USB3_USB01_RXN     I8 @T6G_MB_LIB.T6G(SCH_1):PAGE56
   C29 NC_CPU1_USB3_USB01_RXP @T6G_MB_LIB.T6G(SCH_1):NC_CPU1_USB3_USB01_RXP     I8 @T6G_MB_LIB.T6G(SCH_1):PAGE56
   E29 NC_CPU1_USB3_USB01_TXN @T6G_MB_LIB.T6G(SCH_1):NC_CPU1_USB3_USB01_TXN     I8 @T6G_MB_LIB.T6G(SCH_1):PAGE56
   E30 NC_CPU1_USB3_USB01_TXP @T6G_MB_LIB.T6G(SCH_1):NC_CPU1_USB3_USB01_TXP     I8 @T6G_MB_LIB.T6G(SCH_1):PAGE56
  DH67 NC_CPU1_USB2_USB10_DN @T6G_MB_LIB.T6G(SCH_1):NC_CPU1_USB2_USB10_DN     I8 @T6G_MB_LIB.T6G(SCH_1):PAGE56
  DJ67 NC_CPU1_USB2_USB10_DP @T6G_MB_LIB.T6G(SCH_1):NC_CPU1_USB2_USB10_DP     I8 @T6G_MB_LIB.T6G(SCH_1):PAGE56
  DH65 NC_CPU1_USB3_USB10_RXN @T6G_MB_LIB.T6G(SCH_1):NC_CPU1_USB3_USB10_RXN     I8 @T6G_MB_LIB.T6G(SCH_1):PAGE56
  DJ65 NC_CPU1_USB3_USB10_RXP @T6G_MB_LIB.T6G(SCH_1):NC_CPU1_USB3_USB10_RXP     I8 @T6G_MB_LIB.T6G(SCH_1):PAGE56
  DJ69 NC_CPU1_USB3_USB10_TXN @T6G_MB_LIB.T6G(SCH_1):NC_CPU1_USB3_USB10_TXN     I8 @T6G_MB_LIB.T6G(SCH_1):PAGE56
  DH69 NC_CPU1_USB3_USB10_TXP @T6G_MB_LIB.T6G(SCH_1):NC_CPU1_USB3_USB10_TXP     I8 @T6G_MB_LIB.T6G(SCH_1):PAGE56
  DJ60 NC_CPU1_USB2_USB11_DN @T6G_MB_LIB.T6G(SCH_1):NC_CPU1_USB2_USB11_DN     I8 @T6G_MB_LIB.T6G(SCH_1):PAGE56
  DH60 NC_CPU1_USB2_USB11_DP @T6G_MB_LIB.T6G(SCH_1):NC_CPU1_USB2_USB11_DP     I8 @T6G_MB_LIB.T6G(SCH_1):PAGE56
  DH62 NC_CPU1_USB3_USB11_RXN @T6G_MB_LIB.T6G(SCH_1):NC_CPU1_USB3_USB11_RXN     I8 @T6G_MB_LIB.T6G(SCH_1):PAGE56
  DJ62 NC_CPU1_USB3_USB11_RXP @T6G_MB_LIB.T6G(SCH_1):NC_CPU1_USB3_USB11_RXP     I8 @T6G_MB_LIB.T6G(SCH_1):PAGE56
  DH58 NC_CPU1_USB3_USB11_TXN @T6G_MB_LIB.T6G(SCH_1):NC_CPU1_USB3_USB11_TXN     I8 @T6G_MB_LIB.T6G(SCH_1):PAGE56
  DG58 NC_CPU1_USB3_USB11_TXP @T6G_MB_LIB.T6G(SCH_1):NC_CPU1_USB3_USB11_TXP     I8 @T6G_MB_LIB.T6G(SCH_1):PAGE56
  DG40 NC_CPU1_USB10_OC_N @T6G_MB_LIB.T6G(SCH_1):NC_CPU1_USB10_OC_N     I8 @T6G_MB_LIB.T6G(SCH_1):PAGE56
  DH40 NC_CPU1_USB11_OC_N @T6G_MB_LIB.T6G(SCH_1):NC_CPU1_USB11_OC_N     I8 @T6G_MB_LIB.T6G(SCH_1):PAGE56
  DG28     NC     NC     I8 @T6G_MB_LIB.T6G(SCH_1):PAGE56
   E23 NC_CPU1_USB00_OC_N @T6G_MB_LIB.T6G(SCH_1):NC_CPU1_USB00_OC_N     I8 @T6G_MB_LIB.T6G(SCH_1):PAGE56
  DF30     NC     NC     I8 @T6G_MB_LIB.T6G(SCH_1):PAGE56
  DE24     NC     NC     I8 @T6G_MB_LIB.T6G(SCH_1):PAGE56
  DH24     NC     NC     I8 @T6G_MB_LIB.T6G(SCH_1):PAGE56
  DJ23     NC     NC     I8 @T6G_MB_LIB.T6G(SCH_1):PAGE56
  DG25     NC     NC     I8 @T6G_MB_LIB.T6G(SCH_1):PAGE56
  DF25     NC     NC     I8 @T6G_MB_LIB.T6G(SCH_1):PAGE56
  DG29     NC     NC     I8 @T6G_MB_LIB.T6G(SCH_1):PAGE56
  DJ28     NC     NC     I8 @T6G_MB_LIB.T6G(SCH_1):PAGE56
  DG22     NC     NC     I8 @T6G_MB_LIB.T6G(SCH_1):PAGE56
  DF28     NC     NC     I8 @T6G_MB_LIB.T6G(SCH_1):PAGE56
  DH27     NC     NC     I8 @T6G_MB_LIB.T6G(SCH_1):PAGE56
  DG26     NC     NC     I8 @T6G_MB_LIB.T6G(SCH_1):PAGE56
   E24 NC_CPU1_USB01_OC_N @T6G_MB_LIB.T6G(SCH_1):NC_CPU1_USB01_OC_N     I8 @T6G_MB_LIB.T6G(SCH_1):PAGE56
  DJ26     NC     NC     I8 @T6G_MB_LIB.T6G(SCH_1):PAGE56
  DF24     NC     NC     I8 @T6G_MB_LIB.T6G(SCH_1):PAGE56
  DJ27 SPI_CPU1_R_CLK @T6G_MB_LIB.T6G(SCH_1):SPI_CPU1_R_CLK     I8 @T6G_MB_LIB.T6G(SCH_1):PAGE56
  DJ25     NC     NC     I8 @T6G_MB_LIB.T6G(SCH_1):PAGE56
  DJ22     NC     NC     I8 @T6G_MB_LIB.T6G(SCH_1):PAGE56
  DF27 PD_ESPI_CPU1_CLK2 @T6G_MB_LIB.T6G(SCH_1):PD_ESPI_CPU1_CLK2     I8 @T6G_MB_LIB.T6G(SCH_1):PAGE56
  DG23     NC     NC     I8 @T6G_MB_LIB.T6G(SCH_1):PAGE56
  DE27     NC     NC     I8 @T6G_MB_LIB.T6G(SCH_1):PAGE56
  BD62     NC     NC    I46 @T6G_MB_LIB.T6G(SCH_1):PAGE57
   D72     NC     NC    I46 @T6G_MB_LIB.T6G(SCH_1):PAGE57
   C54     NC     NC    I46 @T6G_MB_LIB.T6G(SCH_1):PAGE57
  BD65     NC     NC    I46 @T6G_MB_LIB.T6G(SCH_1):PAGE57
   E33     NC     NC    I46 @T6G_MB_LIB.T6G(SCH_1):PAGE57
    D4     NC     NC    I46 @T6G_MB_LIB.T6G(SCH_1):PAGE57
   A55     NC     NC    I46 @T6G_MB_LIB.T6G(SCH_1):PAGE57
  BD69     NC     NC    I46 @T6G_MB_LIB.T6G(SCH_1):PAGE57
   E36     NC     NC    I46 @T6G_MB_LIB.T6G(SCH_1):PAGE57
    D8     NC     NC    I46 @T6G_MB_LIB.T6G(SCH_1):PAGE57
   A56     NC     NC    I46 @T6G_MB_LIB.T6G(SCH_1):PAGE57
  BD72     NC     NC    I46 @T6G_MB_LIB.T6G(SCH_1):PAGE57
   BD4     NC     NC    I46 @T6G_MB_LIB.T6G(SCH_1):PAGE57
   D11     NC     NC    I46 @T6G_MB_LIB.T6G(SCH_1):PAGE57
   A57     NC     NC    I46 @T6G_MB_LIB.T6G(SCH_1):PAGE57
  DG17     NC     NC    I46 @T6G_MB_LIB.T6G(SCH_1):PAGE57
   D22     NC     NC    I46 @T6G_MB_LIB.T6G(SCH_1):PAGE57
   A59     NC     NC    I46 @T6G_MB_LIB.T6G(SCH_1):PAGE57
  DH17     NC     NC    I46 @T6G_MB_LIB.T6G(SCH_1):PAGE57
  BD11     NC     NC    I46 @T6G_MB_LIB.T6G(SCH_1):PAGE57
   D34     NC     NC    I46 @T6G_MB_LIB.T6G(SCH_1):PAGE57
   A31     NC     NC    I46 @T6G_MB_LIB.T6G(SCH_1):PAGE57
  DH21     NC     NC    I46 @T6G_MB_LIB.T6G(SCH_1):PAGE57
  BD14     NC     NC    I46 @T6G_MB_LIB.T6G(SCH_1):PAGE57
   B40     NC     NC    I46 @T6G_MB_LIB.T6G(SCH_1):PAGE57
   A35     NC     NC    I46 @T6G_MB_LIB.T6G(SCH_1):PAGE57
   DJ4     NC     NC    I46 @T6G_MB_LIB.T6G(SCH_1):PAGE57
  BD18     NC     NC    I46 @T6G_MB_LIB.T6G(SCH_1):PAGE57
   D58     NC     NC    I46 @T6G_MB_LIB.T6G(SCH_1):PAGE57
   C31     NC     NC    I46 @T6G_MB_LIB.T6G(SCH_1):PAGE57
   A41     NC     NC    I46 @T6G_MB_LIB.T6G(SCH_1):PAGE57
  BD21     NC     NC    I46 @T6G_MB_LIB.T6G(SCH_1):PAGE57
   D62     NC     NC    I46 @T6G_MB_LIB.T6G(SCH_1):PAGE57
   C34     NC     NC    I46 @T6G_MB_LIB.T6G(SCH_1):PAGE57
   A42     NC     NC    I46 @T6G_MB_LIB.T6G(SCH_1):PAGE57
   D65     NC     NC    I46 @T6G_MB_LIB.T6G(SCH_1):PAGE57
   C35     NC     NC    I46 @T6G_MB_LIB.T6G(SCH_1):PAGE57
   A45     NC     NC    I46 @T6G_MB_LIB.T6G(SCH_1):PAGE57
   C53     NC     NC    I46 @T6G_MB_LIB.T6G(SCH_1):PAGE57
   A48     NC     NC    I46 @T6G_MB_LIB.T6G(SCH_1):PAGE57
   A50     NC     NC    I46 @T6G_MB_LIB.T6G(SCH_1):PAGE57
   A51     NC     NC    I46 @T6G_MB_LIB.T6G(SCH_1):PAGE57
   A54     NC     NC    I46 @T6G_MB_LIB.T6G(SCH_1):PAGE57
  BD55     NC     NC    I46 @T6G_MB_LIB.T6G(SCH_1):PAGE57
  BD58     NC     NC    I46 @T6G_MB_LIB.T6G(SCH_1):PAGE57
   D36     NC     NC    I46 @T6G_MB_LIB.T6G(SCH_1):PAGE57
   BD7     NC     NC    I46 @T6G_MB_LIB.T6G(SCH_1):PAGE57
   A60     NC     NC    I46 @T6G_MB_LIB.T6G(SCH_1):PAGE57
  DJ57     NC     NC    I46 @T6G_MB_LIB.T6G(SCH_1):PAGE57
  DH14     NC     NC    I46 @T6G_MB_LIB.T6G(SCH_1):PAGE57
  DH13     NC     NC    I46 @T6G_MB_LIB.T6G(SCH_1):PAGE57
  DG42     NC     NC    I46 @T6G_MB_LIB.T6G(SCH_1):PAGE57
  DF41     NC     NC    I46 @T6G_MB_LIB.T6G(SCH_1):PAGE57
   D23     NC     NC    I46 @T6G_MB_LIB.T6G(SCH_1):PAGE57
   C59     NC     NC    I46 @T6G_MB_LIB.T6G(SCH_1):PAGE57
   C58     NC     NC    I46 @T6G_MB_LIB.T6G(SCH_1):PAGE57
   C23     NC     NC    I46 @T6G_MB_LIB.T6G(SCH_1):PAGE57
   B36     NC     NC    I46 @T6G_MB_LIB.T6G(SCH_1):PAGE57
   W47 PVDDCR_CPU0_P1 @T6G_MB_LIB.T6G(SCH_1):PVDDCR_CPU0_P1    I29 @T6G_MB_LIB.T6G(SCH_1):PAGE57
   W46 PVDDCR_CPU0_P1 @T6G_MB_LIB.T6G(SCH_1):PVDDCR_CPU0_P1    I29 @T6G_MB_LIB.T6G(SCH_1):PAGE57
   W44 PVDDCR_CPU0_P1 @T6G_MB_LIB.T6G(SCH_1):PVDDCR_CPU0_P1    I29 @T6G_MB_LIB.T6G(SCH_1):PAGE57
   W43 PVDDCR_CPU0_P1 @T6G_MB_LIB.T6G(SCH_1):PVDDCR_CPU0_P1    I29 @T6G_MB_LIB.T6G(SCH_1):PAGE57
   W33 PVDDCR_CPU0_P1 @T6G_MB_LIB.T6G(SCH_1):PVDDCR_CPU0_P1    I29 @T6G_MB_LIB.T6G(SCH_1):PAGE57
   W32 PVDDCR_CPU0_P1 @T6G_MB_LIB.T6G(SCH_1):PVDDCR_CPU0_P1    I29 @T6G_MB_LIB.T6G(SCH_1):PAGE57
   W30 PVDDCR_CPU0_P1 @T6G_MB_LIB.T6G(SCH_1):PVDDCR_CPU0_P1    I29 @T6G_MB_LIB.T6G(SCH_1):PAGE57
   W29 PVDDCR_CPU0_P1 @T6G_MB_LIB.T6G(SCH_1):PVDDCR_CPU0_P1    I29 @T6G_MB_LIB.T6G(SCH_1):PAGE57
   U41 PVDDCR_CPU0_P1 @T6G_MB_LIB.T6G(SCH_1):PVDDCR_CPU0_P1    I29 @T6G_MB_LIB.T6G(SCH_1):PAGE57
   U40 PVDDCR_CPU0_P1 @T6G_MB_LIB.T6G(SCH_1):PVDDCR_CPU0_P1    I29 @T6G_MB_LIB.T6G(SCH_1):PAGE57
   U36 PVDDCR_CPU0_P1 @T6G_MB_LIB.T6G(SCH_1):PVDDCR_CPU0_P1    I29 @T6G_MB_LIB.T6G(SCH_1):PAGE57
   U35 PVDDCR_CPU0_P1 @T6G_MB_LIB.T6G(SCH_1):PVDDCR_CPU0_P1    I29 @T6G_MB_LIB.T6G(SCH_1):PAGE57
   T53 PVDDCR_CPU0_P1 @T6G_MB_LIB.T6G(SCH_1):PVDDCR_CPU0_P1    I29 @T6G_MB_LIB.T6G(SCH_1):PAGE57
   T52 PVDDCR_CPU0_P1 @T6G_MB_LIB.T6G(SCH_1):PVDDCR_CPU0_P1    I29 @T6G_MB_LIB.T6G(SCH_1):PAGE57
   T50 PVDDCR_CPU0_P1 @T6G_MB_LIB.T6G(SCH_1):PVDDCR_CPU0_P1    I29 @T6G_MB_LIB.T6G(SCH_1):PAGE57
   T49 PVDDCR_CPU0_P1 @T6G_MB_LIB.T6G(SCH_1):PVDDCR_CPU0_P1    I29 @T6G_MB_LIB.T6G(SCH_1):PAGE57
   T47 PVDDCR_CPU0_P1 @T6G_MB_LIB.T6G(SCH_1):PVDDCR_CPU0_P1    I29 @T6G_MB_LIB.T6G(SCH_1):PAGE57
   T46 PVDDCR_CPU0_P1 @T6G_MB_LIB.T6G(SCH_1):PVDDCR_CPU0_P1    I29 @T6G_MB_LIB.T6G(SCH_1):PAGE57
   T44 PVDDCR_CPU0_P1 @T6G_MB_LIB.T6G(SCH_1):PVDDCR_CPU0_P1    I29 @T6G_MB_LIB.T6G(SCH_1):PAGE57
   T43 PVDDCR_CPU0_P1 @T6G_MB_LIB.T6G(SCH_1):PVDDCR_CPU0_P1    I29 @T6G_MB_LIB.T6G(SCH_1):PAGE57
   T33 PVDDCR_CPU0_P1 @T6G_MB_LIB.T6G(SCH_1):PVDDCR_CPU0_P1    I29 @T6G_MB_LIB.T6G(SCH_1):PAGE57
   T32 PVDDCR_CPU0_P1 @T6G_MB_LIB.T6G(SCH_1):PVDDCR_CPU0_P1    I29 @T6G_MB_LIB.T6G(SCH_1):PAGE57
   T30 PVDDCR_CPU0_P1 @T6G_MB_LIB.T6G(SCH_1):PVDDCR_CPU0_P1    I29 @T6G_MB_LIB.T6G(SCH_1):PAGE57
   T29 PVDDCR_CPU0_P1 @T6G_MB_LIB.T6G(SCH_1):PVDDCR_CPU0_P1    I29 @T6G_MB_LIB.T6G(SCH_1):PAGE57
   T27 PVDDCR_CPU0_P1 @T6G_MB_LIB.T6G(SCH_1):PVDDCR_CPU0_P1    I29 @T6G_MB_LIB.T6G(SCH_1):PAGE57
   T26 PVDDCR_CPU0_P1 @T6G_MB_LIB.T6G(SCH_1):PVDDCR_CPU0_P1    I29 @T6G_MB_LIB.T6G(SCH_1):PAGE57
   T24 PVDDCR_CPU0_P1 @T6G_MB_LIB.T6G(SCH_1):PVDDCR_CPU0_P1    I29 @T6G_MB_LIB.T6G(SCH_1):PAGE57
   T23 PVDDCR_CPU0_P1 @T6G_MB_LIB.T6G(SCH_1):PVDDCR_CPU0_P1    I29 @T6G_MB_LIB.T6G(SCH_1):PAGE57
   N41 PVDDCR_CPU0_P1 @T6G_MB_LIB.T6G(SCH_1):PVDDCR_CPU0_P1    I29 @T6G_MB_LIB.T6G(SCH_1):PAGE57
   N40 PVDDCR_CPU0_P1 @T6G_MB_LIB.T6G(SCH_1):PVDDCR_CPU0_P1    I29 @T6G_MB_LIB.T6G(SCH_1):PAGE57
   N36 PVDDCR_CPU0_P1 @T6G_MB_LIB.T6G(SCH_1):PVDDCR_CPU0_P1    I29 @T6G_MB_LIB.T6G(SCH_1):PAGE57
   N35 PVDDCR_CPU0_P1 @T6G_MB_LIB.T6G(SCH_1):PVDDCR_CPU0_P1    I29 @T6G_MB_LIB.T6G(SCH_1):PAGE57
   M53 PVDDCR_CPU0_P1 @T6G_MB_LIB.T6G(SCH_1):PVDDCR_CPU0_P1    I29 @T6G_MB_LIB.T6G(SCH_1):PAGE57
   M52 PVDDCR_CPU0_P1 @T6G_MB_LIB.T6G(SCH_1):PVDDCR_CPU0_P1    I29 @T6G_MB_LIB.T6G(SCH_1):PAGE57
   M50 PVDDCR_CPU0_P1 @T6G_MB_LIB.T6G(SCH_1):PVDDCR_CPU0_P1    I29 @T6G_MB_LIB.T6G(SCH_1):PAGE57
   M49 PVDDCR_CPU0_P1 @T6G_MB_LIB.T6G(SCH_1):PVDDCR_CPU0_P1    I29 @T6G_MB_LIB.T6G(SCH_1):PAGE57
   M47 PVDDCR_CPU0_P1 @T6G_MB_LIB.T6G(SCH_1):PVDDCR_CPU0_P1    I29 @T6G_MB_LIB.T6G(SCH_1):PAGE57
   M46 PVDDCR_CPU0_P1 @T6G_MB_LIB.T6G(SCH_1):PVDDCR_CPU0_P1    I29 @T6G_MB_LIB.T6G(SCH_1):PAGE57
   M44 PVDDCR_CPU0_P1 @T6G_MB_LIB.T6G(SCH_1):PVDDCR_CPU0_P1    I29 @T6G_MB_LIB.T6G(SCH_1):PAGE57
   M43 PVDDCR_CPU0_P1 @T6G_MB_LIB.T6G(SCH_1):PVDDCR_CPU0_P1    I29 @T6G_MB_LIB.T6G(SCH_1):PAGE57
   M33 PVDDCR_CPU0_P1 @T6G_MB_LIB.T6G(SCH_1):PVDDCR_CPU0_P1    I29 @T6G_MB_LIB.T6G(SCH_1):PAGE57
   M32 PVDDCR_CPU0_P1 @T6G_MB_LIB.T6G(SCH_1):PVDDCR_CPU0_P1    I29 @T6G_MB_LIB.T6G(SCH_1):PAGE57
   M30 PVDDCR_CPU0_P1 @T6G_MB_LIB.T6G(SCH_1):PVDDCR_CPU0_P1    I29 @T6G_MB_LIB.T6G(SCH_1):PAGE57
   M29 PVDDCR_CPU0_P1 @T6G_MB_LIB.T6G(SCH_1):PVDDCR_CPU0_P1    I29 @T6G_MB_LIB.T6G(SCH_1):PAGE57
   M27 PVDDCR_CPU0_P1 @T6G_MB_LIB.T6G(SCH_1):PVDDCR_CPU0_P1    I29 @T6G_MB_LIB.T6G(SCH_1):PAGE57
   M26 PVDDCR_CPU0_P1 @T6G_MB_LIB.T6G(SCH_1):PVDDCR_CPU0_P1    I29 @T6G_MB_LIB.T6G(SCH_1):PAGE57
   M24 PVDDCR_CPU0_P1 @T6G_MB_LIB.T6G(SCH_1):PVDDCR_CPU0_P1    I29 @T6G_MB_LIB.T6G(SCH_1):PAGE57
   M23 PVDDCR_CPU0_P1 @T6G_MB_LIB.T6G(SCH_1):PVDDCR_CPU0_P1    I29 @T6G_MB_LIB.T6G(SCH_1):PAGE57
   J41 PVDDCR_CPU0_P1 @T6G_MB_LIB.T6G(SCH_1):PVDDCR_CPU0_P1    I29 @T6G_MB_LIB.T6G(SCH_1):PAGE57
   J40 PVDDCR_CPU0_P1 @T6G_MB_LIB.T6G(SCH_1):PVDDCR_CPU0_P1    I29 @T6G_MB_LIB.T6G(SCH_1):PAGE57
   J36 PVDDCR_CPU0_P1 @T6G_MB_LIB.T6G(SCH_1):PVDDCR_CPU0_P1    I29 @T6G_MB_LIB.T6G(SCH_1):PAGE57
   J35 PVDDCR_CPU0_P1 @T6G_MB_LIB.T6G(SCH_1):PVDDCR_CPU0_P1    I29 @T6G_MB_LIB.T6G(SCH_1):PAGE57
   H53 PVDDCR_CPU0_P1 @T6G_MB_LIB.T6G(SCH_1):PVDDCR_CPU0_P1    I29 @T6G_MB_LIB.T6G(SCH_1):PAGE57
   H52 PVDDCR_CPU0_P1 @T6G_MB_LIB.T6G(SCH_1):PVDDCR_CPU0_P1    I29 @T6G_MB_LIB.T6G(SCH_1):PAGE57
   H50 PVDDCR_CPU0_P1 @T6G_MB_LIB.T6G(SCH_1):PVDDCR_CPU0_P1    I29 @T6G_MB_LIB.T6G(SCH_1):PAGE57
   H49 PVDDCR_CPU0_P1 @T6G_MB_LIB.T6G(SCH_1):PVDDCR_CPU0_P1    I29 @T6G_MB_LIB.T6G(SCH_1):PAGE57
   H47 PVDDCR_CPU0_P1 @T6G_MB_LIB.T6G(SCH_1):PVDDCR_CPU0_P1    I29 @T6G_MB_LIB.T6G(SCH_1):PAGE57
   H46 PVDDCR_CPU0_P1 @T6G_MB_LIB.T6G(SCH_1):PVDDCR_CPU0_P1    I29 @T6G_MB_LIB.T6G(SCH_1):PAGE57
   H44 PVDDCR_CPU0_P1 @T6G_MB_LIB.T6G(SCH_1):PVDDCR_CPU0_P1    I29 @T6G_MB_LIB.T6G(SCH_1):PAGE57
   H43 PVDDCR_CPU0_P1 @T6G_MB_LIB.T6G(SCH_1):PVDDCR_CPU0_P1    I29 @T6G_MB_LIB.T6G(SCH_1):PAGE57
   H33 PVDDCR_CPU0_P1 @T6G_MB_LIB.T6G(SCH_1):PVDDCR_CPU0_P1    I29 @T6G_MB_LIB.T6G(SCH_1):PAGE57
   H32 PVDDCR_CPU0_P1 @T6G_MB_LIB.T6G(SCH_1):PVDDCR_CPU0_P1    I29 @T6G_MB_LIB.T6G(SCH_1):PAGE57
   H30 PVDDCR_CPU0_P1 @T6G_MB_LIB.T6G(SCH_1):PVDDCR_CPU0_P1    I29 @T6G_MB_LIB.T6G(SCH_1):PAGE57
   H29 PVDDCR_CPU0_P1 @T6G_MB_LIB.T6G(SCH_1):PVDDCR_CPU0_P1    I29 @T6G_MB_LIB.T6G(SCH_1):PAGE57
   H27 PVDDCR_CPU0_P1 @T6G_MB_LIB.T6G(SCH_1):PVDDCR_CPU0_P1    I29 @T6G_MB_LIB.T6G(SCH_1):PAGE57
   H26 PVDDCR_CPU0_P1 @T6G_MB_LIB.T6G(SCH_1):PVDDCR_CPU0_P1    I29 @T6G_MB_LIB.T6G(SCH_1):PAGE57
   H24 PVDDCR_CPU0_P1 @T6G_MB_LIB.T6G(SCH_1):PVDDCR_CPU0_P1    I29 @T6G_MB_LIB.T6G(SCH_1):PAGE57
   H23 PVDDCR_CPU0_P1 @T6G_MB_LIB.T6G(SCH_1):PVDDCR_CPU0_P1    I29 @T6G_MB_LIB.T6G(SCH_1):PAGE57
   G41 PVDDCR_CPU0_P1 @T6G_MB_LIB.T6G(SCH_1):PVDDCR_CPU0_P1    I29 @T6G_MB_LIB.T6G(SCH_1):PAGE57
   G40 PVDDCR_CPU0_P1 @T6G_MB_LIB.T6G(SCH_1):PVDDCR_CPU0_P1    I29 @T6G_MB_LIB.T6G(SCH_1):PAGE57
   G36 PVDDCR_CPU0_P1 @T6G_MB_LIB.T6G(SCH_1):PVDDCR_CPU0_P1    I29 @T6G_MB_LIB.T6G(SCH_1):PAGE57
   G35 PVDDCR_CPU0_P1 @T6G_MB_LIB.T6G(SCH_1):PVDDCR_CPU0_P1    I29 @T6G_MB_LIB.T6G(SCH_1):PAGE57
   F54 PVDDCR_CPU0_P1 @T6G_MB_LIB.T6G(SCH_1):PVDDCR_CPU0_P1    I29 @T6G_MB_LIB.T6G(SCH_1):PAGE57
   F51 PVDDCR_CPU0_P1 @T6G_MB_LIB.T6G(SCH_1):PVDDCR_CPU0_P1    I29 @T6G_MB_LIB.T6G(SCH_1):PAGE57
   F48 PVDDCR_CPU0_P1 @T6G_MB_LIB.T6G(SCH_1):PVDDCR_CPU0_P1    I29 @T6G_MB_LIB.T6G(SCH_1):PAGE57
   F45 PVDDCR_CPU0_P1 @T6G_MB_LIB.T6G(SCH_1):PVDDCR_CPU0_P1    I29 @T6G_MB_LIB.T6G(SCH_1):PAGE57
   F42 PVDDCR_CPU0_P1 @T6G_MB_LIB.T6G(SCH_1):PVDDCR_CPU0_P1    I29 @T6G_MB_LIB.T6G(SCH_1):PAGE57
   F34 PVDDCR_CPU0_P1 @T6G_MB_LIB.T6G(SCH_1):PVDDCR_CPU0_P1    I29 @T6G_MB_LIB.T6G(SCH_1):PAGE57
   F31 PVDDCR_CPU0_P1 @T6G_MB_LIB.T6G(SCH_1):PVDDCR_CPU0_P1    I29 @T6G_MB_LIB.T6G(SCH_1):PAGE57
   F28 PVDDCR_CPU0_P1 @T6G_MB_LIB.T6G(SCH_1):PVDDCR_CPU0_P1    I29 @T6G_MB_LIB.T6G(SCH_1):PAGE57
   F25 PVDDCR_CPU0_P1 @T6G_MB_LIB.T6G(SCH_1):PVDDCR_CPU0_P1    I29 @T6G_MB_LIB.T6G(SCH_1):PAGE57
   F22 PVDDCR_CPU0_P1 @T6G_MB_LIB.T6G(SCH_1):PVDDCR_CPU0_P1    I29 @T6G_MB_LIB.T6G(SCH_1):PAGE57
   E54 PVDDCR_CPU0_P1 @T6G_MB_LIB.T6G(SCH_1):PVDDCR_CPU0_P1    I29 @T6G_MB_LIB.T6G(SCH_1):PAGE57
   E51 PVDDCR_CPU0_P1 @T6G_MB_LIB.T6G(SCH_1):PVDDCR_CPU0_P1    I29 @T6G_MB_LIB.T6G(SCH_1):PAGE57
   E48 PVDDCR_CPU0_P1 @T6G_MB_LIB.T6G(SCH_1):PVDDCR_CPU0_P1    I29 @T6G_MB_LIB.T6G(SCH_1):PAGE57
   E45 PVDDCR_CPU0_P1 @T6G_MB_LIB.T6G(SCH_1):PVDDCR_CPU0_P1    I29 @T6G_MB_LIB.T6G(SCH_1):PAGE57
   E42 PVDDCR_CPU0_P1 @T6G_MB_LIB.T6G(SCH_1):PVDDCR_CPU0_P1    I29 @T6G_MB_LIB.T6G(SCH_1):PAGE57
   E35 PVDDCR_CPU0_P1 @T6G_MB_LIB.T6G(SCH_1):PVDDCR_CPU0_P1    I29 @T6G_MB_LIB.T6G(SCH_1):PAGE57
   E34 PVDDCR_CPU0_P1 @T6G_MB_LIB.T6G(SCH_1):PVDDCR_CPU0_P1    I29 @T6G_MB_LIB.T6G(SCH_1):PAGE57
   E31 PVDDCR_CPU0_P1 @T6G_MB_LIB.T6G(SCH_1):PVDDCR_CPU0_P1    I29 @T6G_MB_LIB.T6G(SCH_1):PAGE57
   E28 PVDDCR_CPU0_P1 @T6G_MB_LIB.T6G(SCH_1):PVDDCR_CPU0_P1    I29 @T6G_MB_LIB.T6G(SCH_1):PAGE57
   E25 PVDDCR_CPU0_P1 @T6G_MB_LIB.T6G(SCH_1):PVDDCR_CPU0_P1    I29 @T6G_MB_LIB.T6G(SCH_1):PAGE57
   E22 PVDDCR_CPU0_P1 @T6G_MB_LIB.T6G(SCH_1):PVDDCR_CPU0_P1    I29 @T6G_MB_LIB.T6G(SCH_1):PAGE57
   D56 PVDDCR_CPU0_P1 @T6G_MB_LIB.T6G(SCH_1):PVDDCR_CPU0_P1    I29 @T6G_MB_LIB.T6G(SCH_1):PAGE57
   D55 PVDDCR_CPU0_P1 @T6G_MB_LIB.T6G(SCH_1):PVDDCR_CPU0_P1    I29 @T6G_MB_LIB.T6G(SCH_1):PAGE57
   C20 PVDDCR_CPU0_P1 @T6G_MB_LIB.T6G(SCH_1):PVDDCR_CPU0_P1    I29 @T6G_MB_LIB.T6G(SCH_1):PAGE57
   B57 PVDDCR_CPU0_P1 @T6G_MB_LIB.T6G(SCH_1):PVDDCR_CPU0_P1    I29 @T6G_MB_LIB.T6G(SCH_1):PAGE57
   B56 PVDDCR_CPU0_P1 @T6G_MB_LIB.T6G(SCH_1):PVDDCR_CPU0_P1    I29 @T6G_MB_LIB.T6G(SCH_1):PAGE57
   B54 PVDDCR_CPU0_P1 @T6G_MB_LIB.T6G(SCH_1):PVDDCR_CPU0_P1    I29 @T6G_MB_LIB.T6G(SCH_1):PAGE57
   B53 PVDDCR_CPU0_P1 @T6G_MB_LIB.T6G(SCH_1):PVDDCR_CPU0_P1    I29 @T6G_MB_LIB.T6G(SCH_1):PAGE57
   B51 PVDDCR_CPU0_P1 @T6G_MB_LIB.T6G(SCH_1):PVDDCR_CPU0_P1    I29 @T6G_MB_LIB.T6G(SCH_1):PAGE57
   B50 PVDDCR_CPU0_P1 @T6G_MB_LIB.T6G(SCH_1):PVDDCR_CPU0_P1    I29 @T6G_MB_LIB.T6G(SCH_1):PAGE57
   B48 PVDDCR_CPU0_P1 @T6G_MB_LIB.T6G(SCH_1):PVDDCR_CPU0_P1    I29 @T6G_MB_LIB.T6G(SCH_1):PAGE57
   B47 PVDDCR_CPU0_P1 @T6G_MB_LIB.T6G(SCH_1):PVDDCR_CPU0_P1    I29 @T6G_MB_LIB.T6G(SCH_1):PAGE57
   B45 PVDDCR_CPU0_P1 @T6G_MB_LIB.T6G(SCH_1):PVDDCR_CPU0_P1    I29 @T6G_MB_LIB.T6G(SCH_1):PAGE57
   B44 PVDDCR_CPU0_P1 @T6G_MB_LIB.T6G(SCH_1):PVDDCR_CPU0_P1    I29 @T6G_MB_LIB.T6G(SCH_1):PAGE57
   B42 PVDDCR_CPU0_P1 @T6G_MB_LIB.T6G(SCH_1):PVDDCR_CPU0_P1    I29 @T6G_MB_LIB.T6G(SCH_1):PAGE57
   B41 PVDDCR_CPU0_P1 @T6G_MB_LIB.T6G(SCH_1):PVDDCR_CPU0_P1    I29 @T6G_MB_LIB.T6G(SCH_1):PAGE57
   B35 PVDDCR_CPU0_P1 @T6G_MB_LIB.T6G(SCH_1):PVDDCR_CPU0_P1    I29 @T6G_MB_LIB.T6G(SCH_1):PAGE57
   B34 PVDDCR_CPU0_P1 @T6G_MB_LIB.T6G(SCH_1):PVDDCR_CPU0_P1    I29 @T6G_MB_LIB.T6G(SCH_1):PAGE57
   B32 PVDDCR_CPU0_P1 @T6G_MB_LIB.T6G(SCH_1):PVDDCR_CPU0_P1    I29 @T6G_MB_LIB.T6G(SCH_1):PAGE57
   B31 PVDDCR_CPU0_P1 @T6G_MB_LIB.T6G(SCH_1):PVDDCR_CPU0_P1    I29 @T6G_MB_LIB.T6G(SCH_1):PAGE57
   B29 PVDDCR_CPU0_P1 @T6G_MB_LIB.T6G(SCH_1):PVDDCR_CPU0_P1    I29 @T6G_MB_LIB.T6G(SCH_1):PAGE57
   B28 PVDDCR_CPU0_P1 @T6G_MB_LIB.T6G(SCH_1):PVDDCR_CPU0_P1    I29 @T6G_MB_LIB.T6G(SCH_1):PAGE57
   B26 PVDDCR_CPU0_P1 @T6G_MB_LIB.T6G(SCH_1):PVDDCR_CPU0_P1    I29 @T6G_MB_LIB.T6G(SCH_1):PAGE57
   B25 PVDDCR_CPU0_P1 @T6G_MB_LIB.T6G(SCH_1):PVDDCR_CPU0_P1    I29 @T6G_MB_LIB.T6G(SCH_1):PAGE57
   B23 PVDDCR_CPU0_P1 @T6G_MB_LIB.T6G(SCH_1):PVDDCR_CPU0_P1    I29 @T6G_MB_LIB.T6G(SCH_1):PAGE57
   B22 PVDDCR_CPU0_P1 @T6G_MB_LIB.T6G(SCH_1):PVDDCR_CPU0_P1    I29 @T6G_MB_LIB.T6G(SCH_1):PAGE57
   B20 PVDDCR_CPU0_P1 @T6G_MB_LIB.T6G(SCH_1):PVDDCR_CPU0_P1    I29 @T6G_MB_LIB.T6G(SCH_1):PAGE57
   B19 PVDDCR_CPU0_P1 @T6G_MB_LIB.T6G(SCH_1):PVDDCR_CPU0_P1    I29 @T6G_MB_LIB.T6G(SCH_1):PAGE57
  AT47 PVDDCR_CPU0_P1 @T6G_MB_LIB.T6G(SCH_1):PVDDCR_CPU0_P1    I29 @T6G_MB_LIB.T6G(SCH_1):PAGE57
  AT45 PVDDCR_CPU0_P1 @T6G_MB_LIB.T6G(SCH_1):PVDDCR_CPU0_P1    I29 @T6G_MB_LIB.T6G(SCH_1):PAGE57
  AT43 PVDDCR_CPU0_P1 @T6G_MB_LIB.T6G(SCH_1):PVDDCR_CPU0_P1    I29 @T6G_MB_LIB.T6G(SCH_1):PAGE57
  AT41 PVDDCR_CPU0_P1 @T6G_MB_LIB.T6G(SCH_1):PVDDCR_CPU0_P1    I29 @T6G_MB_LIB.T6G(SCH_1):PAGE57
  AT39 PVDDCR_CPU0_P1 @T6G_MB_LIB.T6G(SCH_1):PVDDCR_CPU0_P1    I29 @T6G_MB_LIB.T6G(SCH_1):PAGE57
  AT36 PVDDCR_CPU0_P1 @T6G_MB_LIB.T6G(SCH_1):PVDDCR_CPU0_P1    I29 @T6G_MB_LIB.T6G(SCH_1):PAGE57
  AT34 PVDDCR_CPU0_P1 @T6G_MB_LIB.T6G(SCH_1):PVDDCR_CPU0_P1    I29 @T6G_MB_LIB.T6G(SCH_1):PAGE57
  AT32 PVDDCR_CPU0_P1 @T6G_MB_LIB.T6G(SCH_1):PVDDCR_CPU0_P1    I29 @T6G_MB_LIB.T6G(SCH_1):PAGE57
  AT30 PVDDCR_CPU0_P1 @T6G_MB_LIB.T6G(SCH_1):PVDDCR_CPU0_P1    I29 @T6G_MB_LIB.T6G(SCH_1):PAGE57
  AT28 PVDDCR_CPU0_P1 @T6G_MB_LIB.T6G(SCH_1):PVDDCR_CPU0_P1    I29 @T6G_MB_LIB.T6G(SCH_1):PAGE57
  AT26 PVDDCR_CPU0_P1 @T6G_MB_LIB.T6G(SCH_1):PVDDCR_CPU0_P1    I29 @T6G_MB_LIB.T6G(SCH_1):PAGE57
  AT24 PVDDCR_CPU0_P1 @T6G_MB_LIB.T6G(SCH_1):PVDDCR_CPU0_P1    I29 @T6G_MB_LIB.T6G(SCH_1):PAGE57
  AR50 PVDDCR_CPU0_P1 @T6G_MB_LIB.T6G(SCH_1):PVDDCR_CPU0_P1    I29 @T6G_MB_LIB.T6G(SCH_1):PAGE57
  AR48 PVDDCR_CPU0_P1 @T6G_MB_LIB.T6G(SCH_1):PVDDCR_CPU0_P1    I29 @T6G_MB_LIB.T6G(SCH_1):PAGE57
  AR46 PVDDCR_CPU0_P1 @T6G_MB_LIB.T6G(SCH_1):PVDDCR_CPU0_P1    I29 @T6G_MB_LIB.T6G(SCH_1):PAGE57
  AR44 PVDDCR_CPU0_P1 @T6G_MB_LIB.T6G(SCH_1):PVDDCR_CPU0_P1    I29 @T6G_MB_LIB.T6G(SCH_1):PAGE57
  AR42 PVDDCR_CPU0_P1 @T6G_MB_LIB.T6G(SCH_1):PVDDCR_CPU0_P1    I29 @T6G_MB_LIB.T6G(SCH_1):PAGE57
  AR40 PVDDCR_CPU0_P1 @T6G_MB_LIB.T6G(SCH_1):PVDDCR_CPU0_P1    I29 @T6G_MB_LIB.T6G(SCH_1):PAGE57
  AR35 PVDDCR_CPU0_P1 @T6G_MB_LIB.T6G(SCH_1):PVDDCR_CPU0_P1    I29 @T6G_MB_LIB.T6G(SCH_1):PAGE57
  AR33 PVDDCR_CPU0_P1 @T6G_MB_LIB.T6G(SCH_1):PVDDCR_CPU0_P1    I29 @T6G_MB_LIB.T6G(SCH_1):PAGE57
  AR31 PVDDCR_CPU0_P1 @T6G_MB_LIB.T6G(SCH_1):PVDDCR_CPU0_P1    I29 @T6G_MB_LIB.T6G(SCH_1):PAGE57
  AR29 PVDDCR_CPU0_P1 @T6G_MB_LIB.T6G(SCH_1):PVDDCR_CPU0_P1    I29 @T6G_MB_LIB.T6G(SCH_1):PAGE57
  AR27 PVDDCR_CPU0_P1 @T6G_MB_LIB.T6G(SCH_1):PVDDCR_CPU0_P1    I29 @T6G_MB_LIB.T6G(SCH_1):PAGE57
  AR25 PVDDCR_CPU0_P1 @T6G_MB_LIB.T6G(SCH_1):PVDDCR_CPU0_P1    I29 @T6G_MB_LIB.T6G(SCH_1):PAGE57
  AR23 PVDDCR_CPU0_P1 @T6G_MB_LIB.T6G(SCH_1):PVDDCR_CPU0_P1    I29 @T6G_MB_LIB.T6G(SCH_1):PAGE57
  AP53 PVDDCR_CPU0_P1 @T6G_MB_LIB.T6G(SCH_1):PVDDCR_CPU0_P1    I29 @T6G_MB_LIB.T6G(SCH_1):PAGE57
  AP52 PVDDCR_CPU0_P1 @T6G_MB_LIB.T6G(SCH_1):PVDDCR_CPU0_P1    I29 @T6G_MB_LIB.T6G(SCH_1):PAGE57
  AP50 PVDDCR_CPU0_P1 @T6G_MB_LIB.T6G(SCH_1):PVDDCR_CPU0_P1    I29 @T6G_MB_LIB.T6G(SCH_1):PAGE57
  AP49 PVDDCR_CPU0_P1 @T6G_MB_LIB.T6G(SCH_1):PVDDCR_CPU0_P1    I29 @T6G_MB_LIB.T6G(SCH_1):PAGE57
  AP47 PVDDCR_CPU0_P1 @T6G_MB_LIB.T6G(SCH_1):PVDDCR_CPU0_P1    I29 @T6G_MB_LIB.T6G(SCH_1):PAGE57
  AP46 PVDDCR_CPU0_P1 @T6G_MB_LIB.T6G(SCH_1):PVDDCR_CPU0_P1    I29 @T6G_MB_LIB.T6G(SCH_1):PAGE57
  AP44 PVDDCR_CPU0_P1 @T6G_MB_LIB.T6G(SCH_1):PVDDCR_CPU0_P1    I29 @T6G_MB_LIB.T6G(SCH_1):PAGE57
  AP43 PVDDCR_CPU0_P1 @T6G_MB_LIB.T6G(SCH_1):PVDDCR_CPU0_P1    I29 @T6G_MB_LIB.T6G(SCH_1):PAGE57
  AP33 PVDDCR_CPU0_P1 @T6G_MB_LIB.T6G(SCH_1):PVDDCR_CPU0_P1    I29 @T6G_MB_LIB.T6G(SCH_1):PAGE57
  AP32 PVDDCR_CPU0_P1 @T6G_MB_LIB.T6G(SCH_1):PVDDCR_CPU0_P1    I29 @T6G_MB_LIB.T6G(SCH_1):PAGE57
  AP30 PVDDCR_CPU0_P1 @T6G_MB_LIB.T6G(SCH_1):PVDDCR_CPU0_P1    I29 @T6G_MB_LIB.T6G(SCH_1):PAGE57
  AP29 PVDDCR_CPU0_P1 @T6G_MB_LIB.T6G(SCH_1):PVDDCR_CPU0_P1    I29 @T6G_MB_LIB.T6G(SCH_1):PAGE57
  AP27 PVDDCR_CPU0_P1 @T6G_MB_LIB.T6G(SCH_1):PVDDCR_CPU0_P1    I29 @T6G_MB_LIB.T6G(SCH_1):PAGE57
  AP26 PVDDCR_CPU0_P1 @T6G_MB_LIB.T6G(SCH_1):PVDDCR_CPU0_P1    I29 @T6G_MB_LIB.T6G(SCH_1):PAGE57
  AP24 PVDDCR_CPU0_P1 @T6G_MB_LIB.T6G(SCH_1):PVDDCR_CPU0_P1    I29 @T6G_MB_LIB.T6G(SCH_1):PAGE57
  AP23 PVDDCR_CPU0_P1 @T6G_MB_LIB.T6G(SCH_1):PVDDCR_CPU0_P1    I29 @T6G_MB_LIB.T6G(SCH_1):PAGE57
  AL41 PVDDCR_CPU0_P1 @T6G_MB_LIB.T6G(SCH_1):PVDDCR_CPU0_P1    I29 @T6G_MB_LIB.T6G(SCH_1):PAGE57
  AL40 PVDDCR_CPU0_P1 @T6G_MB_LIB.T6G(SCH_1):PVDDCR_CPU0_P1    I29 @T6G_MB_LIB.T6G(SCH_1):PAGE57
  AL36 PVDDCR_CPU0_P1 @T6G_MB_LIB.T6G(SCH_1):PVDDCR_CPU0_P1    I29 @T6G_MB_LIB.T6G(SCH_1):PAGE57
  AL35 PVDDCR_CPU0_P1 @T6G_MB_LIB.T6G(SCH_1):PVDDCR_CPU0_P1    I29 @T6G_MB_LIB.T6G(SCH_1):PAGE57
  AK53 PVDDCR_CPU0_P1 @T6G_MB_LIB.T6G(SCH_1):PVDDCR_CPU0_P1    I29 @T6G_MB_LIB.T6G(SCH_1):PAGE57
  AK52 PVDDCR_CPU0_P1 @T6G_MB_LIB.T6G(SCH_1):PVDDCR_CPU0_P1    I29 @T6G_MB_LIB.T6G(SCH_1):PAGE57
  AK50 PVDDCR_CPU0_P1 @T6G_MB_LIB.T6G(SCH_1):PVDDCR_CPU0_P1    I29 @T6G_MB_LIB.T6G(SCH_1):PAGE57
  AK49 PVDDCR_CPU0_P1 @T6G_MB_LIB.T6G(SCH_1):PVDDCR_CPU0_P1    I29 @T6G_MB_LIB.T6G(SCH_1):PAGE57
  AK47 PVDDCR_CPU0_P1 @T6G_MB_LIB.T6G(SCH_1):PVDDCR_CPU0_P1    I29 @T6G_MB_LIB.T6G(SCH_1):PAGE57
  AK46 PVDDCR_CPU0_P1 @T6G_MB_LIB.T6G(SCH_1):PVDDCR_CPU0_P1    I29 @T6G_MB_LIB.T6G(SCH_1):PAGE57
  AK44 PVDDCR_CPU0_P1 @T6G_MB_LIB.T6G(SCH_1):PVDDCR_CPU0_P1    I29 @T6G_MB_LIB.T6G(SCH_1):PAGE57
  AK43 PVDDCR_CPU0_P1 @T6G_MB_LIB.T6G(SCH_1):PVDDCR_CPU0_P1    I29 @T6G_MB_LIB.T6G(SCH_1):PAGE57
  AK33 PVDDCR_CPU0_P1 @T6G_MB_LIB.T6G(SCH_1):PVDDCR_CPU0_P1    I29 @T6G_MB_LIB.T6G(SCH_1):PAGE57
  AK32 PVDDCR_CPU0_P1 @T6G_MB_LIB.T6G(SCH_1):PVDDCR_CPU0_P1    I29 @T6G_MB_LIB.T6G(SCH_1):PAGE57
  AK30 PVDDCR_CPU0_P1 @T6G_MB_LIB.T6G(SCH_1):PVDDCR_CPU0_P1    I29 @T6G_MB_LIB.T6G(SCH_1):PAGE57
  AK29 PVDDCR_CPU0_P1 @T6G_MB_LIB.T6G(SCH_1):PVDDCR_CPU0_P1    I29 @T6G_MB_LIB.T6G(SCH_1):PAGE57
  AK27 PVDDCR_CPU0_P1 @T6G_MB_LIB.T6G(SCH_1):PVDDCR_CPU0_P1    I29 @T6G_MB_LIB.T6G(SCH_1):PAGE57
  AK26 PVDDCR_CPU0_P1 @T6G_MB_LIB.T6G(SCH_1):PVDDCR_CPU0_P1    I29 @T6G_MB_LIB.T6G(SCH_1):PAGE57
  AK24 PVDDCR_CPU0_P1 @T6G_MB_LIB.T6G(SCH_1):PVDDCR_CPU0_P1    I29 @T6G_MB_LIB.T6G(SCH_1):PAGE57
  AK23 PVDDCR_CPU0_P1 @T6G_MB_LIB.T6G(SCH_1):PVDDCR_CPU0_P1    I29 @T6G_MB_LIB.T6G(SCH_1):PAGE57
  AG41 PVDDCR_CPU0_P1 @T6G_MB_LIB.T6G(SCH_1):PVDDCR_CPU0_P1    I29 @T6G_MB_LIB.T6G(SCH_1):PAGE57
  AG40 PVDDCR_CPU0_P1 @T6G_MB_LIB.T6G(SCH_1):PVDDCR_CPU0_P1    I29 @T6G_MB_LIB.T6G(SCH_1):PAGE57
  AG36 PVDDCR_CPU0_P1 @T6G_MB_LIB.T6G(SCH_1):PVDDCR_CPU0_P1    I29 @T6G_MB_LIB.T6G(SCH_1):PAGE57
  AG35 PVDDCR_CPU0_P1 @T6G_MB_LIB.T6G(SCH_1):PVDDCR_CPU0_P1    I29 @T6G_MB_LIB.T6G(SCH_1):PAGE57
  AF53 PVDDCR_CPU0_P1 @T6G_MB_LIB.T6G(SCH_1):PVDDCR_CPU0_P1    I29 @T6G_MB_LIB.T6G(SCH_1):PAGE57
  AF52 PVDDCR_CPU0_P1 @T6G_MB_LIB.T6G(SCH_1):PVDDCR_CPU0_P1    I29 @T6G_MB_LIB.T6G(SCH_1):PAGE57
  AF50 PVDDCR_CPU0_P1 @T6G_MB_LIB.T6G(SCH_1):PVDDCR_CPU0_P1    I29 @T6G_MB_LIB.T6G(SCH_1):PAGE57
  AF49 PVDDCR_CPU0_P1 @T6G_MB_LIB.T6G(SCH_1):PVDDCR_CPU0_P1    I29 @T6G_MB_LIB.T6G(SCH_1):PAGE57
  AF47 PVDDCR_CPU0_P1 @T6G_MB_LIB.T6G(SCH_1):PVDDCR_CPU0_P1    I29 @T6G_MB_LIB.T6G(SCH_1):PAGE57
  AF46 PVDDCR_CPU0_P1 @T6G_MB_LIB.T6G(SCH_1):PVDDCR_CPU0_P1    I29 @T6G_MB_LIB.T6G(SCH_1):PAGE57
  AF44 PVDDCR_CPU0_P1 @T6G_MB_LIB.T6G(SCH_1):PVDDCR_CPU0_P1    I29 @T6G_MB_LIB.T6G(SCH_1):PAGE57
  AF43 PVDDCR_CPU0_P1 @T6G_MB_LIB.T6G(SCH_1):PVDDCR_CPU0_P1    I29 @T6G_MB_LIB.T6G(SCH_1):PAGE57
  AF33 PVDDCR_CPU0_P1 @T6G_MB_LIB.T6G(SCH_1):PVDDCR_CPU0_P1    I29 @T6G_MB_LIB.T6G(SCH_1):PAGE57
  AF32 PVDDCR_CPU0_P1 @T6G_MB_LIB.T6G(SCH_1):PVDDCR_CPU0_P1    I29 @T6G_MB_LIB.T6G(SCH_1):PAGE57
  AF30 PVDDCR_CPU0_P1 @T6G_MB_LIB.T6G(SCH_1):PVDDCR_CPU0_P1    I29 @T6G_MB_LIB.T6G(SCH_1):PAGE57
  AF29 PVDDCR_CPU0_P1 @T6G_MB_LIB.T6G(SCH_1):PVDDCR_CPU0_P1    I29 @T6G_MB_LIB.T6G(SCH_1):PAGE57
  AF27 PVDDCR_CPU0_P1 @T6G_MB_LIB.T6G(SCH_1):PVDDCR_CPU0_P1    I29 @T6G_MB_LIB.T6G(SCH_1):PAGE57
  AF26 PVDDCR_CPU0_P1 @T6G_MB_LIB.T6G(SCH_1):PVDDCR_CPU0_P1    I29 @T6G_MB_LIB.T6G(SCH_1):PAGE57
  AF24 PVDDCR_CPU0_P1 @T6G_MB_LIB.T6G(SCH_1):PVDDCR_CPU0_P1    I29 @T6G_MB_LIB.T6G(SCH_1):PAGE57
  AF23 PVDDCR_CPU0_P1 @T6G_MB_LIB.T6G(SCH_1):PVDDCR_CPU0_P1    I29 @T6G_MB_LIB.T6G(SCH_1):PAGE57
  AC41 PVDDCR_CPU0_P1 @T6G_MB_LIB.T6G(SCH_1):PVDDCR_CPU0_P1    I29 @T6G_MB_LIB.T6G(SCH_1):PAGE57
  AC40 PVDDCR_CPU0_P1 @T6G_MB_LIB.T6G(SCH_1):PVDDCR_CPU0_P1    I29 @T6G_MB_LIB.T6G(SCH_1):PAGE57
  AC36 PVDDCR_CPU0_P1 @T6G_MB_LIB.T6G(SCH_1):PVDDCR_CPU0_P1    I29 @T6G_MB_LIB.T6G(SCH_1):PAGE57
  AC35 PVDDCR_CPU0_P1 @T6G_MB_LIB.T6G(SCH_1):PVDDCR_CPU0_P1    I29 @T6G_MB_LIB.T6G(SCH_1):PAGE57
  AB53 PVDDCR_CPU0_P1 @T6G_MB_LIB.T6G(SCH_1):PVDDCR_CPU0_P1    I29 @T6G_MB_LIB.T6G(SCH_1):PAGE57
  AB52 PVDDCR_CPU0_P1 @T6G_MB_LIB.T6G(SCH_1):PVDDCR_CPU0_P1    I29 @T6G_MB_LIB.T6G(SCH_1):PAGE57
  AB50 PVDDCR_CPU0_P1 @T6G_MB_LIB.T6G(SCH_1):PVDDCR_CPU0_P1    I29 @T6G_MB_LIB.T6G(SCH_1):PAGE57
  AB49 PVDDCR_CPU0_P1 @T6G_MB_LIB.T6G(SCH_1):PVDDCR_CPU0_P1    I29 @T6G_MB_LIB.T6G(SCH_1):PAGE57
  AB47 PVDDCR_CPU0_P1 @T6G_MB_LIB.T6G(SCH_1):PVDDCR_CPU0_P1    I29 @T6G_MB_LIB.T6G(SCH_1):PAGE57
  AB46 PVDDCR_CPU0_P1 @T6G_MB_LIB.T6G(SCH_1):PVDDCR_CPU0_P1    I29 @T6G_MB_LIB.T6G(SCH_1):PAGE57
  AB44 PVDDCR_CPU0_P1 @T6G_MB_LIB.T6G(SCH_1):PVDDCR_CPU0_P1    I29 @T6G_MB_LIB.T6G(SCH_1):PAGE57
  AB43 PVDDCR_CPU0_P1 @T6G_MB_LIB.T6G(SCH_1):PVDDCR_CPU0_P1    I29 @T6G_MB_LIB.T6G(SCH_1):PAGE57
  AB33 PVDDCR_CPU0_P1 @T6G_MB_LIB.T6G(SCH_1):PVDDCR_CPU0_P1    I29 @T6G_MB_LIB.T6G(SCH_1):PAGE57
  AB32 PVDDCR_CPU0_P1 @T6G_MB_LIB.T6G(SCH_1):PVDDCR_CPU0_P1    I29 @T6G_MB_LIB.T6G(SCH_1):PAGE57
  AB30 PVDDCR_CPU0_P1 @T6G_MB_LIB.T6G(SCH_1):PVDDCR_CPU0_P1    I29 @T6G_MB_LIB.T6G(SCH_1):PAGE57
  AB29 PVDDCR_CPU0_P1 @T6G_MB_LIB.T6G(SCH_1):PVDDCR_CPU0_P1    I29 @T6G_MB_LIB.T6G(SCH_1):PAGE57
  AB27 PVDDCR_CPU0_P1 @T6G_MB_LIB.T6G(SCH_1):PVDDCR_CPU0_P1    I29 @T6G_MB_LIB.T6G(SCH_1):PAGE57
  AB26 PVDDCR_CPU0_P1 @T6G_MB_LIB.T6G(SCH_1):PVDDCR_CPU0_P1    I29 @T6G_MB_LIB.T6G(SCH_1):PAGE57
  AB24 PVDDCR_CPU0_P1 @T6G_MB_LIB.T6G(SCH_1):PVDDCR_CPU0_P1    I29 @T6G_MB_LIB.T6G(SCH_1):PAGE57
  AB23 PVDDCR_CPU0_P1 @T6G_MB_LIB.T6G(SCH_1):PVDDCR_CPU0_P1    I29 @T6G_MB_LIB.T6G(SCH_1):PAGE57
   Y41 PVDDCR_CPU0_P1 @T6G_MB_LIB.T6G(SCH_1):PVDDCR_CPU0_P1    I29 @T6G_MB_LIB.T6G(SCH_1):PAGE57
   Y40 PVDDCR_CPU0_P1 @T6G_MB_LIB.T6G(SCH_1):PVDDCR_CPU0_P1    I29 @T6G_MB_LIB.T6G(SCH_1):PAGE57
   Y36 PVDDCR_CPU0_P1 @T6G_MB_LIB.T6G(SCH_1):PVDDCR_CPU0_P1    I29 @T6G_MB_LIB.T6G(SCH_1):PAGE57
   Y35 PVDDCR_CPU0_P1 @T6G_MB_LIB.T6G(SCH_1):PVDDCR_CPU0_P1    I29 @T6G_MB_LIB.T6G(SCH_1):PAGE57
  AU42 PVDDCR_CPU0_P1 @T6G_MB_LIB.T6G(SCH_1):PVDDCR_CPU0_P1    I29 @T6G_MB_LIB.T6G(SCH_1):PAGE57
  AU46 PVDDCR_CPU0_P1 @T6G_MB_LIB.T6G(SCH_1):PVDDCR_CPU0_P1    I29 @T6G_MB_LIB.T6G(SCH_1):PAGE57
  AT49 PVDDCR_CPU0_P1 @T6G_MB_LIB.T6G(SCH_1):PVDDCR_CPU0_P1    I29 @T6G_MB_LIB.T6G(SCH_1):PAGE57
  AU29 PVDDCR_CPU0_P1 @T6G_MB_LIB.T6G(SCH_1):PVDDCR_CPU0_P1    I29 @T6G_MB_LIB.T6G(SCH_1):PAGE57
  AU44 PVDDCR_CPU0_P1 @T6G_MB_LIB.T6G(SCH_1):PVDDCR_CPU0_P1    I29 @T6G_MB_LIB.T6G(SCH_1):PAGE57
  AU48 PVDDCR_CPU0_P1 @T6G_MB_LIB.T6G(SCH_1):PVDDCR_CPU0_P1    I29 @T6G_MB_LIB.T6G(SCH_1):PAGE57
  AU25 PVDDCR_CPU0_P1 @T6G_MB_LIB.T6G(SCH_1):PVDDCR_CPU0_P1    I29 @T6G_MB_LIB.T6G(SCH_1):PAGE57
  AU33 PVDDCR_CPU0_P1 @T6G_MB_LIB.T6G(SCH_1):PVDDCR_CPU0_P1    I29 @T6G_MB_LIB.T6G(SCH_1):PAGE57
  BN31 PVDDCR_CPU1_P1 @T6G_MB_LIB.T6G(SCH_1):PVDDCR_CPU1_P1    I32 @T6G_MB_LIB.T6G(SCH_1):PAGE57
  BN42 PVDDCR_CPU1_P1 @T6G_MB_LIB.T6G(SCH_1):PVDDCR_CPU1_P1    I32 @T6G_MB_LIB.T6G(SCH_1):PAGE57
  BN50 PVDDCR_CPU1_P1 @T6G_MB_LIB.T6G(SCH_1):PVDDCR_CPU1_P1    I32 @T6G_MB_LIB.T6G(SCH_1):PAGE57
  BP26 PVDDCR_CPU1_P1 @T6G_MB_LIB.T6G(SCH_1):PVDDCR_CPU1_P1    I32 @T6G_MB_LIB.T6G(SCH_1):PAGE57
  BP30 PVDDCR_CPU1_P1 @T6G_MB_LIB.T6G(SCH_1):PVDDCR_CPU1_P1    I32 @T6G_MB_LIB.T6G(SCH_1):PAGE57
  BP34 PVDDCR_CPU1_P1 @T6G_MB_LIB.T6G(SCH_1):PVDDCR_CPU1_P1    I32 @T6G_MB_LIB.T6G(SCH_1):PAGE57
  BP36 PVDDCR_CPU1_P1 @T6G_MB_LIB.T6G(SCH_1):PVDDCR_CPU1_P1    I32 @T6G_MB_LIB.T6G(SCH_1):PAGE57
  BP39 PVDDCR_CPU1_P1 @T6G_MB_LIB.T6G(SCH_1):PVDDCR_CPU1_P1    I32 @T6G_MB_LIB.T6G(SCH_1):PAGE57
  BP41 PVDDCR_CPU1_P1 @T6G_MB_LIB.T6G(SCH_1):PVDDCR_CPU1_P1    I32 @T6G_MB_LIB.T6G(SCH_1):PAGE57
  BP43 PVDDCR_CPU1_P1 @T6G_MB_LIB.T6G(SCH_1):PVDDCR_CPU1_P1    I32 @T6G_MB_LIB.T6G(SCH_1):PAGE57
  BP45 PVDDCR_CPU1_P1 @T6G_MB_LIB.T6G(SCH_1):PVDDCR_CPU1_P1    I32 @T6G_MB_LIB.T6G(SCH_1):PAGE57
  BP47 PVDDCR_CPU1_P1 @T6G_MB_LIB.T6G(SCH_1):PVDDCR_CPU1_P1    I32 @T6G_MB_LIB.T6G(SCH_1):PAGE57
  BP49 PVDDCR_CPU1_P1 @T6G_MB_LIB.T6G(SCH_1):PVDDCR_CPU1_P1    I32 @T6G_MB_LIB.T6G(SCH_1):PAGE57
  BR23 PVDDCR_CPU1_P1 @T6G_MB_LIB.T6G(SCH_1):PVDDCR_CPU1_P1    I32 @T6G_MB_LIB.T6G(SCH_1):PAGE57
  BR25 PVDDCR_CPU1_P1 @T6G_MB_LIB.T6G(SCH_1):PVDDCR_CPU1_P1    I32 @T6G_MB_LIB.T6G(SCH_1):PAGE57
  BR27 PVDDCR_CPU1_P1 @T6G_MB_LIB.T6G(SCH_1):PVDDCR_CPU1_P1    I32 @T6G_MB_LIB.T6G(SCH_1):PAGE57
  BR29 PVDDCR_CPU1_P1 @T6G_MB_LIB.T6G(SCH_1):PVDDCR_CPU1_P1    I32 @T6G_MB_LIB.T6G(SCH_1):PAGE57
  BR31 PVDDCR_CPU1_P1 @T6G_MB_LIB.T6G(SCH_1):PVDDCR_CPU1_P1    I32 @T6G_MB_LIB.T6G(SCH_1):PAGE57
  BR33 PVDDCR_CPU1_P1 @T6G_MB_LIB.T6G(SCH_1):PVDDCR_CPU1_P1    I32 @T6G_MB_LIB.T6G(SCH_1):PAGE57
  BR35 PVDDCR_CPU1_P1 @T6G_MB_LIB.T6G(SCH_1):PVDDCR_CPU1_P1    I32 @T6G_MB_LIB.T6G(SCH_1):PAGE57
  BR40 PVDDCR_CPU1_P1 @T6G_MB_LIB.T6G(SCH_1):PVDDCR_CPU1_P1    I32 @T6G_MB_LIB.T6G(SCH_1):PAGE57
  BR42 PVDDCR_CPU1_P1 @T6G_MB_LIB.T6G(SCH_1):PVDDCR_CPU1_P1    I32 @T6G_MB_LIB.T6G(SCH_1):PAGE57
  BR44 PVDDCR_CPU1_P1 @T6G_MB_LIB.T6G(SCH_1):PVDDCR_CPU1_P1    I32 @T6G_MB_LIB.T6G(SCH_1):PAGE57
  BR46 PVDDCR_CPU1_P1 @T6G_MB_LIB.T6G(SCH_1):PVDDCR_CPU1_P1    I32 @T6G_MB_LIB.T6G(SCH_1):PAGE57
  BR48 PVDDCR_CPU1_P1 @T6G_MB_LIB.T6G(SCH_1):PVDDCR_CPU1_P1    I32 @T6G_MB_LIB.T6G(SCH_1):PAGE57
  BR50 PVDDCR_CPU1_P1 @T6G_MB_LIB.T6G(SCH_1):PVDDCR_CPU1_P1    I32 @T6G_MB_LIB.T6G(SCH_1):PAGE57
  BR52 PVDDCR_CPU1_P1 @T6G_MB_LIB.T6G(SCH_1):PVDDCR_CPU1_P1    I32 @T6G_MB_LIB.T6G(SCH_1):PAGE57
  BT23 PVDDCR_CPU1_P1 @T6G_MB_LIB.T6G(SCH_1):PVDDCR_CPU1_P1    I32 @T6G_MB_LIB.T6G(SCH_1):PAGE57
  BT24 PVDDCR_CPU1_P1 @T6G_MB_LIB.T6G(SCH_1):PVDDCR_CPU1_P1    I32 @T6G_MB_LIB.T6G(SCH_1):PAGE57
  BT26 PVDDCR_CPU1_P1 @T6G_MB_LIB.T6G(SCH_1):PVDDCR_CPU1_P1    I32 @T6G_MB_LIB.T6G(SCH_1):PAGE57
  BT27 PVDDCR_CPU1_P1 @T6G_MB_LIB.T6G(SCH_1):PVDDCR_CPU1_P1    I32 @T6G_MB_LIB.T6G(SCH_1):PAGE57
  BT29 PVDDCR_CPU1_P1 @T6G_MB_LIB.T6G(SCH_1):PVDDCR_CPU1_P1    I32 @T6G_MB_LIB.T6G(SCH_1):PAGE57
  BT30 PVDDCR_CPU1_P1 @T6G_MB_LIB.T6G(SCH_1):PVDDCR_CPU1_P1    I32 @T6G_MB_LIB.T6G(SCH_1):PAGE57
  BT32 PVDDCR_CPU1_P1 @T6G_MB_LIB.T6G(SCH_1):PVDDCR_CPU1_P1    I32 @T6G_MB_LIB.T6G(SCH_1):PAGE57
  BT33 PVDDCR_CPU1_P1 @T6G_MB_LIB.T6G(SCH_1):PVDDCR_CPU1_P1    I32 @T6G_MB_LIB.T6G(SCH_1):PAGE57
  BT43 PVDDCR_CPU1_P1 @T6G_MB_LIB.T6G(SCH_1):PVDDCR_CPU1_P1    I32 @T6G_MB_LIB.T6G(SCH_1):PAGE57
  BT44 PVDDCR_CPU1_P1 @T6G_MB_LIB.T6G(SCH_1):PVDDCR_CPU1_P1    I32 @T6G_MB_LIB.T6G(SCH_1):PAGE57
  BT46 PVDDCR_CPU1_P1 @T6G_MB_LIB.T6G(SCH_1):PVDDCR_CPU1_P1    I32 @T6G_MB_LIB.T6G(SCH_1):PAGE57
  BT47 PVDDCR_CPU1_P1 @T6G_MB_LIB.T6G(SCH_1):PVDDCR_CPU1_P1    I32 @T6G_MB_LIB.T6G(SCH_1):PAGE57
  BT49 PVDDCR_CPU1_P1 @T6G_MB_LIB.T6G(SCH_1):PVDDCR_CPU1_P1    I32 @T6G_MB_LIB.T6G(SCH_1):PAGE57
  BT50 PVDDCR_CPU1_P1 @T6G_MB_LIB.T6G(SCH_1):PVDDCR_CPU1_P1    I32 @T6G_MB_LIB.T6G(SCH_1):PAGE57
  BT52 PVDDCR_CPU1_P1 @T6G_MB_LIB.T6G(SCH_1):PVDDCR_CPU1_P1    I32 @T6G_MB_LIB.T6G(SCH_1):PAGE57
  BT53 PVDDCR_CPU1_P1 @T6G_MB_LIB.T6G(SCH_1):PVDDCR_CPU1_P1    I32 @T6G_MB_LIB.T6G(SCH_1):PAGE57
  BW35 PVDDCR_CPU1_P1 @T6G_MB_LIB.T6G(SCH_1):PVDDCR_CPU1_P1    I32 @T6G_MB_LIB.T6G(SCH_1):PAGE57
  BW36 PVDDCR_CPU1_P1 @T6G_MB_LIB.T6G(SCH_1):PVDDCR_CPU1_P1    I32 @T6G_MB_LIB.T6G(SCH_1):PAGE57
  BW40 PVDDCR_CPU1_P1 @T6G_MB_LIB.T6G(SCH_1):PVDDCR_CPU1_P1    I32 @T6G_MB_LIB.T6G(SCH_1):PAGE57
  BW41 PVDDCR_CPU1_P1 @T6G_MB_LIB.T6G(SCH_1):PVDDCR_CPU1_P1    I32 @T6G_MB_LIB.T6G(SCH_1):PAGE57
  BY23 PVDDCR_CPU1_P1 @T6G_MB_LIB.T6G(SCH_1):PVDDCR_CPU1_P1    I32 @T6G_MB_LIB.T6G(SCH_1):PAGE57
  BY24 PVDDCR_CPU1_P1 @T6G_MB_LIB.T6G(SCH_1):PVDDCR_CPU1_P1    I32 @T6G_MB_LIB.T6G(SCH_1):PAGE57
  BY26 PVDDCR_CPU1_P1 @T6G_MB_LIB.T6G(SCH_1):PVDDCR_CPU1_P1    I32 @T6G_MB_LIB.T6G(SCH_1):PAGE57
  BY27 PVDDCR_CPU1_P1 @T6G_MB_LIB.T6G(SCH_1):PVDDCR_CPU1_P1    I32 @T6G_MB_LIB.T6G(SCH_1):PAGE57
  BY29 PVDDCR_CPU1_P1 @T6G_MB_LIB.T6G(SCH_1):PVDDCR_CPU1_P1    I32 @T6G_MB_LIB.T6G(SCH_1):PAGE57
  BY30 PVDDCR_CPU1_P1 @T6G_MB_LIB.T6G(SCH_1):PVDDCR_CPU1_P1    I32 @T6G_MB_LIB.T6G(SCH_1):PAGE57
  BY32 PVDDCR_CPU1_P1 @T6G_MB_LIB.T6G(SCH_1):PVDDCR_CPU1_P1    I32 @T6G_MB_LIB.T6G(SCH_1):PAGE57
  BY33 PVDDCR_CPU1_P1 @T6G_MB_LIB.T6G(SCH_1):PVDDCR_CPU1_P1    I32 @T6G_MB_LIB.T6G(SCH_1):PAGE57
  BY43 PVDDCR_CPU1_P1 @T6G_MB_LIB.T6G(SCH_1):PVDDCR_CPU1_P1    I32 @T6G_MB_LIB.T6G(SCH_1):PAGE57
  BY44 PVDDCR_CPU1_P1 @T6G_MB_LIB.T6G(SCH_1):PVDDCR_CPU1_P1    I32 @T6G_MB_LIB.T6G(SCH_1):PAGE57
  BY46 PVDDCR_CPU1_P1 @T6G_MB_LIB.T6G(SCH_1):PVDDCR_CPU1_P1    I32 @T6G_MB_LIB.T6G(SCH_1):PAGE57
  BY47 PVDDCR_CPU1_P1 @T6G_MB_LIB.T6G(SCH_1):PVDDCR_CPU1_P1    I32 @T6G_MB_LIB.T6G(SCH_1):PAGE57
  BY49 PVDDCR_CPU1_P1 @T6G_MB_LIB.T6G(SCH_1):PVDDCR_CPU1_P1    I32 @T6G_MB_LIB.T6G(SCH_1):PAGE57
  BY50 PVDDCR_CPU1_P1 @T6G_MB_LIB.T6G(SCH_1):PVDDCR_CPU1_P1    I32 @T6G_MB_LIB.T6G(SCH_1):PAGE57
  BY52 PVDDCR_CPU1_P1 @T6G_MB_LIB.T6G(SCH_1):PVDDCR_CPU1_P1    I32 @T6G_MB_LIB.T6G(SCH_1):PAGE57
  BY53 PVDDCR_CPU1_P1 @T6G_MB_LIB.T6G(SCH_1):PVDDCR_CPU1_P1    I32 @T6G_MB_LIB.T6G(SCH_1):PAGE57
  CC35 PVDDCR_CPU1_P1 @T6G_MB_LIB.T6G(SCH_1):PVDDCR_CPU1_P1    I32 @T6G_MB_LIB.T6G(SCH_1):PAGE57
  CC36 PVDDCR_CPU1_P1 @T6G_MB_LIB.T6G(SCH_1):PVDDCR_CPU1_P1    I32 @T6G_MB_LIB.T6G(SCH_1):PAGE57
  CC40 PVDDCR_CPU1_P1 @T6G_MB_LIB.T6G(SCH_1):PVDDCR_CPU1_P1    I32 @T6G_MB_LIB.T6G(SCH_1):PAGE57
  CC41 PVDDCR_CPU1_P1 @T6G_MB_LIB.T6G(SCH_1):PVDDCR_CPU1_P1    I32 @T6G_MB_LIB.T6G(SCH_1):PAGE57
  CD23 PVDDCR_CPU1_P1 @T6G_MB_LIB.T6G(SCH_1):PVDDCR_CPU1_P1    I32 @T6G_MB_LIB.T6G(SCH_1):PAGE57
  CD24 PVDDCR_CPU1_P1 @T6G_MB_LIB.T6G(SCH_1):PVDDCR_CPU1_P1    I32 @T6G_MB_LIB.T6G(SCH_1):PAGE57
  CD26 PVDDCR_CPU1_P1 @T6G_MB_LIB.T6G(SCH_1):PVDDCR_CPU1_P1    I32 @T6G_MB_LIB.T6G(SCH_1):PAGE57
  CD27 PVDDCR_CPU1_P1 @T6G_MB_LIB.T6G(SCH_1):PVDDCR_CPU1_P1    I32 @T6G_MB_LIB.T6G(SCH_1):PAGE57
  CD29 PVDDCR_CPU1_P1 @T6G_MB_LIB.T6G(SCH_1):PVDDCR_CPU1_P1    I32 @T6G_MB_LIB.T6G(SCH_1):PAGE57
  CD30 PVDDCR_CPU1_P1 @T6G_MB_LIB.T6G(SCH_1):PVDDCR_CPU1_P1    I32 @T6G_MB_LIB.T6G(SCH_1):PAGE57
  CD32 PVDDCR_CPU1_P1 @T6G_MB_LIB.T6G(SCH_1):PVDDCR_CPU1_P1    I32 @T6G_MB_LIB.T6G(SCH_1):PAGE57
  CD33 PVDDCR_CPU1_P1 @T6G_MB_LIB.T6G(SCH_1):PVDDCR_CPU1_P1    I32 @T6G_MB_LIB.T6G(SCH_1):PAGE57
  CD43 PVDDCR_CPU1_P1 @T6G_MB_LIB.T6G(SCH_1):PVDDCR_CPU1_P1    I32 @T6G_MB_LIB.T6G(SCH_1):PAGE57
  CD44 PVDDCR_CPU1_P1 @T6G_MB_LIB.T6G(SCH_1):PVDDCR_CPU1_P1    I32 @T6G_MB_LIB.T6G(SCH_1):PAGE57
  CD46 PVDDCR_CPU1_P1 @T6G_MB_LIB.T6G(SCH_1):PVDDCR_CPU1_P1    I32 @T6G_MB_LIB.T6G(SCH_1):PAGE57
  CD47 PVDDCR_CPU1_P1 @T6G_MB_LIB.T6G(SCH_1):PVDDCR_CPU1_P1    I32 @T6G_MB_LIB.T6G(SCH_1):PAGE57
  CD49 PVDDCR_CPU1_P1 @T6G_MB_LIB.T6G(SCH_1):PVDDCR_CPU1_P1    I32 @T6G_MB_LIB.T6G(SCH_1):PAGE57
  CD50 PVDDCR_CPU1_P1 @T6G_MB_LIB.T6G(SCH_1):PVDDCR_CPU1_P1    I32 @T6G_MB_LIB.T6G(SCH_1):PAGE57
  CD52 PVDDCR_CPU1_P1 @T6G_MB_LIB.T6G(SCH_1):PVDDCR_CPU1_P1    I32 @T6G_MB_LIB.T6G(SCH_1):PAGE57
  CD53 PVDDCR_CPU1_P1 @T6G_MB_LIB.T6G(SCH_1):PVDDCR_CPU1_P1    I32 @T6G_MB_LIB.T6G(SCH_1):PAGE57
  CG35 PVDDCR_CPU1_P1 @T6G_MB_LIB.T6G(SCH_1):PVDDCR_CPU1_P1    I32 @T6G_MB_LIB.T6G(SCH_1):PAGE57
  CG36 PVDDCR_CPU1_P1 @T6G_MB_LIB.T6G(SCH_1):PVDDCR_CPU1_P1    I32 @T6G_MB_LIB.T6G(SCH_1):PAGE57
  CG40 PVDDCR_CPU1_P1 @T6G_MB_LIB.T6G(SCH_1):PVDDCR_CPU1_P1    I32 @T6G_MB_LIB.T6G(SCH_1):PAGE57
  CG41 PVDDCR_CPU1_P1 @T6G_MB_LIB.T6G(SCH_1):PVDDCR_CPU1_P1    I32 @T6G_MB_LIB.T6G(SCH_1):PAGE57
  CH23 PVDDCR_CPU1_P1 @T6G_MB_LIB.T6G(SCH_1):PVDDCR_CPU1_P1    I32 @T6G_MB_LIB.T6G(SCH_1):PAGE57
  CH24 PVDDCR_CPU1_P1 @T6G_MB_LIB.T6G(SCH_1):PVDDCR_CPU1_P1    I32 @T6G_MB_LIB.T6G(SCH_1):PAGE57
  CH26 PVDDCR_CPU1_P1 @T6G_MB_LIB.T6G(SCH_1):PVDDCR_CPU1_P1    I32 @T6G_MB_LIB.T6G(SCH_1):PAGE57
  CH27 PVDDCR_CPU1_P1 @T6G_MB_LIB.T6G(SCH_1):PVDDCR_CPU1_P1    I32 @T6G_MB_LIB.T6G(SCH_1):PAGE57
  CH29 PVDDCR_CPU1_P1 @T6G_MB_LIB.T6G(SCH_1):PVDDCR_CPU1_P1    I32 @T6G_MB_LIB.T6G(SCH_1):PAGE57
  CH30 PVDDCR_CPU1_P1 @T6G_MB_LIB.T6G(SCH_1):PVDDCR_CPU1_P1    I32 @T6G_MB_LIB.T6G(SCH_1):PAGE57
  CH32 PVDDCR_CPU1_P1 @T6G_MB_LIB.T6G(SCH_1):PVDDCR_CPU1_P1    I32 @T6G_MB_LIB.T6G(SCH_1):PAGE57
  CH33 PVDDCR_CPU1_P1 @T6G_MB_LIB.T6G(SCH_1):PVDDCR_CPU1_P1    I32 @T6G_MB_LIB.T6G(SCH_1):PAGE57
  CH43 PVDDCR_CPU1_P1 @T6G_MB_LIB.T6G(SCH_1):PVDDCR_CPU1_P1    I32 @T6G_MB_LIB.T6G(SCH_1):PAGE57
  CH44 PVDDCR_CPU1_P1 @T6G_MB_LIB.T6G(SCH_1):PVDDCR_CPU1_P1    I32 @T6G_MB_LIB.T6G(SCH_1):PAGE57
  CH46 PVDDCR_CPU1_P1 @T6G_MB_LIB.T6G(SCH_1):PVDDCR_CPU1_P1    I32 @T6G_MB_LIB.T6G(SCH_1):PAGE57
  CH47 PVDDCR_CPU1_P1 @T6G_MB_LIB.T6G(SCH_1):PVDDCR_CPU1_P1    I32 @T6G_MB_LIB.T6G(SCH_1):PAGE57
  CH49 PVDDCR_CPU1_P1 @T6G_MB_LIB.T6G(SCH_1):PVDDCR_CPU1_P1    I32 @T6G_MB_LIB.T6G(SCH_1):PAGE57
  CH50 PVDDCR_CPU1_P1 @T6G_MB_LIB.T6G(SCH_1):PVDDCR_CPU1_P1    I32 @T6G_MB_LIB.T6G(SCH_1):PAGE57
  CH52 PVDDCR_CPU1_P1 @T6G_MB_LIB.T6G(SCH_1):PVDDCR_CPU1_P1    I32 @T6G_MB_LIB.T6G(SCH_1):PAGE57
  CH53 PVDDCR_CPU1_P1 @T6G_MB_LIB.T6G(SCH_1):PVDDCR_CPU1_P1    I32 @T6G_MB_LIB.T6G(SCH_1):PAGE57
  CK35 PVDDCR_CPU1_P1 @T6G_MB_LIB.T6G(SCH_1):PVDDCR_CPU1_P1    I32 @T6G_MB_LIB.T6G(SCH_1):PAGE57
  CK36 PVDDCR_CPU1_P1 @T6G_MB_LIB.T6G(SCH_1):PVDDCR_CPU1_P1    I32 @T6G_MB_LIB.T6G(SCH_1):PAGE57
  CK40 PVDDCR_CPU1_P1 @T6G_MB_LIB.T6G(SCH_1):PVDDCR_CPU1_P1    I32 @T6G_MB_LIB.T6G(SCH_1):PAGE57
  CK41 PVDDCR_CPU1_P1 @T6G_MB_LIB.T6G(SCH_1):PVDDCR_CPU1_P1    I32 @T6G_MB_LIB.T6G(SCH_1):PAGE57
  CL29 PVDDCR_CPU1_P1 @T6G_MB_LIB.T6G(SCH_1):PVDDCR_CPU1_P1    I32 @T6G_MB_LIB.T6G(SCH_1):PAGE57
  CL30 PVDDCR_CPU1_P1 @T6G_MB_LIB.T6G(SCH_1):PVDDCR_CPU1_P1    I32 @T6G_MB_LIB.T6G(SCH_1):PAGE57
  CL32 PVDDCR_CPU1_P1 @T6G_MB_LIB.T6G(SCH_1):PVDDCR_CPU1_P1    I32 @T6G_MB_LIB.T6G(SCH_1):PAGE57
  CL33 PVDDCR_CPU1_P1 @T6G_MB_LIB.T6G(SCH_1):PVDDCR_CPU1_P1    I32 @T6G_MB_LIB.T6G(SCH_1):PAGE57
  CL43 PVDDCR_CPU1_P1 @T6G_MB_LIB.T6G(SCH_1):PVDDCR_CPU1_P1    I32 @T6G_MB_LIB.T6G(SCH_1):PAGE57
  CL44 PVDDCR_CPU1_P1 @T6G_MB_LIB.T6G(SCH_1):PVDDCR_CPU1_P1    I32 @T6G_MB_LIB.T6G(SCH_1):PAGE57
  CL46 PVDDCR_CPU1_P1 @T6G_MB_LIB.T6G(SCH_1):PVDDCR_CPU1_P1    I32 @T6G_MB_LIB.T6G(SCH_1):PAGE57
  CL47 PVDDCR_CPU1_P1 @T6G_MB_LIB.T6G(SCH_1):PVDDCR_CPU1_P1    I32 @T6G_MB_LIB.T6G(SCH_1):PAGE57
  CN35 PVDDCR_CPU1_P1 @T6G_MB_LIB.T6G(SCH_1):PVDDCR_CPU1_P1    I32 @T6G_MB_LIB.T6G(SCH_1):PAGE57
  CN36 PVDDCR_CPU1_P1 @T6G_MB_LIB.T6G(SCH_1):PVDDCR_CPU1_P1    I32 @T6G_MB_LIB.T6G(SCH_1):PAGE57
  CN40 PVDDCR_CPU1_P1 @T6G_MB_LIB.T6G(SCH_1):PVDDCR_CPU1_P1    I32 @T6G_MB_LIB.T6G(SCH_1):PAGE57
  CN41 PVDDCR_CPU1_P1 @T6G_MB_LIB.T6G(SCH_1):PVDDCR_CPU1_P1    I32 @T6G_MB_LIB.T6G(SCH_1):PAGE57
  CP23 PVDDCR_CPU1_P1 @T6G_MB_LIB.T6G(SCH_1):PVDDCR_CPU1_P1    I32 @T6G_MB_LIB.T6G(SCH_1):PAGE57
  CP24 PVDDCR_CPU1_P1 @T6G_MB_LIB.T6G(SCH_1):PVDDCR_CPU1_P1    I32 @T6G_MB_LIB.T6G(SCH_1):PAGE57
  CP26 PVDDCR_CPU1_P1 @T6G_MB_LIB.T6G(SCH_1):PVDDCR_CPU1_P1    I32 @T6G_MB_LIB.T6G(SCH_1):PAGE57
  CP27 PVDDCR_CPU1_P1 @T6G_MB_LIB.T6G(SCH_1):PVDDCR_CPU1_P1    I32 @T6G_MB_LIB.T6G(SCH_1):PAGE57
  CP29 PVDDCR_CPU1_P1 @T6G_MB_LIB.T6G(SCH_1):PVDDCR_CPU1_P1    I32 @T6G_MB_LIB.T6G(SCH_1):PAGE57
  CP30 PVDDCR_CPU1_P1 @T6G_MB_LIB.T6G(SCH_1):PVDDCR_CPU1_P1    I32 @T6G_MB_LIB.T6G(SCH_1):PAGE57
  CP32 PVDDCR_CPU1_P1 @T6G_MB_LIB.T6G(SCH_1):PVDDCR_CPU1_P1    I32 @T6G_MB_LIB.T6G(SCH_1):PAGE57
  CP33 PVDDCR_CPU1_P1 @T6G_MB_LIB.T6G(SCH_1):PVDDCR_CPU1_P1    I32 @T6G_MB_LIB.T6G(SCH_1):PAGE57
  CP43 PVDDCR_CPU1_P1 @T6G_MB_LIB.T6G(SCH_1):PVDDCR_CPU1_P1    I32 @T6G_MB_LIB.T6G(SCH_1):PAGE57
  CP44 PVDDCR_CPU1_P1 @T6G_MB_LIB.T6G(SCH_1):PVDDCR_CPU1_P1    I32 @T6G_MB_LIB.T6G(SCH_1):PAGE57
  CP46 PVDDCR_CPU1_P1 @T6G_MB_LIB.T6G(SCH_1):PVDDCR_CPU1_P1    I32 @T6G_MB_LIB.T6G(SCH_1):PAGE57
  CP47 PVDDCR_CPU1_P1 @T6G_MB_LIB.T6G(SCH_1):PVDDCR_CPU1_P1    I32 @T6G_MB_LIB.T6G(SCH_1):PAGE57
  CP49 PVDDCR_CPU1_P1 @T6G_MB_LIB.T6G(SCH_1):PVDDCR_CPU1_P1    I32 @T6G_MB_LIB.T6G(SCH_1):PAGE57
  CP50 PVDDCR_CPU1_P1 @T6G_MB_LIB.T6G(SCH_1):PVDDCR_CPU1_P1    I32 @T6G_MB_LIB.T6G(SCH_1):PAGE57
  CP52 PVDDCR_CPU1_P1 @T6G_MB_LIB.T6G(SCH_1):PVDDCR_CPU1_P1    I32 @T6G_MB_LIB.T6G(SCH_1):PAGE57
  CP53 PVDDCR_CPU1_P1 @T6G_MB_LIB.T6G(SCH_1):PVDDCR_CPU1_P1    I32 @T6G_MB_LIB.T6G(SCH_1):PAGE57
  CU35 PVDDCR_CPU1_P1 @T6G_MB_LIB.T6G(SCH_1):PVDDCR_CPU1_P1    I32 @T6G_MB_LIB.T6G(SCH_1):PAGE57
  CU36 PVDDCR_CPU1_P1 @T6G_MB_LIB.T6G(SCH_1):PVDDCR_CPU1_P1    I32 @T6G_MB_LIB.T6G(SCH_1):PAGE57
  CU40 PVDDCR_CPU1_P1 @T6G_MB_LIB.T6G(SCH_1):PVDDCR_CPU1_P1    I32 @T6G_MB_LIB.T6G(SCH_1):PAGE57
  CU41 PVDDCR_CPU1_P1 @T6G_MB_LIB.T6G(SCH_1):PVDDCR_CPU1_P1    I32 @T6G_MB_LIB.T6G(SCH_1):PAGE57
  CV23 PVDDCR_CPU1_P1 @T6G_MB_LIB.T6G(SCH_1):PVDDCR_CPU1_P1    I32 @T6G_MB_LIB.T6G(SCH_1):PAGE57
  CV24 PVDDCR_CPU1_P1 @T6G_MB_LIB.T6G(SCH_1):PVDDCR_CPU1_P1    I32 @T6G_MB_LIB.T6G(SCH_1):PAGE57
  CV26 PVDDCR_CPU1_P1 @T6G_MB_LIB.T6G(SCH_1):PVDDCR_CPU1_P1    I32 @T6G_MB_LIB.T6G(SCH_1):PAGE57
  CV27 PVDDCR_CPU1_P1 @T6G_MB_LIB.T6G(SCH_1):PVDDCR_CPU1_P1    I32 @T6G_MB_LIB.T6G(SCH_1):PAGE57
  CV29 PVDDCR_CPU1_P1 @T6G_MB_LIB.T6G(SCH_1):PVDDCR_CPU1_P1    I32 @T6G_MB_LIB.T6G(SCH_1):PAGE57
  CV30 PVDDCR_CPU1_P1 @T6G_MB_LIB.T6G(SCH_1):PVDDCR_CPU1_P1    I32 @T6G_MB_LIB.T6G(SCH_1):PAGE57
  CV32 PVDDCR_CPU1_P1 @T6G_MB_LIB.T6G(SCH_1):PVDDCR_CPU1_P1    I32 @T6G_MB_LIB.T6G(SCH_1):PAGE57
  CV33 PVDDCR_CPU1_P1 @T6G_MB_LIB.T6G(SCH_1):PVDDCR_CPU1_P1    I32 @T6G_MB_LIB.T6G(SCH_1):PAGE57
  CV43 PVDDCR_CPU1_P1 @T6G_MB_LIB.T6G(SCH_1):PVDDCR_CPU1_P1    I32 @T6G_MB_LIB.T6G(SCH_1):PAGE57
  CV44 PVDDCR_CPU1_P1 @T6G_MB_LIB.T6G(SCH_1):PVDDCR_CPU1_P1    I32 @T6G_MB_LIB.T6G(SCH_1):PAGE57
  CV46 PVDDCR_CPU1_P1 @T6G_MB_LIB.T6G(SCH_1):PVDDCR_CPU1_P1    I32 @T6G_MB_LIB.T6G(SCH_1):PAGE57
  CV47 PVDDCR_CPU1_P1 @T6G_MB_LIB.T6G(SCH_1):PVDDCR_CPU1_P1    I32 @T6G_MB_LIB.T6G(SCH_1):PAGE57
  CV49 PVDDCR_CPU1_P1 @T6G_MB_LIB.T6G(SCH_1):PVDDCR_CPU1_P1    I32 @T6G_MB_LIB.T6G(SCH_1):PAGE57
  CV50 PVDDCR_CPU1_P1 @T6G_MB_LIB.T6G(SCH_1):PVDDCR_CPU1_P1    I32 @T6G_MB_LIB.T6G(SCH_1):PAGE57
  CV52 PVDDCR_CPU1_P1 @T6G_MB_LIB.T6G(SCH_1):PVDDCR_CPU1_P1    I32 @T6G_MB_LIB.T6G(SCH_1):PAGE57
  CV53 PVDDCR_CPU1_P1 @T6G_MB_LIB.T6G(SCH_1):PVDDCR_CPU1_P1    I32 @T6G_MB_LIB.T6G(SCH_1):PAGE57
  DA35 PVDDCR_CPU1_P1 @T6G_MB_LIB.T6G(SCH_1):PVDDCR_CPU1_P1    I32 @T6G_MB_LIB.T6G(SCH_1):PAGE57
  DA36 PVDDCR_CPU1_P1 @T6G_MB_LIB.T6G(SCH_1):PVDDCR_CPU1_P1    I32 @T6G_MB_LIB.T6G(SCH_1):PAGE57
  DA40 PVDDCR_CPU1_P1 @T6G_MB_LIB.T6G(SCH_1):PVDDCR_CPU1_P1    I32 @T6G_MB_LIB.T6G(SCH_1):PAGE57
  DA41 PVDDCR_CPU1_P1 @T6G_MB_LIB.T6G(SCH_1):PVDDCR_CPU1_P1    I32 @T6G_MB_LIB.T6G(SCH_1):PAGE57
  DB23 PVDDCR_CPU1_P1 @T6G_MB_LIB.T6G(SCH_1):PVDDCR_CPU1_P1    I32 @T6G_MB_LIB.T6G(SCH_1):PAGE57
  DB24 PVDDCR_CPU1_P1 @T6G_MB_LIB.T6G(SCH_1):PVDDCR_CPU1_P1    I32 @T6G_MB_LIB.T6G(SCH_1):PAGE57
  DB26 PVDDCR_CPU1_P1 @T6G_MB_LIB.T6G(SCH_1):PVDDCR_CPU1_P1    I32 @T6G_MB_LIB.T6G(SCH_1):PAGE57
  DB27 PVDDCR_CPU1_P1 @T6G_MB_LIB.T6G(SCH_1):PVDDCR_CPU1_P1    I32 @T6G_MB_LIB.T6G(SCH_1):PAGE57
  DB29 PVDDCR_CPU1_P1 @T6G_MB_LIB.T6G(SCH_1):PVDDCR_CPU1_P1    I32 @T6G_MB_LIB.T6G(SCH_1):PAGE57
  DB30 PVDDCR_CPU1_P1 @T6G_MB_LIB.T6G(SCH_1):PVDDCR_CPU1_P1    I32 @T6G_MB_LIB.T6G(SCH_1):PAGE57
  DB32 PVDDCR_CPU1_P1 @T6G_MB_LIB.T6G(SCH_1):PVDDCR_CPU1_P1    I32 @T6G_MB_LIB.T6G(SCH_1):PAGE57
  DB33 PVDDCR_CPU1_P1 @T6G_MB_LIB.T6G(SCH_1):PVDDCR_CPU1_P1    I32 @T6G_MB_LIB.T6G(SCH_1):PAGE57
  DB43 PVDDCR_CPU1_P1 @T6G_MB_LIB.T6G(SCH_1):PVDDCR_CPU1_P1    I32 @T6G_MB_LIB.T6G(SCH_1):PAGE57
  DB44 PVDDCR_CPU1_P1 @T6G_MB_LIB.T6G(SCH_1):PVDDCR_CPU1_P1    I32 @T6G_MB_LIB.T6G(SCH_1):PAGE57
  DB46 PVDDCR_CPU1_P1 @T6G_MB_LIB.T6G(SCH_1):PVDDCR_CPU1_P1    I32 @T6G_MB_LIB.T6G(SCH_1):PAGE57
  DB47 PVDDCR_CPU1_P1 @T6G_MB_LIB.T6G(SCH_1):PVDDCR_CPU1_P1    I32 @T6G_MB_LIB.T6G(SCH_1):PAGE57
  DB49 PVDDCR_CPU1_P1 @T6G_MB_LIB.T6G(SCH_1):PVDDCR_CPU1_P1    I32 @T6G_MB_LIB.T6G(SCH_1):PAGE57
  DB50 PVDDCR_CPU1_P1 @T6G_MB_LIB.T6G(SCH_1):PVDDCR_CPU1_P1    I32 @T6G_MB_LIB.T6G(SCH_1):PAGE57
  DB52 PVDDCR_CPU1_P1 @T6G_MB_LIB.T6G(SCH_1):PVDDCR_CPU1_P1    I32 @T6G_MB_LIB.T6G(SCH_1):PAGE57
  DB53 PVDDCR_CPU1_P1 @T6G_MB_LIB.T6G(SCH_1):PVDDCR_CPU1_P1    I32 @T6G_MB_LIB.T6G(SCH_1):PAGE57
  DC35 PVDDCR_CPU1_P1 @T6G_MB_LIB.T6G(SCH_1):PVDDCR_CPU1_P1    I32 @T6G_MB_LIB.T6G(SCH_1):PAGE57
  DC36 PVDDCR_CPU1_P1 @T6G_MB_LIB.T6G(SCH_1):PVDDCR_CPU1_P1    I32 @T6G_MB_LIB.T6G(SCH_1):PAGE57
  DC40 PVDDCR_CPU1_P1 @T6G_MB_LIB.T6G(SCH_1):PVDDCR_CPU1_P1    I32 @T6G_MB_LIB.T6G(SCH_1):PAGE57
  DC41 PVDDCR_CPU1_P1 @T6G_MB_LIB.T6G(SCH_1):PVDDCR_CPU1_P1    I32 @T6G_MB_LIB.T6G(SCH_1):PAGE57
  DD22 PVDDCR_CPU1_P1 @T6G_MB_LIB.T6G(SCH_1):PVDDCR_CPU1_P1    I32 @T6G_MB_LIB.T6G(SCH_1):PAGE57
  DD25 PVDDCR_CPU1_P1 @T6G_MB_LIB.T6G(SCH_1):PVDDCR_CPU1_P1    I32 @T6G_MB_LIB.T6G(SCH_1):PAGE57
  DD28 PVDDCR_CPU1_P1 @T6G_MB_LIB.T6G(SCH_1):PVDDCR_CPU1_P1    I32 @T6G_MB_LIB.T6G(SCH_1):PAGE57
  DD31 PVDDCR_CPU1_P1 @T6G_MB_LIB.T6G(SCH_1):PVDDCR_CPU1_P1    I32 @T6G_MB_LIB.T6G(SCH_1):PAGE57
  DD34 PVDDCR_CPU1_P1 @T6G_MB_LIB.T6G(SCH_1):PVDDCR_CPU1_P1    I32 @T6G_MB_LIB.T6G(SCH_1):PAGE57
  DD42 PVDDCR_CPU1_P1 @T6G_MB_LIB.T6G(SCH_1):PVDDCR_CPU1_P1    I32 @T6G_MB_LIB.T6G(SCH_1):PAGE57
  DD45 PVDDCR_CPU1_P1 @T6G_MB_LIB.T6G(SCH_1):PVDDCR_CPU1_P1    I32 @T6G_MB_LIB.T6G(SCH_1):PAGE57
  DD48 PVDDCR_CPU1_P1 @T6G_MB_LIB.T6G(SCH_1):PVDDCR_CPU1_P1    I32 @T6G_MB_LIB.T6G(SCH_1):PAGE57
  DD51 PVDDCR_CPU1_P1 @T6G_MB_LIB.T6G(SCH_1):PVDDCR_CPU1_P1    I32 @T6G_MB_LIB.T6G(SCH_1):PAGE57
  DD54 PVDDCR_CPU1_P1 @T6G_MB_LIB.T6G(SCH_1):PVDDCR_CPU1_P1    I32 @T6G_MB_LIB.T6G(SCH_1):PAGE57
  DE22 PVDDCR_CPU1_P1 @T6G_MB_LIB.T6G(SCH_1):PVDDCR_CPU1_P1    I32 @T6G_MB_LIB.T6G(SCH_1):PAGE57
  DE25 PVDDCR_CPU1_P1 @T6G_MB_LIB.T6G(SCH_1):PVDDCR_CPU1_P1    I32 @T6G_MB_LIB.T6G(SCH_1):PAGE57
  DE28 PVDDCR_CPU1_P1 @T6G_MB_LIB.T6G(SCH_1):PVDDCR_CPU1_P1    I32 @T6G_MB_LIB.T6G(SCH_1):PAGE57
  DE31 PVDDCR_CPU1_P1 @T6G_MB_LIB.T6G(SCH_1):PVDDCR_CPU1_P1    I32 @T6G_MB_LIB.T6G(SCH_1):PAGE57
  DE34 PVDDCR_CPU1_P1 @T6G_MB_LIB.T6G(SCH_1):PVDDCR_CPU1_P1    I32 @T6G_MB_LIB.T6G(SCH_1):PAGE57
  DE35 PVDDCR_CPU1_P1 @T6G_MB_LIB.T6G(SCH_1):PVDDCR_CPU1_P1    I32 @T6G_MB_LIB.T6G(SCH_1):PAGE57
  DE41 PVDDCR_CPU1_P1 @T6G_MB_LIB.T6G(SCH_1):PVDDCR_CPU1_P1    I32 @T6G_MB_LIB.T6G(SCH_1):PAGE57
  DE42 PVDDCR_CPU1_P1 @T6G_MB_LIB.T6G(SCH_1):PVDDCR_CPU1_P1    I32 @T6G_MB_LIB.T6G(SCH_1):PAGE57
  DE45 PVDDCR_CPU1_P1 @T6G_MB_LIB.T6G(SCH_1):PVDDCR_CPU1_P1    I32 @T6G_MB_LIB.T6G(SCH_1):PAGE57
  DE48 PVDDCR_CPU1_P1 @T6G_MB_LIB.T6G(SCH_1):PVDDCR_CPU1_P1    I32 @T6G_MB_LIB.T6G(SCH_1):PAGE57
  DE51 PVDDCR_CPU1_P1 @T6G_MB_LIB.T6G(SCH_1):PVDDCR_CPU1_P1    I32 @T6G_MB_LIB.T6G(SCH_1):PAGE57
  DE54 PVDDCR_CPU1_P1 @T6G_MB_LIB.T6G(SCH_1):PVDDCR_CPU1_P1    I32 @T6G_MB_LIB.T6G(SCH_1):PAGE57
  DG19 PVDDCR_CPU1_P1 @T6G_MB_LIB.T6G(SCH_1):PVDDCR_CPU1_P1    I32 @T6G_MB_LIB.T6G(SCH_1):PAGE57
  DG57 PVDDCR_CPU1_P1 @T6G_MB_LIB.T6G(SCH_1):PVDDCR_CPU1_P1    I32 @T6G_MB_LIB.T6G(SCH_1):PAGE57
  DH19 PVDDCR_CPU1_P1 @T6G_MB_LIB.T6G(SCH_1):PVDDCR_CPU1_P1    I32 @T6G_MB_LIB.T6G(SCH_1):PAGE57
  DH20 PVDDCR_CPU1_P1 @T6G_MB_LIB.T6G(SCH_1):PVDDCR_CPU1_P1    I32 @T6G_MB_LIB.T6G(SCH_1):PAGE57
  DH22 PVDDCR_CPU1_P1 @T6G_MB_LIB.T6G(SCH_1):PVDDCR_CPU1_P1    I32 @T6G_MB_LIB.T6G(SCH_1):PAGE57
  DH23 PVDDCR_CPU1_P1 @T6G_MB_LIB.T6G(SCH_1):PVDDCR_CPU1_P1    I32 @T6G_MB_LIB.T6G(SCH_1):PAGE57
  DH25 PVDDCR_CPU1_P1 @T6G_MB_LIB.T6G(SCH_1):PVDDCR_CPU1_P1    I32 @T6G_MB_LIB.T6G(SCH_1):PAGE57
  DH26 PVDDCR_CPU1_P1 @T6G_MB_LIB.T6G(SCH_1):PVDDCR_CPU1_P1    I32 @T6G_MB_LIB.T6G(SCH_1):PAGE57
  DH28 PVDDCR_CPU1_P1 @T6G_MB_LIB.T6G(SCH_1):PVDDCR_CPU1_P1    I32 @T6G_MB_LIB.T6G(SCH_1):PAGE57
  DH29 PVDDCR_CPU1_P1 @T6G_MB_LIB.T6G(SCH_1):PVDDCR_CPU1_P1    I32 @T6G_MB_LIB.T6G(SCH_1):PAGE57
  DH31 PVDDCR_CPU1_P1 @T6G_MB_LIB.T6G(SCH_1):PVDDCR_CPU1_P1    I32 @T6G_MB_LIB.T6G(SCH_1):PAGE57
  DH32 PVDDCR_CPU1_P1 @T6G_MB_LIB.T6G(SCH_1):PVDDCR_CPU1_P1    I32 @T6G_MB_LIB.T6G(SCH_1):PAGE57
  DH34 PVDDCR_CPU1_P1 @T6G_MB_LIB.T6G(SCH_1):PVDDCR_CPU1_P1    I32 @T6G_MB_LIB.T6G(SCH_1):PAGE57
  DH35 PVDDCR_CPU1_P1 @T6G_MB_LIB.T6G(SCH_1):PVDDCR_CPU1_P1    I32 @T6G_MB_LIB.T6G(SCH_1):PAGE57
  DH41 PVDDCR_CPU1_P1 @T6G_MB_LIB.T6G(SCH_1):PVDDCR_CPU1_P1    I32 @T6G_MB_LIB.T6G(SCH_1):PAGE57
  DH42 PVDDCR_CPU1_P1 @T6G_MB_LIB.T6G(SCH_1):PVDDCR_CPU1_P1    I32 @T6G_MB_LIB.T6G(SCH_1):PAGE57
  DH44 PVDDCR_CPU1_P1 @T6G_MB_LIB.T6G(SCH_1):PVDDCR_CPU1_P1    I32 @T6G_MB_LIB.T6G(SCH_1):PAGE57
  DH53 PVDDCR_CPU1_P1 @T6G_MB_LIB.T6G(SCH_1):PVDDCR_CPU1_P1    I32 @T6G_MB_LIB.T6G(SCH_1):PAGE57
  DH54 PVDDCR_CPU1_P1 @T6G_MB_LIB.T6G(SCH_1):PVDDCR_CPU1_P1    I32 @T6G_MB_LIB.T6G(SCH_1):PAGE57
  DH56 PVDDCR_CPU1_P1 @T6G_MB_LIB.T6G(SCH_1):PVDDCR_CPU1_P1    I32 @T6G_MB_LIB.T6G(SCH_1):PAGE57
  DH57 PVDDCR_CPU1_P1 @T6G_MB_LIB.T6G(SCH_1):PVDDCR_CPU1_P1    I32 @T6G_MB_LIB.T6G(SCH_1):PAGE57
  DH45 PVDDCR_CPU1_P1 @T6G_MB_LIB.T6G(SCH_1):PVDDCR_CPU1_P1    I32 @T6G_MB_LIB.T6G(SCH_1):PAGE57
  DH47 PVDDCR_CPU1_P1 @T6G_MB_LIB.T6G(SCH_1):PVDDCR_CPU1_P1    I32 @T6G_MB_LIB.T6G(SCH_1):PAGE57
  DH48 PVDDCR_CPU1_P1 @T6G_MB_LIB.T6G(SCH_1):PVDDCR_CPU1_P1    I32 @T6G_MB_LIB.T6G(SCH_1):PAGE57
  DH50 PVDDCR_CPU1_P1 @T6G_MB_LIB.T6G(SCH_1):PVDDCR_CPU1_P1    I32 @T6G_MB_LIB.T6G(SCH_1):PAGE57
  DH51 PVDDCR_CPU1_P1 @T6G_MB_LIB.T6G(SCH_1):PVDDCR_CPU1_P1    I32 @T6G_MB_LIB.T6G(SCH_1):PAGE57
  BP24 PVDDCR_CPU1_P1 @T6G_MB_LIB.T6G(SCH_1):PVDDCR_CPU1_P1    I32 @T6G_MB_LIB.T6G(SCH_1):PAGE57
  BP28 PVDDCR_CPU1_P1 @T6G_MB_LIB.T6G(SCH_1):PVDDCR_CPU1_P1    I32 @T6G_MB_LIB.T6G(SCH_1):PAGE57
  BP32 PVDDCR_CPU1_P1 @T6G_MB_LIB.T6G(SCH_1):PVDDCR_CPU1_P1    I32 @T6G_MB_LIB.T6G(SCH_1):PAGE57
  BN27 PVDDCR_CPU1_P1 @T6G_MB_LIB.T6G(SCH_1):PVDDCR_CPU1_P1    I32 @T6G_MB_LIB.T6G(SCH_1):PAGE57
  BN35 PVDDCR_CPU1_P1 @T6G_MB_LIB.T6G(SCH_1):PVDDCR_CPU1_P1    I32 @T6G_MB_LIB.T6G(SCH_1):PAGE57
  BN46 PVDDCR_CPU1_P1 @T6G_MB_LIB.T6G(SCH_1):PVDDCR_CPU1_P1    I32 @T6G_MB_LIB.T6G(SCH_1):PAGE57
    B5 PVDDCR_SOC_P1 @T6G_MB_LIB.T6G(SCH_1):PVDDCR_SOC_P1    I49 @T6G_MB_LIB.T6G(SCH_1):PAGE57
    C4 PVDDCR_SOC_P1 @T6G_MB_LIB.T6G(SCH_1):PVDDCR_SOC_P1    I49 @T6G_MB_LIB.T6G(SCH_1):PAGE57
    E4 PVDDCR_SOC_P1 @T6G_MB_LIB.T6G(SCH_1):PVDDCR_SOC_P1    I49 @T6G_MB_LIB.T6G(SCH_1):PAGE57
   E11 PVDDCR_SOC_P1 @T6G_MB_LIB.T6G(SCH_1):PVDDCR_SOC_P1    I49 @T6G_MB_LIB.T6G(SCH_1):PAGE57
    H5 PVDDCR_SOC_P1 @T6G_MB_LIB.T6G(SCH_1):PVDDCR_SOC_P1    I49 @T6G_MB_LIB.T6G(SCH_1):PAGE57
   H12 PVDDCR_SOC_P1 @T6G_MB_LIB.T6G(SCH_1):PVDDCR_SOC_P1    I49 @T6G_MB_LIB.T6G(SCH_1):PAGE57
   H19 PVDDCR_SOC_P1 @T6G_MB_LIB.T6G(SCH_1):PVDDCR_SOC_P1    I49 @T6G_MB_LIB.T6G(SCH_1):PAGE57
   K22 PVDDCR_SOC_P1 @T6G_MB_LIB.T6G(SCH_1):PVDDCR_SOC_P1    I49 @T6G_MB_LIB.T6G(SCH_1):PAGE57
    L4 PVDDCR_SOC_P1 @T6G_MB_LIB.T6G(SCH_1):PVDDCR_SOC_P1    I49 @T6G_MB_LIB.T6G(SCH_1):PAGE57
   L11 PVDDCR_SOC_P1 @T6G_MB_LIB.T6G(SCH_1):PVDDCR_SOC_P1    I49 @T6G_MB_LIB.T6G(SCH_1):PAGE57
   L18 PVDDCR_SOC_P1 @T6G_MB_LIB.T6G(SCH_1):PVDDCR_SOC_P1    I49 @T6G_MB_LIB.T6G(SCH_1):PAGE57
    P5 PVDDCR_SOC_P1 @T6G_MB_LIB.T6G(SCH_1):PVDDCR_SOC_P1    I49 @T6G_MB_LIB.T6G(SCH_1):PAGE57
   P12 PVDDCR_SOC_P1 @T6G_MB_LIB.T6G(SCH_1):PVDDCR_SOC_P1    I49 @T6G_MB_LIB.T6G(SCH_1):PAGE57
   P19 PVDDCR_SOC_P1 @T6G_MB_LIB.T6G(SCH_1):PVDDCR_SOC_P1    I49 @T6G_MB_LIB.T6G(SCH_1):PAGE57
   P22 PVDDCR_SOC_P1 @T6G_MB_LIB.T6G(SCH_1):PVDDCR_SOC_P1    I49 @T6G_MB_LIB.T6G(SCH_1):PAGE57
    U4 PVDDCR_SOC_P1 @T6G_MB_LIB.T6G(SCH_1):PVDDCR_SOC_P1    I49 @T6G_MB_LIB.T6G(SCH_1):PAGE57
   U11 PVDDCR_SOC_P1 @T6G_MB_LIB.T6G(SCH_1):PVDDCR_SOC_P1    I49 @T6G_MB_LIB.T6G(SCH_1):PAGE57
   U18 PVDDCR_SOC_P1 @T6G_MB_LIB.T6G(SCH_1):PVDDCR_SOC_P1    I49 @T6G_MB_LIB.T6G(SCH_1):PAGE57
   V22 PVDDCR_SOC_P1 @T6G_MB_LIB.T6G(SCH_1):PVDDCR_SOC_P1    I49 @T6G_MB_LIB.T6G(SCH_1):PAGE57
    Y5 PVDDCR_SOC_P1 @T6G_MB_LIB.T6G(SCH_1):PVDDCR_SOC_P1    I49 @T6G_MB_LIB.T6G(SCH_1):PAGE57
   Y12 PVDDCR_SOC_P1 @T6G_MB_LIB.T6G(SCH_1):PVDDCR_SOC_P1    I49 @T6G_MB_LIB.T6G(SCH_1):PAGE57
   Y19 PVDDCR_SOC_P1 @T6G_MB_LIB.T6G(SCH_1):PVDDCR_SOC_P1    I49 @T6G_MB_LIB.T6G(SCH_1):PAGE57
  AA22 PVDDCR_SOC_P1 @T6G_MB_LIB.T6G(SCH_1):PVDDCR_SOC_P1    I49 @T6G_MB_LIB.T6G(SCH_1):PAGE57
   AC4 PVDDCR_SOC_P1 @T6G_MB_LIB.T6G(SCH_1):PVDDCR_SOC_P1    I49 @T6G_MB_LIB.T6G(SCH_1):PAGE57
  AC11 PVDDCR_SOC_P1 @T6G_MB_LIB.T6G(SCH_1):PVDDCR_SOC_P1    I49 @T6G_MB_LIB.T6G(SCH_1):PAGE57
  AC18 PVDDCR_SOC_P1 @T6G_MB_LIB.T6G(SCH_1):PVDDCR_SOC_P1    I49 @T6G_MB_LIB.T6G(SCH_1):PAGE57
  AD22 PVDDCR_SOC_P1 @T6G_MB_LIB.T6G(SCH_1):PVDDCR_SOC_P1    I49 @T6G_MB_LIB.T6G(SCH_1):PAGE57
   AF5 PVDDCR_SOC_P1 @T6G_MB_LIB.T6G(SCH_1):PVDDCR_SOC_P1    I49 @T6G_MB_LIB.T6G(SCH_1):PAGE57
  AF12 PVDDCR_SOC_P1 @T6G_MB_LIB.T6G(SCH_1):PVDDCR_SOC_P1    I49 @T6G_MB_LIB.T6G(SCH_1):PAGE57
  AF19 PVDDCR_SOC_P1 @T6G_MB_LIB.T6G(SCH_1):PVDDCR_SOC_P1    I49 @T6G_MB_LIB.T6G(SCH_1):PAGE57
  AH22 PVDDCR_SOC_P1 @T6G_MB_LIB.T6G(SCH_1):PVDDCR_SOC_P1    I49 @T6G_MB_LIB.T6G(SCH_1):PAGE57
   AJ4 PVDDCR_SOC_P1 @T6G_MB_LIB.T6G(SCH_1):PVDDCR_SOC_P1    I49 @T6G_MB_LIB.T6G(SCH_1):PAGE57
  AJ11 PVDDCR_SOC_P1 @T6G_MB_LIB.T6G(SCH_1):PVDDCR_SOC_P1    I49 @T6G_MB_LIB.T6G(SCH_1):PAGE57
  AJ18 PVDDCR_SOC_P1 @T6G_MB_LIB.T6G(SCH_1):PVDDCR_SOC_P1    I49 @T6G_MB_LIB.T6G(SCH_1):PAGE57
   AM5 PVDDCR_SOC_P1 @T6G_MB_LIB.T6G(SCH_1):PVDDCR_SOC_P1    I49 @T6G_MB_LIB.T6G(SCH_1):PAGE57
  AM12 PVDDCR_SOC_P1 @T6G_MB_LIB.T6G(SCH_1):PVDDCR_SOC_P1    I49 @T6G_MB_LIB.T6G(SCH_1):PAGE57
  AM19 PVDDCR_SOC_P1 @T6G_MB_LIB.T6G(SCH_1):PVDDCR_SOC_P1    I49 @T6G_MB_LIB.T6G(SCH_1):PAGE57
  AM22 PVDDCR_SOC_P1 @T6G_MB_LIB.T6G(SCH_1):PVDDCR_SOC_P1    I49 @T6G_MB_LIB.T6G(SCH_1):PAGE57
   AR4 PVDDCR_SOC_P1 @T6G_MB_LIB.T6G(SCH_1):PVDDCR_SOC_P1    I49 @T6G_MB_LIB.T6G(SCH_1):PAGE57
  AR11 PVDDCR_SOC_P1 @T6G_MB_LIB.T6G(SCH_1):PVDDCR_SOC_P1    I49 @T6G_MB_LIB.T6G(SCH_1):PAGE57
  AR18 PVDDCR_SOC_P1 @T6G_MB_LIB.T6G(SCH_1):PVDDCR_SOC_P1    I49 @T6G_MB_LIB.T6G(SCH_1):PAGE57
  AT22 PVDDCR_SOC_P1 @T6G_MB_LIB.T6G(SCH_1):PVDDCR_SOC_P1    I49 @T6G_MB_LIB.T6G(SCH_1):PAGE57
  AU23 PVDDCR_SOC_P1 @T6G_MB_LIB.T6G(SCH_1):PVDDCR_SOC_P1    I49 @T6G_MB_LIB.T6G(SCH_1):PAGE57
  AU27 PVDDCR_SOC_P1 @T6G_MB_LIB.T6G(SCH_1):PVDDCR_SOC_P1    I49 @T6G_MB_LIB.T6G(SCH_1):PAGE57
  AU31 PVDDCR_SOC_P1 @T6G_MB_LIB.T6G(SCH_1):PVDDCR_SOC_P1    I49 @T6G_MB_LIB.T6G(SCH_1):PAGE57
  AU35 PVDDCR_SOC_P1 @T6G_MB_LIB.T6G(SCH_1):PVDDCR_SOC_P1    I49 @T6G_MB_LIB.T6G(SCH_1):PAGE57
  AU40 PVDDCR_SOC_P1 @T6G_MB_LIB.T6G(SCH_1):PVDDCR_SOC_P1    I49 @T6G_MB_LIB.T6G(SCH_1):PAGE57
   AV5 PVDDCR_SOC_P1 @T6G_MB_LIB.T6G(SCH_1):PVDDCR_SOC_P1    I49 @T6G_MB_LIB.T6G(SCH_1):PAGE57
  AV12 PVDDCR_SOC_P1 @T6G_MB_LIB.T6G(SCH_1):PVDDCR_SOC_P1    I49 @T6G_MB_LIB.T6G(SCH_1):PAGE57
  AV19 PVDDCR_SOC_P1 @T6G_MB_LIB.T6G(SCH_1):PVDDCR_SOC_P1    I49 @T6G_MB_LIB.T6G(SCH_1):PAGE57
  AV22 PVDDCR_SOC_P1 @T6G_MB_LIB.T6G(SCH_1):PVDDCR_SOC_P1    I49 @T6G_MB_LIB.T6G(SCH_1):PAGE57
  AV24 PVDDCR_SOC_P1 @T6G_MB_LIB.T6G(SCH_1):PVDDCR_SOC_P1    I49 @T6G_MB_LIB.T6G(SCH_1):PAGE57
  AV26 PVDDCR_SOC_P1 @T6G_MB_LIB.T6G(SCH_1):PVDDCR_SOC_P1    I49 @T6G_MB_LIB.T6G(SCH_1):PAGE57
  AV28 PVDDCR_SOC_P1 @T6G_MB_LIB.T6G(SCH_1):PVDDCR_SOC_P1    I49 @T6G_MB_LIB.T6G(SCH_1):PAGE57
  AV30 PVDDCR_SOC_P1 @T6G_MB_LIB.T6G(SCH_1):PVDDCR_SOC_P1    I49 @T6G_MB_LIB.T6G(SCH_1):PAGE57
  AV32 PVDDCR_SOC_P1 @T6G_MB_LIB.T6G(SCH_1):PVDDCR_SOC_P1    I49 @T6G_MB_LIB.T6G(SCH_1):PAGE57
  AV34 PVDDCR_SOC_P1 @T6G_MB_LIB.T6G(SCH_1):PVDDCR_SOC_P1    I49 @T6G_MB_LIB.T6G(SCH_1):PAGE57
  AV36 PVDDCR_SOC_P1 @T6G_MB_LIB.T6G(SCH_1):PVDDCR_SOC_P1    I49 @T6G_MB_LIB.T6G(SCH_1):PAGE57
  AV39 PVDDCR_SOC_P1 @T6G_MB_LIB.T6G(SCH_1):PVDDCR_SOC_P1    I49 @T6G_MB_LIB.T6G(SCH_1):PAGE57
  AV41 PVDDCR_SOC_P1 @T6G_MB_LIB.T6G(SCH_1):PVDDCR_SOC_P1    I49 @T6G_MB_LIB.T6G(SCH_1):PAGE57
  AV43 PVDDCR_SOC_P1 @T6G_MB_LIB.T6G(SCH_1):PVDDCR_SOC_P1    I49 @T6G_MB_LIB.T6G(SCH_1):PAGE57
  AV45 PVDDCR_SOC_P1 @T6G_MB_LIB.T6G(SCH_1):PVDDCR_SOC_P1    I49 @T6G_MB_LIB.T6G(SCH_1):PAGE57
  AV47 PVDDCR_SOC_P1 @T6G_MB_LIB.T6G(SCH_1):PVDDCR_SOC_P1    I49 @T6G_MB_LIB.T6G(SCH_1):PAGE57
  AW23 PVDDCR_SOC_P1 @T6G_MB_LIB.T6G(SCH_1):PVDDCR_SOC_P1    I49 @T6G_MB_LIB.T6G(SCH_1):PAGE57
  AW25 PVDDCR_SOC_P1 @T6G_MB_LIB.T6G(SCH_1):PVDDCR_SOC_P1    I49 @T6G_MB_LIB.T6G(SCH_1):PAGE57
  AW27 PVDDCR_SOC_P1 @T6G_MB_LIB.T6G(SCH_1):PVDDCR_SOC_P1    I49 @T6G_MB_LIB.T6G(SCH_1):PAGE57
  AW48 PVDDCR_SOC_P1 @T6G_MB_LIB.T6G(SCH_1):PVDDCR_SOC_P1    I49 @T6G_MB_LIB.T6G(SCH_1):PAGE57
  AY22 PVDDCR_SOC_P1 @T6G_MB_LIB.T6G(SCH_1):PVDDCR_SOC_P1    I49 @T6G_MB_LIB.T6G(SCH_1):PAGE57
  AY24 PVDDCR_SOC_P1 @T6G_MB_LIB.T6G(SCH_1):PVDDCR_SOC_P1    I49 @T6G_MB_LIB.T6G(SCH_1):PAGE57
  AY26 PVDDCR_SOC_P1 @T6G_MB_LIB.T6G(SCH_1):PVDDCR_SOC_P1    I49 @T6G_MB_LIB.T6G(SCH_1):PAGE57
  AY28 PVDDCR_SOC_P1 @T6G_MB_LIB.T6G(SCH_1):PVDDCR_SOC_P1    I49 @T6G_MB_LIB.T6G(SCH_1):PAGE57
  AY49 PVDDCR_SOC_P1 @T6G_MB_LIB.T6G(SCH_1):PVDDCR_SOC_P1    I49 @T6G_MB_LIB.T6G(SCH_1):PAGE57
   BA4 PVDDCR_SOC_P1 @T6G_MB_LIB.T6G(SCH_1):PVDDCR_SOC_P1    I49 @T6G_MB_LIB.T6G(SCH_1):PAGE57
  BA11 PVDDCR_SOC_P1 @T6G_MB_LIB.T6G(SCH_1):PVDDCR_SOC_P1    I49 @T6G_MB_LIB.T6G(SCH_1):PAGE57
  BA18 PVDDCR_SOC_P1 @T6G_MB_LIB.T6G(SCH_1):PVDDCR_SOC_P1    I49 @T6G_MB_LIB.T6G(SCH_1):PAGE57
  BA23 PVDDCR_SOC_P1 @T6G_MB_LIB.T6G(SCH_1):PVDDCR_SOC_P1    I49 @T6G_MB_LIB.T6G(SCH_1):PAGE57
  BA25 PVDDCR_SOC_P1 @T6G_MB_LIB.T6G(SCH_1):PVDDCR_SOC_P1    I49 @T6G_MB_LIB.T6G(SCH_1):PAGE57
  BA27 PVDDCR_SOC_P1 @T6G_MB_LIB.T6G(SCH_1):PVDDCR_SOC_P1    I49 @T6G_MB_LIB.T6G(SCH_1):PAGE57
  BA48 PVDDCR_SOC_P1 @T6G_MB_LIB.T6G(SCH_1):PVDDCR_SOC_P1    I49 @T6G_MB_LIB.T6G(SCH_1):PAGE57
  BB22 PVDDCR_SOC_P1 @T6G_MB_LIB.T6G(SCH_1):PVDDCR_SOC_P1    I49 @T6G_MB_LIB.T6G(SCH_1):PAGE57
  BB24 PVDDCR_SOC_P1 @T6G_MB_LIB.T6G(SCH_1):PVDDCR_SOC_P1    I49 @T6G_MB_LIB.T6G(SCH_1):PAGE57
  BB26 PVDDCR_SOC_P1 @T6G_MB_LIB.T6G(SCH_1):PVDDCR_SOC_P1    I49 @T6G_MB_LIB.T6G(SCH_1):PAGE57
  BB28 PVDDCR_SOC_P1 @T6G_MB_LIB.T6G(SCH_1):PVDDCR_SOC_P1    I49 @T6G_MB_LIB.T6G(SCH_1):PAGE57
  BB49 PVDDCR_SOC_P1 @T6G_MB_LIB.T6G(SCH_1):PVDDCR_SOC_P1    I49 @T6G_MB_LIB.T6G(SCH_1):PAGE57
  BC23 PVDDCR_SOC_P1 @T6G_MB_LIB.T6G(SCH_1):PVDDCR_SOC_P1    I49 @T6G_MB_LIB.T6G(SCH_1):PAGE57
  BC25 PVDDCR_SOC_P1 @T6G_MB_LIB.T6G(SCH_1):PVDDCR_SOC_P1    I49 @T6G_MB_LIB.T6G(SCH_1):PAGE57
  BC27 PVDDCR_SOC_P1 @T6G_MB_LIB.T6G(SCH_1):PVDDCR_SOC_P1    I49 @T6G_MB_LIB.T6G(SCH_1):PAGE57
  BC48 PVDDCR_SOC_P1 @T6G_MB_LIB.T6G(SCH_1):PVDDCR_SOC_P1    I49 @T6G_MB_LIB.T6G(SCH_1):PAGE57
   BD5 PVDDCR_SOC_P1 @T6G_MB_LIB.T6G(SCH_1):PVDDCR_SOC_P1    I49 @T6G_MB_LIB.T6G(SCH_1):PAGE57
  BD12 PVDDCR_SOC_P1 @T6G_MB_LIB.T6G(SCH_1):PVDDCR_SOC_P1    I49 @T6G_MB_LIB.T6G(SCH_1):PAGE57
  BD19 PVDDCR_SOC_P1 @T6G_MB_LIB.T6G(SCH_1):PVDDCR_SOC_P1    I49 @T6G_MB_LIB.T6G(SCH_1):PAGE57
  BD22 PVDDCR_SOC_P1 @T6G_MB_LIB.T6G(SCH_1):PVDDCR_SOC_P1    I49 @T6G_MB_LIB.T6G(SCH_1):PAGE57
  BD24 PVDDCR_SOC_P1 @T6G_MB_LIB.T6G(SCH_1):PVDDCR_SOC_P1    I49 @T6G_MB_LIB.T6G(SCH_1):PAGE57
  BD26 PVDDCR_SOC_P1 @T6G_MB_LIB.T6G(SCH_1):PVDDCR_SOC_P1    I49 @T6G_MB_LIB.T6G(SCH_1):PAGE57
  BD28 PVDDCR_SOC_P1 @T6G_MB_LIB.T6G(SCH_1):PVDDCR_SOC_P1    I49 @T6G_MB_LIB.T6G(SCH_1):PAGE57
  BD48 PVDDCR_SOC_P1 @T6G_MB_LIB.T6G(SCH_1):PVDDCR_SOC_P1    I49 @T6G_MB_LIB.T6G(SCH_1):PAGE57
  BF23 PVDDCR_SOC_P1 @T6G_MB_LIB.T6G(SCH_1):PVDDCR_SOC_P1    I49 @T6G_MB_LIB.T6G(SCH_1):PAGE57
  BF25 PVDDCR_SOC_P1 @T6G_MB_LIB.T6G(SCH_1):PVDDCR_SOC_P1    I49 @T6G_MB_LIB.T6G(SCH_1):PAGE57
  BF27 PVDDCR_SOC_P1 @T6G_MB_LIB.T6G(SCH_1):PVDDCR_SOC_P1    I49 @T6G_MB_LIB.T6G(SCH_1):PAGE57
  BF48 PVDDCR_SOC_P1 @T6G_MB_LIB.T6G(SCH_1):PVDDCR_SOC_P1    I49 @T6G_MB_LIB.T6G(SCH_1):PAGE57
   BM5 PVDDCR_SOC_P1 @T6G_MB_LIB.T6G(SCH_1):PVDDCR_SOC_P1    I49 @T6G_MB_LIB.T6G(SCH_1):PAGE57
  BJ48 PVDDCR_SOC_P1 @T6G_MB_LIB.T6G(SCH_1):PVDDCR_SOC_P1    I49 @T6G_MB_LIB.T6G(SCH_1):PAGE57
  BJ11 PVDDCR_SOC_P1 @T6G_MB_LIB.T6G(SCH_1):PVDDCR_SOC_P1    I49 @T6G_MB_LIB.T6G(SCH_1):PAGE57
   BJ4 PVDDCR_SOC_P1 @T6G_MB_LIB.T6G(SCH_1):PVDDCR_SOC_P1    I49 @T6G_MB_LIB.T6G(SCH_1):PAGE57
  BH48 PVDDCR_SOC_P1 @T6G_MB_LIB.T6G(SCH_1):PVDDCR_SOC_P1    I49 @T6G_MB_LIB.T6G(SCH_1):PAGE57
  BH25 PVDDCR_SOC_P1 @T6G_MB_LIB.T6G(SCH_1):PVDDCR_SOC_P1    I49 @T6G_MB_LIB.T6G(SCH_1):PAGE57
  BH23 PVDDCR_SOC_P1 @T6G_MB_LIB.T6G(SCH_1):PVDDCR_SOC_P1    I49 @T6G_MB_LIB.T6G(SCH_1):PAGE57
  BG48 PVDDCR_SOC_P1 @T6G_MB_LIB.T6G(SCH_1):PVDDCR_SOC_P1    I49 @T6G_MB_LIB.T6G(SCH_1):PAGE57
  BG28 PVDDCR_SOC_P1 @T6G_MB_LIB.T6G(SCH_1):PVDDCR_SOC_P1    I49 @T6G_MB_LIB.T6G(SCH_1):PAGE57
  BG26 PVDDCR_SOC_P1 @T6G_MB_LIB.T6G(SCH_1):PVDDCR_SOC_P1    I49 @T6G_MB_LIB.T6G(SCH_1):PAGE57
  BG24 PVDDCR_SOC_P1 @T6G_MB_LIB.T6G(SCH_1):PVDDCR_SOC_P1    I49 @T6G_MB_LIB.T6G(SCH_1):PAGE57
  BG22 PVDDCR_SOC_P1 @T6G_MB_LIB.T6G(SCH_1):PVDDCR_SOC_P1    I49 @T6G_MB_LIB.T6G(SCH_1):PAGE57
   H57 PVDDIO_P1 @T6G_MB_LIB.T6G(SCH_1):PVDDIO_P1    I45 @T6G_MB_LIB.T6G(SCH_1):PAGE57
   H64 PVDDIO_P1 @T6G_MB_LIB.T6G(SCH_1):PVDDIO_P1    I45 @T6G_MB_LIB.T6G(SCH_1):PAGE57
   H71 PVDDIO_P1 @T6G_MB_LIB.T6G(SCH_1):PVDDIO_P1    I45 @T6G_MB_LIB.T6G(SCH_1):PAGE57
   K54 PVDDIO_P1 @T6G_MB_LIB.T6G(SCH_1):PVDDIO_P1    I45 @T6G_MB_LIB.T6G(SCH_1):PAGE57
   L58 PVDDIO_P1 @T6G_MB_LIB.T6G(SCH_1):PVDDIO_P1    I45 @T6G_MB_LIB.T6G(SCH_1):PAGE57
   L65 PVDDIO_P1 @T6G_MB_LIB.T6G(SCH_1):PVDDIO_P1    I45 @T6G_MB_LIB.T6G(SCH_1):PAGE57
   L72 PVDDIO_P1 @T6G_MB_LIB.T6G(SCH_1):PVDDIO_P1    I45 @T6G_MB_LIB.T6G(SCH_1):PAGE57
   P54 PVDDIO_P1 @T6G_MB_LIB.T6G(SCH_1):PVDDIO_P1    I45 @T6G_MB_LIB.T6G(SCH_1):PAGE57
   P57 PVDDIO_P1 @T6G_MB_LIB.T6G(SCH_1):PVDDIO_P1    I45 @T6G_MB_LIB.T6G(SCH_1):PAGE57
   P64 PVDDIO_P1 @T6G_MB_LIB.T6G(SCH_1):PVDDIO_P1    I45 @T6G_MB_LIB.T6G(SCH_1):PAGE57
   P71 PVDDIO_P1 @T6G_MB_LIB.T6G(SCH_1):PVDDIO_P1    I45 @T6G_MB_LIB.T6G(SCH_1):PAGE57
   U58 PVDDIO_P1 @T6G_MB_LIB.T6G(SCH_1):PVDDIO_P1    I45 @T6G_MB_LIB.T6G(SCH_1):PAGE57
   U65 PVDDIO_P1 @T6G_MB_LIB.T6G(SCH_1):PVDDIO_P1    I45 @T6G_MB_LIB.T6G(SCH_1):PAGE57
   U72 PVDDIO_P1 @T6G_MB_LIB.T6G(SCH_1):PVDDIO_P1    I45 @T6G_MB_LIB.T6G(SCH_1):PAGE57
   V54 PVDDIO_P1 @T6G_MB_LIB.T6G(SCH_1):PVDDIO_P1    I45 @T6G_MB_LIB.T6G(SCH_1):PAGE57
   Y57 PVDDIO_P1 @T6G_MB_LIB.T6G(SCH_1):PVDDIO_P1    I45 @T6G_MB_LIB.T6G(SCH_1):PAGE57
   Y64 PVDDIO_P1 @T6G_MB_LIB.T6G(SCH_1):PVDDIO_P1    I45 @T6G_MB_LIB.T6G(SCH_1):PAGE57
   Y71 PVDDIO_P1 @T6G_MB_LIB.T6G(SCH_1):PVDDIO_P1    I45 @T6G_MB_LIB.T6G(SCH_1):PAGE57
  AA54 PVDDIO_P1 @T6G_MB_LIB.T6G(SCH_1):PVDDIO_P1    I45 @T6G_MB_LIB.T6G(SCH_1):PAGE57
  AC58 PVDDIO_P1 @T6G_MB_LIB.T6G(SCH_1):PVDDIO_P1    I45 @T6G_MB_LIB.T6G(SCH_1):PAGE57
  AC65 PVDDIO_P1 @T6G_MB_LIB.T6G(SCH_1):PVDDIO_P1    I45 @T6G_MB_LIB.T6G(SCH_1):PAGE57
  AC72 PVDDIO_P1 @T6G_MB_LIB.T6G(SCH_1):PVDDIO_P1    I45 @T6G_MB_LIB.T6G(SCH_1):PAGE57
  AD54 PVDDIO_P1 @T6G_MB_LIB.T6G(SCH_1):PVDDIO_P1    I45 @T6G_MB_LIB.T6G(SCH_1):PAGE57
  AF57 PVDDIO_P1 @T6G_MB_LIB.T6G(SCH_1):PVDDIO_P1    I45 @T6G_MB_LIB.T6G(SCH_1):PAGE57
  AF64 PVDDIO_P1 @T6G_MB_LIB.T6G(SCH_1):PVDDIO_P1    I45 @T6G_MB_LIB.T6G(SCH_1):PAGE57
  AF71 PVDDIO_P1 @T6G_MB_LIB.T6G(SCH_1):PVDDIO_P1    I45 @T6G_MB_LIB.T6G(SCH_1):PAGE57
  AH54 PVDDIO_P1 @T6G_MB_LIB.T6G(SCH_1):PVDDIO_P1    I45 @T6G_MB_LIB.T6G(SCH_1):PAGE57
  AJ58 PVDDIO_P1 @T6G_MB_LIB.T6G(SCH_1):PVDDIO_P1    I45 @T6G_MB_LIB.T6G(SCH_1):PAGE57
  AJ65 PVDDIO_P1 @T6G_MB_LIB.T6G(SCH_1):PVDDIO_P1    I45 @T6G_MB_LIB.T6G(SCH_1):PAGE57
  AJ72 PVDDIO_P1 @T6G_MB_LIB.T6G(SCH_1):PVDDIO_P1    I45 @T6G_MB_LIB.T6G(SCH_1):PAGE57
  AM54 PVDDIO_P1 @T6G_MB_LIB.T6G(SCH_1):PVDDIO_P1    I45 @T6G_MB_LIB.T6G(SCH_1):PAGE57
  AM57 PVDDIO_P1 @T6G_MB_LIB.T6G(SCH_1):PVDDIO_P1    I45 @T6G_MB_LIB.T6G(SCH_1):PAGE57
  AM64 PVDDIO_P1 @T6G_MB_LIB.T6G(SCH_1):PVDDIO_P1    I45 @T6G_MB_LIB.T6G(SCH_1):PAGE57
  AM71 PVDDIO_P1 @T6G_MB_LIB.T6G(SCH_1):PVDDIO_P1    I45 @T6G_MB_LIB.T6G(SCH_1):PAGE57
  AR58 PVDDIO_P1 @T6G_MB_LIB.T6G(SCH_1):PVDDIO_P1    I45 @T6G_MB_LIB.T6G(SCH_1):PAGE57
  AR65 PVDDIO_P1 @T6G_MB_LIB.T6G(SCH_1):PVDDIO_P1    I45 @T6G_MB_LIB.T6G(SCH_1):PAGE57
  AR72 PVDDIO_P1 @T6G_MB_LIB.T6G(SCH_1):PVDDIO_P1    I45 @T6G_MB_LIB.T6G(SCH_1):PAGE57
  AV57 PVDDIO_P1 @T6G_MB_LIB.T6G(SCH_1):PVDDIO_P1    I45 @T6G_MB_LIB.T6G(SCH_1):PAGE57
  AV64 PVDDIO_P1 @T6G_MB_LIB.T6G(SCH_1):PVDDIO_P1    I45 @T6G_MB_LIB.T6G(SCH_1):PAGE57
  AV71 PVDDIO_P1 @T6G_MB_LIB.T6G(SCH_1):PVDDIO_P1    I45 @T6G_MB_LIB.T6G(SCH_1):PAGE57
  BA58 PVDDIO_P1 @T6G_MB_LIB.T6G(SCH_1):PVDDIO_P1    I45 @T6G_MB_LIB.T6G(SCH_1):PAGE57
  BA65 PVDDIO_P1 @T6G_MB_LIB.T6G(SCH_1):PVDDIO_P1    I45 @T6G_MB_LIB.T6G(SCH_1):PAGE57
  BA72 PVDDIO_P1 @T6G_MB_LIB.T6G(SCH_1):PVDDIO_P1    I45 @T6G_MB_LIB.T6G(SCH_1):PAGE57
  BD50 PVDDIO_P1 @T6G_MB_LIB.T6G(SCH_1):PVDDIO_P1    I45 @T6G_MB_LIB.T6G(SCH_1):PAGE57
  BD52 PVDDIO_P1 @T6G_MB_LIB.T6G(SCH_1):PVDDIO_P1    I45 @T6G_MB_LIB.T6G(SCH_1):PAGE57
  BD54 PVDDIO_P1 @T6G_MB_LIB.T6G(SCH_1):PVDDIO_P1    I45 @T6G_MB_LIB.T6G(SCH_1):PAGE57
  BF51 PVDDIO_P1 @T6G_MB_LIB.T6G(SCH_1):PVDDIO_P1    I45 @T6G_MB_LIB.T6G(SCH_1):PAGE57
  BF53 PVDDIO_P1 @T6G_MB_LIB.T6G(SCH_1):PVDDIO_P1    I45 @T6G_MB_LIB.T6G(SCH_1):PAGE57
  BF57 PVDDIO_P1 @T6G_MB_LIB.T6G(SCH_1):PVDDIO_P1    I45 @T6G_MB_LIB.T6G(SCH_1):PAGE57
  BF64 PVDDIO_P1 @T6G_MB_LIB.T6G(SCH_1):PVDDIO_P1    I45 @T6G_MB_LIB.T6G(SCH_1):PAGE57
  BF71 PVDDIO_P1 @T6G_MB_LIB.T6G(SCH_1):PVDDIO_P1    I45 @T6G_MB_LIB.T6G(SCH_1):PAGE57
  BG50 PVDDIO_P1 @T6G_MB_LIB.T6G(SCH_1):PVDDIO_P1    I45 @T6G_MB_LIB.T6G(SCH_1):PAGE57
  BG52 PVDDIO_P1 @T6G_MB_LIB.T6G(SCH_1):PVDDIO_P1    I45 @T6G_MB_LIB.T6G(SCH_1):PAGE57
  BG54 PVDDIO_P1 @T6G_MB_LIB.T6G(SCH_1):PVDDIO_P1    I45 @T6G_MB_LIB.T6G(SCH_1):PAGE57
  BH51 PVDDIO_P1 @T6G_MB_LIB.T6G(SCH_1):PVDDIO_P1    I45 @T6G_MB_LIB.T6G(SCH_1):PAGE57
  BH53 PVDDIO_P1 @T6G_MB_LIB.T6G(SCH_1):PVDDIO_P1    I45 @T6G_MB_LIB.T6G(SCH_1):PAGE57
  BJ50 PVDDIO_P1 @T6G_MB_LIB.T6G(SCH_1):PVDDIO_P1    I45 @T6G_MB_LIB.T6G(SCH_1):PAGE57
  BJ52 PVDDIO_P1 @T6G_MB_LIB.T6G(SCH_1):PVDDIO_P1    I45 @T6G_MB_LIB.T6G(SCH_1):PAGE57
  BJ54 PVDDIO_P1 @T6G_MB_LIB.T6G(SCH_1):PVDDIO_P1    I45 @T6G_MB_LIB.T6G(SCH_1):PAGE57
  BJ58 PVDDIO_P1 @T6G_MB_LIB.T6G(SCH_1):PVDDIO_P1    I45 @T6G_MB_LIB.T6G(SCH_1):PAGE57
  BJ65 PVDDIO_P1 @T6G_MB_LIB.T6G(SCH_1):PVDDIO_P1    I45 @T6G_MB_LIB.T6G(SCH_1):PAGE57
  BJ72 PVDDIO_P1 @T6G_MB_LIB.T6G(SCH_1):PVDDIO_P1    I45 @T6G_MB_LIB.T6G(SCH_1):PAGE57
  BK51 PVDDIO_P1 @T6G_MB_LIB.T6G(SCH_1):PVDDIO_P1    I45 @T6G_MB_LIB.T6G(SCH_1):PAGE57
  BK53 PVDDIO_P1 @T6G_MB_LIB.T6G(SCH_1):PVDDIO_P1    I45 @T6G_MB_LIB.T6G(SCH_1):PAGE57
  BL50 PVDDIO_P1 @T6G_MB_LIB.T6G(SCH_1):PVDDIO_P1    I45 @T6G_MB_LIB.T6G(SCH_1):PAGE57
  BL52 PVDDIO_P1 @T6G_MB_LIB.T6G(SCH_1):PVDDIO_P1    I45 @T6G_MB_LIB.T6G(SCH_1):PAGE57
  BL54 PVDDIO_P1 @T6G_MB_LIB.T6G(SCH_1):PVDDIO_P1    I45 @T6G_MB_LIB.T6G(SCH_1):PAGE57
  BM51 PVDDIO_P1 @T6G_MB_LIB.T6G(SCH_1):PVDDIO_P1    I45 @T6G_MB_LIB.T6G(SCH_1):PAGE57
  BM53 PVDDIO_P1 @T6G_MB_LIB.T6G(SCH_1):PVDDIO_P1    I45 @T6G_MB_LIB.T6G(SCH_1):PAGE57
  BM57 PVDDIO_P1 @T6G_MB_LIB.T6G(SCH_1):PVDDIO_P1    I45 @T6G_MB_LIB.T6G(SCH_1):PAGE57
  BM64 PVDDIO_P1 @T6G_MB_LIB.T6G(SCH_1):PVDDIO_P1    I45 @T6G_MB_LIB.T6G(SCH_1):PAGE57
  BM71 PVDDIO_P1 @T6G_MB_LIB.T6G(SCH_1):PVDDIO_P1    I45 @T6G_MB_LIB.T6G(SCH_1):PAGE57
  BN54 PVDDIO_P1 @T6G_MB_LIB.T6G(SCH_1):PVDDIO_P1    I45 @T6G_MB_LIB.T6G(SCH_1):PAGE57
  BR58 PVDDIO_P1 @T6G_MB_LIB.T6G(SCH_1):PVDDIO_P1    I45 @T6G_MB_LIB.T6G(SCH_1):PAGE57
  BR65 PVDDIO_P1 @T6G_MB_LIB.T6G(SCH_1):PVDDIO_P1    I45 @T6G_MB_LIB.T6G(SCH_1):PAGE57
  BR72 PVDDIO_P1 @T6G_MB_LIB.T6G(SCH_1):PVDDIO_P1    I45 @T6G_MB_LIB.T6G(SCH_1):PAGE57
  BV54 PVDDIO_P1 @T6G_MB_LIB.T6G(SCH_1):PVDDIO_P1    I45 @T6G_MB_LIB.T6G(SCH_1):PAGE57
  BV57 PVDDIO_P1 @T6G_MB_LIB.T6G(SCH_1):PVDDIO_P1    I45 @T6G_MB_LIB.T6G(SCH_1):PAGE57
  BV64 PVDDIO_P1 @T6G_MB_LIB.T6G(SCH_1):PVDDIO_P1    I45 @T6G_MB_LIB.T6G(SCH_1):PAGE57
  BV71 PVDDIO_P1 @T6G_MB_LIB.T6G(SCH_1):PVDDIO_P1    I45 @T6G_MB_LIB.T6G(SCH_1):PAGE57
  CA58 PVDDIO_P1 @T6G_MB_LIB.T6G(SCH_1):PVDDIO_P1    I45 @T6G_MB_LIB.T6G(SCH_1):PAGE57
  CA65 PVDDIO_P1 @T6G_MB_LIB.T6G(SCH_1):PVDDIO_P1    I45 @T6G_MB_LIB.T6G(SCH_1):PAGE57
  CA72 PVDDIO_P1 @T6G_MB_LIB.T6G(SCH_1):PVDDIO_P1    I45 @T6G_MB_LIB.T6G(SCH_1):PAGE57
  CB54 PVDDIO_P1 @T6G_MB_LIB.T6G(SCH_1):PVDDIO_P1    I45 @T6G_MB_LIB.T6G(SCH_1):PAGE57
  CD57 PVDDIO_P1 @T6G_MB_LIB.T6G(SCH_1):PVDDIO_P1    I45 @T6G_MB_LIB.T6G(SCH_1):PAGE57
  CD64 PVDDIO_P1 @T6G_MB_LIB.T6G(SCH_1):PVDDIO_P1    I45 @T6G_MB_LIB.T6G(SCH_1):PAGE57
  CD71 PVDDIO_P1 @T6G_MB_LIB.T6G(SCH_1):PVDDIO_P1    I45 @T6G_MB_LIB.T6G(SCH_1):PAGE57
  CF54 PVDDIO_P1 @T6G_MB_LIB.T6G(SCH_1):PVDDIO_P1    I45 @T6G_MB_LIB.T6G(SCH_1):PAGE57
  CG58 PVDDIO_P1 @T6G_MB_LIB.T6G(SCH_1):PVDDIO_P1    I45 @T6G_MB_LIB.T6G(SCH_1):PAGE57
  CG65 PVDDIO_P1 @T6G_MB_LIB.T6G(SCH_1):PVDDIO_P1    I45 @T6G_MB_LIB.T6G(SCH_1):PAGE57
  CG72 PVDDIO_P1 @T6G_MB_LIB.T6G(SCH_1):PVDDIO_P1    I45 @T6G_MB_LIB.T6G(SCH_1):PAGE57
  CJ54 PVDDIO_P1 @T6G_MB_LIB.T6G(SCH_1):PVDDIO_P1    I45 @T6G_MB_LIB.T6G(SCH_1):PAGE57
  CK57 PVDDIO_P1 @T6G_MB_LIB.T6G(SCH_1):PVDDIO_P1    I45 @T6G_MB_LIB.T6G(SCH_1):PAGE57
  CK64 PVDDIO_P1 @T6G_MB_LIB.T6G(SCH_1):PVDDIO_P1    I45 @T6G_MB_LIB.T6G(SCH_1):PAGE57
  CK71 PVDDIO_P1 @T6G_MB_LIB.T6G(SCH_1):PVDDIO_P1    I45 @T6G_MB_LIB.T6G(SCH_1):PAGE57
  CM54 PVDDIO_P1 @T6G_MB_LIB.T6G(SCH_1):PVDDIO_P1    I45 @T6G_MB_LIB.T6G(SCH_1):PAGE57
  CN58 PVDDIO_P1 @T6G_MB_LIB.T6G(SCH_1):PVDDIO_P1    I45 @T6G_MB_LIB.T6G(SCH_1):PAGE57
  CN65 PVDDIO_P1 @T6G_MB_LIB.T6G(SCH_1):PVDDIO_P1    I45 @T6G_MB_LIB.T6G(SCH_1):PAGE57
  CN72 PVDDIO_P1 @T6G_MB_LIB.T6G(SCH_1):PVDDIO_P1    I45 @T6G_MB_LIB.T6G(SCH_1):PAGE57
  CT54 PVDDIO_P1 @T6G_MB_LIB.T6G(SCH_1):PVDDIO_P1    I45 @T6G_MB_LIB.T6G(SCH_1):PAGE57
  CT57 PVDDIO_P1 @T6G_MB_LIB.T6G(SCH_1):PVDDIO_P1    I45 @T6G_MB_LIB.T6G(SCH_1):PAGE57
  BJ18 PVDD11_S3_P1 @T6G_MB_LIB.T6G(SCH_1):PVDD11_S3_P1    I45 @T6G_MB_LIB.T6G(SCH_1):PAGE57
  BJ23 PVDD11_S3_P1 @T6G_MB_LIB.T6G(SCH_1):PVDD11_S3_P1    I45 @T6G_MB_LIB.T6G(SCH_1):PAGE57
  BJ25 PVDD11_S3_P1 @T6G_MB_LIB.T6G(SCH_1):PVDD11_S3_P1    I45 @T6G_MB_LIB.T6G(SCH_1):PAGE57
  BJ27 PVDD11_S3_P1 @T6G_MB_LIB.T6G(SCH_1):PVDD11_S3_P1    I45 @T6G_MB_LIB.T6G(SCH_1):PAGE57
  BK22 PVDD11_S3_P1 @T6G_MB_LIB.T6G(SCH_1):PVDD11_S3_P1    I45 @T6G_MB_LIB.T6G(SCH_1):PAGE57
  BK24 PVDD11_S3_P1 @T6G_MB_LIB.T6G(SCH_1):PVDD11_S3_P1    I45 @T6G_MB_LIB.T6G(SCH_1):PAGE57
  BK26 PVDD11_S3_P1 @T6G_MB_LIB.T6G(SCH_1):PVDD11_S3_P1    I45 @T6G_MB_LIB.T6G(SCH_1):PAGE57
  BK28 PVDD11_S3_P1 @T6G_MB_LIB.T6G(SCH_1):PVDD11_S3_P1    I45 @T6G_MB_LIB.T6G(SCH_1):PAGE57
  BK49 PVDD11_S3_P1 @T6G_MB_LIB.T6G(SCH_1):PVDD11_S3_P1    I45 @T6G_MB_LIB.T6G(SCH_1):PAGE57
  BL23 PVDD11_S3_P1 @T6G_MB_LIB.T6G(SCH_1):PVDD11_S3_P1    I45 @T6G_MB_LIB.T6G(SCH_1):PAGE57
  BL25 PVDD11_S3_P1 @T6G_MB_LIB.T6G(SCH_1):PVDD11_S3_P1    I45 @T6G_MB_LIB.T6G(SCH_1):PAGE57
  BL27 PVDD11_S3_P1 @T6G_MB_LIB.T6G(SCH_1):PVDD11_S3_P1    I45 @T6G_MB_LIB.T6G(SCH_1):PAGE57
  BL48 PVDD11_S3_P1 @T6G_MB_LIB.T6G(SCH_1):PVDD11_S3_P1    I45 @T6G_MB_LIB.T6G(SCH_1):PAGE57
  BM12 PVDD11_S3_P1 @T6G_MB_LIB.T6G(SCH_1):PVDD11_S3_P1    I45 @T6G_MB_LIB.T6G(SCH_1):PAGE57
  BM19 PVDD11_S3_P1 @T6G_MB_LIB.T6G(SCH_1):PVDD11_S3_P1    I45 @T6G_MB_LIB.T6G(SCH_1):PAGE57
  BM22 PVDD11_S3_P1 @T6G_MB_LIB.T6G(SCH_1):PVDD11_S3_P1    I45 @T6G_MB_LIB.T6G(SCH_1):PAGE57
  BM24 PVDD11_S3_P1 @T6G_MB_LIB.T6G(SCH_1):PVDD11_S3_P1    I45 @T6G_MB_LIB.T6G(SCH_1):PAGE57
  BM26 PVDD11_S3_P1 @T6G_MB_LIB.T6G(SCH_1):PVDD11_S3_P1    I45 @T6G_MB_LIB.T6G(SCH_1):PAGE57
  BM28 PVDD11_S3_P1 @T6G_MB_LIB.T6G(SCH_1):PVDD11_S3_P1    I45 @T6G_MB_LIB.T6G(SCH_1):PAGE57
  BM30 PVDD11_S3_P1 @T6G_MB_LIB.T6G(SCH_1):PVDD11_S3_P1    I45 @T6G_MB_LIB.T6G(SCH_1):PAGE57
  BM32 PVDD11_S3_P1 @T6G_MB_LIB.T6G(SCH_1):PVDD11_S3_P1    I45 @T6G_MB_LIB.T6G(SCH_1):PAGE57
  BM34 PVDD11_S3_P1 @T6G_MB_LIB.T6G(SCH_1):PVDD11_S3_P1    I45 @T6G_MB_LIB.T6G(SCH_1):PAGE57
  BM36 PVDD11_S3_P1 @T6G_MB_LIB.T6G(SCH_1):PVDD11_S3_P1    I45 @T6G_MB_LIB.T6G(SCH_1):PAGE57
  BM39 PVDD11_S3_P1 @T6G_MB_LIB.T6G(SCH_1):PVDD11_S3_P1    I45 @T6G_MB_LIB.T6G(SCH_1):PAGE57
  BM41 PVDD11_S3_P1 @T6G_MB_LIB.T6G(SCH_1):PVDD11_S3_P1    I45 @T6G_MB_LIB.T6G(SCH_1):PAGE57
  BM43 PVDD11_S3_P1 @T6G_MB_LIB.T6G(SCH_1):PVDD11_S3_P1    I45 @T6G_MB_LIB.T6G(SCH_1):PAGE57
  BM45 PVDD11_S3_P1 @T6G_MB_LIB.T6G(SCH_1):PVDD11_S3_P1    I45 @T6G_MB_LIB.T6G(SCH_1):PAGE57
  BM47 PVDD11_S3_P1 @T6G_MB_LIB.T6G(SCH_1):PVDD11_S3_P1    I45 @T6G_MB_LIB.T6G(SCH_1):PAGE57
  BM49 PVDD11_S3_P1 @T6G_MB_LIB.T6G(SCH_1):PVDD11_S3_P1    I45 @T6G_MB_LIB.T6G(SCH_1):PAGE57
  BN25 PVDD11_S3_P1 @T6G_MB_LIB.T6G(SCH_1):PVDD11_S3_P1    I45 @T6G_MB_LIB.T6G(SCH_1):PAGE57
  BN29 PVDD11_S3_P1 @T6G_MB_LIB.T6G(SCH_1):PVDD11_S3_P1    I45 @T6G_MB_LIB.T6G(SCH_1):PAGE57
  BN33 PVDD11_S3_P1 @T6G_MB_LIB.T6G(SCH_1):PVDD11_S3_P1    I45 @T6G_MB_LIB.T6G(SCH_1):PAGE57
  BN40 PVDD11_S3_P1 @T6G_MB_LIB.T6G(SCH_1):PVDD11_S3_P1    I45 @T6G_MB_LIB.T6G(SCH_1):PAGE57
  BN44 PVDD11_S3_P1 @T6G_MB_LIB.T6G(SCH_1):PVDD11_S3_P1    I45 @T6G_MB_LIB.T6G(SCH_1):PAGE57
  BN48 PVDD11_S3_P1 @T6G_MB_LIB.T6G(SCH_1):PVDD11_S3_P1    I45 @T6G_MB_LIB.T6G(SCH_1):PAGE57
  BP22 PVDD11_S3_P1 @T6G_MB_LIB.T6G(SCH_1):PVDD11_S3_P1    I45 @T6G_MB_LIB.T6G(SCH_1):PAGE57
   BR4 PVDD11_S3_P1 @T6G_MB_LIB.T6G(SCH_1):PVDD11_S3_P1    I45 @T6G_MB_LIB.T6G(SCH_1):PAGE57
  BR11 PVDD11_S3_P1 @T6G_MB_LIB.T6G(SCH_1):PVDD11_S3_P1    I45 @T6G_MB_LIB.T6G(SCH_1):PAGE57
  BR18 PVDD11_S3_P1 @T6G_MB_LIB.T6G(SCH_1):PVDD11_S3_P1    I45 @T6G_MB_LIB.T6G(SCH_1):PAGE57
   BV5 PVDD11_S3_P1 @T6G_MB_LIB.T6G(SCH_1):PVDD11_S3_P1    I45 @T6G_MB_LIB.T6G(SCH_1):PAGE57
  BV12 PVDD11_S3_P1 @T6G_MB_LIB.T6G(SCH_1):PVDD11_S3_P1    I45 @T6G_MB_LIB.T6G(SCH_1):PAGE57
  BV19 PVDD11_S3_P1 @T6G_MB_LIB.T6G(SCH_1):PVDD11_S3_P1    I45 @T6G_MB_LIB.T6G(SCH_1):PAGE57
  BV22 PVDD11_S3_P1 @T6G_MB_LIB.T6G(SCH_1):PVDD11_S3_P1    I45 @T6G_MB_LIB.T6G(SCH_1):PAGE57
   CA4 PVDD11_S3_P1 @T6G_MB_LIB.T6G(SCH_1):PVDD11_S3_P1    I45 @T6G_MB_LIB.T6G(SCH_1):PAGE57
  CA11 PVDD11_S3_P1 @T6G_MB_LIB.T6G(SCH_1):PVDD11_S3_P1    I45 @T6G_MB_LIB.T6G(SCH_1):PAGE57
  CA18 PVDD11_S3_P1 @T6G_MB_LIB.T6G(SCH_1):PVDD11_S3_P1    I45 @T6G_MB_LIB.T6G(SCH_1):PAGE57
  CB22 PVDD11_S3_P1 @T6G_MB_LIB.T6G(SCH_1):PVDD11_S3_P1    I45 @T6G_MB_LIB.T6G(SCH_1):PAGE57
   CD5 PVDD11_S3_P1 @T6G_MB_LIB.T6G(SCH_1):PVDD11_S3_P1    I45 @T6G_MB_LIB.T6G(SCH_1):PAGE57
  CD12 PVDD11_S3_P1 @T6G_MB_LIB.T6G(SCH_1):PVDD11_S3_P1    I45 @T6G_MB_LIB.T6G(SCH_1):PAGE57
  CD19 PVDD11_S3_P1 @T6G_MB_LIB.T6G(SCH_1):PVDD11_S3_P1    I45 @T6G_MB_LIB.T6G(SCH_1):PAGE57
  CF22 PVDD11_S3_P1 @T6G_MB_LIB.T6G(SCH_1):PVDD11_S3_P1    I45 @T6G_MB_LIB.T6G(SCH_1):PAGE57
   CG4 PVDD11_S3_P1 @T6G_MB_LIB.T6G(SCH_1):PVDD11_S3_P1    I45 @T6G_MB_LIB.T6G(SCH_1):PAGE57
  CG11 PVDD11_S3_P1 @T6G_MB_LIB.T6G(SCH_1):PVDD11_S3_P1    I45 @T6G_MB_LIB.T6G(SCH_1):PAGE57
  CG18 PVDD11_S3_P1 @T6G_MB_LIB.T6G(SCH_1):PVDD11_S3_P1    I45 @T6G_MB_LIB.T6G(SCH_1):PAGE57
  CJ22 PVDD11_S3_P1 @T6G_MB_LIB.T6G(SCH_1):PVDD11_S3_P1    I45 @T6G_MB_LIB.T6G(SCH_1):PAGE57
   CK5 PVDD11_S3_P1 @T6G_MB_LIB.T6G(SCH_1):PVDD11_S3_P1    I45 @T6G_MB_LIB.T6G(SCH_1):PAGE57
  CK12 PVDD11_S3_P1 @T6G_MB_LIB.T6G(SCH_1):PVDD11_S3_P1    I45 @T6G_MB_LIB.T6G(SCH_1):PAGE57
  CK19 PVDD11_S3_P1 @T6G_MB_LIB.T6G(SCH_1):PVDD11_S3_P1    I45 @T6G_MB_LIB.T6G(SCH_1):PAGE57
  CM22 PVDD11_S3_P1 @T6G_MB_LIB.T6G(SCH_1):PVDD11_S3_P1    I45 @T6G_MB_LIB.T6G(SCH_1):PAGE57
   CN4 PVDD11_S3_P1 @T6G_MB_LIB.T6G(SCH_1):PVDD11_S3_P1    I45 @T6G_MB_LIB.T6G(SCH_1):PAGE57
  CN11 PVDD11_S3_P1 @T6G_MB_LIB.T6G(SCH_1):PVDD11_S3_P1    I45 @T6G_MB_LIB.T6G(SCH_1):PAGE57
  CN18 PVDD11_S3_P1 @T6G_MB_LIB.T6G(SCH_1):PVDD11_S3_P1    I45 @T6G_MB_LIB.T6G(SCH_1):PAGE57
   CT5 PVDD11_S3_P1 @T6G_MB_LIB.T6G(SCH_1):PVDD11_S3_P1    I45 @T6G_MB_LIB.T6G(SCH_1):PAGE57
  AU54 PVDD18_S5_P1 @T6G_MB_LIB.T6G(SCH_1):PVDD18_S5_P1    I45 @T6G_MB_LIB.T6G(SCH_1):PAGE57
  AR52 PVDD18_S5_P1 @T6G_MB_LIB.T6G(SCH_1):PVDD18_S5_P1    I45 @T6G_MB_LIB.T6G(SCH_1):PAGE57
  AR54 PVDD18_S5_P1 @T6G_MB_LIB.T6G(SCH_1):PVDD18_S5_P1    I45 @T6G_MB_LIB.T6G(SCH_1):PAGE57
  AT51 PVDD18_S5_P1 @T6G_MB_LIB.T6G(SCH_1):PVDD18_S5_P1    I45 @T6G_MB_LIB.T6G(SCH_1):PAGE57
  AT53 PVDD18_S5_P1 @T6G_MB_LIB.T6G(SCH_1):PVDD18_S5_P1    I45 @T6G_MB_LIB.T6G(SCH_1):PAGE57
  AU50 PVDD18_S5_P1 @T6G_MB_LIB.T6G(SCH_1):PVDD18_S5_P1    I45 @T6G_MB_LIB.T6G(SCH_1):PAGE57
  AU52 PVDD18_S5_P1 @T6G_MB_LIB.T6G(SCH_1):PVDD18_S5_P1    I45 @T6G_MB_LIB.T6G(SCH_1):PAGE57
  AV49 PVDD18_S5_P1 @T6G_MB_LIB.T6G(SCH_1):PVDD18_S5_P1    I45 @T6G_MB_LIB.T6G(SCH_1):PAGE57
  AV51 PVDD18_S5_P1 @T6G_MB_LIB.T6G(SCH_1):PVDD18_S5_P1    I45 @T6G_MB_LIB.T6G(SCH_1):PAGE57
  AV53 PVDD18_S5_P1 @T6G_MB_LIB.T6G(SCH_1):PVDD18_S5_P1    I45 @T6G_MB_LIB.T6G(SCH_1):PAGE57
  AW50 PVDD18_S5_P1 @T6G_MB_LIB.T6G(SCH_1):PVDD18_S5_P1    I45 @T6G_MB_LIB.T6G(SCH_1):PAGE57
  BC52 PVDD18_S5_P1 @T6G_MB_LIB.T6G(SCH_1):PVDD18_S5_P1    I45 @T6G_MB_LIB.T6G(SCH_1):PAGE57
  BC54 PVDD18_S5_P1 @T6G_MB_LIB.T6G(SCH_1):PVDD18_S5_P1    I45 @T6G_MB_LIB.T6G(SCH_1):PAGE57
  AW52 PVDD18_S5_P1 @T6G_MB_LIB.T6G(SCH_1):PVDD18_S5_P1    I45 @T6G_MB_LIB.T6G(SCH_1):PAGE57
  AW54 PVDD18_S5_P1 @T6G_MB_LIB.T6G(SCH_1):PVDD18_S5_P1    I45 @T6G_MB_LIB.T6G(SCH_1):PAGE57
  AY51 PVDD18_S5_P1 @T6G_MB_LIB.T6G(SCH_1):PVDD18_S5_P1    I45 @T6G_MB_LIB.T6G(SCH_1):PAGE57
  AY53 PVDD18_S5_P1 @T6G_MB_LIB.T6G(SCH_1):PVDD18_S5_P1    I45 @T6G_MB_LIB.T6G(SCH_1):PAGE57
  BA50 PVDD18_S5_P1 @T6G_MB_LIB.T6G(SCH_1):PVDD18_S5_P1    I45 @T6G_MB_LIB.T6G(SCH_1):PAGE57
  BA52 PVDD18_S5_P1 @T6G_MB_LIB.T6G(SCH_1):PVDD18_S5_P1    I45 @T6G_MB_LIB.T6G(SCH_1):PAGE57
  BA54 PVDD18_S5_P1 @T6G_MB_LIB.T6G(SCH_1):PVDD18_S5_P1    I45 @T6G_MB_LIB.T6G(SCH_1):PAGE57
  BB51 PVDD18_S5_P1 @T6G_MB_LIB.T6G(SCH_1):PVDD18_S5_P1    I45 @T6G_MB_LIB.T6G(SCH_1):PAGE57
  BB53 PVDD18_S5_P1 @T6G_MB_LIB.T6G(SCH_1):PVDD18_S5_P1    I45 @T6G_MB_LIB.T6G(SCH_1):PAGE57
  CT12 PVDD11_S3_P1 @T6G_MB_LIB.T6G(SCH_1):PVDD11_S3_P1    I45 @T6G_MB_LIB.T6G(SCH_1):PAGE57
  BN52 PVDD_33_S5 @T6G_MB_LIB.T6G(SCH_1):PVDD_33_S5    I45 @T6G_MB_LIB.T6G(SCH_1):PAGE57
  BP51 PVDD_33_S5 @T6G_MB_LIB.T6G(SCH_1):PVDD_33_S5    I45 @T6G_MB_LIB.T6G(SCH_1):PAGE57
  BH27 PVDD18_S5_P1 @T6G_MB_LIB.T6G(SCH_1):PVDD18_S5_P1    I45 @T6G_MB_LIB.T6G(SCH_1):PAGE57
  BN23 CPU1_VDDBT_RTC_G @T6G_MB_LIB.T6G(SCH_1):CPU1_VDDBT_RTC_G    I45 @T6G_MB_LIB.T6G(SCH_1):PAGE57
  DG71 PVDDIO_P1 @T6G_MB_LIB.T6G(SCH_1):PVDDIO_P1    I45 @T6G_MB_LIB.T6G(SCH_1):PAGE57
  DG64 PVDDIO_P1 @T6G_MB_LIB.T6G(SCH_1):PVDDIO_P1    I45 @T6G_MB_LIB.T6G(SCH_1):PAGE57
  DE72 PVDDIO_P1 @T6G_MB_LIB.T6G(SCH_1):PVDDIO_P1    I45 @T6G_MB_LIB.T6G(SCH_1):PAGE57
  DE65 PVDDIO_P1 @T6G_MB_LIB.T6G(SCH_1):PVDDIO_P1    I45 @T6G_MB_LIB.T6G(SCH_1):PAGE57
  DE58 PVDDIO_P1 @T6G_MB_LIB.T6G(SCH_1):PVDDIO_P1    I45 @T6G_MB_LIB.T6G(SCH_1):PAGE57
  DB71 PVDDIO_P1 @T6G_MB_LIB.T6G(SCH_1):PVDDIO_P1    I45 @T6G_MB_LIB.T6G(SCH_1):PAGE57
  DB64 PVDDIO_P1 @T6G_MB_LIB.T6G(SCH_1):PVDDIO_P1    I45 @T6G_MB_LIB.T6G(SCH_1):PAGE57
  DB57 PVDDIO_P1 @T6G_MB_LIB.T6G(SCH_1):PVDDIO_P1    I45 @T6G_MB_LIB.T6G(SCH_1):PAGE57
  CY54 PVDDIO_P1 @T6G_MB_LIB.T6G(SCH_1):PVDDIO_P1    I45 @T6G_MB_LIB.T6G(SCH_1):PAGE57
  CW72 PVDDIO_P1 @T6G_MB_LIB.T6G(SCH_1):PVDDIO_P1    I45 @T6G_MB_LIB.T6G(SCH_1):PAGE57
  CW65 PVDDIO_P1 @T6G_MB_LIB.T6G(SCH_1):PVDDIO_P1    I45 @T6G_MB_LIB.T6G(SCH_1):PAGE57
  CW58 PVDDIO_P1 @T6G_MB_LIB.T6G(SCH_1):PVDDIO_P1    I45 @T6G_MB_LIB.T6G(SCH_1):PAGE57
  CT71 PVDDIO_P1 @T6G_MB_LIB.T6G(SCH_1):PVDDIO_P1    I45 @T6G_MB_LIB.T6G(SCH_1):PAGE57
  CT64 PVDDIO_P1 @T6G_MB_LIB.T6G(SCH_1):PVDDIO_P1    I45 @T6G_MB_LIB.T6G(SCH_1):PAGE57
   DG5 PVDD11_S3_P1 @T6G_MB_LIB.T6G(SCH_1):PVDD11_S3_P1    I45 @T6G_MB_LIB.T6G(SCH_1):PAGE57
  DE18 PVDD11_S3_P1 @T6G_MB_LIB.T6G(SCH_1):PVDD11_S3_P1    I45 @T6G_MB_LIB.T6G(SCH_1):PAGE57
  DE11 PVDD11_S3_P1 @T6G_MB_LIB.T6G(SCH_1):PVDD11_S3_P1    I45 @T6G_MB_LIB.T6G(SCH_1):PAGE57
   DE4 PVDD11_S3_P1 @T6G_MB_LIB.T6G(SCH_1):PVDD11_S3_P1    I45 @T6G_MB_LIB.T6G(SCH_1):PAGE57
  DB19 PVDD11_S3_P1 @T6G_MB_LIB.T6G(SCH_1):PVDD11_S3_P1    I45 @T6G_MB_LIB.T6G(SCH_1):PAGE57
  DB12 PVDD11_S3_P1 @T6G_MB_LIB.T6G(SCH_1):PVDD11_S3_P1    I45 @T6G_MB_LIB.T6G(SCH_1):PAGE57
   DB5 PVDD11_S3_P1 @T6G_MB_LIB.T6G(SCH_1):PVDD11_S3_P1    I45 @T6G_MB_LIB.T6G(SCH_1):PAGE57
  CY22 PVDD11_S3_P1 @T6G_MB_LIB.T6G(SCH_1):PVDD11_S3_P1    I45 @T6G_MB_LIB.T6G(SCH_1):PAGE57
  CW18 PVDD11_S3_P1 @T6G_MB_LIB.T6G(SCH_1):PVDD11_S3_P1    I45 @T6G_MB_LIB.T6G(SCH_1):PAGE57
  CW11 PVDD11_S3_P1 @T6G_MB_LIB.T6G(SCH_1):PVDD11_S3_P1    I45 @T6G_MB_LIB.T6G(SCH_1):PAGE57
   CW4 PVDD11_S3_P1 @T6G_MB_LIB.T6G(SCH_1):PVDD11_S3_P1    I45 @T6G_MB_LIB.T6G(SCH_1):PAGE57
  CT22 PVDD11_S3_P1 @T6G_MB_LIB.T6G(SCH_1):PVDD11_S3_P1    I45 @T6G_MB_LIB.T6G(SCH_1):PAGE57
  CT19 PVDD11_S3_P1 @T6G_MB_LIB.T6G(SCH_1):PVDD11_S3_P1    I45 @T6G_MB_LIB.T6G(SCH_1):PAGE57
   H37    GND @T6G_MB_LIB.T6G(SCH_1):GND     I1 @T6G_MB_LIB.T6G(SCH_1):PAGE58
   H39    GND @T6G_MB_LIB.T6G(SCH_1):GND     I1 @T6G_MB_LIB.T6G(SCH_1):PAGE58
   H42    GND @T6G_MB_LIB.T6G(SCH_1):GND     I1 @T6G_MB_LIB.T6G(SCH_1):PAGE58
   H45    GND @T6G_MB_LIB.T6G(SCH_1):GND     I1 @T6G_MB_LIB.T6G(SCH_1):PAGE58
   H48    GND @T6G_MB_LIB.T6G(SCH_1):GND     I1 @T6G_MB_LIB.T6G(SCH_1):PAGE58
   H51    GND @T6G_MB_LIB.T6G(SCH_1):GND     I1 @T6G_MB_LIB.T6G(SCH_1):PAGE58
   H54    GND @T6G_MB_LIB.T6G(SCH_1):GND     I1 @T6G_MB_LIB.T6G(SCH_1):PAGE58
   H59    GND @T6G_MB_LIB.T6G(SCH_1):GND     I1 @T6G_MB_LIB.T6G(SCH_1):PAGE58
   H61    GND @T6G_MB_LIB.T6G(SCH_1):GND     I1 @T6G_MB_LIB.T6G(SCH_1):PAGE58
   H66    GND @T6G_MB_LIB.T6G(SCH_1):GND     I1 @T6G_MB_LIB.T6G(SCH_1):PAGE58
   H68    GND @T6G_MB_LIB.T6G(SCH_1):GND     I1 @T6G_MB_LIB.T6G(SCH_1):PAGE58
   H73    GND @T6G_MB_LIB.T6G(SCH_1):GND     I1 @T6G_MB_LIB.T6G(SCH_1):PAGE58
    J1    GND @T6G_MB_LIB.T6G(SCH_1):GND     I1 @T6G_MB_LIB.T6G(SCH_1):PAGE58
    J4    GND @T6G_MB_LIB.T6G(SCH_1):GND     I1 @T6G_MB_LIB.T6G(SCH_1):PAGE58
    J6    GND @T6G_MB_LIB.T6G(SCH_1):GND     I1 @T6G_MB_LIB.T6G(SCH_1):PAGE58
    J8    GND @T6G_MB_LIB.T6G(SCH_1):GND     I1 @T6G_MB_LIB.T6G(SCH_1):PAGE58
   J11    GND @T6G_MB_LIB.T6G(SCH_1):GND     I1 @T6G_MB_LIB.T6G(SCH_1):PAGE58
   J13    GND @T6G_MB_LIB.T6G(SCH_1):GND     I1 @T6G_MB_LIB.T6G(SCH_1):PAGE58
    A3    GND @T6G_MB_LIB.T6G(SCH_1):GND     I1 @T6G_MB_LIB.T6G(SCH_1):PAGE58
    A9    GND @T6G_MB_LIB.T6G(SCH_1):GND     I1 @T6G_MB_LIB.T6G(SCH_1):PAGE58
   A15    GND @T6G_MB_LIB.T6G(SCH_1):GND     I1 @T6G_MB_LIB.T6G(SCH_1):PAGE58
   A21    GND @T6G_MB_LIB.T6G(SCH_1):GND     I1 @T6G_MB_LIB.T6G(SCH_1):PAGE58
   A27    GND @T6G_MB_LIB.T6G(SCH_1):GND     I1 @T6G_MB_LIB.T6G(SCH_1):PAGE58
   A43    GND @T6G_MB_LIB.T6G(SCH_1):GND     I1 @T6G_MB_LIB.T6G(SCH_1):PAGE58
   A44    GND @T6G_MB_LIB.T6G(SCH_1):GND     I1 @T6G_MB_LIB.T6G(SCH_1):PAGE58
   A47    GND @T6G_MB_LIB.T6G(SCH_1):GND     I1 @T6G_MB_LIB.T6G(SCH_1):PAGE58
   A49    GND @T6G_MB_LIB.T6G(SCH_1):GND     I1 @T6G_MB_LIB.T6G(SCH_1):PAGE58
   A53    GND @T6G_MB_LIB.T6G(SCH_1):GND     I1 @T6G_MB_LIB.T6G(SCH_1):PAGE58
   A61    GND @T6G_MB_LIB.T6G(SCH_1):GND     I1 @T6G_MB_LIB.T6G(SCH_1):PAGE58
   A67    GND @T6G_MB_LIB.T6G(SCH_1):GND     I1 @T6G_MB_LIB.T6G(SCH_1):PAGE58
   A72    GND @T6G_MB_LIB.T6G(SCH_1):GND     I1 @T6G_MB_LIB.T6G(SCH_1):PAGE58
   A73    GND @T6G_MB_LIB.T6G(SCH_1):GND     I1 @T6G_MB_LIB.T6G(SCH_1):PAGE58
    B7    GND @T6G_MB_LIB.T6G(SCH_1):GND     I1 @T6G_MB_LIB.T6G(SCH_1):PAGE58
    B8    GND @T6G_MB_LIB.T6G(SCH_1):GND     I1 @T6G_MB_LIB.T6G(SCH_1):PAGE58
   B10    GND @T6G_MB_LIB.T6G(SCH_1):GND     I1 @T6G_MB_LIB.T6G(SCH_1):PAGE58
   B11    GND @T6G_MB_LIB.T6G(SCH_1):GND     I1 @T6G_MB_LIB.T6G(SCH_1):PAGE58
   B13    GND @T6G_MB_LIB.T6G(SCH_1):GND     I1 @T6G_MB_LIB.T6G(SCH_1):PAGE58
   B18    GND @T6G_MB_LIB.T6G(SCH_1):GND     I1 @T6G_MB_LIB.T6G(SCH_1):PAGE58
   B24    GND @T6G_MB_LIB.T6G(SCH_1):GND     I1 @T6G_MB_LIB.T6G(SCH_1):PAGE58
   B27    GND @T6G_MB_LIB.T6G(SCH_1):GND     I1 @T6G_MB_LIB.T6G(SCH_1):PAGE58
   B30    GND @T6G_MB_LIB.T6G(SCH_1):GND     I1 @T6G_MB_LIB.T6G(SCH_1):PAGE58
   B33    GND @T6G_MB_LIB.T6G(SCH_1):GND     I1 @T6G_MB_LIB.T6G(SCH_1):PAGE58
   B37    GND @T6G_MB_LIB.T6G(SCH_1):GND     I1 @T6G_MB_LIB.T6G(SCH_1):PAGE58
   B39    GND @T6G_MB_LIB.T6G(SCH_1):GND     I1 @T6G_MB_LIB.T6G(SCH_1):PAGE58
   B43    GND @T6G_MB_LIB.T6G(SCH_1):GND     I1 @T6G_MB_LIB.T6G(SCH_1):PAGE58
   B46    GND @T6G_MB_LIB.T6G(SCH_1):GND     I1 @T6G_MB_LIB.T6G(SCH_1):PAGE58
   B49    GND @T6G_MB_LIB.T6G(SCH_1):GND     I1 @T6G_MB_LIB.T6G(SCH_1):PAGE58
   B52    GND @T6G_MB_LIB.T6G(SCH_1):GND     I1 @T6G_MB_LIB.T6G(SCH_1):PAGE58
   B55    GND @T6G_MB_LIB.T6G(SCH_1):GND     I1 @T6G_MB_LIB.T6G(SCH_1):PAGE58
   B59    GND @T6G_MB_LIB.T6G(SCH_1):GND     I1 @T6G_MB_LIB.T6G(SCH_1):PAGE58
   B62    GND @T6G_MB_LIB.T6G(SCH_1):GND     I1 @T6G_MB_LIB.T6G(SCH_1):PAGE58
   B65    GND @T6G_MB_LIB.T6G(SCH_1):GND     I1 @T6G_MB_LIB.T6G(SCH_1):PAGE58
   B68    GND @T6G_MB_LIB.T6G(SCH_1):GND     I1 @T6G_MB_LIB.T6G(SCH_1):PAGE58
   B70    GND @T6G_MB_LIB.T6G(SCH_1):GND     I1 @T6G_MB_LIB.T6G(SCH_1):PAGE58
    C1    GND @T6G_MB_LIB.T6G(SCH_1):GND     I1 @T6G_MB_LIB.T6G(SCH_1):PAGE58
    C5    GND @T6G_MB_LIB.T6G(SCH_1):GND     I1 @T6G_MB_LIB.T6G(SCH_1):PAGE58
    C8    GND @T6G_MB_LIB.T6G(SCH_1):GND     I1 @T6G_MB_LIB.T6G(SCH_1):PAGE58
   C10    GND @T6G_MB_LIB.T6G(SCH_1):GND     I1 @T6G_MB_LIB.T6G(SCH_1):PAGE58
   C11    GND @T6G_MB_LIB.T6G(SCH_1):GND     I1 @T6G_MB_LIB.T6G(SCH_1):PAGE58
   C13    GND @T6G_MB_LIB.T6G(SCH_1):GND     I1 @T6G_MB_LIB.T6G(SCH_1):PAGE58
   C15    GND @T6G_MB_LIB.T6G(SCH_1):GND     I1 @T6G_MB_LIB.T6G(SCH_1):PAGE58
   C21    GND @T6G_MB_LIB.T6G(SCH_1):GND     I1 @T6G_MB_LIB.T6G(SCH_1):PAGE58
   C24    GND @T6G_MB_LIB.T6G(SCH_1):GND     I1 @T6G_MB_LIB.T6G(SCH_1):PAGE58
   C27    GND @T6G_MB_LIB.T6G(SCH_1):GND     I1 @T6G_MB_LIB.T6G(SCH_1):PAGE58
   C30    GND @T6G_MB_LIB.T6G(SCH_1):GND     I1 @T6G_MB_LIB.T6G(SCH_1):PAGE58
   C36    GND @T6G_MB_LIB.T6G(SCH_1):GND     I1 @T6G_MB_LIB.T6G(SCH_1):PAGE58
   C40    GND @T6G_MB_LIB.T6G(SCH_1):GND     I1 @T6G_MB_LIB.T6G(SCH_1):PAGE58
   C43    GND @T6G_MB_LIB.T6G(SCH_1):GND     I1 @T6G_MB_LIB.T6G(SCH_1):PAGE58
   C46    GND @T6G_MB_LIB.T6G(SCH_1):GND     I1 @T6G_MB_LIB.T6G(SCH_1):PAGE58
   C49    GND @T6G_MB_LIB.T6G(SCH_1):GND     I1 @T6G_MB_LIB.T6G(SCH_1):PAGE58
   C52    GND @T6G_MB_LIB.T6G(SCH_1):GND     I1 @T6G_MB_LIB.T6G(SCH_1):PAGE58
   C55    GND @T6G_MB_LIB.T6G(SCH_1):GND     I1 @T6G_MB_LIB.T6G(SCH_1):PAGE58
   C56    GND @T6G_MB_LIB.T6G(SCH_1):GND     I1 @T6G_MB_LIB.T6G(SCH_1):PAGE58
   C57    GND @T6G_MB_LIB.T6G(SCH_1):GND     I1 @T6G_MB_LIB.T6G(SCH_1):PAGE58
   C61    GND @T6G_MB_LIB.T6G(SCH_1):GND     I1 @T6G_MB_LIB.T6G(SCH_1):PAGE58
   C64    GND @T6G_MB_LIB.T6G(SCH_1):GND     I1 @T6G_MB_LIB.T6G(SCH_1):PAGE58
   C67    GND @T6G_MB_LIB.T6G(SCH_1):GND     I1 @T6G_MB_LIB.T6G(SCH_1):PAGE58
   C69    GND @T6G_MB_LIB.T6G(SCH_1):GND     I1 @T6G_MB_LIB.T6G(SCH_1):PAGE58
   C71    GND @T6G_MB_LIB.T6G(SCH_1):GND     I1 @T6G_MB_LIB.T6G(SCH_1):PAGE58
   C73    GND @T6G_MB_LIB.T6G(SCH_1):GND     I1 @T6G_MB_LIB.T6G(SCH_1):PAGE58
   C75    GND @T6G_MB_LIB.T6G(SCH_1):GND     I1 @T6G_MB_LIB.T6G(SCH_1):PAGE58
    D2    GND @T6G_MB_LIB.T6G(SCH_1):GND     I1 @T6G_MB_LIB.T6G(SCH_1):PAGE58
    D3    GND @T6G_MB_LIB.T6G(SCH_1):GND     I1 @T6G_MB_LIB.T6G(SCH_1):PAGE58
    D5    GND @T6G_MB_LIB.T6G(SCH_1):GND     I1 @T6G_MB_LIB.T6G(SCH_1):PAGE58
    D6    GND @T6G_MB_LIB.T6G(SCH_1):GND     I1 @T6G_MB_LIB.T6G(SCH_1):PAGE58
    D9    GND @T6G_MB_LIB.T6G(SCH_1):GND     I1 @T6G_MB_LIB.T6G(SCH_1):PAGE58
   D10    GND @T6G_MB_LIB.T6G(SCH_1):GND     I1 @T6G_MB_LIB.T6G(SCH_1):PAGE58
   D12    GND @T6G_MB_LIB.T6G(SCH_1):GND     I1 @T6G_MB_LIB.T6G(SCH_1):PAGE58
   D13    GND @T6G_MB_LIB.T6G(SCH_1):GND     I1 @T6G_MB_LIB.T6G(SCH_1):PAGE58
   D16    GND @T6G_MB_LIB.T6G(SCH_1):GND     I1 @T6G_MB_LIB.T6G(SCH_1):PAGE58
   D17    GND @T6G_MB_LIB.T6G(SCH_1):GND     I1 @T6G_MB_LIB.T6G(SCH_1):PAGE58
   D19    GND @T6G_MB_LIB.T6G(SCH_1):GND     I1 @T6G_MB_LIB.T6G(SCH_1):PAGE58
   D20    GND @T6G_MB_LIB.T6G(SCH_1):GND     I1 @T6G_MB_LIB.T6G(SCH_1):PAGE58
   D21    GND @T6G_MB_LIB.T6G(SCH_1):GND     I1 @T6G_MB_LIB.T6G(SCH_1):PAGE58
   D24    GND @T6G_MB_LIB.T6G(SCH_1):GND     I1 @T6G_MB_LIB.T6G(SCH_1):PAGE58
   D25    GND @T6G_MB_LIB.T6G(SCH_1):GND     I1 @T6G_MB_LIB.T6G(SCH_1):PAGE58
   D26    GND @T6G_MB_LIB.T6G(SCH_1):GND     I1 @T6G_MB_LIB.T6G(SCH_1):PAGE58
   D27    GND @T6G_MB_LIB.T6G(SCH_1):GND     I1 @T6G_MB_LIB.T6G(SCH_1):PAGE58
   D28    GND @T6G_MB_LIB.T6G(SCH_1):GND     I1 @T6G_MB_LIB.T6G(SCH_1):PAGE58
   D29    GND @T6G_MB_LIB.T6G(SCH_1):GND     I1 @T6G_MB_LIB.T6G(SCH_1):PAGE58
   D30    GND @T6G_MB_LIB.T6G(SCH_1):GND     I1 @T6G_MB_LIB.T6G(SCH_1):PAGE58
   D31    GND @T6G_MB_LIB.T6G(SCH_1):GND     I1 @T6G_MB_LIB.T6G(SCH_1):PAGE58
   D35    GND @T6G_MB_LIB.T6G(SCH_1):GND     I1 @T6G_MB_LIB.T6G(SCH_1):PAGE58
   D37    GND @T6G_MB_LIB.T6G(SCH_1):GND     I1 @T6G_MB_LIB.T6G(SCH_1):PAGE58
   D39    GND @T6G_MB_LIB.T6G(SCH_1):GND     I1 @T6G_MB_LIB.T6G(SCH_1):PAGE58
   D40    GND @T6G_MB_LIB.T6G(SCH_1):GND     I1 @T6G_MB_LIB.T6G(SCH_1):PAGE58
   D41    GND @T6G_MB_LIB.T6G(SCH_1):GND     I1 @T6G_MB_LIB.T6G(SCH_1):PAGE58
   D42    GND @T6G_MB_LIB.T6G(SCH_1):GND     I1 @T6G_MB_LIB.T6G(SCH_1):PAGE58
   D43    GND @T6G_MB_LIB.T6G(SCH_1):GND     I1 @T6G_MB_LIB.T6G(SCH_1):PAGE58
   D44    GND @T6G_MB_LIB.T6G(SCH_1):GND     I1 @T6G_MB_LIB.T6G(SCH_1):PAGE58
   D45    GND @T6G_MB_LIB.T6G(SCH_1):GND     I1 @T6G_MB_LIB.T6G(SCH_1):PAGE58
   D46    GND @T6G_MB_LIB.T6G(SCH_1):GND     I1 @T6G_MB_LIB.T6G(SCH_1):PAGE58
   D47    GND @T6G_MB_LIB.T6G(SCH_1):GND     I1 @T6G_MB_LIB.T6G(SCH_1):PAGE58
   D48    GND @T6G_MB_LIB.T6G(SCH_1):GND     I1 @T6G_MB_LIB.T6G(SCH_1):PAGE58
   D49    GND @T6G_MB_LIB.T6G(SCH_1):GND     I1 @T6G_MB_LIB.T6G(SCH_1):PAGE58
   D50    GND @T6G_MB_LIB.T6G(SCH_1):GND     I1 @T6G_MB_LIB.T6G(SCH_1):PAGE58
   D51    GND @T6G_MB_LIB.T6G(SCH_1):GND     I1 @T6G_MB_LIB.T6G(SCH_1):PAGE58
   D52    GND @T6G_MB_LIB.T6G(SCH_1):GND     I1 @T6G_MB_LIB.T6G(SCH_1):PAGE58
   D53    GND @T6G_MB_LIB.T6G(SCH_1):GND     I1 @T6G_MB_LIB.T6G(SCH_1):PAGE58
   D54    GND @T6G_MB_LIB.T6G(SCH_1):GND     I1 @T6G_MB_LIB.T6G(SCH_1):PAGE58
   D57    GND @T6G_MB_LIB.T6G(SCH_1):GND     I1 @T6G_MB_LIB.T6G(SCH_1):PAGE58
   D59    GND @T6G_MB_LIB.T6G(SCH_1):GND     I1 @T6G_MB_LIB.T6G(SCH_1):PAGE58
   D60    GND @T6G_MB_LIB.T6G(SCH_1):GND     I1 @T6G_MB_LIB.T6G(SCH_1):PAGE58
   D61    GND @T6G_MB_LIB.T6G(SCH_1):GND     I1 @T6G_MB_LIB.T6G(SCH_1):PAGE58
   D63    GND @T6G_MB_LIB.T6G(SCH_1):GND     I1 @T6G_MB_LIB.T6G(SCH_1):PAGE58
   D64    GND @T6G_MB_LIB.T6G(SCH_1):GND     I1 @T6G_MB_LIB.T6G(SCH_1):PAGE58
   D66    GND @T6G_MB_LIB.T6G(SCH_1):GND     I1 @T6G_MB_LIB.T6G(SCH_1):PAGE58
   D67    GND @T6G_MB_LIB.T6G(SCH_1):GND     I1 @T6G_MB_LIB.T6G(SCH_1):PAGE58
   D70    GND @T6G_MB_LIB.T6G(SCH_1):GND     I1 @T6G_MB_LIB.T6G(SCH_1):PAGE58
   D71    GND @T6G_MB_LIB.T6G(SCH_1):GND     I1 @T6G_MB_LIB.T6G(SCH_1):PAGE58
   D73    GND @T6G_MB_LIB.T6G(SCH_1):GND     I1 @T6G_MB_LIB.T6G(SCH_1):PAGE58
   D74    GND @T6G_MB_LIB.T6G(SCH_1):GND     I1 @T6G_MB_LIB.T6G(SCH_1):PAGE58
    E1    GND @T6G_MB_LIB.T6G(SCH_1):GND     I1 @T6G_MB_LIB.T6G(SCH_1):PAGE58
    E3    GND @T6G_MB_LIB.T6G(SCH_1):GND     I1 @T6G_MB_LIB.T6G(SCH_1):PAGE58
    E6    GND @T6G_MB_LIB.T6G(SCH_1):GND     I1 @T6G_MB_LIB.T6G(SCH_1):PAGE58
    E7    GND @T6G_MB_LIB.T6G(SCH_1):GND     I1 @T6G_MB_LIB.T6G(SCH_1):PAGE58
    E8    GND @T6G_MB_LIB.T6G(SCH_1):GND     I1 @T6G_MB_LIB.T6G(SCH_1):PAGE58
   E10    GND @T6G_MB_LIB.T6G(SCH_1):GND     I1 @T6G_MB_LIB.T6G(SCH_1):PAGE58
   E13    GND @T6G_MB_LIB.T6G(SCH_1):GND     I1 @T6G_MB_LIB.T6G(SCH_1):PAGE58
   E14    GND @T6G_MB_LIB.T6G(SCH_1):GND     I1 @T6G_MB_LIB.T6G(SCH_1):PAGE58
   E15    GND @T6G_MB_LIB.T6G(SCH_1):GND     I1 @T6G_MB_LIB.T6G(SCH_1):PAGE58
   E17    GND @T6G_MB_LIB.T6G(SCH_1):GND     I1 @T6G_MB_LIB.T6G(SCH_1):PAGE58
   E18    GND @T6G_MB_LIB.T6G(SCH_1):GND     I1 @T6G_MB_LIB.T6G(SCH_1):PAGE58
   E20    GND @T6G_MB_LIB.T6G(SCH_1):GND     I1 @T6G_MB_LIB.T6G(SCH_1):PAGE58
   E21    GND @T6G_MB_LIB.T6G(SCH_1):GND     I1 @T6G_MB_LIB.T6G(SCH_1):PAGE58
   E52    GND @T6G_MB_LIB.T6G(SCH_1):GND     I1 @T6G_MB_LIB.T6G(SCH_1):PAGE58
   E53    GND @T6G_MB_LIB.T6G(SCH_1):GND     I1 @T6G_MB_LIB.T6G(SCH_1):PAGE58
   E55    GND @T6G_MB_LIB.T6G(SCH_1):GND     I1 @T6G_MB_LIB.T6G(SCH_1):PAGE58
   E56    GND @T6G_MB_LIB.T6G(SCH_1):GND     I1 @T6G_MB_LIB.T6G(SCH_1):PAGE58
   E58    GND @T6G_MB_LIB.T6G(SCH_1):GND     I1 @T6G_MB_LIB.T6G(SCH_1):PAGE58
   E59    GND @T6G_MB_LIB.T6G(SCH_1):GND     I1 @T6G_MB_LIB.T6G(SCH_1):PAGE58
   E61    GND @T6G_MB_LIB.T6G(SCH_1):GND     I1 @T6G_MB_LIB.T6G(SCH_1):PAGE58
   E62    GND @T6G_MB_LIB.T6G(SCH_1):GND     I1 @T6G_MB_LIB.T6G(SCH_1):PAGE58
   E63    GND @T6G_MB_LIB.T6G(SCH_1):GND     I1 @T6G_MB_LIB.T6G(SCH_1):PAGE58
   E65    GND @T6G_MB_LIB.T6G(SCH_1):GND     I1 @T6G_MB_LIB.T6G(SCH_1):PAGE58
   E66    GND @T6G_MB_LIB.T6G(SCH_1):GND     I1 @T6G_MB_LIB.T6G(SCH_1):PAGE58
   E68    GND @T6G_MB_LIB.T6G(SCH_1):GND     I1 @T6G_MB_LIB.T6G(SCH_1):PAGE58
   E69    GND @T6G_MB_LIB.T6G(SCH_1):GND     I1 @T6G_MB_LIB.T6G(SCH_1):PAGE58
   E70    GND @T6G_MB_LIB.T6G(SCH_1):GND     I1 @T6G_MB_LIB.T6G(SCH_1):PAGE58
   E72    GND @T6G_MB_LIB.T6G(SCH_1):GND     I1 @T6G_MB_LIB.T6G(SCH_1):PAGE58
   E73    GND @T6G_MB_LIB.T6G(SCH_1):GND     I1 @T6G_MB_LIB.T6G(SCH_1):PAGE58
   E75    GND @T6G_MB_LIB.T6G(SCH_1):GND     I1 @T6G_MB_LIB.T6G(SCH_1):PAGE58
    F3    GND @T6G_MB_LIB.T6G(SCH_1):GND     I1 @T6G_MB_LIB.T6G(SCH_1):PAGE58
    F5    GND @T6G_MB_LIB.T6G(SCH_1):GND     I1 @T6G_MB_LIB.T6G(SCH_1):PAGE58
    F8    GND @T6G_MB_LIB.T6G(SCH_1):GND     I1 @T6G_MB_LIB.T6G(SCH_1):PAGE58
   F10    GND @T6G_MB_LIB.T6G(SCH_1):GND     I1 @T6G_MB_LIB.T6G(SCH_1):PAGE58
   F12    GND @T6G_MB_LIB.T6G(SCH_1):GND     I1 @T6G_MB_LIB.T6G(SCH_1):PAGE58
   F15    GND @T6G_MB_LIB.T6G(SCH_1):GND     I1 @T6G_MB_LIB.T6G(SCH_1):PAGE58
   F17    GND @T6G_MB_LIB.T6G(SCH_1):GND     I1 @T6G_MB_LIB.T6G(SCH_1):PAGE58
   F19    GND @T6G_MB_LIB.T6G(SCH_1):GND     I1 @T6G_MB_LIB.T6G(SCH_1):PAGE58
   F23    GND @T6G_MB_LIB.T6G(SCH_1):GND     I1 @T6G_MB_LIB.T6G(SCH_1):PAGE58
   F24    GND @T6G_MB_LIB.T6G(SCH_1):GND     I1 @T6G_MB_LIB.T6G(SCH_1):PAGE58
   F26    GND @T6G_MB_LIB.T6G(SCH_1):GND     I1 @T6G_MB_LIB.T6G(SCH_1):PAGE58
   F27    GND @T6G_MB_LIB.T6G(SCH_1):GND     I1 @T6G_MB_LIB.T6G(SCH_1):PAGE58
   F29    GND @T6G_MB_LIB.T6G(SCH_1):GND     I1 @T6G_MB_LIB.T6G(SCH_1):PAGE58
   F30    GND @T6G_MB_LIB.T6G(SCH_1):GND     I1 @T6G_MB_LIB.T6G(SCH_1):PAGE58
   F32    GND @T6G_MB_LIB.T6G(SCH_1):GND     I1 @T6G_MB_LIB.T6G(SCH_1):PAGE58
   F33    GND @T6G_MB_LIB.T6G(SCH_1):GND     I1 @T6G_MB_LIB.T6G(SCH_1):PAGE58
   F35    GND @T6G_MB_LIB.T6G(SCH_1):GND     I1 @T6G_MB_LIB.T6G(SCH_1):PAGE58
   F36    GND @T6G_MB_LIB.T6G(SCH_1):GND     I1 @T6G_MB_LIB.T6G(SCH_1):PAGE58
   F37    GND @T6G_MB_LIB.T6G(SCH_1):GND     I1 @T6G_MB_LIB.T6G(SCH_1):PAGE58
   F39    GND @T6G_MB_LIB.T6G(SCH_1):GND     I1 @T6G_MB_LIB.T6G(SCH_1):PAGE58
   F40    GND @T6G_MB_LIB.T6G(SCH_1):GND     I1 @T6G_MB_LIB.T6G(SCH_1):PAGE58
   F41    GND @T6G_MB_LIB.T6G(SCH_1):GND     I1 @T6G_MB_LIB.T6G(SCH_1):PAGE58
   F43    GND @T6G_MB_LIB.T6G(SCH_1):GND     I1 @T6G_MB_LIB.T6G(SCH_1):PAGE58
   F44    GND @T6G_MB_LIB.T6G(SCH_1):GND     I1 @T6G_MB_LIB.T6G(SCH_1):PAGE58
   F46    GND @T6G_MB_LIB.T6G(SCH_1):GND     I1 @T6G_MB_LIB.T6G(SCH_1):PAGE58
   F47    GND @T6G_MB_LIB.T6G(SCH_1):GND     I1 @T6G_MB_LIB.T6G(SCH_1):PAGE58
   F49    GND @T6G_MB_LIB.T6G(SCH_1):GND     I1 @T6G_MB_LIB.T6G(SCH_1):PAGE58
   F50    GND @T6G_MB_LIB.T6G(SCH_1):GND     I1 @T6G_MB_LIB.T6G(SCH_1):PAGE58
   F52    GND @T6G_MB_LIB.T6G(SCH_1):GND     I1 @T6G_MB_LIB.T6G(SCH_1):PAGE58
   F53    GND @T6G_MB_LIB.T6G(SCH_1):GND     I1 @T6G_MB_LIB.T6G(SCH_1):PAGE58
   F57    GND @T6G_MB_LIB.T6G(SCH_1):GND     I1 @T6G_MB_LIB.T6G(SCH_1):PAGE58
   F59    GND @T6G_MB_LIB.T6G(SCH_1):GND     I1 @T6G_MB_LIB.T6G(SCH_1):PAGE58
   F61    GND @T6G_MB_LIB.T6G(SCH_1):GND     I1 @T6G_MB_LIB.T6G(SCH_1):PAGE58
   F64    GND @T6G_MB_LIB.T6G(SCH_1):GND     I1 @T6G_MB_LIB.T6G(SCH_1):PAGE58
   F66    GND @T6G_MB_LIB.T6G(SCH_1):GND     I1 @T6G_MB_LIB.T6G(SCH_1):PAGE58
   F68    GND @T6G_MB_LIB.T6G(SCH_1):GND     I1 @T6G_MB_LIB.T6G(SCH_1):PAGE58
   F71    GND @T6G_MB_LIB.T6G(SCH_1):GND     I1 @T6G_MB_LIB.T6G(SCH_1):PAGE58
   F73    GND @T6G_MB_LIB.T6G(SCH_1):GND     I1 @T6G_MB_LIB.T6G(SCH_1):PAGE58
    G1    GND @T6G_MB_LIB.T6G(SCH_1):GND     I1 @T6G_MB_LIB.T6G(SCH_1):PAGE58
    G4    GND @T6G_MB_LIB.T6G(SCH_1):GND     I1 @T6G_MB_LIB.T6G(SCH_1):PAGE58
    G6    GND @T6G_MB_LIB.T6G(SCH_1):GND     I1 @T6G_MB_LIB.T6G(SCH_1):PAGE58
    G8    GND @T6G_MB_LIB.T6G(SCH_1):GND     I1 @T6G_MB_LIB.T6G(SCH_1):PAGE58
   G11    GND @T6G_MB_LIB.T6G(SCH_1):GND     I1 @T6G_MB_LIB.T6G(SCH_1):PAGE58
   G13    GND @T6G_MB_LIB.T6G(SCH_1):GND     I1 @T6G_MB_LIB.T6G(SCH_1):PAGE58
   G15    GND @T6G_MB_LIB.T6G(SCH_1):GND     I1 @T6G_MB_LIB.T6G(SCH_1):PAGE58
   G18    GND @T6G_MB_LIB.T6G(SCH_1):GND     I1 @T6G_MB_LIB.T6G(SCH_1):PAGE58
   G20    GND @T6G_MB_LIB.T6G(SCH_1):GND     I1 @T6G_MB_LIB.T6G(SCH_1):PAGE58
   G22    GND @T6G_MB_LIB.T6G(SCH_1):GND     I1 @T6G_MB_LIB.T6G(SCH_1):PAGE58
   G25    GND @T6G_MB_LIB.T6G(SCH_1):GND     I1 @T6G_MB_LIB.T6G(SCH_1):PAGE58
   G28    GND @T6G_MB_LIB.T6G(SCH_1):GND     I1 @T6G_MB_LIB.T6G(SCH_1):PAGE58
   G31    GND @T6G_MB_LIB.T6G(SCH_1):GND     I1 @T6G_MB_LIB.T6G(SCH_1):PAGE58
   G34    GND @T6G_MB_LIB.T6G(SCH_1):GND     I1 @T6G_MB_LIB.T6G(SCH_1):PAGE58
   G42    GND @T6G_MB_LIB.T6G(SCH_1):GND     I1 @T6G_MB_LIB.T6G(SCH_1):PAGE58
   G45    GND @T6G_MB_LIB.T6G(SCH_1):GND     I1 @T6G_MB_LIB.T6G(SCH_1):PAGE58
   G48    GND @T6G_MB_LIB.T6G(SCH_1):GND     I1 @T6G_MB_LIB.T6G(SCH_1):PAGE58
   G51    GND @T6G_MB_LIB.T6G(SCH_1):GND     I1 @T6G_MB_LIB.T6G(SCH_1):PAGE58
   G54    GND @T6G_MB_LIB.T6G(SCH_1):GND     I1 @T6G_MB_LIB.T6G(SCH_1):PAGE58
   G56    GND @T6G_MB_LIB.T6G(SCH_1):GND     I1 @T6G_MB_LIB.T6G(SCH_1):PAGE58
   G58    GND @T6G_MB_LIB.T6G(SCH_1):GND     I1 @T6G_MB_LIB.T6G(SCH_1):PAGE58
   G61    GND @T6G_MB_LIB.T6G(SCH_1):GND     I1 @T6G_MB_LIB.T6G(SCH_1):PAGE58
   G63    GND @T6G_MB_LIB.T6G(SCH_1):GND     I1 @T6G_MB_LIB.T6G(SCH_1):PAGE58
   G65    GND @T6G_MB_LIB.T6G(SCH_1):GND     I1 @T6G_MB_LIB.T6G(SCH_1):PAGE58
   G68    GND @T6G_MB_LIB.T6G(SCH_1):GND     I1 @T6G_MB_LIB.T6G(SCH_1):PAGE58
   G70    GND @T6G_MB_LIB.T6G(SCH_1):GND     I1 @T6G_MB_LIB.T6G(SCH_1):PAGE58
   G72    GND @T6G_MB_LIB.T6G(SCH_1):GND     I1 @T6G_MB_LIB.T6G(SCH_1):PAGE58
   G75    GND @T6G_MB_LIB.T6G(SCH_1):GND     I1 @T6G_MB_LIB.T6G(SCH_1):PAGE58
    H3    GND @T6G_MB_LIB.T6G(SCH_1):GND     I1 @T6G_MB_LIB.T6G(SCH_1):PAGE58
    H8    GND @T6G_MB_LIB.T6G(SCH_1):GND     I1 @T6G_MB_LIB.T6G(SCH_1):PAGE58
   H10    GND @T6G_MB_LIB.T6G(SCH_1):GND     I1 @T6G_MB_LIB.T6G(SCH_1):PAGE58
   H15    GND @T6G_MB_LIB.T6G(SCH_1):GND     I1 @T6G_MB_LIB.T6G(SCH_1):PAGE58
   H17    GND @T6G_MB_LIB.T6G(SCH_1):GND     I1 @T6G_MB_LIB.T6G(SCH_1):PAGE58
   H22    GND @T6G_MB_LIB.T6G(SCH_1):GND     I1 @T6G_MB_LIB.T6G(SCH_1):PAGE58
   H25    GND @T6G_MB_LIB.T6G(SCH_1):GND     I1 @T6G_MB_LIB.T6G(SCH_1):PAGE58
   H28    GND @T6G_MB_LIB.T6G(SCH_1):GND     I1 @T6G_MB_LIB.T6G(SCH_1):PAGE58
   H31    GND @T6G_MB_LIB.T6G(SCH_1):GND     I1 @T6G_MB_LIB.T6G(SCH_1):PAGE58
   H34    GND @T6G_MB_LIB.T6G(SCH_1):GND     I1 @T6G_MB_LIB.T6G(SCH_1):PAGE58
   R48    GND @T6G_MB_LIB.T6G(SCH_1):GND    I15 @T6G_MB_LIB.T6G(SCH_1):PAGE58
   R51    GND @T6G_MB_LIB.T6G(SCH_1):GND    I15 @T6G_MB_LIB.T6G(SCH_1):PAGE58
   R54    GND @T6G_MB_LIB.T6G(SCH_1):GND    I15 @T6G_MB_LIB.T6G(SCH_1):PAGE58
   R56    GND @T6G_MB_LIB.T6G(SCH_1):GND    I15 @T6G_MB_LIB.T6G(SCH_1):PAGE58
   R58    GND @T6G_MB_LIB.T6G(SCH_1):GND    I15 @T6G_MB_LIB.T6G(SCH_1):PAGE58
   R61    GND @T6G_MB_LIB.T6G(SCH_1):GND    I15 @T6G_MB_LIB.T6G(SCH_1):PAGE58
   R63    GND @T6G_MB_LIB.T6G(SCH_1):GND    I15 @T6G_MB_LIB.T6G(SCH_1):PAGE58
   R65    GND @T6G_MB_LIB.T6G(SCH_1):GND    I15 @T6G_MB_LIB.T6G(SCH_1):PAGE58
   R68    GND @T6G_MB_LIB.T6G(SCH_1):GND    I15 @T6G_MB_LIB.T6G(SCH_1):PAGE58
   R70    GND @T6G_MB_LIB.T6G(SCH_1):GND    I15 @T6G_MB_LIB.T6G(SCH_1):PAGE58
   R72    GND @T6G_MB_LIB.T6G(SCH_1):GND    I15 @T6G_MB_LIB.T6G(SCH_1):PAGE58
   R75    GND @T6G_MB_LIB.T6G(SCH_1):GND    I15 @T6G_MB_LIB.T6G(SCH_1):PAGE58
    T3    GND @T6G_MB_LIB.T6G(SCH_1):GND    I15 @T6G_MB_LIB.T6G(SCH_1):PAGE58
    T5    GND @T6G_MB_LIB.T6G(SCH_1):GND    I15 @T6G_MB_LIB.T6G(SCH_1):PAGE58
    T8    GND @T6G_MB_LIB.T6G(SCH_1):GND    I15 @T6G_MB_LIB.T6G(SCH_1):PAGE58
   T10    GND @T6G_MB_LIB.T6G(SCH_1):GND    I15 @T6G_MB_LIB.T6G(SCH_1):PAGE58
   T12    GND @T6G_MB_LIB.T6G(SCH_1):GND    I15 @T6G_MB_LIB.T6G(SCH_1):PAGE58
   T15    GND @T6G_MB_LIB.T6G(SCH_1):GND    I15 @T6G_MB_LIB.T6G(SCH_1):PAGE58
   T17    GND @T6G_MB_LIB.T6G(SCH_1):GND    I15 @T6G_MB_LIB.T6G(SCH_1):PAGE58
   T19    GND @T6G_MB_LIB.T6G(SCH_1):GND    I15 @T6G_MB_LIB.T6G(SCH_1):PAGE58
   T22    GND @T6G_MB_LIB.T6G(SCH_1):GND    I15 @T6G_MB_LIB.T6G(SCH_1):PAGE58
   T25    GND @T6G_MB_LIB.T6G(SCH_1):GND    I15 @T6G_MB_LIB.T6G(SCH_1):PAGE58
   T28    GND @T6G_MB_LIB.T6G(SCH_1):GND    I15 @T6G_MB_LIB.T6G(SCH_1):PAGE58
   T31    GND @T6G_MB_LIB.T6G(SCH_1):GND    I15 @T6G_MB_LIB.T6G(SCH_1):PAGE58
   T34    GND @T6G_MB_LIB.T6G(SCH_1):GND    I15 @T6G_MB_LIB.T6G(SCH_1):PAGE58
   T37    GND @T6G_MB_LIB.T6G(SCH_1):GND    I15 @T6G_MB_LIB.T6G(SCH_1):PAGE58
   T39    GND @T6G_MB_LIB.T6G(SCH_1):GND    I15 @T6G_MB_LIB.T6G(SCH_1):PAGE58
   T42    GND @T6G_MB_LIB.T6G(SCH_1):GND    I15 @T6G_MB_LIB.T6G(SCH_1):PAGE58
   T45    GND @T6G_MB_LIB.T6G(SCH_1):GND    I15 @T6G_MB_LIB.T6G(SCH_1):PAGE58
   T48    GND @T6G_MB_LIB.T6G(SCH_1):GND    I15 @T6G_MB_LIB.T6G(SCH_1):PAGE58
   T51    GND @T6G_MB_LIB.T6G(SCH_1):GND    I15 @T6G_MB_LIB.T6G(SCH_1):PAGE58
   T54    GND @T6G_MB_LIB.T6G(SCH_1):GND    I15 @T6G_MB_LIB.T6G(SCH_1):PAGE58
   T57    GND @T6G_MB_LIB.T6G(SCH_1):GND    I15 @T6G_MB_LIB.T6G(SCH_1):PAGE58
   T59    GND @T6G_MB_LIB.T6G(SCH_1):GND    I15 @T6G_MB_LIB.T6G(SCH_1):PAGE58
   T61    GND @T6G_MB_LIB.T6G(SCH_1):GND    I15 @T6G_MB_LIB.T6G(SCH_1):PAGE58
   T64    GND @T6G_MB_LIB.T6G(SCH_1):GND    I15 @T6G_MB_LIB.T6G(SCH_1):PAGE58
   J15    GND @T6G_MB_LIB.T6G(SCH_1):GND    I15 @T6G_MB_LIB.T6G(SCH_1):PAGE58
   J18    GND @T6G_MB_LIB.T6G(SCH_1):GND    I15 @T6G_MB_LIB.T6G(SCH_1):PAGE58
   J20    GND @T6G_MB_LIB.T6G(SCH_1):GND    I15 @T6G_MB_LIB.T6G(SCH_1):PAGE58
   J22    GND @T6G_MB_LIB.T6G(SCH_1):GND    I15 @T6G_MB_LIB.T6G(SCH_1):PAGE58
   J25    GND @T6G_MB_LIB.T6G(SCH_1):GND    I15 @T6G_MB_LIB.T6G(SCH_1):PAGE58
   J28    GND @T6G_MB_LIB.T6G(SCH_1):GND    I15 @T6G_MB_LIB.T6G(SCH_1):PAGE58
   J31    GND @T6G_MB_LIB.T6G(SCH_1):GND    I15 @T6G_MB_LIB.T6G(SCH_1):PAGE58
   J34    GND @T6G_MB_LIB.T6G(SCH_1):GND    I15 @T6G_MB_LIB.T6G(SCH_1):PAGE58
   J42    GND @T6G_MB_LIB.T6G(SCH_1):GND    I15 @T6G_MB_LIB.T6G(SCH_1):PAGE58
   J45    GND @T6G_MB_LIB.T6G(SCH_1):GND    I15 @T6G_MB_LIB.T6G(SCH_1):PAGE58
   J48    GND @T6G_MB_LIB.T6G(SCH_1):GND    I15 @T6G_MB_LIB.T6G(SCH_1):PAGE58
   J51    GND @T6G_MB_LIB.T6G(SCH_1):GND    I15 @T6G_MB_LIB.T6G(SCH_1):PAGE58
   J54    GND @T6G_MB_LIB.T6G(SCH_1):GND    I15 @T6G_MB_LIB.T6G(SCH_1):PAGE58
   J56    GND @T6G_MB_LIB.T6G(SCH_1):GND    I15 @T6G_MB_LIB.T6G(SCH_1):PAGE58
   J58    GND @T6G_MB_LIB.T6G(SCH_1):GND    I15 @T6G_MB_LIB.T6G(SCH_1):PAGE58
   J61    GND @T6G_MB_LIB.T6G(SCH_1):GND    I15 @T6G_MB_LIB.T6G(SCH_1):PAGE58
   J63    GND @T6G_MB_LIB.T6G(SCH_1):GND    I15 @T6G_MB_LIB.T6G(SCH_1):PAGE58
   J65    GND @T6G_MB_LIB.T6G(SCH_1):GND    I15 @T6G_MB_LIB.T6G(SCH_1):PAGE58
   J68    GND @T6G_MB_LIB.T6G(SCH_1):GND    I15 @T6G_MB_LIB.T6G(SCH_1):PAGE58
   J70    GND @T6G_MB_LIB.T6G(SCH_1):GND    I15 @T6G_MB_LIB.T6G(SCH_1):PAGE58
   J72    GND @T6G_MB_LIB.T6G(SCH_1):GND    I15 @T6G_MB_LIB.T6G(SCH_1):PAGE58
   J75    GND @T6G_MB_LIB.T6G(SCH_1):GND    I15 @T6G_MB_LIB.T6G(SCH_1):PAGE58
    K3    GND @T6G_MB_LIB.T6G(SCH_1):GND    I15 @T6G_MB_LIB.T6G(SCH_1):PAGE58
    K5    GND @T6G_MB_LIB.T6G(SCH_1):GND    I15 @T6G_MB_LIB.T6G(SCH_1):PAGE58
    K8    GND @T6G_MB_LIB.T6G(SCH_1):GND    I15 @T6G_MB_LIB.T6G(SCH_1):PAGE58
   K10    GND @T6G_MB_LIB.T6G(SCH_1):GND    I15 @T6G_MB_LIB.T6G(SCH_1):PAGE58
   K12    GND @T6G_MB_LIB.T6G(SCH_1):GND    I15 @T6G_MB_LIB.T6G(SCH_1):PAGE58
   K15    GND @T6G_MB_LIB.T6G(SCH_1):GND    I15 @T6G_MB_LIB.T6G(SCH_1):PAGE58
   K17    GND @T6G_MB_LIB.T6G(SCH_1):GND    I15 @T6G_MB_LIB.T6G(SCH_1):PAGE58
   K19    GND @T6G_MB_LIB.T6G(SCH_1):GND    I15 @T6G_MB_LIB.T6G(SCH_1):PAGE58
   K24    GND @T6G_MB_LIB.T6G(SCH_1):GND    I15 @T6G_MB_LIB.T6G(SCH_1):PAGE58
   K25    GND @T6G_MB_LIB.T6G(SCH_1):GND    I15 @T6G_MB_LIB.T6G(SCH_1):PAGE58
   K26    GND @T6G_MB_LIB.T6G(SCH_1):GND    I15 @T6G_MB_LIB.T6G(SCH_1):PAGE58
   K27    GND @T6G_MB_LIB.T6G(SCH_1):GND    I15 @T6G_MB_LIB.T6G(SCH_1):PAGE58
   K28    GND @T6G_MB_LIB.T6G(SCH_1):GND    I15 @T6G_MB_LIB.T6G(SCH_1):PAGE58
   K29    GND @T6G_MB_LIB.T6G(SCH_1):GND    I15 @T6G_MB_LIB.T6G(SCH_1):PAGE58
   K30    GND @T6G_MB_LIB.T6G(SCH_1):GND    I15 @T6G_MB_LIB.T6G(SCH_1):PAGE58
   K31    GND @T6G_MB_LIB.T6G(SCH_1):GND    I15 @T6G_MB_LIB.T6G(SCH_1):PAGE58
   K32    GND @T6G_MB_LIB.T6G(SCH_1):GND    I15 @T6G_MB_LIB.T6G(SCH_1):PAGE58
   K33    GND @T6G_MB_LIB.T6G(SCH_1):GND    I15 @T6G_MB_LIB.T6G(SCH_1):PAGE58
   K34    GND @T6G_MB_LIB.T6G(SCH_1):GND    I15 @T6G_MB_LIB.T6G(SCH_1):PAGE58
   K37    GND @T6G_MB_LIB.T6G(SCH_1):GND    I15 @T6G_MB_LIB.T6G(SCH_1):PAGE58
   K39    GND @T6G_MB_LIB.T6G(SCH_1):GND    I15 @T6G_MB_LIB.T6G(SCH_1):PAGE58
   K42    GND @T6G_MB_LIB.T6G(SCH_1):GND    I15 @T6G_MB_LIB.T6G(SCH_1):PAGE58
   K43    GND @T6G_MB_LIB.T6G(SCH_1):GND    I15 @T6G_MB_LIB.T6G(SCH_1):PAGE58
   K44    GND @T6G_MB_LIB.T6G(SCH_1):GND    I15 @T6G_MB_LIB.T6G(SCH_1):PAGE58
   K45    GND @T6G_MB_LIB.T6G(SCH_1):GND    I15 @T6G_MB_LIB.T6G(SCH_1):PAGE58
   K46    GND @T6G_MB_LIB.T6G(SCH_1):GND    I15 @T6G_MB_LIB.T6G(SCH_1):PAGE58
   K47    GND @T6G_MB_LIB.T6G(SCH_1):GND    I15 @T6G_MB_LIB.T6G(SCH_1):PAGE58
   K48    GND @T6G_MB_LIB.T6G(SCH_1):GND    I15 @T6G_MB_LIB.T6G(SCH_1):PAGE58
   K49    GND @T6G_MB_LIB.T6G(SCH_1):GND    I15 @T6G_MB_LIB.T6G(SCH_1):PAGE58
   K50    GND @T6G_MB_LIB.T6G(SCH_1):GND    I15 @T6G_MB_LIB.T6G(SCH_1):PAGE58
   K51    GND @T6G_MB_LIB.T6G(SCH_1):GND    I15 @T6G_MB_LIB.T6G(SCH_1):PAGE58
   K52    GND @T6G_MB_LIB.T6G(SCH_1):GND    I15 @T6G_MB_LIB.T6G(SCH_1):PAGE58
   K53    GND @T6G_MB_LIB.T6G(SCH_1):GND    I15 @T6G_MB_LIB.T6G(SCH_1):PAGE58
   K57    GND @T6G_MB_LIB.T6G(SCH_1):GND    I15 @T6G_MB_LIB.T6G(SCH_1):PAGE58
   K61    GND @T6G_MB_LIB.T6G(SCH_1):GND    I15 @T6G_MB_LIB.T6G(SCH_1):PAGE58
   K64    GND @T6G_MB_LIB.T6G(SCH_1):GND    I15 @T6G_MB_LIB.T6G(SCH_1):PAGE58
   K66    GND @T6G_MB_LIB.T6G(SCH_1):GND    I15 @T6G_MB_LIB.T6G(SCH_1):PAGE58
   K68    GND @T6G_MB_LIB.T6G(SCH_1):GND    I15 @T6G_MB_LIB.T6G(SCH_1):PAGE58
   K71    GND @T6G_MB_LIB.T6G(SCH_1):GND    I15 @T6G_MB_LIB.T6G(SCH_1):PAGE58
   K73    GND @T6G_MB_LIB.T6G(SCH_1):GND    I15 @T6G_MB_LIB.T6G(SCH_1):PAGE58
    L1    GND @T6G_MB_LIB.T6G(SCH_1):GND    I15 @T6G_MB_LIB.T6G(SCH_1):PAGE58
    L6    GND @T6G_MB_LIB.T6G(SCH_1):GND    I15 @T6G_MB_LIB.T6G(SCH_1):PAGE58
    L8    GND @T6G_MB_LIB.T6G(SCH_1):GND    I15 @T6G_MB_LIB.T6G(SCH_1):PAGE58
   L13    GND @T6G_MB_LIB.T6G(SCH_1):GND    I15 @T6G_MB_LIB.T6G(SCH_1):PAGE58
   L15    GND @T6G_MB_LIB.T6G(SCH_1):GND    I15 @T6G_MB_LIB.T6G(SCH_1):PAGE58
   L20    GND @T6G_MB_LIB.T6G(SCH_1):GND    I15 @T6G_MB_LIB.T6G(SCH_1):PAGE58
   L22    GND @T6G_MB_LIB.T6G(SCH_1):GND    I15 @T6G_MB_LIB.T6G(SCH_1):PAGE58
   L25    GND @T6G_MB_LIB.T6G(SCH_1):GND    I15 @T6G_MB_LIB.T6G(SCH_1):PAGE58
   L28    GND @T6G_MB_LIB.T6G(SCH_1):GND    I15 @T6G_MB_LIB.T6G(SCH_1):PAGE58
   L31    GND @T6G_MB_LIB.T6G(SCH_1):GND    I15 @T6G_MB_LIB.T6G(SCH_1):PAGE58
   L34    GND @T6G_MB_LIB.T6G(SCH_1):GND    I15 @T6G_MB_LIB.T6G(SCH_1):PAGE58
   L35    GND @T6G_MB_LIB.T6G(SCH_1):GND    I15 @T6G_MB_LIB.T6G(SCH_1):PAGE58
   L36    GND @T6G_MB_LIB.T6G(SCH_1):GND    I15 @T6G_MB_LIB.T6G(SCH_1):PAGE58
   L40    GND @T6G_MB_LIB.T6G(SCH_1):GND    I15 @T6G_MB_LIB.T6G(SCH_1):PAGE58
   L41    GND @T6G_MB_LIB.T6G(SCH_1):GND    I15 @T6G_MB_LIB.T6G(SCH_1):PAGE58
   L42    GND @T6G_MB_LIB.T6G(SCH_1):GND    I15 @T6G_MB_LIB.T6G(SCH_1):PAGE58
   L45    GND @T6G_MB_LIB.T6G(SCH_1):GND    I15 @T6G_MB_LIB.T6G(SCH_1):PAGE58
   L48    GND @T6G_MB_LIB.T6G(SCH_1):GND    I15 @T6G_MB_LIB.T6G(SCH_1):PAGE58
   L51    GND @T6G_MB_LIB.T6G(SCH_1):GND    I15 @T6G_MB_LIB.T6G(SCH_1):PAGE58
   L54    GND @T6G_MB_LIB.T6G(SCH_1):GND    I15 @T6G_MB_LIB.T6G(SCH_1):PAGE58
   L56    GND @T6G_MB_LIB.T6G(SCH_1):GND    I15 @T6G_MB_LIB.T6G(SCH_1):PAGE58
   L61    GND @T6G_MB_LIB.T6G(SCH_1):GND    I15 @T6G_MB_LIB.T6G(SCH_1):PAGE58
   L63    GND @T6G_MB_LIB.T6G(SCH_1):GND    I15 @T6G_MB_LIB.T6G(SCH_1):PAGE58
   L68    GND @T6G_MB_LIB.T6G(SCH_1):GND    I15 @T6G_MB_LIB.T6G(SCH_1):PAGE58
   L70    GND @T6G_MB_LIB.T6G(SCH_1):GND    I15 @T6G_MB_LIB.T6G(SCH_1):PAGE58
   L75    GND @T6G_MB_LIB.T6G(SCH_1):GND    I15 @T6G_MB_LIB.T6G(SCH_1):PAGE58
    M3    GND @T6G_MB_LIB.T6G(SCH_1):GND    I15 @T6G_MB_LIB.T6G(SCH_1):PAGE58
    M5    GND @T6G_MB_LIB.T6G(SCH_1):GND    I15 @T6G_MB_LIB.T6G(SCH_1):PAGE58
    M8    GND @T6G_MB_LIB.T6G(SCH_1):GND    I15 @T6G_MB_LIB.T6G(SCH_1):PAGE58
   M10    GND @T6G_MB_LIB.T6G(SCH_1):GND    I15 @T6G_MB_LIB.T6G(SCH_1):PAGE58
   M12    GND @T6G_MB_LIB.T6G(SCH_1):GND    I15 @T6G_MB_LIB.T6G(SCH_1):PAGE58
   M15    GND @T6G_MB_LIB.T6G(SCH_1):GND    I15 @T6G_MB_LIB.T6G(SCH_1):PAGE58
   M17    GND @T6G_MB_LIB.T6G(SCH_1):GND    I15 @T6G_MB_LIB.T6G(SCH_1):PAGE58
   M19    GND @T6G_MB_LIB.T6G(SCH_1):GND    I15 @T6G_MB_LIB.T6G(SCH_1):PAGE58
   M22    GND @T6G_MB_LIB.T6G(SCH_1):GND    I15 @T6G_MB_LIB.T6G(SCH_1):PAGE58
   M25    GND @T6G_MB_LIB.T6G(SCH_1):GND    I15 @T6G_MB_LIB.T6G(SCH_1):PAGE58
   M28    GND @T6G_MB_LIB.T6G(SCH_1):GND    I15 @T6G_MB_LIB.T6G(SCH_1):PAGE58
   M31    GND @T6G_MB_LIB.T6G(SCH_1):GND    I15 @T6G_MB_LIB.T6G(SCH_1):PAGE58
   M34    GND @T6G_MB_LIB.T6G(SCH_1):GND    I15 @T6G_MB_LIB.T6G(SCH_1):PAGE58
   M37    GND @T6G_MB_LIB.T6G(SCH_1):GND    I15 @T6G_MB_LIB.T6G(SCH_1):PAGE58
   M39    GND @T6G_MB_LIB.T6G(SCH_1):GND    I15 @T6G_MB_LIB.T6G(SCH_1):PAGE58
   M42    GND @T6G_MB_LIB.T6G(SCH_1):GND    I15 @T6G_MB_LIB.T6G(SCH_1):PAGE58
   M45    GND @T6G_MB_LIB.T6G(SCH_1):GND    I15 @T6G_MB_LIB.T6G(SCH_1):PAGE58
   M48    GND @T6G_MB_LIB.T6G(SCH_1):GND    I15 @T6G_MB_LIB.T6G(SCH_1):PAGE58
   M51    GND @T6G_MB_LIB.T6G(SCH_1):GND    I15 @T6G_MB_LIB.T6G(SCH_1):PAGE58
   M54    GND @T6G_MB_LIB.T6G(SCH_1):GND    I15 @T6G_MB_LIB.T6G(SCH_1):PAGE58
   M57    GND @T6G_MB_LIB.T6G(SCH_1):GND    I15 @T6G_MB_LIB.T6G(SCH_1):PAGE58
   M59    GND @T6G_MB_LIB.T6G(SCH_1):GND    I15 @T6G_MB_LIB.T6G(SCH_1):PAGE58
   M61    GND @T6G_MB_LIB.T6G(SCH_1):GND    I15 @T6G_MB_LIB.T6G(SCH_1):PAGE58
   M64    GND @T6G_MB_LIB.T6G(SCH_1):GND    I15 @T6G_MB_LIB.T6G(SCH_1):PAGE58
   M66    GND @T6G_MB_LIB.T6G(SCH_1):GND    I15 @T6G_MB_LIB.T6G(SCH_1):PAGE58
   M68    GND @T6G_MB_LIB.T6G(SCH_1):GND    I15 @T6G_MB_LIB.T6G(SCH_1):PAGE58
   M71    GND @T6G_MB_LIB.T6G(SCH_1):GND    I15 @T6G_MB_LIB.T6G(SCH_1):PAGE58
   M73    GND @T6G_MB_LIB.T6G(SCH_1):GND    I15 @T6G_MB_LIB.T6G(SCH_1):PAGE58
    N1    GND @T6G_MB_LIB.T6G(SCH_1):GND    I15 @T6G_MB_LIB.T6G(SCH_1):PAGE58
    N4    GND @T6G_MB_LIB.T6G(SCH_1):GND    I15 @T6G_MB_LIB.T6G(SCH_1):PAGE58
    N6    GND @T6G_MB_LIB.T6G(SCH_1):GND    I15 @T6G_MB_LIB.T6G(SCH_1):PAGE58
    N8    GND @T6G_MB_LIB.T6G(SCH_1):GND    I15 @T6G_MB_LIB.T6G(SCH_1):PAGE58
   N11    GND @T6G_MB_LIB.T6G(SCH_1):GND    I15 @T6G_MB_LIB.T6G(SCH_1):PAGE58
   N13    GND @T6G_MB_LIB.T6G(SCH_1):GND    I15 @T6G_MB_LIB.T6G(SCH_1):PAGE58
   N15    GND @T6G_MB_LIB.T6G(SCH_1):GND    I15 @T6G_MB_LIB.T6G(SCH_1):PAGE58
   N18    GND @T6G_MB_LIB.T6G(SCH_1):GND    I15 @T6G_MB_LIB.T6G(SCH_1):PAGE58
   N20    GND @T6G_MB_LIB.T6G(SCH_1):GND    I15 @T6G_MB_LIB.T6G(SCH_1):PAGE58
   N22    GND @T6G_MB_LIB.T6G(SCH_1):GND    I15 @T6G_MB_LIB.T6G(SCH_1):PAGE58
   N25    GND @T6G_MB_LIB.T6G(SCH_1):GND    I15 @T6G_MB_LIB.T6G(SCH_1):PAGE58
   N28    GND @T6G_MB_LIB.T6G(SCH_1):GND    I15 @T6G_MB_LIB.T6G(SCH_1):PAGE58
   N31    GND @T6G_MB_LIB.T6G(SCH_1):GND    I15 @T6G_MB_LIB.T6G(SCH_1):PAGE58
   N34    GND @T6G_MB_LIB.T6G(SCH_1):GND    I15 @T6G_MB_LIB.T6G(SCH_1):PAGE58
   N42    GND @T6G_MB_LIB.T6G(SCH_1):GND    I15 @T6G_MB_LIB.T6G(SCH_1):PAGE58
   N45    GND @T6G_MB_LIB.T6G(SCH_1):GND    I15 @T6G_MB_LIB.T6G(SCH_1):PAGE58
   N48    GND @T6G_MB_LIB.T6G(SCH_1):GND    I15 @T6G_MB_LIB.T6G(SCH_1):PAGE58
   N51    GND @T6G_MB_LIB.T6G(SCH_1):GND    I15 @T6G_MB_LIB.T6G(SCH_1):PAGE58
   N54    GND @T6G_MB_LIB.T6G(SCH_1):GND    I15 @T6G_MB_LIB.T6G(SCH_1):PAGE58
   N56    GND @T6G_MB_LIB.T6G(SCH_1):GND    I15 @T6G_MB_LIB.T6G(SCH_1):PAGE58
   N58    GND @T6G_MB_LIB.T6G(SCH_1):GND    I15 @T6G_MB_LIB.T6G(SCH_1):PAGE58
   N61    GND @T6G_MB_LIB.T6G(SCH_1):GND    I15 @T6G_MB_LIB.T6G(SCH_1):PAGE58
   N63    GND @T6G_MB_LIB.T6G(SCH_1):GND    I15 @T6G_MB_LIB.T6G(SCH_1):PAGE58
   N65    GND @T6G_MB_LIB.T6G(SCH_1):GND    I15 @T6G_MB_LIB.T6G(SCH_1):PAGE58
   N68    GND @T6G_MB_LIB.T6G(SCH_1):GND    I15 @T6G_MB_LIB.T6G(SCH_1):PAGE58
   N70    GND @T6G_MB_LIB.T6G(SCH_1):GND    I15 @T6G_MB_LIB.T6G(SCH_1):PAGE58
   N72    GND @T6G_MB_LIB.T6G(SCH_1):GND    I15 @T6G_MB_LIB.T6G(SCH_1):PAGE58
   N75    GND @T6G_MB_LIB.T6G(SCH_1):GND    I15 @T6G_MB_LIB.T6G(SCH_1):PAGE58
    P3    GND @T6G_MB_LIB.T6G(SCH_1):GND    I15 @T6G_MB_LIB.T6G(SCH_1):PAGE58
    P8    GND @T6G_MB_LIB.T6G(SCH_1):GND    I15 @T6G_MB_LIB.T6G(SCH_1):PAGE58
   P10    GND @T6G_MB_LIB.T6G(SCH_1):GND    I15 @T6G_MB_LIB.T6G(SCH_1):PAGE58
   P15    GND @T6G_MB_LIB.T6G(SCH_1):GND    I15 @T6G_MB_LIB.T6G(SCH_1):PAGE58
   P17    GND @T6G_MB_LIB.T6G(SCH_1):GND    I15 @T6G_MB_LIB.T6G(SCH_1):PAGE58
   P23    GND @T6G_MB_LIB.T6G(SCH_1):GND    I15 @T6G_MB_LIB.T6G(SCH_1):PAGE58
   P24    GND @T6G_MB_LIB.T6G(SCH_1):GND    I15 @T6G_MB_LIB.T6G(SCH_1):PAGE58
   P26    GND @T6G_MB_LIB.T6G(SCH_1):GND    I15 @T6G_MB_LIB.T6G(SCH_1):PAGE58
   P27    GND @T6G_MB_LIB.T6G(SCH_1):GND    I15 @T6G_MB_LIB.T6G(SCH_1):PAGE58
   P28    GND @T6G_MB_LIB.T6G(SCH_1):GND    I15 @T6G_MB_LIB.T6G(SCH_1):PAGE58
   P29    GND @T6G_MB_LIB.T6G(SCH_1):GND    I15 @T6G_MB_LIB.T6G(SCH_1):PAGE58
   P30    GND @T6G_MB_LIB.T6G(SCH_1):GND    I15 @T6G_MB_LIB.T6G(SCH_1):PAGE58
   P31    GND @T6G_MB_LIB.T6G(SCH_1):GND    I15 @T6G_MB_LIB.T6G(SCH_1):PAGE58
   P32    GND @T6G_MB_LIB.T6G(SCH_1):GND    I15 @T6G_MB_LIB.T6G(SCH_1):PAGE58
   P33    GND @T6G_MB_LIB.T6G(SCH_1):GND    I15 @T6G_MB_LIB.T6G(SCH_1):PAGE58
   P34    GND @T6G_MB_LIB.T6G(SCH_1):GND    I15 @T6G_MB_LIB.T6G(SCH_1):PAGE58
   P37    GND @T6G_MB_LIB.T6G(SCH_1):GND    I15 @T6G_MB_LIB.T6G(SCH_1):PAGE58
   P39    GND @T6G_MB_LIB.T6G(SCH_1):GND    I15 @T6G_MB_LIB.T6G(SCH_1):PAGE58
   P42    GND @T6G_MB_LIB.T6G(SCH_1):GND    I15 @T6G_MB_LIB.T6G(SCH_1):PAGE58
   P43    GND @T6G_MB_LIB.T6G(SCH_1):GND    I15 @T6G_MB_LIB.T6G(SCH_1):PAGE58
   P44    GND @T6G_MB_LIB.T6G(SCH_1):GND    I15 @T6G_MB_LIB.T6G(SCH_1):PAGE58
   P45    GND @T6G_MB_LIB.T6G(SCH_1):GND    I15 @T6G_MB_LIB.T6G(SCH_1):PAGE58
   P46    GND @T6G_MB_LIB.T6G(SCH_1):GND    I15 @T6G_MB_LIB.T6G(SCH_1):PAGE58
   P47    GND @T6G_MB_LIB.T6G(SCH_1):GND    I15 @T6G_MB_LIB.T6G(SCH_1):PAGE58
   P48    GND @T6G_MB_LIB.T6G(SCH_1):GND    I15 @T6G_MB_LIB.T6G(SCH_1):PAGE58
   P49    GND @T6G_MB_LIB.T6G(SCH_1):GND    I15 @T6G_MB_LIB.T6G(SCH_1):PAGE58
   P50    GND @T6G_MB_LIB.T6G(SCH_1):GND    I15 @T6G_MB_LIB.T6G(SCH_1):PAGE58
   P51    GND @T6G_MB_LIB.T6G(SCH_1):GND    I15 @T6G_MB_LIB.T6G(SCH_1):PAGE58
   P52    GND @T6G_MB_LIB.T6G(SCH_1):GND    I15 @T6G_MB_LIB.T6G(SCH_1):PAGE58
   P53    GND @T6G_MB_LIB.T6G(SCH_1):GND    I15 @T6G_MB_LIB.T6G(SCH_1):PAGE58
   P59    GND @T6G_MB_LIB.T6G(SCH_1):GND    I15 @T6G_MB_LIB.T6G(SCH_1):PAGE58
   P61    GND @T6G_MB_LIB.T6G(SCH_1):GND    I15 @T6G_MB_LIB.T6G(SCH_1):PAGE58
   P66    GND @T6G_MB_LIB.T6G(SCH_1):GND    I15 @T6G_MB_LIB.T6G(SCH_1):PAGE58
   P73    GND @T6G_MB_LIB.T6G(SCH_1):GND    I15 @T6G_MB_LIB.T6G(SCH_1):PAGE58
    R1    GND @T6G_MB_LIB.T6G(SCH_1):GND    I15 @T6G_MB_LIB.T6G(SCH_1):PAGE58
    R4    GND @T6G_MB_LIB.T6G(SCH_1):GND    I15 @T6G_MB_LIB.T6G(SCH_1):PAGE58
    R6    GND @T6G_MB_LIB.T6G(SCH_1):GND    I15 @T6G_MB_LIB.T6G(SCH_1):PAGE58
    R8    GND @T6G_MB_LIB.T6G(SCH_1):GND    I15 @T6G_MB_LIB.T6G(SCH_1):PAGE58
   R11    GND @T6G_MB_LIB.T6G(SCH_1):GND    I15 @T6G_MB_LIB.T6G(SCH_1):PAGE58
   R13    GND @T6G_MB_LIB.T6G(SCH_1):GND    I15 @T6G_MB_LIB.T6G(SCH_1):PAGE58
   R15    GND @T6G_MB_LIB.T6G(SCH_1):GND    I15 @T6G_MB_LIB.T6G(SCH_1):PAGE58
   R18    GND @T6G_MB_LIB.T6G(SCH_1):GND    I15 @T6G_MB_LIB.T6G(SCH_1):PAGE58
   R20    GND @T6G_MB_LIB.T6G(SCH_1):GND    I15 @T6G_MB_LIB.T6G(SCH_1):PAGE58
   R22    GND @T6G_MB_LIB.T6G(SCH_1):GND    I15 @T6G_MB_LIB.T6G(SCH_1):PAGE58
   R25    GND @T6G_MB_LIB.T6G(SCH_1):GND    I15 @T6G_MB_LIB.T6G(SCH_1):PAGE58
   R28    GND @T6G_MB_LIB.T6G(SCH_1):GND    I15 @T6G_MB_LIB.T6G(SCH_1):PAGE58
   R31    GND @T6G_MB_LIB.T6G(SCH_1):GND    I15 @T6G_MB_LIB.T6G(SCH_1):PAGE58
   R34    GND @T6G_MB_LIB.T6G(SCH_1):GND    I15 @T6G_MB_LIB.T6G(SCH_1):PAGE58
   R35    GND @T6G_MB_LIB.T6G(SCH_1):GND    I15 @T6G_MB_LIB.T6G(SCH_1):PAGE58
   R36    GND @T6G_MB_LIB.T6G(SCH_1):GND    I15 @T6G_MB_LIB.T6G(SCH_1):PAGE58
   R40    GND @T6G_MB_LIB.T6G(SCH_1):GND    I15 @T6G_MB_LIB.T6G(SCH_1):PAGE58
   R41    GND @T6G_MB_LIB.T6G(SCH_1):GND    I15 @T6G_MB_LIB.T6G(SCH_1):PAGE58
   R42    GND @T6G_MB_LIB.T6G(SCH_1):GND    I15 @T6G_MB_LIB.T6G(SCH_1):PAGE58
   R45    GND @T6G_MB_LIB.T6G(SCH_1):GND    I15 @T6G_MB_LIB.T6G(SCH_1):PAGE58
  AB68    GND @T6G_MB_LIB.T6G(SCH_1):GND    I12 @T6G_MB_LIB.T6G(SCH_1):PAGE58
  AB71    GND @T6G_MB_LIB.T6G(SCH_1):GND    I12 @T6G_MB_LIB.T6G(SCH_1):PAGE58
  AB73    GND @T6G_MB_LIB.T6G(SCH_1):GND    I12 @T6G_MB_LIB.T6G(SCH_1):PAGE58
   AC1    GND @T6G_MB_LIB.T6G(SCH_1):GND    I12 @T6G_MB_LIB.T6G(SCH_1):PAGE58
   AC6    GND @T6G_MB_LIB.T6G(SCH_1):GND    I12 @T6G_MB_LIB.T6G(SCH_1):PAGE58
   AC8    GND @T6G_MB_LIB.T6G(SCH_1):GND    I12 @T6G_MB_LIB.T6G(SCH_1):PAGE58
  AC13    GND @T6G_MB_LIB.T6G(SCH_1):GND    I12 @T6G_MB_LIB.T6G(SCH_1):PAGE58
  AC15    GND @T6G_MB_LIB.T6G(SCH_1):GND    I12 @T6G_MB_LIB.T6G(SCH_1):PAGE58
  AC20    GND @T6G_MB_LIB.T6G(SCH_1):GND    I12 @T6G_MB_LIB.T6G(SCH_1):PAGE58
  AC22    GND @T6G_MB_LIB.T6G(SCH_1):GND    I12 @T6G_MB_LIB.T6G(SCH_1):PAGE58
  AC25    GND @T6G_MB_LIB.T6G(SCH_1):GND    I12 @T6G_MB_LIB.T6G(SCH_1):PAGE58
  AC28    GND @T6G_MB_LIB.T6G(SCH_1):GND    I12 @T6G_MB_LIB.T6G(SCH_1):PAGE58
  AC31    GND @T6G_MB_LIB.T6G(SCH_1):GND    I12 @T6G_MB_LIB.T6G(SCH_1):PAGE58
  AC34    GND @T6G_MB_LIB.T6G(SCH_1):GND    I12 @T6G_MB_LIB.T6G(SCH_1):PAGE58
  AC42    GND @T6G_MB_LIB.T6G(SCH_1):GND    I12 @T6G_MB_LIB.T6G(SCH_1):PAGE58
  AC45    GND @T6G_MB_LIB.T6G(SCH_1):GND    I12 @T6G_MB_LIB.T6G(SCH_1):PAGE58
  AC48    GND @T6G_MB_LIB.T6G(SCH_1):GND    I12 @T6G_MB_LIB.T6G(SCH_1):PAGE58
  AC51    GND @T6G_MB_LIB.T6G(SCH_1):GND    I12 @T6G_MB_LIB.T6G(SCH_1):PAGE58
  AC54    GND @T6G_MB_LIB.T6G(SCH_1):GND    I12 @T6G_MB_LIB.T6G(SCH_1):PAGE58
  AC56    GND @T6G_MB_LIB.T6G(SCH_1):GND    I12 @T6G_MB_LIB.T6G(SCH_1):PAGE58
  AC61    GND @T6G_MB_LIB.T6G(SCH_1):GND    I12 @T6G_MB_LIB.T6G(SCH_1):PAGE58
  AC63    GND @T6G_MB_LIB.T6G(SCH_1):GND    I12 @T6G_MB_LIB.T6G(SCH_1):PAGE58
  AC68    GND @T6G_MB_LIB.T6G(SCH_1):GND    I12 @T6G_MB_LIB.T6G(SCH_1):PAGE58
  AC70    GND @T6G_MB_LIB.T6G(SCH_1):GND    I12 @T6G_MB_LIB.T6G(SCH_1):PAGE58
  AC75    GND @T6G_MB_LIB.T6G(SCH_1):GND    I12 @T6G_MB_LIB.T6G(SCH_1):PAGE58
   AD3    GND @T6G_MB_LIB.T6G(SCH_1):GND    I12 @T6G_MB_LIB.T6G(SCH_1):PAGE58
   AD5    GND @T6G_MB_LIB.T6G(SCH_1):GND    I12 @T6G_MB_LIB.T6G(SCH_1):PAGE58
   AD8    GND @T6G_MB_LIB.T6G(SCH_1):GND    I12 @T6G_MB_LIB.T6G(SCH_1):PAGE58
  AD10    GND @T6G_MB_LIB.T6G(SCH_1):GND    I12 @T6G_MB_LIB.T6G(SCH_1):PAGE58
  AD12    GND @T6G_MB_LIB.T6G(SCH_1):GND    I12 @T6G_MB_LIB.T6G(SCH_1):PAGE58
  AD15    GND @T6G_MB_LIB.T6G(SCH_1):GND    I12 @T6G_MB_LIB.T6G(SCH_1):PAGE58
  AD17    GND @T6G_MB_LIB.T6G(SCH_1):GND    I12 @T6G_MB_LIB.T6G(SCH_1):PAGE58
  AD19    GND @T6G_MB_LIB.T6G(SCH_1):GND    I12 @T6G_MB_LIB.T6G(SCH_1):PAGE58
  AD23    GND @T6G_MB_LIB.T6G(SCH_1):GND    I12 @T6G_MB_LIB.T6G(SCH_1):PAGE58
  AD24    GND @T6G_MB_LIB.T6G(SCH_1):GND    I12 @T6G_MB_LIB.T6G(SCH_1):PAGE58
  AD25    GND @T6G_MB_LIB.T6G(SCH_1):GND    I12 @T6G_MB_LIB.T6G(SCH_1):PAGE58
  AD26    GND @T6G_MB_LIB.T6G(SCH_1):GND    I12 @T6G_MB_LIB.T6G(SCH_1):PAGE58
  AD27    GND @T6G_MB_LIB.T6G(SCH_1):GND    I12 @T6G_MB_LIB.T6G(SCH_1):PAGE58
  AD28    GND @T6G_MB_LIB.T6G(SCH_1):GND    I12 @T6G_MB_LIB.T6G(SCH_1):PAGE58
  AD29    GND @T6G_MB_LIB.T6G(SCH_1):GND    I12 @T6G_MB_LIB.T6G(SCH_1):PAGE58
  AD30    GND @T6G_MB_LIB.T6G(SCH_1):GND    I12 @T6G_MB_LIB.T6G(SCH_1):PAGE58
  AD32    GND @T6G_MB_LIB.T6G(SCH_1):GND    I12 @T6G_MB_LIB.T6G(SCH_1):PAGE58
  AD33    GND @T6G_MB_LIB.T6G(SCH_1):GND    I12 @T6G_MB_LIB.T6G(SCH_1):PAGE58
  AD34    GND @T6G_MB_LIB.T6G(SCH_1):GND    I12 @T6G_MB_LIB.T6G(SCH_1):PAGE58
  AD37    GND @T6G_MB_LIB.T6G(SCH_1):GND    I12 @T6G_MB_LIB.T6G(SCH_1):PAGE58
  AD39    GND @T6G_MB_LIB.T6G(SCH_1):GND    I12 @T6G_MB_LIB.T6G(SCH_1):PAGE58
  AD42    GND @T6G_MB_LIB.T6G(SCH_1):GND    I12 @T6G_MB_LIB.T6G(SCH_1):PAGE58
  AD43    GND @T6G_MB_LIB.T6G(SCH_1):GND    I12 @T6G_MB_LIB.T6G(SCH_1):PAGE58
  AD44    GND @T6G_MB_LIB.T6G(SCH_1):GND    I12 @T6G_MB_LIB.T6G(SCH_1):PAGE58
  AD45    GND @T6G_MB_LIB.T6G(SCH_1):GND    I12 @T6G_MB_LIB.T6G(SCH_1):PAGE58
  AD46    GND @T6G_MB_LIB.T6G(SCH_1):GND    I12 @T6G_MB_LIB.T6G(SCH_1):PAGE58
  AD47    GND @T6G_MB_LIB.T6G(SCH_1):GND    I12 @T6G_MB_LIB.T6G(SCH_1):PAGE58
  AD48    GND @T6G_MB_LIB.T6G(SCH_1):GND    I12 @T6G_MB_LIB.T6G(SCH_1):PAGE58
   T66    GND @T6G_MB_LIB.T6G(SCH_1):GND    I12 @T6G_MB_LIB.T6G(SCH_1):PAGE58
   T68    GND @T6G_MB_LIB.T6G(SCH_1):GND    I12 @T6G_MB_LIB.T6G(SCH_1):PAGE58
   T71    GND @T6G_MB_LIB.T6G(SCH_1):GND    I12 @T6G_MB_LIB.T6G(SCH_1):PAGE58
   T73    GND @T6G_MB_LIB.T6G(SCH_1):GND    I12 @T6G_MB_LIB.T6G(SCH_1):PAGE58
    U1    GND @T6G_MB_LIB.T6G(SCH_1):GND    I12 @T6G_MB_LIB.T6G(SCH_1):PAGE58
    U6    GND @T6G_MB_LIB.T6G(SCH_1):GND    I12 @T6G_MB_LIB.T6G(SCH_1):PAGE58
    U8    GND @T6G_MB_LIB.T6G(SCH_1):GND    I12 @T6G_MB_LIB.T6G(SCH_1):PAGE58
   U13    GND @T6G_MB_LIB.T6G(SCH_1):GND    I12 @T6G_MB_LIB.T6G(SCH_1):PAGE58
   U15    GND @T6G_MB_LIB.T6G(SCH_1):GND    I12 @T6G_MB_LIB.T6G(SCH_1):PAGE58
   U20    GND @T6G_MB_LIB.T6G(SCH_1):GND    I12 @T6G_MB_LIB.T6G(SCH_1):PAGE58
   U22    GND @T6G_MB_LIB.T6G(SCH_1):GND    I12 @T6G_MB_LIB.T6G(SCH_1):PAGE58
   U25    GND @T6G_MB_LIB.T6G(SCH_1):GND    I12 @T6G_MB_LIB.T6G(SCH_1):PAGE58
   U28    GND @T6G_MB_LIB.T6G(SCH_1):GND    I12 @T6G_MB_LIB.T6G(SCH_1):PAGE58
   U31    GND @T6G_MB_LIB.T6G(SCH_1):GND    I12 @T6G_MB_LIB.T6G(SCH_1):PAGE58
   U34    GND @T6G_MB_LIB.T6G(SCH_1):GND    I12 @T6G_MB_LIB.T6G(SCH_1):PAGE58
   U42    GND @T6G_MB_LIB.T6G(SCH_1):GND    I12 @T6G_MB_LIB.T6G(SCH_1):PAGE58
   U45    GND @T6G_MB_LIB.T6G(SCH_1):GND    I12 @T6G_MB_LIB.T6G(SCH_1):PAGE58
   U48    GND @T6G_MB_LIB.T6G(SCH_1):GND    I12 @T6G_MB_LIB.T6G(SCH_1):PAGE58
   U51    GND @T6G_MB_LIB.T6G(SCH_1):GND    I12 @T6G_MB_LIB.T6G(SCH_1):PAGE58
   U54    GND @T6G_MB_LIB.T6G(SCH_1):GND    I12 @T6G_MB_LIB.T6G(SCH_1):PAGE58
   U56    GND @T6G_MB_LIB.T6G(SCH_1):GND    I12 @T6G_MB_LIB.T6G(SCH_1):PAGE58
   U61    GND @T6G_MB_LIB.T6G(SCH_1):GND    I12 @T6G_MB_LIB.T6G(SCH_1):PAGE58
   U63    GND @T6G_MB_LIB.T6G(SCH_1):GND    I12 @T6G_MB_LIB.T6G(SCH_1):PAGE58
   U68    GND @T6G_MB_LIB.T6G(SCH_1):GND    I12 @T6G_MB_LIB.T6G(SCH_1):PAGE58
   U70    GND @T6G_MB_LIB.T6G(SCH_1):GND    I12 @T6G_MB_LIB.T6G(SCH_1):PAGE58
   U75    GND @T6G_MB_LIB.T6G(SCH_1):GND    I12 @T6G_MB_LIB.T6G(SCH_1):PAGE58
    V3    GND @T6G_MB_LIB.T6G(SCH_1):GND    I12 @T6G_MB_LIB.T6G(SCH_1):PAGE58
    V5    GND @T6G_MB_LIB.T6G(SCH_1):GND    I12 @T6G_MB_LIB.T6G(SCH_1):PAGE58
    V8    GND @T6G_MB_LIB.T6G(SCH_1):GND    I12 @T6G_MB_LIB.T6G(SCH_1):PAGE58
   V10    GND @T6G_MB_LIB.T6G(SCH_1):GND    I12 @T6G_MB_LIB.T6G(SCH_1):PAGE58
   V12    GND @T6G_MB_LIB.T6G(SCH_1):GND    I12 @T6G_MB_LIB.T6G(SCH_1):PAGE58
   V15    GND @T6G_MB_LIB.T6G(SCH_1):GND    I12 @T6G_MB_LIB.T6G(SCH_1):PAGE58
   V17    GND @T6G_MB_LIB.T6G(SCH_1):GND    I12 @T6G_MB_LIB.T6G(SCH_1):PAGE58
   V19    GND @T6G_MB_LIB.T6G(SCH_1):GND    I12 @T6G_MB_LIB.T6G(SCH_1):PAGE58
   V23    GND @T6G_MB_LIB.T6G(SCH_1):GND    I12 @T6G_MB_LIB.T6G(SCH_1):PAGE58
   V24    GND @T6G_MB_LIB.T6G(SCH_1):GND    I12 @T6G_MB_LIB.T6G(SCH_1):PAGE58
   V25    GND @T6G_MB_LIB.T6G(SCH_1):GND    I12 @T6G_MB_LIB.T6G(SCH_1):PAGE58
   V26    GND @T6G_MB_LIB.T6G(SCH_1):GND    I12 @T6G_MB_LIB.T6G(SCH_1):PAGE58
   V28    GND @T6G_MB_LIB.T6G(SCH_1):GND    I12 @T6G_MB_LIB.T6G(SCH_1):PAGE58
   V29    GND @T6G_MB_LIB.T6G(SCH_1):GND    I12 @T6G_MB_LIB.T6G(SCH_1):PAGE58
   V30    GND @T6G_MB_LIB.T6G(SCH_1):GND    I12 @T6G_MB_LIB.T6G(SCH_1):PAGE58
   V31    GND @T6G_MB_LIB.T6G(SCH_1):GND    I12 @T6G_MB_LIB.T6G(SCH_1):PAGE58
   V32    GND @T6G_MB_LIB.T6G(SCH_1):GND    I12 @T6G_MB_LIB.T6G(SCH_1):PAGE58
   V33    GND @T6G_MB_LIB.T6G(SCH_1):GND    I12 @T6G_MB_LIB.T6G(SCH_1):PAGE58
   V34    GND @T6G_MB_LIB.T6G(SCH_1):GND    I12 @T6G_MB_LIB.T6G(SCH_1):PAGE58
   V37    GND @T6G_MB_LIB.T6G(SCH_1):GND    I12 @T6G_MB_LIB.T6G(SCH_1):PAGE58
   V39    GND @T6G_MB_LIB.T6G(SCH_1):GND    I12 @T6G_MB_LIB.T6G(SCH_1):PAGE58
   V42    GND @T6G_MB_LIB.T6G(SCH_1):GND    I12 @T6G_MB_LIB.T6G(SCH_1):PAGE58
   V43    GND @T6G_MB_LIB.T6G(SCH_1):GND    I12 @T6G_MB_LIB.T6G(SCH_1):PAGE58
   V44    GND @T6G_MB_LIB.T6G(SCH_1):GND    I12 @T6G_MB_LIB.T6G(SCH_1):PAGE58
   V45    GND @T6G_MB_LIB.T6G(SCH_1):GND    I12 @T6G_MB_LIB.T6G(SCH_1):PAGE58
   V46    GND @T6G_MB_LIB.T6G(SCH_1):GND    I12 @T6G_MB_LIB.T6G(SCH_1):PAGE58
   V47    GND @T6G_MB_LIB.T6G(SCH_1):GND    I12 @T6G_MB_LIB.T6G(SCH_1):PAGE58
   V48    GND @T6G_MB_LIB.T6G(SCH_1):GND    I12 @T6G_MB_LIB.T6G(SCH_1):PAGE58
   V49    GND @T6G_MB_LIB.T6G(SCH_1):GND    I12 @T6G_MB_LIB.T6G(SCH_1):PAGE58
   V50    GND @T6G_MB_LIB.T6G(SCH_1):GND    I12 @T6G_MB_LIB.T6G(SCH_1):PAGE58
   V51    GND @T6G_MB_LIB.T6G(SCH_1):GND    I12 @T6G_MB_LIB.T6G(SCH_1):PAGE58
   V52    GND @T6G_MB_LIB.T6G(SCH_1):GND    I12 @T6G_MB_LIB.T6G(SCH_1):PAGE58
   V53    GND @T6G_MB_LIB.T6G(SCH_1):GND    I12 @T6G_MB_LIB.T6G(SCH_1):PAGE58
   V57    GND @T6G_MB_LIB.T6G(SCH_1):GND    I12 @T6G_MB_LIB.T6G(SCH_1):PAGE58
   V59    GND @T6G_MB_LIB.T6G(SCH_1):GND    I12 @T6G_MB_LIB.T6G(SCH_1):PAGE58
   V61    GND @T6G_MB_LIB.T6G(SCH_1):GND    I12 @T6G_MB_LIB.T6G(SCH_1):PAGE58
   V64    GND @T6G_MB_LIB.T6G(SCH_1):GND    I12 @T6G_MB_LIB.T6G(SCH_1):PAGE58
   V66    GND @T6G_MB_LIB.T6G(SCH_1):GND    I12 @T6G_MB_LIB.T6G(SCH_1):PAGE58
   V71    GND @T6G_MB_LIB.T6G(SCH_1):GND    I12 @T6G_MB_LIB.T6G(SCH_1):PAGE58
   V73    GND @T6G_MB_LIB.T6G(SCH_1):GND    I12 @T6G_MB_LIB.T6G(SCH_1):PAGE58
    W1    GND @T6G_MB_LIB.T6G(SCH_1):GND    I12 @T6G_MB_LIB.T6G(SCH_1):PAGE58
    W4    GND @T6G_MB_LIB.T6G(SCH_1):GND    I12 @T6G_MB_LIB.T6G(SCH_1):PAGE58
    W6    GND @T6G_MB_LIB.T6G(SCH_1):GND    I12 @T6G_MB_LIB.T6G(SCH_1):PAGE58
    W8    GND @T6G_MB_LIB.T6G(SCH_1):GND    I12 @T6G_MB_LIB.T6G(SCH_1):PAGE58
   W11    GND @T6G_MB_LIB.T6G(SCH_1):GND    I12 @T6G_MB_LIB.T6G(SCH_1):PAGE58
   W13    GND @T6G_MB_LIB.T6G(SCH_1):GND    I12 @T6G_MB_LIB.T6G(SCH_1):PAGE58
   W15    GND @T6G_MB_LIB.T6G(SCH_1):GND    I12 @T6G_MB_LIB.T6G(SCH_1):PAGE58
   W18    GND @T6G_MB_LIB.T6G(SCH_1):GND    I12 @T6G_MB_LIB.T6G(SCH_1):PAGE58
   W20    GND @T6G_MB_LIB.T6G(SCH_1):GND    I12 @T6G_MB_LIB.T6G(SCH_1):PAGE58
   W22    GND @T6G_MB_LIB.T6G(SCH_1):GND    I12 @T6G_MB_LIB.T6G(SCH_1):PAGE58
   W25    GND @T6G_MB_LIB.T6G(SCH_1):GND    I12 @T6G_MB_LIB.T6G(SCH_1):PAGE58
   W28    GND @T6G_MB_LIB.T6G(SCH_1):GND    I12 @T6G_MB_LIB.T6G(SCH_1):PAGE58
   W34    GND @T6G_MB_LIB.T6G(SCH_1):GND    I12 @T6G_MB_LIB.T6G(SCH_1):PAGE58
   W35    GND @T6G_MB_LIB.T6G(SCH_1):GND    I12 @T6G_MB_LIB.T6G(SCH_1):PAGE58
   W36    GND @T6G_MB_LIB.T6G(SCH_1):GND    I12 @T6G_MB_LIB.T6G(SCH_1):PAGE58
   W40    GND @T6G_MB_LIB.T6G(SCH_1):GND    I12 @T6G_MB_LIB.T6G(SCH_1):PAGE58
   W41    GND @T6G_MB_LIB.T6G(SCH_1):GND    I12 @T6G_MB_LIB.T6G(SCH_1):PAGE58
   W42    GND @T6G_MB_LIB.T6G(SCH_1):GND    I12 @T6G_MB_LIB.T6G(SCH_1):PAGE58
   W45    GND @T6G_MB_LIB.T6G(SCH_1):GND    I12 @T6G_MB_LIB.T6G(SCH_1):PAGE58
   W48    GND @T6G_MB_LIB.T6G(SCH_1):GND    I12 @T6G_MB_LIB.T6G(SCH_1):PAGE58
   W51    GND @T6G_MB_LIB.T6G(SCH_1):GND    I12 @T6G_MB_LIB.T6G(SCH_1):PAGE58
   W54    GND @T6G_MB_LIB.T6G(SCH_1):GND    I12 @T6G_MB_LIB.T6G(SCH_1):PAGE58
   W56    GND @T6G_MB_LIB.T6G(SCH_1):GND    I12 @T6G_MB_LIB.T6G(SCH_1):PAGE58
   W58    GND @T6G_MB_LIB.T6G(SCH_1):GND    I12 @T6G_MB_LIB.T6G(SCH_1):PAGE58
   W61    GND @T6G_MB_LIB.T6G(SCH_1):GND    I12 @T6G_MB_LIB.T6G(SCH_1):PAGE58
   W63    GND @T6G_MB_LIB.T6G(SCH_1):GND    I12 @T6G_MB_LIB.T6G(SCH_1):PAGE58
   W65    GND @T6G_MB_LIB.T6G(SCH_1):GND    I12 @T6G_MB_LIB.T6G(SCH_1):PAGE58
   W68    GND @T6G_MB_LIB.T6G(SCH_1):GND    I12 @T6G_MB_LIB.T6G(SCH_1):PAGE58
   W70    GND @T6G_MB_LIB.T6G(SCH_1):GND    I12 @T6G_MB_LIB.T6G(SCH_1):PAGE58
   W72    GND @T6G_MB_LIB.T6G(SCH_1):GND    I12 @T6G_MB_LIB.T6G(SCH_1):PAGE58
   W75    GND @T6G_MB_LIB.T6G(SCH_1):GND    I12 @T6G_MB_LIB.T6G(SCH_1):PAGE58
    Y3    GND @T6G_MB_LIB.T6G(SCH_1):GND    I12 @T6G_MB_LIB.T6G(SCH_1):PAGE58
    Y8    GND @T6G_MB_LIB.T6G(SCH_1):GND    I12 @T6G_MB_LIB.T6G(SCH_1):PAGE58
   Y10    GND @T6G_MB_LIB.T6G(SCH_1):GND    I12 @T6G_MB_LIB.T6G(SCH_1):PAGE58
   Y15    GND @T6G_MB_LIB.T6G(SCH_1):GND    I12 @T6G_MB_LIB.T6G(SCH_1):PAGE58
   Y17    GND @T6G_MB_LIB.T6G(SCH_1):GND    I12 @T6G_MB_LIB.T6G(SCH_1):PAGE58
   Y22    GND @T6G_MB_LIB.T6G(SCH_1):GND    I12 @T6G_MB_LIB.T6G(SCH_1):PAGE58
   Y23    GND @T6G_MB_LIB.T6G(SCH_1):GND    I12 @T6G_MB_LIB.T6G(SCH_1):PAGE58
   Y24    GND @T6G_MB_LIB.T6G(SCH_1):GND    I12 @T6G_MB_LIB.T6G(SCH_1):PAGE58
   Y25    GND @T6G_MB_LIB.T6G(SCH_1):GND    I12 @T6G_MB_LIB.T6G(SCH_1):PAGE58
   Y26    GND @T6G_MB_LIB.T6G(SCH_1):GND    I12 @T6G_MB_LIB.T6G(SCH_1):PAGE58
   Y27    GND @T6G_MB_LIB.T6G(SCH_1):GND    I12 @T6G_MB_LIB.T6G(SCH_1):PAGE58
   Y28    GND @T6G_MB_LIB.T6G(SCH_1):GND    I12 @T6G_MB_LIB.T6G(SCH_1):PAGE58
   Y31    GND @T6G_MB_LIB.T6G(SCH_1):GND    I12 @T6G_MB_LIB.T6G(SCH_1):PAGE58
   Y32    GND @T6G_MB_LIB.T6G(SCH_1):GND    I12 @T6G_MB_LIB.T6G(SCH_1):PAGE58
   Y33    GND @T6G_MB_LIB.T6G(SCH_1):GND    I12 @T6G_MB_LIB.T6G(SCH_1):PAGE58
   Y34    GND @T6G_MB_LIB.T6G(SCH_1):GND    I12 @T6G_MB_LIB.T6G(SCH_1):PAGE58
   Y37    GND @T6G_MB_LIB.T6G(SCH_1):GND    I12 @T6G_MB_LIB.T6G(SCH_1):PAGE58
   Y39    GND @T6G_MB_LIB.T6G(SCH_1):GND    I12 @T6G_MB_LIB.T6G(SCH_1):PAGE58
   Y42    GND @T6G_MB_LIB.T6G(SCH_1):GND    I12 @T6G_MB_LIB.T6G(SCH_1):PAGE58
   Y43    GND @T6G_MB_LIB.T6G(SCH_1):GND    I12 @T6G_MB_LIB.T6G(SCH_1):PAGE58
   Y44    GND @T6G_MB_LIB.T6G(SCH_1):GND    I12 @T6G_MB_LIB.T6G(SCH_1):PAGE58
   Y45    GND @T6G_MB_LIB.T6G(SCH_1):GND    I12 @T6G_MB_LIB.T6G(SCH_1):PAGE58
   Y48    GND @T6G_MB_LIB.T6G(SCH_1):GND    I12 @T6G_MB_LIB.T6G(SCH_1):PAGE58
   Y49    GND @T6G_MB_LIB.T6G(SCH_1):GND    I12 @T6G_MB_LIB.T6G(SCH_1):PAGE58
   Y50    GND @T6G_MB_LIB.T6G(SCH_1):GND    I12 @T6G_MB_LIB.T6G(SCH_1):PAGE58
   Y51    GND @T6G_MB_LIB.T6G(SCH_1):GND    I12 @T6G_MB_LIB.T6G(SCH_1):PAGE58
   Y52    GND @T6G_MB_LIB.T6G(SCH_1):GND    I12 @T6G_MB_LIB.T6G(SCH_1):PAGE58
   Y53    GND @T6G_MB_LIB.T6G(SCH_1):GND    I12 @T6G_MB_LIB.T6G(SCH_1):PAGE58
   Y54    GND @T6G_MB_LIB.T6G(SCH_1):GND    I12 @T6G_MB_LIB.T6G(SCH_1):PAGE58
   Y59    GND @T6G_MB_LIB.T6G(SCH_1):GND    I12 @T6G_MB_LIB.T6G(SCH_1):PAGE58
   Y61    GND @T6G_MB_LIB.T6G(SCH_1):GND    I12 @T6G_MB_LIB.T6G(SCH_1):PAGE58
   Y66    GND @T6G_MB_LIB.T6G(SCH_1):GND    I12 @T6G_MB_LIB.T6G(SCH_1):PAGE58
   Y68    GND @T6G_MB_LIB.T6G(SCH_1):GND    I12 @T6G_MB_LIB.T6G(SCH_1):PAGE58
   Y73    GND @T6G_MB_LIB.T6G(SCH_1):GND    I12 @T6G_MB_LIB.T6G(SCH_1):PAGE58
   AA1    GND @T6G_MB_LIB.T6G(SCH_1):GND    I12 @T6G_MB_LIB.T6G(SCH_1):PAGE58
   AA4    GND @T6G_MB_LIB.T6G(SCH_1):GND    I12 @T6G_MB_LIB.T6G(SCH_1):PAGE58
   AA6    GND @T6G_MB_LIB.T6G(SCH_1):GND    I12 @T6G_MB_LIB.T6G(SCH_1):PAGE58
   AA8    GND @T6G_MB_LIB.T6G(SCH_1):GND    I12 @T6G_MB_LIB.T6G(SCH_1):PAGE58
  AA11    GND @T6G_MB_LIB.T6G(SCH_1):GND    I12 @T6G_MB_LIB.T6G(SCH_1):PAGE58
  AA13    GND @T6G_MB_LIB.T6G(SCH_1):GND    I12 @T6G_MB_LIB.T6G(SCH_1):PAGE58
  AA15    GND @T6G_MB_LIB.T6G(SCH_1):GND    I12 @T6G_MB_LIB.T6G(SCH_1):PAGE58
  AA18    GND @T6G_MB_LIB.T6G(SCH_1):GND    I12 @T6G_MB_LIB.T6G(SCH_1):PAGE58
  AA20    GND @T6G_MB_LIB.T6G(SCH_1):GND    I12 @T6G_MB_LIB.T6G(SCH_1):PAGE58
  AA31    GND @T6G_MB_LIB.T6G(SCH_1):GND    I12 @T6G_MB_LIB.T6G(SCH_1):PAGE58
  AA34    GND @T6G_MB_LIB.T6G(SCH_1):GND    I12 @T6G_MB_LIB.T6G(SCH_1):PAGE58
  AA35    GND @T6G_MB_LIB.T6G(SCH_1):GND    I12 @T6G_MB_LIB.T6G(SCH_1):PAGE58
  AA36    GND @T6G_MB_LIB.T6G(SCH_1):GND    I12 @T6G_MB_LIB.T6G(SCH_1):PAGE58
  AA40    GND @T6G_MB_LIB.T6G(SCH_1):GND    I12 @T6G_MB_LIB.T6G(SCH_1):PAGE58
  AA41    GND @T6G_MB_LIB.T6G(SCH_1):GND    I12 @T6G_MB_LIB.T6G(SCH_1):PAGE58
  AA45    GND @T6G_MB_LIB.T6G(SCH_1):GND    I12 @T6G_MB_LIB.T6G(SCH_1):PAGE58
  AA56    GND @T6G_MB_LIB.T6G(SCH_1):GND    I12 @T6G_MB_LIB.T6G(SCH_1):PAGE58
  AA58    GND @T6G_MB_LIB.T6G(SCH_1):GND    I12 @T6G_MB_LIB.T6G(SCH_1):PAGE58
  AA61    GND @T6G_MB_LIB.T6G(SCH_1):GND    I12 @T6G_MB_LIB.T6G(SCH_1):PAGE58
  AA63    GND @T6G_MB_LIB.T6G(SCH_1):GND    I12 @T6G_MB_LIB.T6G(SCH_1):PAGE58
  AA65    GND @T6G_MB_LIB.T6G(SCH_1):GND    I12 @T6G_MB_LIB.T6G(SCH_1):PAGE58
  AA68    GND @T6G_MB_LIB.T6G(SCH_1):GND    I12 @T6G_MB_LIB.T6G(SCH_1):PAGE58
  AA70    GND @T6G_MB_LIB.T6G(SCH_1):GND    I12 @T6G_MB_LIB.T6G(SCH_1):PAGE58
  AA75    GND @T6G_MB_LIB.T6G(SCH_1):GND    I12 @T6G_MB_LIB.T6G(SCH_1):PAGE58
   AB3    GND @T6G_MB_LIB.T6G(SCH_1):GND    I12 @T6G_MB_LIB.T6G(SCH_1):PAGE58
   AB5    GND @T6G_MB_LIB.T6G(SCH_1):GND    I12 @T6G_MB_LIB.T6G(SCH_1):PAGE58
   AB8    GND @T6G_MB_LIB.T6G(SCH_1):GND    I12 @T6G_MB_LIB.T6G(SCH_1):PAGE58
  AB10    GND @T6G_MB_LIB.T6G(SCH_1):GND    I12 @T6G_MB_LIB.T6G(SCH_1):PAGE58
  AB12    GND @T6G_MB_LIB.T6G(SCH_1):GND    I12 @T6G_MB_LIB.T6G(SCH_1):PAGE58
  AB15    GND @T6G_MB_LIB.T6G(SCH_1):GND    I12 @T6G_MB_LIB.T6G(SCH_1):PAGE58
  AB17    GND @T6G_MB_LIB.T6G(SCH_1):GND    I12 @T6G_MB_LIB.T6G(SCH_1):PAGE58
  AB19    GND @T6G_MB_LIB.T6G(SCH_1):GND    I12 @T6G_MB_LIB.T6G(SCH_1):PAGE58
  AB22    GND @T6G_MB_LIB.T6G(SCH_1):GND    I12 @T6G_MB_LIB.T6G(SCH_1):PAGE58
  AB25    GND @T6G_MB_LIB.T6G(SCH_1):GND    I12 @T6G_MB_LIB.T6G(SCH_1):PAGE58
  AB28    GND @T6G_MB_LIB.T6G(SCH_1):GND    I12 @T6G_MB_LIB.T6G(SCH_1):PAGE58
  AB31    GND @T6G_MB_LIB.T6G(SCH_1):GND    I12 @T6G_MB_LIB.T6G(SCH_1):PAGE58
  AB34    GND @T6G_MB_LIB.T6G(SCH_1):GND    I12 @T6G_MB_LIB.T6G(SCH_1):PAGE58
  AB37    GND @T6G_MB_LIB.T6G(SCH_1):GND    I12 @T6G_MB_LIB.T6G(SCH_1):PAGE58
  AB39    GND @T6G_MB_LIB.T6G(SCH_1):GND    I12 @T6G_MB_LIB.T6G(SCH_1):PAGE58
  AB42    GND @T6G_MB_LIB.T6G(SCH_1):GND    I12 @T6G_MB_LIB.T6G(SCH_1):PAGE58
  AB45    GND @T6G_MB_LIB.T6G(SCH_1):GND    I12 @T6G_MB_LIB.T6G(SCH_1):PAGE58
  AB48    GND @T6G_MB_LIB.T6G(SCH_1):GND    I12 @T6G_MB_LIB.T6G(SCH_1):PAGE58
  AB51    GND @T6G_MB_LIB.T6G(SCH_1):GND    I12 @T6G_MB_LIB.T6G(SCH_1):PAGE58
  AB54    GND @T6G_MB_LIB.T6G(SCH_1):GND    I12 @T6G_MB_LIB.T6G(SCH_1):PAGE58
  AB57    GND @T6G_MB_LIB.T6G(SCH_1):GND    I12 @T6G_MB_LIB.T6G(SCH_1):PAGE58
  AB59    GND @T6G_MB_LIB.T6G(SCH_1):GND    I12 @T6G_MB_LIB.T6G(SCH_1):PAGE58
  AB61    GND @T6G_MB_LIB.T6G(SCH_1):GND    I12 @T6G_MB_LIB.T6G(SCH_1):PAGE58
  AB64    GND @T6G_MB_LIB.T6G(SCH_1):GND    I12 @T6G_MB_LIB.T6G(SCH_1):PAGE58
  AB66    GND @T6G_MB_LIB.T6G(SCH_1):GND    I12 @T6G_MB_LIB.T6G(SCH_1):PAGE58
  AK10    GND @T6G_MB_LIB.T6G(SCH_1):GND     I9 @T6G_MB_LIB.T6G(SCH_1):PAGE58
  AK12    GND @T6G_MB_LIB.T6G(SCH_1):GND     I9 @T6G_MB_LIB.T6G(SCH_1):PAGE58
  AK15    GND @T6G_MB_LIB.T6G(SCH_1):GND     I9 @T6G_MB_LIB.T6G(SCH_1):PAGE58
  AK17    GND @T6G_MB_LIB.T6G(SCH_1):GND     I9 @T6G_MB_LIB.T6G(SCH_1):PAGE58
  AK19    GND @T6G_MB_LIB.T6G(SCH_1):GND     I9 @T6G_MB_LIB.T6G(SCH_1):PAGE58
  AK22    GND @T6G_MB_LIB.T6G(SCH_1):GND     I9 @T6G_MB_LIB.T6G(SCH_1):PAGE58
  AK25    GND @T6G_MB_LIB.T6G(SCH_1):GND     I9 @T6G_MB_LIB.T6G(SCH_1):PAGE58
  AK28    GND @T6G_MB_LIB.T6G(SCH_1):GND     I9 @T6G_MB_LIB.T6G(SCH_1):PAGE58
  AK31    GND @T6G_MB_LIB.T6G(SCH_1):GND     I9 @T6G_MB_LIB.T6G(SCH_1):PAGE58
  AK34    GND @T6G_MB_LIB.T6G(SCH_1):GND     I9 @T6G_MB_LIB.T6G(SCH_1):PAGE58
  AK37    GND @T6G_MB_LIB.T6G(SCH_1):GND     I9 @T6G_MB_LIB.T6G(SCH_1):PAGE58
  AK39    GND @T6G_MB_LIB.T6G(SCH_1):GND     I9 @T6G_MB_LIB.T6G(SCH_1):PAGE58
  AK42    GND @T6G_MB_LIB.T6G(SCH_1):GND     I9 @T6G_MB_LIB.T6G(SCH_1):PAGE58
  AK45    GND @T6G_MB_LIB.T6G(SCH_1):GND     I9 @T6G_MB_LIB.T6G(SCH_1):PAGE58
  AK48    GND @T6G_MB_LIB.T6G(SCH_1):GND     I9 @T6G_MB_LIB.T6G(SCH_1):PAGE58
  AK51    GND @T6G_MB_LIB.T6G(SCH_1):GND     I9 @T6G_MB_LIB.T6G(SCH_1):PAGE58
  AK54    GND @T6G_MB_LIB.T6G(SCH_1):GND     I9 @T6G_MB_LIB.T6G(SCH_1):PAGE58
  AK57    GND @T6G_MB_LIB.T6G(SCH_1):GND     I9 @T6G_MB_LIB.T6G(SCH_1):PAGE58
  AK59    GND @T6G_MB_LIB.T6G(SCH_1):GND     I9 @T6G_MB_LIB.T6G(SCH_1):PAGE58
  AK61    GND @T6G_MB_LIB.T6G(SCH_1):GND     I9 @T6G_MB_LIB.T6G(SCH_1):PAGE58
  AK64    GND @T6G_MB_LIB.T6G(SCH_1):GND     I9 @T6G_MB_LIB.T6G(SCH_1):PAGE58
  AK66    GND @T6G_MB_LIB.T6G(SCH_1):GND     I9 @T6G_MB_LIB.T6G(SCH_1):PAGE58
  AK68    GND @T6G_MB_LIB.T6G(SCH_1):GND     I9 @T6G_MB_LIB.T6G(SCH_1):PAGE58
  AK71    GND @T6G_MB_LIB.T6G(SCH_1):GND     I9 @T6G_MB_LIB.T6G(SCH_1):PAGE58
  AK73    GND @T6G_MB_LIB.T6G(SCH_1):GND     I9 @T6G_MB_LIB.T6G(SCH_1):PAGE58
   AL1    GND @T6G_MB_LIB.T6G(SCH_1):GND     I9 @T6G_MB_LIB.T6G(SCH_1):PAGE58
   AL4    GND @T6G_MB_LIB.T6G(SCH_1):GND     I9 @T6G_MB_LIB.T6G(SCH_1):PAGE58
   AL6    GND @T6G_MB_LIB.T6G(SCH_1):GND     I9 @T6G_MB_LIB.T6G(SCH_1):PAGE58
   AL8    GND @T6G_MB_LIB.T6G(SCH_1):GND     I9 @T6G_MB_LIB.T6G(SCH_1):PAGE58
  AL11    GND @T6G_MB_LIB.T6G(SCH_1):GND     I9 @T6G_MB_LIB.T6G(SCH_1):PAGE58
  AL13    GND @T6G_MB_LIB.T6G(SCH_1):GND     I9 @T6G_MB_LIB.T6G(SCH_1):PAGE58
  AL15    GND @T6G_MB_LIB.T6G(SCH_1):GND     I9 @T6G_MB_LIB.T6G(SCH_1):PAGE58
  AL18    GND @T6G_MB_LIB.T6G(SCH_1):GND     I9 @T6G_MB_LIB.T6G(SCH_1):PAGE58
  AL20    GND @T6G_MB_LIB.T6G(SCH_1):GND     I9 @T6G_MB_LIB.T6G(SCH_1):PAGE58
  AL22    GND @T6G_MB_LIB.T6G(SCH_1):GND     I9 @T6G_MB_LIB.T6G(SCH_1):PAGE58
  AL25    GND @T6G_MB_LIB.T6G(SCH_1):GND     I9 @T6G_MB_LIB.T6G(SCH_1):PAGE58
  AL28    GND @T6G_MB_LIB.T6G(SCH_1):GND     I9 @T6G_MB_LIB.T6G(SCH_1):PAGE58
  AL31    GND @T6G_MB_LIB.T6G(SCH_1):GND     I9 @T6G_MB_LIB.T6G(SCH_1):PAGE58
  AL34    GND @T6G_MB_LIB.T6G(SCH_1):GND     I9 @T6G_MB_LIB.T6G(SCH_1):PAGE58
  AL42    GND @T6G_MB_LIB.T6G(SCH_1):GND     I9 @T6G_MB_LIB.T6G(SCH_1):PAGE58
  AL45    GND @T6G_MB_LIB.T6G(SCH_1):GND     I9 @T6G_MB_LIB.T6G(SCH_1):PAGE58
  AL48    GND @T6G_MB_LIB.T6G(SCH_1):GND     I9 @T6G_MB_LIB.T6G(SCH_1):PAGE58
  AL51    GND @T6G_MB_LIB.T6G(SCH_1):GND     I9 @T6G_MB_LIB.T6G(SCH_1):PAGE58
  AL54    GND @T6G_MB_LIB.T6G(SCH_1):GND     I9 @T6G_MB_LIB.T6G(SCH_1):PAGE58
  AL56    GND @T6G_MB_LIB.T6G(SCH_1):GND     I9 @T6G_MB_LIB.T6G(SCH_1):PAGE58
  AL58    GND @T6G_MB_LIB.T6G(SCH_1):GND     I9 @T6G_MB_LIB.T6G(SCH_1):PAGE58
  AL61    GND @T6G_MB_LIB.T6G(SCH_1):GND     I9 @T6G_MB_LIB.T6G(SCH_1):PAGE58
  AL63    GND @T6G_MB_LIB.T6G(SCH_1):GND     I9 @T6G_MB_LIB.T6G(SCH_1):PAGE58
  AL65    GND @T6G_MB_LIB.T6G(SCH_1):GND     I9 @T6G_MB_LIB.T6G(SCH_1):PAGE58
  AL68    GND @T6G_MB_LIB.T6G(SCH_1):GND     I9 @T6G_MB_LIB.T6G(SCH_1):PAGE58
  AL70    GND @T6G_MB_LIB.T6G(SCH_1):GND     I9 @T6G_MB_LIB.T6G(SCH_1):PAGE58
  AL72    GND @T6G_MB_LIB.T6G(SCH_1):GND     I9 @T6G_MB_LIB.T6G(SCH_1):PAGE58
  AL75    GND @T6G_MB_LIB.T6G(SCH_1):GND     I9 @T6G_MB_LIB.T6G(SCH_1):PAGE58
   AM3    GND @T6G_MB_LIB.T6G(SCH_1):GND     I9 @T6G_MB_LIB.T6G(SCH_1):PAGE58
   AM8    GND @T6G_MB_LIB.T6G(SCH_1):GND     I9 @T6G_MB_LIB.T6G(SCH_1):PAGE58
  AM10    GND @T6G_MB_LIB.T6G(SCH_1):GND     I9 @T6G_MB_LIB.T6G(SCH_1):PAGE58
  AM15    GND @T6G_MB_LIB.T6G(SCH_1):GND     I9 @T6G_MB_LIB.T6G(SCH_1):PAGE58
  AM17    GND @T6G_MB_LIB.T6G(SCH_1):GND     I9 @T6G_MB_LIB.T6G(SCH_1):PAGE58
  AM23    GND @T6G_MB_LIB.T6G(SCH_1):GND     I9 @T6G_MB_LIB.T6G(SCH_1):PAGE58
  AM24    GND @T6G_MB_LIB.T6G(SCH_1):GND     I9 @T6G_MB_LIB.T6G(SCH_1):PAGE58
  AM25    GND @T6G_MB_LIB.T6G(SCH_1):GND     I9 @T6G_MB_LIB.T6G(SCH_1):PAGE58
  AM26    GND @T6G_MB_LIB.T6G(SCH_1):GND     I9 @T6G_MB_LIB.T6G(SCH_1):PAGE58
  AM27    GND @T6G_MB_LIB.T6G(SCH_1):GND     I9 @T6G_MB_LIB.T6G(SCH_1):PAGE58
  AM28    GND @T6G_MB_LIB.T6G(SCH_1):GND     I9 @T6G_MB_LIB.T6G(SCH_1):PAGE58
  AM29    GND @T6G_MB_LIB.T6G(SCH_1):GND     I9 @T6G_MB_LIB.T6G(SCH_1):PAGE58
  AM30    GND @T6G_MB_LIB.T6G(SCH_1):GND     I9 @T6G_MB_LIB.T6G(SCH_1):PAGE58
  AM31    GND @T6G_MB_LIB.T6G(SCH_1):GND     I9 @T6G_MB_LIB.T6G(SCH_1):PAGE58
  AM32    GND @T6G_MB_LIB.T6G(SCH_1):GND     I9 @T6G_MB_LIB.T6G(SCH_1):PAGE58
  AM33    GND @T6G_MB_LIB.T6G(SCH_1):GND     I9 @T6G_MB_LIB.T6G(SCH_1):PAGE58
  AM34    GND @T6G_MB_LIB.T6G(SCH_1):GND     I9 @T6G_MB_LIB.T6G(SCH_1):PAGE58
  AM39    GND @T6G_MB_LIB.T6G(SCH_1):GND     I9 @T6G_MB_LIB.T6G(SCH_1):PAGE58
  AD49    GND @T6G_MB_LIB.T6G(SCH_1):GND     I9 @T6G_MB_LIB.T6G(SCH_1):PAGE58
  AD50    GND @T6G_MB_LIB.T6G(SCH_1):GND     I9 @T6G_MB_LIB.T6G(SCH_1):PAGE58
  AD51    GND @T6G_MB_LIB.T6G(SCH_1):GND     I9 @T6G_MB_LIB.T6G(SCH_1):PAGE58
  AD52    GND @T6G_MB_LIB.T6G(SCH_1):GND     I9 @T6G_MB_LIB.T6G(SCH_1):PAGE58
  AD53    GND @T6G_MB_LIB.T6G(SCH_1):GND     I9 @T6G_MB_LIB.T6G(SCH_1):PAGE58
  AD57    GND @T6G_MB_LIB.T6G(SCH_1):GND     I9 @T6G_MB_LIB.T6G(SCH_1):PAGE58
  AD59    GND @T6G_MB_LIB.T6G(SCH_1):GND     I9 @T6G_MB_LIB.T6G(SCH_1):PAGE58
  AD61    GND @T6G_MB_LIB.T6G(SCH_1):GND     I9 @T6G_MB_LIB.T6G(SCH_1):PAGE58
  AD64    GND @T6G_MB_LIB.T6G(SCH_1):GND     I9 @T6G_MB_LIB.T6G(SCH_1):PAGE58
  AD66    GND @T6G_MB_LIB.T6G(SCH_1):GND     I9 @T6G_MB_LIB.T6G(SCH_1):PAGE58
  AD68    GND @T6G_MB_LIB.T6G(SCH_1):GND     I9 @T6G_MB_LIB.T6G(SCH_1):PAGE58
  AD71    GND @T6G_MB_LIB.T6G(SCH_1):GND     I9 @T6G_MB_LIB.T6G(SCH_1):PAGE58
  AD73    GND @T6G_MB_LIB.T6G(SCH_1):GND     I9 @T6G_MB_LIB.T6G(SCH_1):PAGE58
   AE1    GND @T6G_MB_LIB.T6G(SCH_1):GND     I9 @T6G_MB_LIB.T6G(SCH_1):PAGE58
   AE6    GND @T6G_MB_LIB.T6G(SCH_1):GND     I9 @T6G_MB_LIB.T6G(SCH_1):PAGE58
   AE8    GND @T6G_MB_LIB.T6G(SCH_1):GND     I9 @T6G_MB_LIB.T6G(SCH_1):PAGE58
  AE11    GND @T6G_MB_LIB.T6G(SCH_1):GND     I9 @T6G_MB_LIB.T6G(SCH_1):PAGE58
  AE13    GND @T6G_MB_LIB.T6G(SCH_1):GND     I9 @T6G_MB_LIB.T6G(SCH_1):PAGE58
  AE15    GND @T6G_MB_LIB.T6G(SCH_1):GND     I9 @T6G_MB_LIB.T6G(SCH_1):PAGE58
  AE18    GND @T6G_MB_LIB.T6G(SCH_1):GND     I9 @T6G_MB_LIB.T6G(SCH_1):PAGE58
  AE20    GND @T6G_MB_LIB.T6G(SCH_1):GND     I9 @T6G_MB_LIB.T6G(SCH_1):PAGE58
  AE22    GND @T6G_MB_LIB.T6G(SCH_1):GND     I9 @T6G_MB_LIB.T6G(SCH_1):PAGE58
  AE25    GND @T6G_MB_LIB.T6G(SCH_1):GND     I9 @T6G_MB_LIB.T6G(SCH_1):PAGE58
  AE28    GND @T6G_MB_LIB.T6G(SCH_1):GND     I9 @T6G_MB_LIB.T6G(SCH_1):PAGE58
  AE31    GND @T6G_MB_LIB.T6G(SCH_1):GND     I9 @T6G_MB_LIB.T6G(SCH_1):PAGE58
  AE34    GND @T6G_MB_LIB.T6G(SCH_1):GND     I9 @T6G_MB_LIB.T6G(SCH_1):PAGE58
  AE35    GND @T6G_MB_LIB.T6G(SCH_1):GND     I9 @T6G_MB_LIB.T6G(SCH_1):PAGE58
  AE36    GND @T6G_MB_LIB.T6G(SCH_1):GND     I9 @T6G_MB_LIB.T6G(SCH_1):PAGE58
  AE40    GND @T6G_MB_LIB.T6G(SCH_1):GND     I9 @T6G_MB_LIB.T6G(SCH_1):PAGE58
  AE41    GND @T6G_MB_LIB.T6G(SCH_1):GND     I9 @T6G_MB_LIB.T6G(SCH_1):PAGE58
  AE42    GND @T6G_MB_LIB.T6G(SCH_1):GND     I9 @T6G_MB_LIB.T6G(SCH_1):PAGE58
  AE45    GND @T6G_MB_LIB.T6G(SCH_1):GND     I9 @T6G_MB_LIB.T6G(SCH_1):PAGE58
  AE48    GND @T6G_MB_LIB.T6G(SCH_1):GND     I9 @T6G_MB_LIB.T6G(SCH_1):PAGE58
  AE51    GND @T6G_MB_LIB.T6G(SCH_1):GND     I9 @T6G_MB_LIB.T6G(SCH_1):PAGE58
  AE54    GND @T6G_MB_LIB.T6G(SCH_1):GND     I9 @T6G_MB_LIB.T6G(SCH_1):PAGE58
  AE56    GND @T6G_MB_LIB.T6G(SCH_1):GND     I9 @T6G_MB_LIB.T6G(SCH_1):PAGE58
  AE58    GND @T6G_MB_LIB.T6G(SCH_1):GND     I9 @T6G_MB_LIB.T6G(SCH_1):PAGE58
  AE61    GND @T6G_MB_LIB.T6G(SCH_1):GND     I9 @T6G_MB_LIB.T6G(SCH_1):PAGE58
  AE63    GND @T6G_MB_LIB.T6G(SCH_1):GND     I9 @T6G_MB_LIB.T6G(SCH_1):PAGE58
  AE65    GND @T6G_MB_LIB.T6G(SCH_1):GND     I9 @T6G_MB_LIB.T6G(SCH_1):PAGE58
  AE68    GND @T6G_MB_LIB.T6G(SCH_1):GND     I9 @T6G_MB_LIB.T6G(SCH_1):PAGE58
  AE70    GND @T6G_MB_LIB.T6G(SCH_1):GND     I9 @T6G_MB_LIB.T6G(SCH_1):PAGE58
  AE72    GND @T6G_MB_LIB.T6G(SCH_1):GND     I9 @T6G_MB_LIB.T6G(SCH_1):PAGE58
  AE75    GND @T6G_MB_LIB.T6G(SCH_1):GND     I9 @T6G_MB_LIB.T6G(SCH_1):PAGE58
   AF3    GND @T6G_MB_LIB.T6G(SCH_1):GND     I9 @T6G_MB_LIB.T6G(SCH_1):PAGE58
   AF8    GND @T6G_MB_LIB.T6G(SCH_1):GND     I9 @T6G_MB_LIB.T6G(SCH_1):PAGE58
  AF10    GND @T6G_MB_LIB.T6G(SCH_1):GND     I9 @T6G_MB_LIB.T6G(SCH_1):PAGE58
  AF15    GND @T6G_MB_LIB.T6G(SCH_1):GND     I9 @T6G_MB_LIB.T6G(SCH_1):PAGE58
  AF17    GND @T6G_MB_LIB.T6G(SCH_1):GND     I9 @T6G_MB_LIB.T6G(SCH_1):PAGE58
  AF22    GND @T6G_MB_LIB.T6G(SCH_1):GND     I9 @T6G_MB_LIB.T6G(SCH_1):PAGE58
  AF25    GND @T6G_MB_LIB.T6G(SCH_1):GND     I9 @T6G_MB_LIB.T6G(SCH_1):PAGE58
  AF28    GND @T6G_MB_LIB.T6G(SCH_1):GND     I9 @T6G_MB_LIB.T6G(SCH_1):PAGE58
  AF31    GND @T6G_MB_LIB.T6G(SCH_1):GND     I9 @T6G_MB_LIB.T6G(SCH_1):PAGE58
  AF34    GND @T6G_MB_LIB.T6G(SCH_1):GND     I9 @T6G_MB_LIB.T6G(SCH_1):PAGE58
  AF37    GND @T6G_MB_LIB.T6G(SCH_1):GND     I9 @T6G_MB_LIB.T6G(SCH_1):PAGE58
  AF39    GND @T6G_MB_LIB.T6G(SCH_1):GND     I9 @T6G_MB_LIB.T6G(SCH_1):PAGE58
  AF42    GND @T6G_MB_LIB.T6G(SCH_1):GND     I9 @T6G_MB_LIB.T6G(SCH_1):PAGE58
  AF45    GND @T6G_MB_LIB.T6G(SCH_1):GND     I9 @T6G_MB_LIB.T6G(SCH_1):PAGE58
  AF48    GND @T6G_MB_LIB.T6G(SCH_1):GND     I9 @T6G_MB_LIB.T6G(SCH_1):PAGE58
  AF51    GND @T6G_MB_LIB.T6G(SCH_1):GND     I9 @T6G_MB_LIB.T6G(SCH_1):PAGE58
  AF54    GND @T6G_MB_LIB.T6G(SCH_1):GND     I9 @T6G_MB_LIB.T6G(SCH_1):PAGE58
  AF59    GND @T6G_MB_LIB.T6G(SCH_1):GND     I9 @T6G_MB_LIB.T6G(SCH_1):PAGE58
  AF61    GND @T6G_MB_LIB.T6G(SCH_1):GND     I9 @T6G_MB_LIB.T6G(SCH_1):PAGE58
  AF66    GND @T6G_MB_LIB.T6G(SCH_1):GND     I9 @T6G_MB_LIB.T6G(SCH_1):PAGE58
  AF68    GND @T6G_MB_LIB.T6G(SCH_1):GND     I9 @T6G_MB_LIB.T6G(SCH_1):PAGE58
  AF73    GND @T6G_MB_LIB.T6G(SCH_1):GND     I9 @T6G_MB_LIB.T6G(SCH_1):PAGE58
   AG1    GND @T6G_MB_LIB.T6G(SCH_1):GND     I9 @T6G_MB_LIB.T6G(SCH_1):PAGE58
   AG4    GND @T6G_MB_LIB.T6G(SCH_1):GND     I9 @T6G_MB_LIB.T6G(SCH_1):PAGE58
   AG6    GND @T6G_MB_LIB.T6G(SCH_1):GND     I9 @T6G_MB_LIB.T6G(SCH_1):PAGE58
   AG8    GND @T6G_MB_LIB.T6G(SCH_1):GND     I9 @T6G_MB_LIB.T6G(SCH_1):PAGE58
  AG11    GND @T6G_MB_LIB.T6G(SCH_1):GND     I9 @T6G_MB_LIB.T6G(SCH_1):PAGE58
  AG13    GND @T6G_MB_LIB.T6G(SCH_1):GND     I9 @T6G_MB_LIB.T6G(SCH_1):PAGE58
  AG15    GND @T6G_MB_LIB.T6G(SCH_1):GND     I9 @T6G_MB_LIB.T6G(SCH_1):PAGE58
  AG18    GND @T6G_MB_LIB.T6G(SCH_1):GND     I9 @T6G_MB_LIB.T6G(SCH_1):PAGE58
  AG20    GND @T6G_MB_LIB.T6G(SCH_1):GND     I9 @T6G_MB_LIB.T6G(SCH_1):PAGE58
  AG22    GND @T6G_MB_LIB.T6G(SCH_1):GND     I9 @T6G_MB_LIB.T6G(SCH_1):PAGE58
  AG25    GND @T6G_MB_LIB.T6G(SCH_1):GND     I9 @T6G_MB_LIB.T6G(SCH_1):PAGE58
  AG28    GND @T6G_MB_LIB.T6G(SCH_1):GND     I9 @T6G_MB_LIB.T6G(SCH_1):PAGE58
  AG31    GND @T6G_MB_LIB.T6G(SCH_1):GND     I9 @T6G_MB_LIB.T6G(SCH_1):PAGE58
  AG34    GND @T6G_MB_LIB.T6G(SCH_1):GND     I9 @T6G_MB_LIB.T6G(SCH_1):PAGE58
  AG42    GND @T6G_MB_LIB.T6G(SCH_1):GND     I9 @T6G_MB_LIB.T6G(SCH_1):PAGE58
  AG45    GND @T6G_MB_LIB.T6G(SCH_1):GND     I9 @T6G_MB_LIB.T6G(SCH_1):PAGE58
  AG48    GND @T6G_MB_LIB.T6G(SCH_1):GND     I9 @T6G_MB_LIB.T6G(SCH_1):PAGE58
  AG51    GND @T6G_MB_LIB.T6G(SCH_1):GND     I9 @T6G_MB_LIB.T6G(SCH_1):PAGE58
  AG54    GND @T6G_MB_LIB.T6G(SCH_1):GND     I9 @T6G_MB_LIB.T6G(SCH_1):PAGE58
  AG56    GND @T6G_MB_LIB.T6G(SCH_1):GND     I9 @T6G_MB_LIB.T6G(SCH_1):PAGE58
  AG58    GND @T6G_MB_LIB.T6G(SCH_1):GND     I9 @T6G_MB_LIB.T6G(SCH_1):PAGE58
  AG61    GND @T6G_MB_LIB.T6G(SCH_1):GND     I9 @T6G_MB_LIB.T6G(SCH_1):PAGE58
  AG63    GND @T6G_MB_LIB.T6G(SCH_1):GND     I9 @T6G_MB_LIB.T6G(SCH_1):PAGE58
  AG65    GND @T6G_MB_LIB.T6G(SCH_1):GND     I9 @T6G_MB_LIB.T6G(SCH_1):PAGE58
  AG68    GND @T6G_MB_LIB.T6G(SCH_1):GND     I9 @T6G_MB_LIB.T6G(SCH_1):PAGE58
  AG70    GND @T6G_MB_LIB.T6G(SCH_1):GND     I9 @T6G_MB_LIB.T6G(SCH_1):PAGE58
  AG72    GND @T6G_MB_LIB.T6G(SCH_1):GND     I9 @T6G_MB_LIB.T6G(SCH_1):PAGE58
  AG75    GND @T6G_MB_LIB.T6G(SCH_1):GND     I9 @T6G_MB_LIB.T6G(SCH_1):PAGE58
   AH3    GND @T6G_MB_LIB.T6G(SCH_1):GND     I9 @T6G_MB_LIB.T6G(SCH_1):PAGE58
   AH5    GND @T6G_MB_LIB.T6G(SCH_1):GND     I9 @T6G_MB_LIB.T6G(SCH_1):PAGE58
   AH8    GND @T6G_MB_LIB.T6G(SCH_1):GND     I9 @T6G_MB_LIB.T6G(SCH_1):PAGE58
  AH10    GND @T6G_MB_LIB.T6G(SCH_1):GND     I9 @T6G_MB_LIB.T6G(SCH_1):PAGE58
  AH12    GND @T6G_MB_LIB.T6G(SCH_1):GND     I9 @T6G_MB_LIB.T6G(SCH_1):PAGE58
  AH15    GND @T6G_MB_LIB.T6G(SCH_1):GND     I9 @T6G_MB_LIB.T6G(SCH_1):PAGE58
  AH17    GND @T6G_MB_LIB.T6G(SCH_1):GND     I9 @T6G_MB_LIB.T6G(SCH_1):PAGE58
  AH19    GND @T6G_MB_LIB.T6G(SCH_1):GND     I9 @T6G_MB_LIB.T6G(SCH_1):PAGE58
  AH23    GND @T6G_MB_LIB.T6G(SCH_1):GND     I9 @T6G_MB_LIB.T6G(SCH_1):PAGE58
  AH24    GND @T6G_MB_LIB.T6G(SCH_1):GND     I9 @T6G_MB_LIB.T6G(SCH_1):PAGE58
  AH25    GND @T6G_MB_LIB.T6G(SCH_1):GND     I9 @T6G_MB_LIB.T6G(SCH_1):PAGE58
  AH26    GND @T6G_MB_LIB.T6G(SCH_1):GND     I9 @T6G_MB_LIB.T6G(SCH_1):PAGE58
  AH27    GND @T6G_MB_LIB.T6G(SCH_1):GND     I9 @T6G_MB_LIB.T6G(SCH_1):PAGE58
  AH28    GND @T6G_MB_LIB.T6G(SCH_1):GND     I9 @T6G_MB_LIB.T6G(SCH_1):PAGE58
  AH29    GND @T6G_MB_LIB.T6G(SCH_1):GND     I9 @T6G_MB_LIB.T6G(SCH_1):PAGE58
  AH30    GND @T6G_MB_LIB.T6G(SCH_1):GND     I9 @T6G_MB_LIB.T6G(SCH_1):PAGE58
  AH31    GND @T6G_MB_LIB.T6G(SCH_1):GND     I9 @T6G_MB_LIB.T6G(SCH_1):PAGE58
  AH32    GND @T6G_MB_LIB.T6G(SCH_1):GND     I9 @T6G_MB_LIB.T6G(SCH_1):PAGE58
  AH34    GND @T6G_MB_LIB.T6G(SCH_1):GND     I9 @T6G_MB_LIB.T6G(SCH_1):PAGE58
  AH37    GND @T6G_MB_LIB.T6G(SCH_1):GND     I9 @T6G_MB_LIB.T6G(SCH_1):PAGE58
  AH39    GND @T6G_MB_LIB.T6G(SCH_1):GND     I9 @T6G_MB_LIB.T6G(SCH_1):PAGE58
  AH42    GND @T6G_MB_LIB.T6G(SCH_1):GND     I9 @T6G_MB_LIB.T6G(SCH_1):PAGE58
  AH43    GND @T6G_MB_LIB.T6G(SCH_1):GND     I9 @T6G_MB_LIB.T6G(SCH_1):PAGE58
  AH44    GND @T6G_MB_LIB.T6G(SCH_1):GND     I9 @T6G_MB_LIB.T6G(SCH_1):PAGE58
  AH45    GND @T6G_MB_LIB.T6G(SCH_1):GND     I9 @T6G_MB_LIB.T6G(SCH_1):PAGE58
  AH46    GND @T6G_MB_LIB.T6G(SCH_1):GND     I9 @T6G_MB_LIB.T6G(SCH_1):PAGE58
  AH47    GND @T6G_MB_LIB.T6G(SCH_1):GND     I9 @T6G_MB_LIB.T6G(SCH_1):PAGE58
  AH48    GND @T6G_MB_LIB.T6G(SCH_1):GND     I9 @T6G_MB_LIB.T6G(SCH_1):PAGE58
  AH49    GND @T6G_MB_LIB.T6G(SCH_1):GND     I9 @T6G_MB_LIB.T6G(SCH_1):PAGE58
  AH50    GND @T6G_MB_LIB.T6G(SCH_1):GND     I9 @T6G_MB_LIB.T6G(SCH_1):PAGE58
  AH51    GND @T6G_MB_LIB.T6G(SCH_1):GND     I9 @T6G_MB_LIB.T6G(SCH_1):PAGE58
  AH52    GND @T6G_MB_LIB.T6G(SCH_1):GND     I9 @T6G_MB_LIB.T6G(SCH_1):PAGE58
  AH53    GND @T6G_MB_LIB.T6G(SCH_1):GND     I9 @T6G_MB_LIB.T6G(SCH_1):PAGE58
  AH57    GND @T6G_MB_LIB.T6G(SCH_1):GND     I9 @T6G_MB_LIB.T6G(SCH_1):PAGE58
  AH59    GND @T6G_MB_LIB.T6G(SCH_1):GND     I9 @T6G_MB_LIB.T6G(SCH_1):PAGE58
  AH61    GND @T6G_MB_LIB.T6G(SCH_1):GND     I9 @T6G_MB_LIB.T6G(SCH_1):PAGE58
  AH64    GND @T6G_MB_LIB.T6G(SCH_1):GND     I9 @T6G_MB_LIB.T6G(SCH_1):PAGE58
  AH66    GND @T6G_MB_LIB.T6G(SCH_1):GND     I9 @T6G_MB_LIB.T6G(SCH_1):PAGE58
  AH68    GND @T6G_MB_LIB.T6G(SCH_1):GND     I9 @T6G_MB_LIB.T6G(SCH_1):PAGE58
  AH71    GND @T6G_MB_LIB.T6G(SCH_1):GND     I9 @T6G_MB_LIB.T6G(SCH_1):PAGE58
  AH73    GND @T6G_MB_LIB.T6G(SCH_1):GND     I9 @T6G_MB_LIB.T6G(SCH_1):PAGE58
   AJ1    GND @T6G_MB_LIB.T6G(SCH_1):GND     I9 @T6G_MB_LIB.T6G(SCH_1):PAGE58
   AJ6    GND @T6G_MB_LIB.T6G(SCH_1):GND     I9 @T6G_MB_LIB.T6G(SCH_1):PAGE58
   AJ8    GND @T6G_MB_LIB.T6G(SCH_1):GND     I9 @T6G_MB_LIB.T6G(SCH_1):PAGE58
  AJ15    GND @T6G_MB_LIB.T6G(SCH_1):GND     I9 @T6G_MB_LIB.T6G(SCH_1):PAGE58
  AJ20    GND @T6G_MB_LIB.T6G(SCH_1):GND     I9 @T6G_MB_LIB.T6G(SCH_1):PAGE58
  AJ22    GND @T6G_MB_LIB.T6G(SCH_1):GND     I9 @T6G_MB_LIB.T6G(SCH_1):PAGE58
  AJ25    GND @T6G_MB_LIB.T6G(SCH_1):GND     I9 @T6G_MB_LIB.T6G(SCH_1):PAGE58
  AJ28    GND @T6G_MB_LIB.T6G(SCH_1):GND     I9 @T6G_MB_LIB.T6G(SCH_1):PAGE58
  AJ31    GND @T6G_MB_LIB.T6G(SCH_1):GND     I9 @T6G_MB_LIB.T6G(SCH_1):PAGE58
  AJ34    GND @T6G_MB_LIB.T6G(SCH_1):GND     I9 @T6G_MB_LIB.T6G(SCH_1):PAGE58
  AJ35    GND @T6G_MB_LIB.T6G(SCH_1):GND     I9 @T6G_MB_LIB.T6G(SCH_1):PAGE58
  AJ36    GND @T6G_MB_LIB.T6G(SCH_1):GND     I9 @T6G_MB_LIB.T6G(SCH_1):PAGE58
  AJ40    GND @T6G_MB_LIB.T6G(SCH_1):GND     I9 @T6G_MB_LIB.T6G(SCH_1):PAGE58
  AJ41    GND @T6G_MB_LIB.T6G(SCH_1):GND     I9 @T6G_MB_LIB.T6G(SCH_1):PAGE58
  AJ42    GND @T6G_MB_LIB.T6G(SCH_1):GND     I9 @T6G_MB_LIB.T6G(SCH_1):PAGE58
  AJ45    GND @T6G_MB_LIB.T6G(SCH_1):GND     I9 @T6G_MB_LIB.T6G(SCH_1):PAGE58
  AJ48    GND @T6G_MB_LIB.T6G(SCH_1):GND     I9 @T6G_MB_LIB.T6G(SCH_1):PAGE58
  AJ51    GND @T6G_MB_LIB.T6G(SCH_1):GND     I9 @T6G_MB_LIB.T6G(SCH_1):PAGE58
  AJ54    GND @T6G_MB_LIB.T6G(SCH_1):GND     I9 @T6G_MB_LIB.T6G(SCH_1):PAGE58
  AJ56    GND @T6G_MB_LIB.T6G(SCH_1):GND     I9 @T6G_MB_LIB.T6G(SCH_1):PAGE58
  AJ61    GND @T6G_MB_LIB.T6G(SCH_1):GND     I9 @T6G_MB_LIB.T6G(SCH_1):PAGE58
  AJ63    GND @T6G_MB_LIB.T6G(SCH_1):GND     I9 @T6G_MB_LIB.T6G(SCH_1):PAGE58
  AJ68    GND @T6G_MB_LIB.T6G(SCH_1):GND     I9 @T6G_MB_LIB.T6G(SCH_1):PAGE58
  AJ70    GND @T6G_MB_LIB.T6G(SCH_1):GND     I9 @T6G_MB_LIB.T6G(SCH_1):PAGE58
  AJ75    GND @T6G_MB_LIB.T6G(SCH_1):GND     I9 @T6G_MB_LIB.T6G(SCH_1):PAGE58
   AK3    GND @T6G_MB_LIB.T6G(SCH_1):GND     I9 @T6G_MB_LIB.T6G(SCH_1):PAGE58
   AK5    GND @T6G_MB_LIB.T6G(SCH_1):GND     I9 @T6G_MB_LIB.T6G(SCH_1):PAGE58
   AK8    GND @T6G_MB_LIB.T6G(SCH_1):GND     I9 @T6G_MB_LIB.T6G(SCH_1):PAGE58
  AM42    GND @T6G_MB_LIB.T6G(SCH_1):GND     I6 @T6G_MB_LIB.T6G(SCH_1):PAGE58
  AM43    GND @T6G_MB_LIB.T6G(SCH_1):GND     I6 @T6G_MB_LIB.T6G(SCH_1):PAGE58
  AM44    GND @T6G_MB_LIB.T6G(SCH_1):GND     I6 @T6G_MB_LIB.T6G(SCH_1):PAGE58
  AM45    GND @T6G_MB_LIB.T6G(SCH_1):GND     I6 @T6G_MB_LIB.T6G(SCH_1):PAGE58
  AM46    GND @T6G_MB_LIB.T6G(SCH_1):GND     I6 @T6G_MB_LIB.T6G(SCH_1):PAGE58
  AM47    GND @T6G_MB_LIB.T6G(SCH_1):GND     I6 @T6G_MB_LIB.T6G(SCH_1):PAGE58
  AM48    GND @T6G_MB_LIB.T6G(SCH_1):GND     I6 @T6G_MB_LIB.T6G(SCH_1):PAGE58
  AM49    GND @T6G_MB_LIB.T6G(SCH_1):GND     I6 @T6G_MB_LIB.T6G(SCH_1):PAGE58
  AM50    GND @T6G_MB_LIB.T6G(SCH_1):GND     I6 @T6G_MB_LIB.T6G(SCH_1):PAGE58
  AM51    GND @T6G_MB_LIB.T6G(SCH_1):GND     I6 @T6G_MB_LIB.T6G(SCH_1):PAGE58
  AM52    GND @T6G_MB_LIB.T6G(SCH_1):GND     I6 @T6G_MB_LIB.T6G(SCH_1):PAGE58
  AM53    GND @T6G_MB_LIB.T6G(SCH_1):GND     I6 @T6G_MB_LIB.T6G(SCH_1):PAGE58
  AM59    GND @T6G_MB_LIB.T6G(SCH_1):GND     I6 @T6G_MB_LIB.T6G(SCH_1):PAGE58
  AM61    GND @T6G_MB_LIB.T6G(SCH_1):GND     I6 @T6G_MB_LIB.T6G(SCH_1):PAGE58
  AM66    GND @T6G_MB_LIB.T6G(SCH_1):GND     I6 @T6G_MB_LIB.T6G(SCH_1):PAGE58
  AM68    GND @T6G_MB_LIB.T6G(SCH_1):GND     I6 @T6G_MB_LIB.T6G(SCH_1):PAGE58
  AM73    GND @T6G_MB_LIB.T6G(SCH_1):GND     I6 @T6G_MB_LIB.T6G(SCH_1):PAGE58
   AN1    GND @T6G_MB_LIB.T6G(SCH_1):GND     I6 @T6G_MB_LIB.T6G(SCH_1):PAGE58
   AN4    GND @T6G_MB_LIB.T6G(SCH_1):GND     I6 @T6G_MB_LIB.T6G(SCH_1):PAGE58
   AN6    GND @T6G_MB_LIB.T6G(SCH_1):GND     I6 @T6G_MB_LIB.T6G(SCH_1):PAGE58
   AN8    GND @T6G_MB_LIB.T6G(SCH_1):GND     I6 @T6G_MB_LIB.T6G(SCH_1):PAGE58
  AN11    GND @T6G_MB_LIB.T6G(SCH_1):GND     I6 @T6G_MB_LIB.T6G(SCH_1):PAGE58
  AN13    GND @T6G_MB_LIB.T6G(SCH_1):GND     I6 @T6G_MB_LIB.T6G(SCH_1):PAGE58
  AN15    GND @T6G_MB_LIB.T6G(SCH_1):GND     I6 @T6G_MB_LIB.T6G(SCH_1):PAGE58
  AN18    GND @T6G_MB_LIB.T6G(SCH_1):GND     I6 @T6G_MB_LIB.T6G(SCH_1):PAGE58
  AN22    GND @T6G_MB_LIB.T6G(SCH_1):GND     I6 @T6G_MB_LIB.T6G(SCH_1):PAGE58
  AN25    GND @T6G_MB_LIB.T6G(SCH_1):GND     I6 @T6G_MB_LIB.T6G(SCH_1):PAGE58
  AN28    GND @T6G_MB_LIB.T6G(SCH_1):GND     I6 @T6G_MB_LIB.T6G(SCH_1):PAGE58
  AN31    GND @T6G_MB_LIB.T6G(SCH_1):GND     I6 @T6G_MB_LIB.T6G(SCH_1):PAGE58
  AN34    GND @T6G_MB_LIB.T6G(SCH_1):GND     I6 @T6G_MB_LIB.T6G(SCH_1):PAGE58
  AN35    GND @T6G_MB_LIB.T6G(SCH_1):GND     I6 @T6G_MB_LIB.T6G(SCH_1):PAGE58
  AN36    GND @T6G_MB_LIB.T6G(SCH_1):GND     I6 @T6G_MB_LIB.T6G(SCH_1):PAGE58
  AN40    GND @T6G_MB_LIB.T6G(SCH_1):GND     I6 @T6G_MB_LIB.T6G(SCH_1):PAGE58
  AN41    GND @T6G_MB_LIB.T6G(SCH_1):GND     I6 @T6G_MB_LIB.T6G(SCH_1):PAGE58
  AN42    GND @T6G_MB_LIB.T6G(SCH_1):GND     I6 @T6G_MB_LIB.T6G(SCH_1):PAGE58
  AN45    GND @T6G_MB_LIB.T6G(SCH_1):GND     I6 @T6G_MB_LIB.T6G(SCH_1):PAGE58
  AN48    GND @T6G_MB_LIB.T6G(SCH_1):GND     I6 @T6G_MB_LIB.T6G(SCH_1):PAGE58
  AN51    GND @T6G_MB_LIB.T6G(SCH_1):GND     I6 @T6G_MB_LIB.T6G(SCH_1):PAGE58
  AN54    GND @T6G_MB_LIB.T6G(SCH_1):GND     I6 @T6G_MB_LIB.T6G(SCH_1):PAGE58
  AN56    GND @T6G_MB_LIB.T6G(SCH_1):GND     I6 @T6G_MB_LIB.T6G(SCH_1):PAGE58
  AN58    GND @T6G_MB_LIB.T6G(SCH_1):GND     I6 @T6G_MB_LIB.T6G(SCH_1):PAGE58
  AN61    GND @T6G_MB_LIB.T6G(SCH_1):GND     I6 @T6G_MB_LIB.T6G(SCH_1):PAGE58
  AN63    GND @T6G_MB_LIB.T6G(SCH_1):GND     I6 @T6G_MB_LIB.T6G(SCH_1):PAGE58
  AN65    GND @T6G_MB_LIB.T6G(SCH_1):GND     I6 @T6G_MB_LIB.T6G(SCH_1):PAGE58
  AN68    GND @T6G_MB_LIB.T6G(SCH_1):GND     I6 @T6G_MB_LIB.T6G(SCH_1):PAGE58
  AN70    GND @T6G_MB_LIB.T6G(SCH_1):GND     I6 @T6G_MB_LIB.T6G(SCH_1):PAGE58
  AN72    GND @T6G_MB_LIB.T6G(SCH_1):GND     I6 @T6G_MB_LIB.T6G(SCH_1):PAGE58
  AN75    GND @T6G_MB_LIB.T6G(SCH_1):GND     I6 @T6G_MB_LIB.T6G(SCH_1):PAGE58
   AP3    GND @T6G_MB_LIB.T6G(SCH_1):GND     I6 @T6G_MB_LIB.T6G(SCH_1):PAGE58
   AP5    GND @T6G_MB_LIB.T6G(SCH_1):GND     I6 @T6G_MB_LIB.T6G(SCH_1):PAGE58
   AP8    GND @T6G_MB_LIB.T6G(SCH_1):GND     I6 @T6G_MB_LIB.T6G(SCH_1):PAGE58
  AP10    GND @T6G_MB_LIB.T6G(SCH_1):GND     I6 @T6G_MB_LIB.T6G(SCH_1):PAGE58
  AP12    GND @T6G_MB_LIB.T6G(SCH_1):GND     I6 @T6G_MB_LIB.T6G(SCH_1):PAGE58
  AP15    GND @T6G_MB_LIB.T6G(SCH_1):GND     I6 @T6G_MB_LIB.T6G(SCH_1):PAGE58
  AP17    GND @T6G_MB_LIB.T6G(SCH_1):GND     I6 @T6G_MB_LIB.T6G(SCH_1):PAGE58
  AP19    GND @T6G_MB_LIB.T6G(SCH_1):GND     I6 @T6G_MB_LIB.T6G(SCH_1):PAGE58
  AP22    GND @T6G_MB_LIB.T6G(SCH_1):GND     I6 @T6G_MB_LIB.T6G(SCH_1):PAGE58
  AP25    GND @T6G_MB_LIB.T6G(SCH_1):GND     I6 @T6G_MB_LIB.T6G(SCH_1):PAGE58
  AP28    GND @T6G_MB_LIB.T6G(SCH_1):GND     I6 @T6G_MB_LIB.T6G(SCH_1):PAGE58
  AP31    GND @T6G_MB_LIB.T6G(SCH_1):GND     I6 @T6G_MB_LIB.T6G(SCH_1):PAGE58
  AP34    GND @T6G_MB_LIB.T6G(SCH_1):GND     I6 @T6G_MB_LIB.T6G(SCH_1):PAGE58
  AP37    GND @T6G_MB_LIB.T6G(SCH_1):GND     I6 @T6G_MB_LIB.T6G(SCH_1):PAGE58
  AP39    GND @T6G_MB_LIB.T6G(SCH_1):GND     I6 @T6G_MB_LIB.T6G(SCH_1):PAGE58
  AP42    GND @T6G_MB_LIB.T6G(SCH_1):GND     I6 @T6G_MB_LIB.T6G(SCH_1):PAGE58
  AP45    GND @T6G_MB_LIB.T6G(SCH_1):GND     I6 @T6G_MB_LIB.T6G(SCH_1):PAGE58
  AP48    GND @T6G_MB_LIB.T6G(SCH_1):GND     I6 @T6G_MB_LIB.T6G(SCH_1):PAGE58
  AP51    GND @T6G_MB_LIB.T6G(SCH_1):GND     I6 @T6G_MB_LIB.T6G(SCH_1):PAGE58
  AP54    GND @T6G_MB_LIB.T6G(SCH_1):GND     I6 @T6G_MB_LIB.T6G(SCH_1):PAGE58
  AP57    GND @T6G_MB_LIB.T6G(SCH_1):GND     I6 @T6G_MB_LIB.T6G(SCH_1):PAGE58
  AP59    GND @T6G_MB_LIB.T6G(SCH_1):GND     I6 @T6G_MB_LIB.T6G(SCH_1):PAGE58
  AP61    GND @T6G_MB_LIB.T6G(SCH_1):GND     I6 @T6G_MB_LIB.T6G(SCH_1):PAGE58
  AP64    GND @T6G_MB_LIB.T6G(SCH_1):GND     I6 @T6G_MB_LIB.T6G(SCH_1):PAGE58
  AP66    GND @T6G_MB_LIB.T6G(SCH_1):GND     I6 @T6G_MB_LIB.T6G(SCH_1):PAGE58
  AP68    GND @T6G_MB_LIB.T6G(SCH_1):GND     I6 @T6G_MB_LIB.T6G(SCH_1):PAGE58
  AP71    GND @T6G_MB_LIB.T6G(SCH_1):GND     I6 @T6G_MB_LIB.T6G(SCH_1):PAGE58
  AP73    GND @T6G_MB_LIB.T6G(SCH_1):GND     I6 @T6G_MB_LIB.T6G(SCH_1):PAGE58
   AR1    GND @T6G_MB_LIB.T6G(SCH_1):GND     I6 @T6G_MB_LIB.T6G(SCH_1):PAGE58
   AR5    GND @T6G_MB_LIB.T6G(SCH_1):GND     I6 @T6G_MB_LIB.T6G(SCH_1):PAGE58
   AR6    GND @T6G_MB_LIB.T6G(SCH_1):GND     I6 @T6G_MB_LIB.T6G(SCH_1):PAGE58
   AR8    GND @T6G_MB_LIB.T6G(SCH_1):GND     I6 @T6G_MB_LIB.T6G(SCH_1):PAGE58
   AR9    GND @T6G_MB_LIB.T6G(SCH_1):GND     I6 @T6G_MB_LIB.T6G(SCH_1):PAGE58
  AR12    GND @T6G_MB_LIB.T6G(SCH_1):GND     I6 @T6G_MB_LIB.T6G(SCH_1):PAGE58
  AR13    GND @T6G_MB_LIB.T6G(SCH_1):GND     I6 @T6G_MB_LIB.T6G(SCH_1):PAGE58
  AR15    GND @T6G_MB_LIB.T6G(SCH_1):GND     I6 @T6G_MB_LIB.T6G(SCH_1):PAGE58
  AR16    GND @T6G_MB_LIB.T6G(SCH_1):GND     I6 @T6G_MB_LIB.T6G(SCH_1):PAGE58
  AR19    GND @T6G_MB_LIB.T6G(SCH_1):GND     I6 @T6G_MB_LIB.T6G(SCH_1):PAGE58
  AR20    GND @T6G_MB_LIB.T6G(SCH_1):GND     I6 @T6G_MB_LIB.T6G(SCH_1):PAGE58
  AR22    GND @T6G_MB_LIB.T6G(SCH_1):GND     I6 @T6G_MB_LIB.T6G(SCH_1):PAGE58
  AR24    GND @T6G_MB_LIB.T6G(SCH_1):GND     I6 @T6G_MB_LIB.T6G(SCH_1):PAGE58
  AR26    GND @T6G_MB_LIB.T6G(SCH_1):GND     I6 @T6G_MB_LIB.T6G(SCH_1):PAGE58
  AR28    GND @T6G_MB_LIB.T6G(SCH_1):GND     I6 @T6G_MB_LIB.T6G(SCH_1):PAGE58
  AR30    GND @T6G_MB_LIB.T6G(SCH_1):GND     I6 @T6G_MB_LIB.T6G(SCH_1):PAGE58
  AR32    GND @T6G_MB_LIB.T6G(SCH_1):GND     I6 @T6G_MB_LIB.T6G(SCH_1):PAGE58
  AR34    GND @T6G_MB_LIB.T6G(SCH_1):GND     I6 @T6G_MB_LIB.T6G(SCH_1):PAGE58
  AR36    GND @T6G_MB_LIB.T6G(SCH_1):GND     I6 @T6G_MB_LIB.T6G(SCH_1):PAGE58
  AR41    GND @T6G_MB_LIB.T6G(SCH_1):GND     I6 @T6G_MB_LIB.T6G(SCH_1):PAGE58
  AR43    GND @T6G_MB_LIB.T6G(SCH_1):GND     I6 @T6G_MB_LIB.T6G(SCH_1):PAGE58
  AR45    GND @T6G_MB_LIB.T6G(SCH_1):GND     I6 @T6G_MB_LIB.T6G(SCH_1):PAGE58
  AR47    GND @T6G_MB_LIB.T6G(SCH_1):GND     I6 @T6G_MB_LIB.T6G(SCH_1):PAGE58
  AR49    GND @T6G_MB_LIB.T6G(SCH_1):GND     I6 @T6G_MB_LIB.T6G(SCH_1):PAGE58
  AR51    GND @T6G_MB_LIB.T6G(SCH_1):GND     I6 @T6G_MB_LIB.T6G(SCH_1):PAGE58
  AR53    GND @T6G_MB_LIB.T6G(SCH_1):GND     I6 @T6G_MB_LIB.T6G(SCH_1):PAGE58
  AR56    GND @T6G_MB_LIB.T6G(SCH_1):GND     I6 @T6G_MB_LIB.T6G(SCH_1):PAGE58
  AR57    GND @T6G_MB_LIB.T6G(SCH_1):GND     I6 @T6G_MB_LIB.T6G(SCH_1):PAGE58
  AR60    GND @T6G_MB_LIB.T6G(SCH_1):GND     I6 @T6G_MB_LIB.T6G(SCH_1):PAGE58
  AR61    GND @T6G_MB_LIB.T6G(SCH_1):GND     I6 @T6G_MB_LIB.T6G(SCH_1):PAGE58
  AR63    GND @T6G_MB_LIB.T6G(SCH_1):GND     I6 @T6G_MB_LIB.T6G(SCH_1):PAGE58
  AR64    GND @T6G_MB_LIB.T6G(SCH_1):GND     I6 @T6G_MB_LIB.T6G(SCH_1):PAGE58
  AR67    GND @T6G_MB_LIB.T6G(SCH_1):GND     I6 @T6G_MB_LIB.T6G(SCH_1):PAGE58
  AR68    GND @T6G_MB_LIB.T6G(SCH_1):GND     I6 @T6G_MB_LIB.T6G(SCH_1):PAGE58
  AR70    GND @T6G_MB_LIB.T6G(SCH_1):GND     I6 @T6G_MB_LIB.T6G(SCH_1):PAGE58
  AR71    GND @T6G_MB_LIB.T6G(SCH_1):GND     I6 @T6G_MB_LIB.T6G(SCH_1):PAGE58
  AR75    GND @T6G_MB_LIB.T6G(SCH_1):GND     I6 @T6G_MB_LIB.T6G(SCH_1):PAGE58
   AT3    GND @T6G_MB_LIB.T6G(SCH_1):GND     I6 @T6G_MB_LIB.T6G(SCH_1):PAGE58
   AT4    GND @T6G_MB_LIB.T6G(SCH_1):GND     I6 @T6G_MB_LIB.T6G(SCH_1):PAGE58
   AT5    GND @T6G_MB_LIB.T6G(SCH_1):GND     I6 @T6G_MB_LIB.T6G(SCH_1):PAGE58
   AT6    GND @T6G_MB_LIB.T6G(SCH_1):GND     I6 @T6G_MB_LIB.T6G(SCH_1):PAGE58
   AT8    GND @T6G_MB_LIB.T6G(SCH_1):GND     I6 @T6G_MB_LIB.T6G(SCH_1):PAGE58
   AT9    GND @T6G_MB_LIB.T6G(SCH_1):GND     I6 @T6G_MB_LIB.T6G(SCH_1):PAGE58
  AT10    GND @T6G_MB_LIB.T6G(SCH_1):GND     I6 @T6G_MB_LIB.T6G(SCH_1):PAGE58
  AT12    GND @T6G_MB_LIB.T6G(SCH_1):GND     I6 @T6G_MB_LIB.T6G(SCH_1):PAGE58
  AT13    GND @T6G_MB_LIB.T6G(SCH_1):GND     I6 @T6G_MB_LIB.T6G(SCH_1):PAGE58
  AT15    GND @T6G_MB_LIB.T6G(SCH_1):GND     I6 @T6G_MB_LIB.T6G(SCH_1):PAGE58
  AT16    GND @T6G_MB_LIB.T6G(SCH_1):GND     I6 @T6G_MB_LIB.T6G(SCH_1):PAGE58
  AT17    GND @T6G_MB_LIB.T6G(SCH_1):GND     I6 @T6G_MB_LIB.T6G(SCH_1):PAGE58
  AT19    GND @T6G_MB_LIB.T6G(SCH_1):GND     I6 @T6G_MB_LIB.T6G(SCH_1):PAGE58
  AT20    GND @T6G_MB_LIB.T6G(SCH_1):GND     I6 @T6G_MB_LIB.T6G(SCH_1):PAGE58
  AT23    GND @T6G_MB_LIB.T6G(SCH_1):GND     I6 @T6G_MB_LIB.T6G(SCH_1):PAGE58
  AT25    GND @T6G_MB_LIB.T6G(SCH_1):GND     I6 @T6G_MB_LIB.T6G(SCH_1):PAGE58
  AT27    GND @T6G_MB_LIB.T6G(SCH_1):GND     I6 @T6G_MB_LIB.T6G(SCH_1):PAGE58
  AT29    GND @T6G_MB_LIB.T6G(SCH_1):GND     I6 @T6G_MB_LIB.T6G(SCH_1):PAGE58
  AT31    GND @T6G_MB_LIB.T6G(SCH_1):GND     I6 @T6G_MB_LIB.T6G(SCH_1):PAGE58
  AT33    GND @T6G_MB_LIB.T6G(SCH_1):GND     I6 @T6G_MB_LIB.T6G(SCH_1):PAGE58
  AT35    GND @T6G_MB_LIB.T6G(SCH_1):GND     I6 @T6G_MB_LIB.T6G(SCH_1):PAGE58
  AT37    GND @T6G_MB_LIB.T6G(SCH_1):GND     I6 @T6G_MB_LIB.T6G(SCH_1):PAGE58
  AT40    GND @T6G_MB_LIB.T6G(SCH_1):GND     I6 @T6G_MB_LIB.T6G(SCH_1):PAGE58
  AT42    GND @T6G_MB_LIB.T6G(SCH_1):GND     I6 @T6G_MB_LIB.T6G(SCH_1):PAGE58
  AT44    GND @T6G_MB_LIB.T6G(SCH_1):GND     I6 @T6G_MB_LIB.T6G(SCH_1):PAGE58
  AT46    GND @T6G_MB_LIB.T6G(SCH_1):GND     I6 @T6G_MB_LIB.T6G(SCH_1):PAGE58
  AT48    GND @T6G_MB_LIB.T6G(SCH_1):GND     I6 @T6G_MB_LIB.T6G(SCH_1):PAGE58
  AT50    GND @T6G_MB_LIB.T6G(SCH_1):GND     I6 @T6G_MB_LIB.T6G(SCH_1):PAGE58
  AT52    GND @T6G_MB_LIB.T6G(SCH_1):GND     I6 @T6G_MB_LIB.T6G(SCH_1):PAGE58
  AT54    GND @T6G_MB_LIB.T6G(SCH_1):GND     I6 @T6G_MB_LIB.T6G(SCH_1):PAGE58
  AT56    GND @T6G_MB_LIB.T6G(SCH_1):GND     I6 @T6G_MB_LIB.T6G(SCH_1):PAGE58
  AT57    GND @T6G_MB_LIB.T6G(SCH_1):GND     I6 @T6G_MB_LIB.T6G(SCH_1):PAGE58
  AT59    GND @T6G_MB_LIB.T6G(SCH_1):GND     I6 @T6G_MB_LIB.T6G(SCH_1):PAGE58
  AT60    GND @T6G_MB_LIB.T6G(SCH_1):GND     I6 @T6G_MB_LIB.T6G(SCH_1):PAGE58
  AT61    GND @T6G_MB_LIB.T6G(SCH_1):GND     I6 @T6G_MB_LIB.T6G(SCH_1):PAGE58
  AT63    GND @T6G_MB_LIB.T6G(SCH_1):GND     I6 @T6G_MB_LIB.T6G(SCH_1):PAGE58
  AT64    GND @T6G_MB_LIB.T6G(SCH_1):GND     I6 @T6G_MB_LIB.T6G(SCH_1):PAGE58
  AT66    GND @T6G_MB_LIB.T6G(SCH_1):GND     I6 @T6G_MB_LIB.T6G(SCH_1):PAGE58
  AT67    GND @T6G_MB_LIB.T6G(SCH_1):GND     I6 @T6G_MB_LIB.T6G(SCH_1):PAGE58
  AT68    GND @T6G_MB_LIB.T6G(SCH_1):GND     I6 @T6G_MB_LIB.T6G(SCH_1):PAGE58
  AT70    GND @T6G_MB_LIB.T6G(SCH_1):GND     I6 @T6G_MB_LIB.T6G(SCH_1):PAGE58
  AT71    GND @T6G_MB_LIB.T6G(SCH_1):GND     I6 @T6G_MB_LIB.T6G(SCH_1):PAGE58
  AT72    GND @T6G_MB_LIB.T6G(SCH_1):GND     I6 @T6G_MB_LIB.T6G(SCH_1):PAGE58
  AT73    GND @T6G_MB_LIB.T6G(SCH_1):GND     I6 @T6G_MB_LIB.T6G(SCH_1):PAGE58
   AU1    GND @T6G_MB_LIB.T6G(SCH_1):GND     I6 @T6G_MB_LIB.T6G(SCH_1):PAGE58
   AU3    GND @T6G_MB_LIB.T6G(SCH_1):GND     I6 @T6G_MB_LIB.T6G(SCH_1):PAGE58
   AU4    GND @T6G_MB_LIB.T6G(SCH_1):GND     I6 @T6G_MB_LIB.T6G(SCH_1):PAGE58
   AU6    GND @T6G_MB_LIB.T6G(SCH_1):GND     I6 @T6G_MB_LIB.T6G(SCH_1):PAGE58
   AU8    GND @T6G_MB_LIB.T6G(SCH_1):GND     I6 @T6G_MB_LIB.T6G(SCH_1):PAGE58
  AU11    GND @T6G_MB_LIB.T6G(SCH_1):GND     I6 @T6G_MB_LIB.T6G(SCH_1):PAGE58
  AU13    GND @T6G_MB_LIB.T6G(SCH_1):GND     I6 @T6G_MB_LIB.T6G(SCH_1):PAGE58
  AU15    GND @T6G_MB_LIB.T6G(SCH_1):GND     I6 @T6G_MB_LIB.T6G(SCH_1):PAGE58
  AU18    GND @T6G_MB_LIB.T6G(SCH_1):GND     I6 @T6G_MB_LIB.T6G(SCH_1):PAGE58
  AU20    GND @T6G_MB_LIB.T6G(SCH_1):GND     I6 @T6G_MB_LIB.T6G(SCH_1):PAGE58
  AU22    GND @T6G_MB_LIB.T6G(SCH_1):GND     I6 @T6G_MB_LIB.T6G(SCH_1):PAGE58
  AU24    GND @T6G_MB_LIB.T6G(SCH_1):GND     I6 @T6G_MB_LIB.T6G(SCH_1):PAGE58
  AU26    GND @T6G_MB_LIB.T6G(SCH_1):GND     I6 @T6G_MB_LIB.T6G(SCH_1):PAGE58
  AU28    GND @T6G_MB_LIB.T6G(SCH_1):GND     I6 @T6G_MB_LIB.T6G(SCH_1):PAGE58
  AU30    GND @T6G_MB_LIB.T6G(SCH_1):GND     I6 @T6G_MB_LIB.T6G(SCH_1):PAGE58
  AU32    GND @T6G_MB_LIB.T6G(SCH_1):GND     I6 @T6G_MB_LIB.T6G(SCH_1):PAGE58
  AU34    GND @T6G_MB_LIB.T6G(SCH_1):GND     I6 @T6G_MB_LIB.T6G(SCH_1):PAGE58
  AU36    GND @T6G_MB_LIB.T6G(SCH_1):GND     I6 @T6G_MB_LIB.T6G(SCH_1):PAGE58
  AU41    GND @T6G_MB_LIB.T6G(SCH_1):GND     I6 @T6G_MB_LIB.T6G(SCH_1):PAGE58
  AU43    GND @T6G_MB_LIB.T6G(SCH_1):GND     I6 @T6G_MB_LIB.T6G(SCH_1):PAGE58
  AU45    GND @T6G_MB_LIB.T6G(SCH_1):GND     I6 @T6G_MB_LIB.T6G(SCH_1):PAGE58
  AU47    GND @T6G_MB_LIB.T6G(SCH_1):GND     I6 @T6G_MB_LIB.T6G(SCH_1):PAGE58
  AU49    GND @T6G_MB_LIB.T6G(SCH_1):GND     I6 @T6G_MB_LIB.T6G(SCH_1):PAGE58
  AU51    GND @T6G_MB_LIB.T6G(SCH_1):GND     I6 @T6G_MB_LIB.T6G(SCH_1):PAGE58
  AU53    GND @T6G_MB_LIB.T6G(SCH_1):GND     I6 @T6G_MB_LIB.T6G(SCH_1):PAGE58
  AU56    GND @T6G_MB_LIB.T6G(SCH_1):GND     I6 @T6G_MB_LIB.T6G(SCH_1):PAGE58
  AU58    GND @T6G_MB_LIB.T6G(SCH_1):GND     I6 @T6G_MB_LIB.T6G(SCH_1):PAGE58
  AU61    GND @T6G_MB_LIB.T6G(SCH_1):GND     I6 @T6G_MB_LIB.T6G(SCH_1):PAGE58
  AU63    GND @T6G_MB_LIB.T6G(SCH_1):GND     I6 @T6G_MB_LIB.T6G(SCH_1):PAGE58
  AU65    GND @T6G_MB_LIB.T6G(SCH_1):GND     I6 @T6G_MB_LIB.T6G(SCH_1):PAGE58
  AU68    GND @T6G_MB_LIB.T6G(SCH_1):GND     I6 @T6G_MB_LIB.T6G(SCH_1):PAGE58
  AU70    GND @T6G_MB_LIB.T6G(SCH_1):GND     I6 @T6G_MB_LIB.T6G(SCH_1):PAGE58
  AU72    GND @T6G_MB_LIB.T6G(SCH_1):GND     I6 @T6G_MB_LIB.T6G(SCH_1):PAGE58
  AU73    GND @T6G_MB_LIB.T6G(SCH_1):GND     I6 @T6G_MB_LIB.T6G(SCH_1):PAGE58
  AU75    GND @T6G_MB_LIB.T6G(SCH_1):GND     I6 @T6G_MB_LIB.T6G(SCH_1):PAGE58
   AV3    GND @T6G_MB_LIB.T6G(SCH_1):GND     I6 @T6G_MB_LIB.T6G(SCH_1):PAGE58
   AV8    GND @T6G_MB_LIB.T6G(SCH_1):GND     I6 @T6G_MB_LIB.T6G(SCH_1):PAGE58
  AV10    GND @T6G_MB_LIB.T6G(SCH_1):GND     I6 @T6G_MB_LIB.T6G(SCH_1):PAGE58
  AV15    GND @T6G_MB_LIB.T6G(SCH_1):GND     I6 @T6G_MB_LIB.T6G(SCH_1):PAGE58
  AV17    GND @T6G_MB_LIB.T6G(SCH_1):GND     I6 @T6G_MB_LIB.T6G(SCH_1):PAGE58
  AV23    GND @T6G_MB_LIB.T6G(SCH_1):GND     I6 @T6G_MB_LIB.T6G(SCH_1):PAGE58
  AV25    GND @T6G_MB_LIB.T6G(SCH_1):GND     I6 @T6G_MB_LIB.T6G(SCH_1):PAGE58
  AV27    GND @T6G_MB_LIB.T6G(SCH_1):GND     I6 @T6G_MB_LIB.T6G(SCH_1):PAGE58
  AV29    GND @T6G_MB_LIB.T6G(SCH_1):GND     I6 @T6G_MB_LIB.T6G(SCH_1):PAGE58
  AV31    GND @T6G_MB_LIB.T6G(SCH_1):GND     I6 @T6G_MB_LIB.T6G(SCH_1):PAGE58
  AV33    GND @T6G_MB_LIB.T6G(SCH_1):GND     I6 @T6G_MB_LIB.T6G(SCH_1):PAGE58
  AV35    GND @T6G_MB_LIB.T6G(SCH_1):GND     I6 @T6G_MB_LIB.T6G(SCH_1):PAGE58
  AV37    GND @T6G_MB_LIB.T6G(SCH_1):GND     I6 @T6G_MB_LIB.T6G(SCH_1):PAGE58
  AV40    GND @T6G_MB_LIB.T6G(SCH_1):GND     I6 @T6G_MB_LIB.T6G(SCH_1):PAGE58
  AV42    GND @T6G_MB_LIB.T6G(SCH_1):GND     I6 @T6G_MB_LIB.T6G(SCH_1):PAGE58
  AV44    GND @T6G_MB_LIB.T6G(SCH_1):GND     I6 @T6G_MB_LIB.T6G(SCH_1):PAGE58
  AV46    GND @T6G_MB_LIB.T6G(SCH_1):GND     I6 @T6G_MB_LIB.T6G(SCH_1):PAGE58
  AV48    GND @T6G_MB_LIB.T6G(SCH_1):GND     I6 @T6G_MB_LIB.T6G(SCH_1):PAGE58
  AV50    GND @T6G_MB_LIB.T6G(SCH_1):GND     I6 @T6G_MB_LIB.T6G(SCH_1):PAGE58
  AV52    GND @T6G_MB_LIB.T6G(SCH_1):GND     I6 @T6G_MB_LIB.T6G(SCH_1):PAGE58
  AV54    GND @T6G_MB_LIB.T6G(SCH_1):GND     I6 @T6G_MB_LIB.T6G(SCH_1):PAGE58
  AV59    GND @T6G_MB_LIB.T6G(SCH_1):GND     I6 @T6G_MB_LIB.T6G(SCH_1):PAGE58
  AV61    GND @T6G_MB_LIB.T6G(SCH_1):GND     I6 @T6G_MB_LIB.T6G(SCH_1):PAGE58
  AV66    GND @T6G_MB_LIB.T6G(SCH_1):GND     I6 @T6G_MB_LIB.T6G(SCH_1):PAGE58
  AV68    GND @T6G_MB_LIB.T6G(SCH_1):GND     I6 @T6G_MB_LIB.T6G(SCH_1):PAGE58
  AV73    GND @T6G_MB_LIB.T6G(SCH_1):GND     I6 @T6G_MB_LIB.T6G(SCH_1):PAGE58
   AW1    GND @T6G_MB_LIB.T6G(SCH_1):GND     I6 @T6G_MB_LIB.T6G(SCH_1):PAGE58
   AW4    GND @T6G_MB_LIB.T6G(SCH_1):GND     I6 @T6G_MB_LIB.T6G(SCH_1):PAGE58
   AW6    GND @T6G_MB_LIB.T6G(SCH_1):GND     I6 @T6G_MB_LIB.T6G(SCH_1):PAGE58
   AW8    GND @T6G_MB_LIB.T6G(SCH_1):GND     I6 @T6G_MB_LIB.T6G(SCH_1):PAGE58
  AW11    GND @T6G_MB_LIB.T6G(SCH_1):GND     I6 @T6G_MB_LIB.T6G(SCH_1):PAGE58
  AW13    GND @T6G_MB_LIB.T6G(SCH_1):GND     I6 @T6G_MB_LIB.T6G(SCH_1):PAGE58
  AW15    GND @T6G_MB_LIB.T6G(SCH_1):GND     I6 @T6G_MB_LIB.T6G(SCH_1):PAGE58
  AW18    GND @T6G_MB_LIB.T6G(SCH_1):GND     I6 @T6G_MB_LIB.T6G(SCH_1):PAGE58
  AW20    GND @T6G_MB_LIB.T6G(SCH_1):GND     I6 @T6G_MB_LIB.T6G(SCH_1):PAGE58
  AW22    GND @T6G_MB_LIB.T6G(SCH_1):GND     I6 @T6G_MB_LIB.T6G(SCH_1):PAGE58
  AW24    GND @T6G_MB_LIB.T6G(SCH_1):GND     I6 @T6G_MB_LIB.T6G(SCH_1):PAGE58
  AW26    GND @T6G_MB_LIB.T6G(SCH_1):GND     I6 @T6G_MB_LIB.T6G(SCH_1):PAGE58
  AW28    GND @T6G_MB_LIB.T6G(SCH_1):GND     I6 @T6G_MB_LIB.T6G(SCH_1):PAGE58
  AW49    GND @T6G_MB_LIB.T6G(SCH_1):GND     I6 @T6G_MB_LIB.T6G(SCH_1):PAGE58
  AW51    GND @T6G_MB_LIB.T6G(SCH_1):GND     I6 @T6G_MB_LIB.T6G(SCH_1):PAGE58
  AW53    GND @T6G_MB_LIB.T6G(SCH_1):GND     I6 @T6G_MB_LIB.T6G(SCH_1):PAGE58
  AW56    GND @T6G_MB_LIB.T6G(SCH_1):GND     I6 @T6G_MB_LIB.T6G(SCH_1):PAGE58
  AW58    GND @T6G_MB_LIB.T6G(SCH_1):GND     I6 @T6G_MB_LIB.T6G(SCH_1):PAGE58
  AW61    GND @T6G_MB_LIB.T6G(SCH_1):GND     I6 @T6G_MB_LIB.T6G(SCH_1):PAGE58
  AW63    GND @T6G_MB_LIB.T6G(SCH_1):GND     I3 @T6G_MB_LIB.T6G(SCH_1):PAGE58
  AW65    GND @T6G_MB_LIB.T6G(SCH_1):GND     I3 @T6G_MB_LIB.T6G(SCH_1):PAGE58
  AW68    GND @T6G_MB_LIB.T6G(SCH_1):GND     I3 @T6G_MB_LIB.T6G(SCH_1):PAGE58
  AW70    GND @T6G_MB_LIB.T6G(SCH_1):GND     I3 @T6G_MB_LIB.T6G(SCH_1):PAGE58
  AW72    GND @T6G_MB_LIB.T6G(SCH_1):GND     I3 @T6G_MB_LIB.T6G(SCH_1):PAGE58
  AW75    GND @T6G_MB_LIB.T6G(SCH_1):GND     I3 @T6G_MB_LIB.T6G(SCH_1):PAGE58
   AY3    GND @T6G_MB_LIB.T6G(SCH_1):GND     I3 @T6G_MB_LIB.T6G(SCH_1):PAGE58
   AY5    GND @T6G_MB_LIB.T6G(SCH_1):GND     I3 @T6G_MB_LIB.T6G(SCH_1):PAGE58
   AY8    GND @T6G_MB_LIB.T6G(SCH_1):GND     I3 @T6G_MB_LIB.T6G(SCH_1):PAGE58
  AY10    GND @T6G_MB_LIB.T6G(SCH_1):GND     I3 @T6G_MB_LIB.T6G(SCH_1):PAGE58
  AY12    GND @T6G_MB_LIB.T6G(SCH_1):GND     I3 @T6G_MB_LIB.T6G(SCH_1):PAGE58
  AY15    GND @T6G_MB_LIB.T6G(SCH_1):GND     I3 @T6G_MB_LIB.T6G(SCH_1):PAGE58
  AY17    GND @T6G_MB_LIB.T6G(SCH_1):GND     I3 @T6G_MB_LIB.T6G(SCH_1):PAGE58
  AY19    GND @T6G_MB_LIB.T6G(SCH_1):GND     I3 @T6G_MB_LIB.T6G(SCH_1):PAGE58
  AY23    GND @T6G_MB_LIB.T6G(SCH_1):GND     I3 @T6G_MB_LIB.T6G(SCH_1):PAGE58
  AY25    GND @T6G_MB_LIB.T6G(SCH_1):GND     I3 @T6G_MB_LIB.T6G(SCH_1):PAGE58
  AY27    GND @T6G_MB_LIB.T6G(SCH_1):GND     I3 @T6G_MB_LIB.T6G(SCH_1):PAGE58
  AY48    GND @T6G_MB_LIB.T6G(SCH_1):GND     I3 @T6G_MB_LIB.T6G(SCH_1):PAGE58
  AY50    GND @T6G_MB_LIB.T6G(SCH_1):GND     I3 @T6G_MB_LIB.T6G(SCH_1):PAGE58
  AY52    GND @T6G_MB_LIB.T6G(SCH_1):GND     I3 @T6G_MB_LIB.T6G(SCH_1):PAGE58
  AY54    GND @T6G_MB_LIB.T6G(SCH_1):GND     I3 @T6G_MB_LIB.T6G(SCH_1):PAGE58
  AY57    GND @T6G_MB_LIB.T6G(SCH_1):GND     I3 @T6G_MB_LIB.T6G(SCH_1):PAGE58
  AY59    GND @T6G_MB_LIB.T6G(SCH_1):GND     I3 @T6G_MB_LIB.T6G(SCH_1):PAGE58
  AY61    GND @T6G_MB_LIB.T6G(SCH_1):GND     I3 @T6G_MB_LIB.T6G(SCH_1):PAGE58
  AY64    GND @T6G_MB_LIB.T6G(SCH_1):GND     I3 @T6G_MB_LIB.T6G(SCH_1):PAGE58
  AY66    GND @T6G_MB_LIB.T6G(SCH_1):GND     I3 @T6G_MB_LIB.T6G(SCH_1):PAGE58
  AY68    GND @T6G_MB_LIB.T6G(SCH_1):GND     I3 @T6G_MB_LIB.T6G(SCH_1):PAGE58
  AY71    GND @T6G_MB_LIB.T6G(SCH_1):GND     I3 @T6G_MB_LIB.T6G(SCH_1):PAGE58
  AY73    GND @T6G_MB_LIB.T6G(SCH_1):GND     I3 @T6G_MB_LIB.T6G(SCH_1):PAGE58
   BA1    GND @T6G_MB_LIB.T6G(SCH_1):GND     I3 @T6G_MB_LIB.T6G(SCH_1):PAGE58
   BA6    GND @T6G_MB_LIB.T6G(SCH_1):GND     I3 @T6G_MB_LIB.T6G(SCH_1):PAGE58
   BA8    GND @T6G_MB_LIB.T6G(SCH_1):GND     I3 @T6G_MB_LIB.T6G(SCH_1):PAGE58
  BA13    GND @T6G_MB_LIB.T6G(SCH_1):GND     I3 @T6G_MB_LIB.T6G(SCH_1):PAGE58
  BA15    GND @T6G_MB_LIB.T6G(SCH_1):GND     I3 @T6G_MB_LIB.T6G(SCH_1):PAGE58
  BA20    GND @T6G_MB_LIB.T6G(SCH_1):GND     I3 @T6G_MB_LIB.T6G(SCH_1):PAGE58
  BA22    GND @T6G_MB_LIB.T6G(SCH_1):GND     I3 @T6G_MB_LIB.T6G(SCH_1):PAGE58
  BA24    GND @T6G_MB_LIB.T6G(SCH_1):GND     I3 @T6G_MB_LIB.T6G(SCH_1):PAGE58
  BA26    GND @T6G_MB_LIB.T6G(SCH_1):GND     I3 @T6G_MB_LIB.T6G(SCH_1):PAGE58
  BA28    GND @T6G_MB_LIB.T6G(SCH_1):GND     I3 @T6G_MB_LIB.T6G(SCH_1):PAGE58
  BA49    GND @T6G_MB_LIB.T6G(SCH_1):GND     I3 @T6G_MB_LIB.T6G(SCH_1):PAGE58
  BA51    GND @T6G_MB_LIB.T6G(SCH_1):GND     I3 @T6G_MB_LIB.T6G(SCH_1):PAGE58
  BA53    GND @T6G_MB_LIB.T6G(SCH_1):GND     I3 @T6G_MB_LIB.T6G(SCH_1):PAGE58
  BA56    GND @T6G_MB_LIB.T6G(SCH_1):GND     I3 @T6G_MB_LIB.T6G(SCH_1):PAGE58
  BA61    GND @T6G_MB_LIB.T6G(SCH_1):GND     I3 @T6G_MB_LIB.T6G(SCH_1):PAGE58
  BA63    GND @T6G_MB_LIB.T6G(SCH_1):GND     I3 @T6G_MB_LIB.T6G(SCH_1):PAGE58
  BA68    GND @T6G_MB_LIB.T6G(SCH_1):GND     I3 @T6G_MB_LIB.T6G(SCH_1):PAGE58
  BA70    GND @T6G_MB_LIB.T6G(SCH_1):GND     I3 @T6G_MB_LIB.T6G(SCH_1):PAGE58
  BA75    GND @T6G_MB_LIB.T6G(SCH_1):GND     I3 @T6G_MB_LIB.T6G(SCH_1):PAGE58
   BB3    GND @T6G_MB_LIB.T6G(SCH_1):GND     I3 @T6G_MB_LIB.T6G(SCH_1):PAGE58
   BB5    GND @T6G_MB_LIB.T6G(SCH_1):GND     I3 @T6G_MB_LIB.T6G(SCH_1):PAGE58
   BB8    GND @T6G_MB_LIB.T6G(SCH_1):GND     I3 @T6G_MB_LIB.T6G(SCH_1):PAGE58
  BB10    GND @T6G_MB_LIB.T6G(SCH_1):GND     I3 @T6G_MB_LIB.T6G(SCH_1):PAGE58
  BB12    GND @T6G_MB_LIB.T6G(SCH_1):GND     I3 @T6G_MB_LIB.T6G(SCH_1):PAGE58
  BB15    GND @T6G_MB_LIB.T6G(SCH_1):GND     I3 @T6G_MB_LIB.T6G(SCH_1):PAGE58
  BB17    GND @T6G_MB_LIB.T6G(SCH_1):GND     I3 @T6G_MB_LIB.T6G(SCH_1):PAGE58
  BB19    GND @T6G_MB_LIB.T6G(SCH_1):GND     I3 @T6G_MB_LIB.T6G(SCH_1):PAGE58
  BB23    GND @T6G_MB_LIB.T6G(SCH_1):GND     I3 @T6G_MB_LIB.T6G(SCH_1):PAGE58
  BB25    GND @T6G_MB_LIB.T6G(SCH_1):GND     I3 @T6G_MB_LIB.T6G(SCH_1):PAGE58
  BB27    GND @T6G_MB_LIB.T6G(SCH_1):GND     I3 @T6G_MB_LIB.T6G(SCH_1):PAGE58
  BB48    GND @T6G_MB_LIB.T6G(SCH_1):GND     I3 @T6G_MB_LIB.T6G(SCH_1):PAGE58
  BB50    GND @T6G_MB_LIB.T6G(SCH_1):GND     I3 @T6G_MB_LIB.T6G(SCH_1):PAGE58
  BB52    GND @T6G_MB_LIB.T6G(SCH_1):GND     I3 @T6G_MB_LIB.T6G(SCH_1):PAGE58
  BB54    GND @T6G_MB_LIB.T6G(SCH_1):GND     I3 @T6G_MB_LIB.T6G(SCH_1):PAGE58
  BB57    GND @T6G_MB_LIB.T6G(SCH_1):GND     I3 @T6G_MB_LIB.T6G(SCH_1):PAGE58
  BB59    GND @T6G_MB_LIB.T6G(SCH_1):GND     I3 @T6G_MB_LIB.T6G(SCH_1):PAGE58
  BB61    GND @T6G_MB_LIB.T6G(SCH_1):GND     I3 @T6G_MB_LIB.T6G(SCH_1):PAGE58
  BB64    GND @T6G_MB_LIB.T6G(SCH_1):GND     I3 @T6G_MB_LIB.T6G(SCH_1):PAGE58
  BB66    GND @T6G_MB_LIB.T6G(SCH_1):GND     I3 @T6G_MB_LIB.T6G(SCH_1):PAGE58
  BB68    GND @T6G_MB_LIB.T6G(SCH_1):GND     I3 @T6G_MB_LIB.T6G(SCH_1):PAGE58
  BB71    GND @T6G_MB_LIB.T6G(SCH_1):GND     I3 @T6G_MB_LIB.T6G(SCH_1):PAGE58
  BB73    GND @T6G_MB_LIB.T6G(SCH_1):GND     I3 @T6G_MB_LIB.T6G(SCH_1):PAGE58
   BC1    GND @T6G_MB_LIB.T6G(SCH_1):GND     I3 @T6G_MB_LIB.T6G(SCH_1):PAGE58
   BC4    GND @T6G_MB_LIB.T6G(SCH_1):GND     I3 @T6G_MB_LIB.T6G(SCH_1):PAGE58
   BC6    GND @T6G_MB_LIB.T6G(SCH_1):GND     I3 @T6G_MB_LIB.T6G(SCH_1):PAGE58
   BC8    GND @T6G_MB_LIB.T6G(SCH_1):GND     I3 @T6G_MB_LIB.T6G(SCH_1):PAGE58
  BC11    GND @T6G_MB_LIB.T6G(SCH_1):GND     I3 @T6G_MB_LIB.T6G(SCH_1):PAGE58
  BC13    GND @T6G_MB_LIB.T6G(SCH_1):GND     I3 @T6G_MB_LIB.T6G(SCH_1):PAGE58
  BC15    GND @T6G_MB_LIB.T6G(SCH_1):GND     I3 @T6G_MB_LIB.T6G(SCH_1):PAGE58
  BC18    GND @T6G_MB_LIB.T6G(SCH_1):GND     I3 @T6G_MB_LIB.T6G(SCH_1):PAGE58
  BC20    GND @T6G_MB_LIB.T6G(SCH_1):GND     I3 @T6G_MB_LIB.T6G(SCH_1):PAGE58
  BC22    GND @T6G_MB_LIB.T6G(SCH_1):GND     I3 @T6G_MB_LIB.T6G(SCH_1):PAGE58
  BC24    GND @T6G_MB_LIB.T6G(SCH_1):GND     I3 @T6G_MB_LIB.T6G(SCH_1):PAGE58
  BC26    GND @T6G_MB_LIB.T6G(SCH_1):GND     I3 @T6G_MB_LIB.T6G(SCH_1):PAGE58
  BC28    GND @T6G_MB_LIB.T6G(SCH_1):GND     I3 @T6G_MB_LIB.T6G(SCH_1):PAGE58
  BC49    GND @T6G_MB_LIB.T6G(SCH_1):GND     I3 @T6G_MB_LIB.T6G(SCH_1):PAGE58
  BC50    GND @T6G_MB_LIB.T6G(SCH_1):GND     I3 @T6G_MB_LIB.T6G(SCH_1):PAGE58
  BC51    GND @T6G_MB_LIB.T6G(SCH_1):GND     I3 @T6G_MB_LIB.T6G(SCH_1):PAGE58
  BC53    GND @T6G_MB_LIB.T6G(SCH_1):GND     I3 @T6G_MB_LIB.T6G(SCH_1):PAGE58
  BC56    GND @T6G_MB_LIB.T6G(SCH_1):GND     I3 @T6G_MB_LIB.T6G(SCH_1):PAGE58
  BC58    GND @T6G_MB_LIB.T6G(SCH_1):GND     I3 @T6G_MB_LIB.T6G(SCH_1):PAGE58
  BC61    GND @T6G_MB_LIB.T6G(SCH_1):GND     I3 @T6G_MB_LIB.T6G(SCH_1):PAGE58
  BC63    GND @T6G_MB_LIB.T6G(SCH_1):GND     I3 @T6G_MB_LIB.T6G(SCH_1):PAGE58
  BC65    GND @T6G_MB_LIB.T6G(SCH_1):GND     I3 @T6G_MB_LIB.T6G(SCH_1):PAGE58
  BC68    GND @T6G_MB_LIB.T6G(SCH_1):GND     I3 @T6G_MB_LIB.T6G(SCH_1):PAGE58
  BC70    GND @T6G_MB_LIB.T6G(SCH_1):GND     I3 @T6G_MB_LIB.T6G(SCH_1):PAGE58
  BC72    GND @T6G_MB_LIB.T6G(SCH_1):GND     I3 @T6G_MB_LIB.T6G(SCH_1):PAGE58
  BC75    GND @T6G_MB_LIB.T6G(SCH_1):GND     I3 @T6G_MB_LIB.T6G(SCH_1):PAGE58
   BD3    GND @T6G_MB_LIB.T6G(SCH_1):GND     I3 @T6G_MB_LIB.T6G(SCH_1):PAGE58
   BD8    GND @T6G_MB_LIB.T6G(SCH_1):GND     I3 @T6G_MB_LIB.T6G(SCH_1):PAGE58
  BD10    GND @T6G_MB_LIB.T6G(SCH_1):GND     I3 @T6G_MB_LIB.T6G(SCH_1):PAGE58
  BD15    GND @T6G_MB_LIB.T6G(SCH_1):GND     I3 @T6G_MB_LIB.T6G(SCH_1):PAGE58
  BD17    GND @T6G_MB_LIB.T6G(SCH_1):GND     I3 @T6G_MB_LIB.T6G(SCH_1):PAGE58
  BD23    GND @T6G_MB_LIB.T6G(SCH_1):GND     I3 @T6G_MB_LIB.T6G(SCH_1):PAGE58
  BD25    GND @T6G_MB_LIB.T6G(SCH_1):GND     I3 @T6G_MB_LIB.T6G(SCH_1):PAGE58
  BD27    GND @T6G_MB_LIB.T6G(SCH_1):GND     I3 @T6G_MB_LIB.T6G(SCH_1):PAGE58
  BD49    GND @T6G_MB_LIB.T6G(SCH_1):GND     I3 @T6G_MB_LIB.T6G(SCH_1):PAGE58
  BD51    GND @T6G_MB_LIB.T6G(SCH_1):GND     I3 @T6G_MB_LIB.T6G(SCH_1):PAGE58
  BD53    GND @T6G_MB_LIB.T6G(SCH_1):GND     I3 @T6G_MB_LIB.T6G(SCH_1):PAGE58
  BD57    GND @T6G_MB_LIB.T6G(SCH_1):GND     I3 @T6G_MB_LIB.T6G(SCH_1):PAGE58
  BD59    GND @T6G_MB_LIB.T6G(SCH_1):GND     I3 @T6G_MB_LIB.T6G(SCH_1):PAGE58
  BD61    GND @T6G_MB_LIB.T6G(SCH_1):GND     I3 @T6G_MB_LIB.T6G(SCH_1):PAGE58
  BD64    GND @T6G_MB_LIB.T6G(SCH_1):GND     I3 @T6G_MB_LIB.T6G(SCH_1):PAGE58
  BD66    GND @T6G_MB_LIB.T6G(SCH_1):GND     I3 @T6G_MB_LIB.T6G(SCH_1):PAGE58
  BD68    GND @T6G_MB_LIB.T6G(SCH_1):GND     I3 @T6G_MB_LIB.T6G(SCH_1):PAGE58
  BD71    GND @T6G_MB_LIB.T6G(SCH_1):GND     I3 @T6G_MB_LIB.T6G(SCH_1):PAGE58
  BD73    GND @T6G_MB_LIB.T6G(SCH_1):GND     I3 @T6G_MB_LIB.T6G(SCH_1):PAGE58
   BF3    GND @T6G_MB_LIB.T6G(SCH_1):GND     I3 @T6G_MB_LIB.T6G(SCH_1):PAGE58
   BF5    GND @T6G_MB_LIB.T6G(SCH_1):GND     I3 @T6G_MB_LIB.T6G(SCH_1):PAGE58
   BF8    GND @T6G_MB_LIB.T6G(SCH_1):GND     I3 @T6G_MB_LIB.T6G(SCH_1):PAGE58
  BF10    GND @T6G_MB_LIB.T6G(SCH_1):GND     I3 @T6G_MB_LIB.T6G(SCH_1):PAGE58
  BF12    GND @T6G_MB_LIB.T6G(SCH_1):GND     I3 @T6G_MB_LIB.T6G(SCH_1):PAGE58
  BF15    GND @T6G_MB_LIB.T6G(SCH_1):GND     I3 @T6G_MB_LIB.T6G(SCH_1):PAGE58
  BF17    GND @T6G_MB_LIB.T6G(SCH_1):GND     I3 @T6G_MB_LIB.T6G(SCH_1):PAGE58
  BF19    GND @T6G_MB_LIB.T6G(SCH_1):GND     I3 @T6G_MB_LIB.T6G(SCH_1):PAGE58
  BF22    GND @T6G_MB_LIB.T6G(SCH_1):GND     I3 @T6G_MB_LIB.T6G(SCH_1):PAGE58
  BF24    GND @T6G_MB_LIB.T6G(SCH_1):GND     I3 @T6G_MB_LIB.T6G(SCH_1):PAGE58
  BF26    GND @T6G_MB_LIB.T6G(SCH_1):GND     I3 @T6G_MB_LIB.T6G(SCH_1):PAGE58
  BF28    GND @T6G_MB_LIB.T6G(SCH_1):GND     I3 @T6G_MB_LIB.T6G(SCH_1):PAGE58
  BF49    GND @T6G_MB_LIB.T6G(SCH_1):GND     I3 @T6G_MB_LIB.T6G(SCH_1):PAGE58
  BF50    GND @T6G_MB_LIB.T6G(SCH_1):GND     I3 @T6G_MB_LIB.T6G(SCH_1):PAGE58
  BF52    GND @T6G_MB_LIB.T6G(SCH_1):GND     I3 @T6G_MB_LIB.T6G(SCH_1):PAGE58
  BF54    GND @T6G_MB_LIB.T6G(SCH_1):GND     I3 @T6G_MB_LIB.T6G(SCH_1):PAGE58
  BF59    GND @T6G_MB_LIB.T6G(SCH_1):GND     I3 @T6G_MB_LIB.T6G(SCH_1):PAGE58
  BF61    GND @T6G_MB_LIB.T6G(SCH_1):GND     I3 @T6G_MB_LIB.T6G(SCH_1):PAGE58
  BF66    GND @T6G_MB_LIB.T6G(SCH_1):GND     I3 @T6G_MB_LIB.T6G(SCH_1):PAGE58
  BF68    GND @T6G_MB_LIB.T6G(SCH_1):GND     I3 @T6G_MB_LIB.T6G(SCH_1):PAGE58
  BF73    GND @T6G_MB_LIB.T6G(SCH_1):GND     I3 @T6G_MB_LIB.T6G(SCH_1):PAGE58
   BG1    GND @T6G_MB_LIB.T6G(SCH_1):GND     I3 @T6G_MB_LIB.T6G(SCH_1):PAGE58
   BG4    GND @T6G_MB_LIB.T6G(SCH_1):GND     I3 @T6G_MB_LIB.T6G(SCH_1):PAGE58
   BG6    GND @T6G_MB_LIB.T6G(SCH_1):GND     I3 @T6G_MB_LIB.T6G(SCH_1):PAGE58
   BG8    GND @T6G_MB_LIB.T6G(SCH_1):GND     I3 @T6G_MB_LIB.T6G(SCH_1):PAGE58
  BG11    GND @T6G_MB_LIB.T6G(SCH_1):GND     I3 @T6G_MB_LIB.T6G(SCH_1):PAGE58
  BG13    GND @T6G_MB_LIB.T6G(SCH_1):GND     I3 @T6G_MB_LIB.T6G(SCH_1):PAGE58
  BG15    GND @T6G_MB_LIB.T6G(SCH_1):GND     I3 @T6G_MB_LIB.T6G(SCH_1):PAGE58
  BG18    GND @T6G_MB_LIB.T6G(SCH_1):GND     I3 @T6G_MB_LIB.T6G(SCH_1):PAGE58
  BG20    GND @T6G_MB_LIB.T6G(SCH_1):GND     I3 @T6G_MB_LIB.T6G(SCH_1):PAGE58
  BG23    GND @T6G_MB_LIB.T6G(SCH_1):GND     I3 @T6G_MB_LIB.T6G(SCH_1):PAGE58
  BG25    GND @T6G_MB_LIB.T6G(SCH_1):GND     I3 @T6G_MB_LIB.T6G(SCH_1):PAGE58
  BG27    GND @T6G_MB_LIB.T6G(SCH_1):GND     I3 @T6G_MB_LIB.T6G(SCH_1):PAGE58
  BG49    GND @T6G_MB_LIB.T6G(SCH_1):GND     I3 @T6G_MB_LIB.T6G(SCH_1):PAGE58
  BG51    GND @T6G_MB_LIB.T6G(SCH_1):GND     I3 @T6G_MB_LIB.T6G(SCH_1):PAGE58
  BG53    GND @T6G_MB_LIB.T6G(SCH_1):GND     I3 @T6G_MB_LIB.T6G(SCH_1):PAGE58
  BG56    GND @T6G_MB_LIB.T6G(SCH_1):GND     I3 @T6G_MB_LIB.T6G(SCH_1):PAGE58
  BG58    GND @T6G_MB_LIB.T6G(SCH_1):GND     I3 @T6G_MB_LIB.T6G(SCH_1):PAGE58
  BG61    GND @T6G_MB_LIB.T6G(SCH_1):GND     I3 @T6G_MB_LIB.T6G(SCH_1):PAGE58
  BG63    GND @T6G_MB_LIB.T6G(SCH_1):GND     I3 @T6G_MB_LIB.T6G(SCH_1):PAGE58
  BG65    GND @T6G_MB_LIB.T6G(SCH_1):GND     I3 @T6G_MB_LIB.T6G(SCH_1):PAGE58
  BG68    GND @T6G_MB_LIB.T6G(SCH_1):GND     I3 @T6G_MB_LIB.T6G(SCH_1):PAGE58
  BG70    GND @T6G_MB_LIB.T6G(SCH_1):GND     I3 @T6G_MB_LIB.T6G(SCH_1):PAGE58
  BG72    GND @T6G_MB_LIB.T6G(SCH_1):GND     I3 @T6G_MB_LIB.T6G(SCH_1):PAGE58
  BG75    GND @T6G_MB_LIB.T6G(SCH_1):GND     I3 @T6G_MB_LIB.T6G(SCH_1):PAGE58
   BH3    GND @T6G_MB_LIB.T6G(SCH_1):GND     I3 @T6G_MB_LIB.T6G(SCH_1):PAGE58
   BH5    GND @T6G_MB_LIB.T6G(SCH_1):GND     I3 @T6G_MB_LIB.T6G(SCH_1):PAGE58
   BH8    GND @T6G_MB_LIB.T6G(SCH_1):GND     I3 @T6G_MB_LIB.T6G(SCH_1):PAGE58
  BH10    GND @T6G_MB_LIB.T6G(SCH_1):GND     I3 @T6G_MB_LIB.T6G(SCH_1):PAGE58
  BH12    GND @T6G_MB_LIB.T6G(SCH_1):GND     I3 @T6G_MB_LIB.T6G(SCH_1):PAGE58
  BH15    GND @T6G_MB_LIB.T6G(SCH_1):GND     I3 @T6G_MB_LIB.T6G(SCH_1):PAGE58
  BH17    GND @T6G_MB_LIB.T6G(SCH_1):GND     I3 @T6G_MB_LIB.T6G(SCH_1):PAGE58
  BH19    GND @T6G_MB_LIB.T6G(SCH_1):GND     I3 @T6G_MB_LIB.T6G(SCH_1):PAGE58
  BH22    GND @T6G_MB_LIB.T6G(SCH_1):GND     I3 @T6G_MB_LIB.T6G(SCH_1):PAGE58
  BH24    GND @T6G_MB_LIB.T6G(SCH_1):GND     I3 @T6G_MB_LIB.T6G(SCH_1):PAGE58
  BH26    GND @T6G_MB_LIB.T6G(SCH_1):GND     I3 @T6G_MB_LIB.T6G(SCH_1):PAGE58
  BH28    GND @T6G_MB_LIB.T6G(SCH_1):GND     I3 @T6G_MB_LIB.T6G(SCH_1):PAGE58
  BH49    GND @T6G_MB_LIB.T6G(SCH_1):GND     I3 @T6G_MB_LIB.T6G(SCH_1):PAGE58
  BH50    GND @T6G_MB_LIB.T6G(SCH_1):GND     I3 @T6G_MB_LIB.T6G(SCH_1):PAGE58
  BH52    GND @T6G_MB_LIB.T6G(SCH_1):GND     I3 @T6G_MB_LIB.T6G(SCH_1):PAGE58
  BH54    GND @T6G_MB_LIB.T6G(SCH_1):GND     I3 @T6G_MB_LIB.T6G(SCH_1):PAGE58
  BH57    GND @T6G_MB_LIB.T6G(SCH_1):GND     I3 @T6G_MB_LIB.T6G(SCH_1):PAGE58
  BH59    GND @T6G_MB_LIB.T6G(SCH_1):GND     I3 @T6G_MB_LIB.T6G(SCH_1):PAGE58
  BH61    GND @T6G_MB_LIB.T6G(SCH_1):GND     I3 @T6G_MB_LIB.T6G(SCH_1):PAGE58
  BH64    GND @T6G_MB_LIB.T6G(SCH_1):GND     I3 @T6G_MB_LIB.T6G(SCH_1):PAGE58
  BH66    GND @T6G_MB_LIB.T6G(SCH_1):GND     I3 @T6G_MB_LIB.T6G(SCH_1):PAGE58
  BH68    GND @T6G_MB_LIB.T6G(SCH_1):GND     I3 @T6G_MB_LIB.T6G(SCH_1):PAGE58
  BH71    GND @T6G_MB_LIB.T6G(SCH_1):GND     I3 @T6G_MB_LIB.T6G(SCH_1):PAGE58
  BH73    GND @T6G_MB_LIB.T6G(SCH_1):GND     I3 @T6G_MB_LIB.T6G(SCH_1):PAGE58
   BJ1    GND @T6G_MB_LIB.T6G(SCH_1):GND     I3 @T6G_MB_LIB.T6G(SCH_1):PAGE58
   BJ6    GND @T6G_MB_LIB.T6G(SCH_1):GND     I3 @T6G_MB_LIB.T6G(SCH_1):PAGE58
   BJ8    GND @T6G_MB_LIB.T6G(SCH_1):GND     I3 @T6G_MB_LIB.T6G(SCH_1):PAGE58
  BJ13    GND @T6G_MB_LIB.T6G(SCH_1):GND     I3 @T6G_MB_LIB.T6G(SCH_1):PAGE58
  BJ15    GND @T6G_MB_LIB.T6G(SCH_1):GND     I3 @T6G_MB_LIB.T6G(SCH_1):PAGE58
  BJ20    GND @T6G_MB_LIB.T6G(SCH_1):GND     I3 @T6G_MB_LIB.T6G(SCH_1):PAGE58
  BJ22    GND @T6G_MB_LIB.T6G(SCH_1):GND     I3 @T6G_MB_LIB.T6G(SCH_1):PAGE58
  BJ24    GND @T6G_MB_LIB.T6G(SCH_1):GND     I3 @T6G_MB_LIB.T6G(SCH_1):PAGE58
  BJ26    GND @T6G_MB_LIB.T6G(SCH_1):GND     I3 @T6G_MB_LIB.T6G(SCH_1):PAGE58
  BJ28    GND @T6G_MB_LIB.T6G(SCH_1):GND     I3 @T6G_MB_LIB.T6G(SCH_1):PAGE58
  BJ49    GND @T6G_MB_LIB.T6G(SCH_1):GND     I3 @T6G_MB_LIB.T6G(SCH_1):PAGE58
  BJ51    GND @T6G_MB_LIB.T6G(SCH_1):GND     I3 @T6G_MB_LIB.T6G(SCH_1):PAGE58
  BJ53    GND @T6G_MB_LIB.T6G(SCH_1):GND     I3 @T6G_MB_LIB.T6G(SCH_1):PAGE58
  BJ56    GND @T6G_MB_LIB.T6G(SCH_1):GND     I3 @T6G_MB_LIB.T6G(SCH_1):PAGE58
  BJ61    GND @T6G_MB_LIB.T6G(SCH_1):GND     I3 @T6G_MB_LIB.T6G(SCH_1):PAGE58
  BJ63    GND @T6G_MB_LIB.T6G(SCH_1):GND     I3 @T6G_MB_LIB.T6G(SCH_1):PAGE58
  BJ68    GND @T6G_MB_LIB.T6G(SCH_1):GND     I3 @T6G_MB_LIB.T6G(SCH_1):PAGE58
  BJ70    GND @T6G_MB_LIB.T6G(SCH_1):GND     I3 @T6G_MB_LIB.T6G(SCH_1):PAGE58
  BJ75    GND @T6G_MB_LIB.T6G(SCH_1):GND     I3 @T6G_MB_LIB.T6G(SCH_1):PAGE58
   BK3    GND @T6G_MB_LIB.T6G(SCH_1):GND     I3 @T6G_MB_LIB.T6G(SCH_1):PAGE58
   BK5    GND @T6G_MB_LIB.T6G(SCH_1):GND     I3 @T6G_MB_LIB.T6G(SCH_1):PAGE58
   BK8    GND @T6G_MB_LIB.T6G(SCH_1):GND     I3 @T6G_MB_LIB.T6G(SCH_1):PAGE58
  BK10    GND @T6G_MB_LIB.T6G(SCH_1):GND     I3 @T6G_MB_LIB.T6G(SCH_1):PAGE58
  BK12    GND @T6G_MB_LIB.T6G(SCH_1):GND     I3 @T6G_MB_LIB.T6G(SCH_1):PAGE58
  BK15    GND @T6G_MB_LIB.T6G(SCH_1):GND     I3 @T6G_MB_LIB.T6G(SCH_1):PAGE58
  BK17    GND @T6G_MB_LIB.T6G(SCH_1):GND     I3 @T6G_MB_LIB.T6G(SCH_1):PAGE58
  BK19    GND @T6G_MB_LIB.T6G(SCH_1):GND     I3 @T6G_MB_LIB.T6G(SCH_1):PAGE58
  BK23    GND @T6G_MB_LIB.T6G(SCH_1):GND     I3 @T6G_MB_LIB.T6G(SCH_1):PAGE58
  BK25    GND @T6G_MB_LIB.T6G(SCH_1):GND     I3 @T6G_MB_LIB.T6G(SCH_1):PAGE58
  BK27    GND @T6G_MB_LIB.T6G(SCH_1):GND     I3 @T6G_MB_LIB.T6G(SCH_1):PAGE58
  BK48    GND @T6G_MB_LIB.T6G(SCH_1):GND     I3 @T6G_MB_LIB.T6G(SCH_1):PAGE58
  BK50    GND @T6G_MB_LIB.T6G(SCH_1):GND     I3 @T6G_MB_LIB.T6G(SCH_1):PAGE58
  BK52    GND @T6G_MB_LIB.T6G(SCH_1):GND     I3 @T6G_MB_LIB.T6G(SCH_1):PAGE58
  BK54    GND @T6G_MB_LIB.T6G(SCH_1):GND     I3 @T6G_MB_LIB.T6G(SCH_1):PAGE58
  BK57    GND @T6G_MB_LIB.T6G(SCH_1):GND     I3 @T6G_MB_LIB.T6G(SCH_1):PAGE58
  BK59    GND @T6G_MB_LIB.T6G(SCH_1):GND     I3 @T6G_MB_LIB.T6G(SCH_1):PAGE58
  BK61    GND @T6G_MB_LIB.T6G(SCH_1):GND     I3 @T6G_MB_LIB.T6G(SCH_1):PAGE58
  BK64    GND @T6G_MB_LIB.T6G(SCH_1):GND     I3 @T6G_MB_LIB.T6G(SCH_1):PAGE58
  BK66    GND @T6G_MB_LIB.T6G(SCH_1):GND     I3 @T6G_MB_LIB.T6G(SCH_1):PAGE58
  BK68    GND @T6G_MB_LIB.T6G(SCH_1):GND     I3 @T6G_MB_LIB.T6G(SCH_1):PAGE58
  BK71    GND @T6G_MB_LIB.T6G(SCH_1):GND     I3 @T6G_MB_LIB.T6G(SCH_1):PAGE58
  BK73    GND @T6G_MB_LIB.T6G(SCH_1):GND     I3 @T6G_MB_LIB.T6G(SCH_1):PAGE58
   BL1    GND @T6G_MB_LIB.T6G(SCH_1):GND     I3 @T6G_MB_LIB.T6G(SCH_1):PAGE58
   BL4    GND @T6G_MB_LIB.T6G(SCH_1):GND     I3 @T6G_MB_LIB.T6G(SCH_1):PAGE58
   BL6    GND @T6G_MB_LIB.T6G(SCH_1):GND     I3 @T6G_MB_LIB.T6G(SCH_1):PAGE58
   BL8    GND @T6G_MB_LIB.T6G(SCH_1):GND     I3 @T6G_MB_LIB.T6G(SCH_1):PAGE58
  BL11    GND @T6G_MB_LIB.T6G(SCH_1):GND     I3 @T6G_MB_LIB.T6G(SCH_1):PAGE58
  BL13    GND @T6G_MB_LIB.T6G(SCH_1):GND     I3 @T6G_MB_LIB.T6G(SCH_1):PAGE58
  BL15    GND @T6G_MB_LIB.T6G(SCH_1):GND     I3 @T6G_MB_LIB.T6G(SCH_1):PAGE58
  BL18    GND @T6G_MB_LIB.T6G(SCH_1):GND     I3 @T6G_MB_LIB.T6G(SCH_1):PAGE58
  BL20    GND @T6G_MB_LIB.T6G(SCH_1):GND     I3 @T6G_MB_LIB.T6G(SCH_1):PAGE58
  BL22    GND @T6G_MB_LIB.T6G(SCH_1):GND     I3 @T6G_MB_LIB.T6G(SCH_1):PAGE58
  BL24    GND @T6G_MB_LIB.T6G(SCH_1):GND     I3 @T6G_MB_LIB.T6G(SCH_1):PAGE58
  BV37    GND @T6G_MB_LIB.T6G(SCH_1):GND     I1 @T6G_MB_LIB.T6G(SCH_1):PAGE59
  BL26    GND @T6G_MB_LIB.T6G(SCH_1):GND     I1 @T6G_MB_LIB.T6G(SCH_1):PAGE59
  BL28    GND @T6G_MB_LIB.T6G(SCH_1):GND     I1 @T6G_MB_LIB.T6G(SCH_1):PAGE59
  BL49    GND @T6G_MB_LIB.T6G(SCH_1):GND     I1 @T6G_MB_LIB.T6G(SCH_1):PAGE59
  BL51    GND @T6G_MB_LIB.T6G(SCH_1):GND     I1 @T6G_MB_LIB.T6G(SCH_1):PAGE59
  BL53    GND @T6G_MB_LIB.T6G(SCH_1):GND     I1 @T6G_MB_LIB.T6G(SCH_1):PAGE59
  BL56    GND @T6G_MB_LIB.T6G(SCH_1):GND     I1 @T6G_MB_LIB.T6G(SCH_1):PAGE59
  BL58    GND @T6G_MB_LIB.T6G(SCH_1):GND     I1 @T6G_MB_LIB.T6G(SCH_1):PAGE59
  BL61    GND @T6G_MB_LIB.T6G(SCH_1):GND     I1 @T6G_MB_LIB.T6G(SCH_1):PAGE59
  BL63    GND @T6G_MB_LIB.T6G(SCH_1):GND     I1 @T6G_MB_LIB.T6G(SCH_1):PAGE59
  BL65    GND @T6G_MB_LIB.T6G(SCH_1):GND     I1 @T6G_MB_LIB.T6G(SCH_1):PAGE59
  BL68    GND @T6G_MB_LIB.T6G(SCH_1):GND     I1 @T6G_MB_LIB.T6G(SCH_1):PAGE59
  BL70    GND @T6G_MB_LIB.T6G(SCH_1):GND     I1 @T6G_MB_LIB.T6G(SCH_1):PAGE59
  BL72    GND @T6G_MB_LIB.T6G(SCH_1):GND     I1 @T6G_MB_LIB.T6G(SCH_1):PAGE59
  BL75    GND @T6G_MB_LIB.T6G(SCH_1):GND     I1 @T6G_MB_LIB.T6G(SCH_1):PAGE59
   BM3    GND @T6G_MB_LIB.T6G(SCH_1):GND     I1 @T6G_MB_LIB.T6G(SCH_1):PAGE59
   BM8    GND @T6G_MB_LIB.T6G(SCH_1):GND     I1 @T6G_MB_LIB.T6G(SCH_1):PAGE59
  BM10    GND @T6G_MB_LIB.T6G(SCH_1):GND     I1 @T6G_MB_LIB.T6G(SCH_1):PAGE59
  BM15    GND @T6G_MB_LIB.T6G(SCH_1):GND     I1 @T6G_MB_LIB.T6G(SCH_1):PAGE59
  BM17    GND @T6G_MB_LIB.T6G(SCH_1):GND     I1 @T6G_MB_LIB.T6G(SCH_1):PAGE59
  BM23    GND @T6G_MB_LIB.T6G(SCH_1):GND     I1 @T6G_MB_LIB.T6G(SCH_1):PAGE59
  BM25    GND @T6G_MB_LIB.T6G(SCH_1):GND     I1 @T6G_MB_LIB.T6G(SCH_1):PAGE59
  BM27    GND @T6G_MB_LIB.T6G(SCH_1):GND     I1 @T6G_MB_LIB.T6G(SCH_1):PAGE59
  BM29    GND @T6G_MB_LIB.T6G(SCH_1):GND     I1 @T6G_MB_LIB.T6G(SCH_1):PAGE59
  BM31    GND @T6G_MB_LIB.T6G(SCH_1):GND     I1 @T6G_MB_LIB.T6G(SCH_1):PAGE59
  BM33    GND @T6G_MB_LIB.T6G(SCH_1):GND     I1 @T6G_MB_LIB.T6G(SCH_1):PAGE59
  BM35    GND @T6G_MB_LIB.T6G(SCH_1):GND     I1 @T6G_MB_LIB.T6G(SCH_1):PAGE59
  BM37    GND @T6G_MB_LIB.T6G(SCH_1):GND     I1 @T6G_MB_LIB.T6G(SCH_1):PAGE59
  BM40    GND @T6G_MB_LIB.T6G(SCH_1):GND     I1 @T6G_MB_LIB.T6G(SCH_1):PAGE59
  BM42    GND @T6G_MB_LIB.T6G(SCH_1):GND     I1 @T6G_MB_LIB.T6G(SCH_1):PAGE59
  BM44    GND @T6G_MB_LIB.T6G(SCH_1):GND     I1 @T6G_MB_LIB.T6G(SCH_1):PAGE59
  BM46    GND @T6G_MB_LIB.T6G(SCH_1):GND     I1 @T6G_MB_LIB.T6G(SCH_1):PAGE59
  BM48    GND @T6G_MB_LIB.T6G(SCH_1):GND     I1 @T6G_MB_LIB.T6G(SCH_1):PAGE59
  BM50    GND @T6G_MB_LIB.T6G(SCH_1):GND     I1 @T6G_MB_LIB.T6G(SCH_1):PAGE59
  BM52    GND @T6G_MB_LIB.T6G(SCH_1):GND     I1 @T6G_MB_LIB.T6G(SCH_1):PAGE59
  BM54    GND @T6G_MB_LIB.T6G(SCH_1):GND     I1 @T6G_MB_LIB.T6G(SCH_1):PAGE59
  BM59    GND @T6G_MB_LIB.T6G(SCH_1):GND     I1 @T6G_MB_LIB.T6G(SCH_1):PAGE59
  BM61    GND @T6G_MB_LIB.T6G(SCH_1):GND     I1 @T6G_MB_LIB.T6G(SCH_1):PAGE59
  BM66    GND @T6G_MB_LIB.T6G(SCH_1):GND     I1 @T6G_MB_LIB.T6G(SCH_1):PAGE59
  BM68    GND @T6G_MB_LIB.T6G(SCH_1):GND     I1 @T6G_MB_LIB.T6G(SCH_1):PAGE59
  BM73    GND @T6G_MB_LIB.T6G(SCH_1):GND     I1 @T6G_MB_LIB.T6G(SCH_1):PAGE59
   BN1    GND @T6G_MB_LIB.T6G(SCH_1):GND     I1 @T6G_MB_LIB.T6G(SCH_1):PAGE59
   BN4    GND @T6G_MB_LIB.T6G(SCH_1):GND     I1 @T6G_MB_LIB.T6G(SCH_1):PAGE59
   BN6    GND @T6G_MB_LIB.T6G(SCH_1):GND     I1 @T6G_MB_LIB.T6G(SCH_1):PAGE59
   BN8    GND @T6G_MB_LIB.T6G(SCH_1):GND     I1 @T6G_MB_LIB.T6G(SCH_1):PAGE59
  BN11    GND @T6G_MB_LIB.T6G(SCH_1):GND     I1 @T6G_MB_LIB.T6G(SCH_1):PAGE59
  BN13    GND @T6G_MB_LIB.T6G(SCH_1):GND     I1 @T6G_MB_LIB.T6G(SCH_1):PAGE59
  BN15    GND @T6G_MB_LIB.T6G(SCH_1):GND     I1 @T6G_MB_LIB.T6G(SCH_1):PAGE59
  BN18    GND @T6G_MB_LIB.T6G(SCH_1):GND     I1 @T6G_MB_LIB.T6G(SCH_1):PAGE59
  BN20    GND @T6G_MB_LIB.T6G(SCH_1):GND     I1 @T6G_MB_LIB.T6G(SCH_1):PAGE59
  BN22    GND @T6G_MB_LIB.T6G(SCH_1):GND     I1 @T6G_MB_LIB.T6G(SCH_1):PAGE59
  BN24    GND @T6G_MB_LIB.T6G(SCH_1):GND     I1 @T6G_MB_LIB.T6G(SCH_1):PAGE59
  BN26    GND @T6G_MB_LIB.T6G(SCH_1):GND     I1 @T6G_MB_LIB.T6G(SCH_1):PAGE59
  BN28    GND @T6G_MB_LIB.T6G(SCH_1):GND     I1 @T6G_MB_LIB.T6G(SCH_1):PAGE59
  BN30    GND @T6G_MB_LIB.T6G(SCH_1):GND     I1 @T6G_MB_LIB.T6G(SCH_1):PAGE59
  BN32    GND @T6G_MB_LIB.T6G(SCH_1):GND     I1 @T6G_MB_LIB.T6G(SCH_1):PAGE59
  BN34    GND @T6G_MB_LIB.T6G(SCH_1):GND     I1 @T6G_MB_LIB.T6G(SCH_1):PAGE59
  BN36    GND @T6G_MB_LIB.T6G(SCH_1):GND     I1 @T6G_MB_LIB.T6G(SCH_1):PAGE59
  BN41    GND @T6G_MB_LIB.T6G(SCH_1):GND     I1 @T6G_MB_LIB.T6G(SCH_1):PAGE59
  BN43    GND @T6G_MB_LIB.T6G(SCH_1):GND     I1 @T6G_MB_LIB.T6G(SCH_1):PAGE59
  BN45    GND @T6G_MB_LIB.T6G(SCH_1):GND     I1 @T6G_MB_LIB.T6G(SCH_1):PAGE59
  BN47    GND @T6G_MB_LIB.T6G(SCH_1):GND     I1 @T6G_MB_LIB.T6G(SCH_1):PAGE59
  BN49    GND @T6G_MB_LIB.T6G(SCH_1):GND     I1 @T6G_MB_LIB.T6G(SCH_1):PAGE59
  BN51    GND @T6G_MB_LIB.T6G(SCH_1):GND     I1 @T6G_MB_LIB.T6G(SCH_1):PAGE59
  BN53    GND @T6G_MB_LIB.T6G(SCH_1):GND     I1 @T6G_MB_LIB.T6G(SCH_1):PAGE59
  BN56    GND @T6G_MB_LIB.T6G(SCH_1):GND     I1 @T6G_MB_LIB.T6G(SCH_1):PAGE59
  BN58    GND @T6G_MB_LIB.T6G(SCH_1):GND     I1 @T6G_MB_LIB.T6G(SCH_1):PAGE59
  BN61    GND @T6G_MB_LIB.T6G(SCH_1):GND     I1 @T6G_MB_LIB.T6G(SCH_1):PAGE59
  BN63    GND @T6G_MB_LIB.T6G(SCH_1):GND     I1 @T6G_MB_LIB.T6G(SCH_1):PAGE59
  BN65    GND @T6G_MB_LIB.T6G(SCH_1):GND     I1 @T6G_MB_LIB.T6G(SCH_1):PAGE59
  BN68    GND @T6G_MB_LIB.T6G(SCH_1):GND     I1 @T6G_MB_LIB.T6G(SCH_1):PAGE59
  BN70    GND @T6G_MB_LIB.T6G(SCH_1):GND     I1 @T6G_MB_LIB.T6G(SCH_1):PAGE59
  BN72    GND @T6G_MB_LIB.T6G(SCH_1):GND     I1 @T6G_MB_LIB.T6G(SCH_1):PAGE59
  BN75    GND @T6G_MB_LIB.T6G(SCH_1):GND     I1 @T6G_MB_LIB.T6G(SCH_1):PAGE59
   BP3    GND @T6G_MB_LIB.T6G(SCH_1):GND     I1 @T6G_MB_LIB.T6G(SCH_1):PAGE59
   BP5    GND @T6G_MB_LIB.T6G(SCH_1):GND     I1 @T6G_MB_LIB.T6G(SCH_1):PAGE59
   BP8    GND @T6G_MB_LIB.T6G(SCH_1):GND     I1 @T6G_MB_LIB.T6G(SCH_1):PAGE59
  BP10    GND @T6G_MB_LIB.T6G(SCH_1):GND     I1 @T6G_MB_LIB.T6G(SCH_1):PAGE59
  BP12    GND @T6G_MB_LIB.T6G(SCH_1):GND     I1 @T6G_MB_LIB.T6G(SCH_1):PAGE59
  BP15    GND @T6G_MB_LIB.T6G(SCH_1):GND     I1 @T6G_MB_LIB.T6G(SCH_1):PAGE59
  BP17    GND @T6G_MB_LIB.T6G(SCH_1):GND     I1 @T6G_MB_LIB.T6G(SCH_1):PAGE59
  BP19    GND @T6G_MB_LIB.T6G(SCH_1):GND     I1 @T6G_MB_LIB.T6G(SCH_1):PAGE59
  BP23    GND @T6G_MB_LIB.T6G(SCH_1):GND     I1 @T6G_MB_LIB.T6G(SCH_1):PAGE59
  BP25    GND @T6G_MB_LIB.T6G(SCH_1):GND     I1 @T6G_MB_LIB.T6G(SCH_1):PAGE59
  BP27    GND @T6G_MB_LIB.T6G(SCH_1):GND     I1 @T6G_MB_LIB.T6G(SCH_1):PAGE59
  BP29    GND @T6G_MB_LIB.T6G(SCH_1):GND     I1 @T6G_MB_LIB.T6G(SCH_1):PAGE59
  BP31    GND @T6G_MB_LIB.T6G(SCH_1):GND     I1 @T6G_MB_LIB.T6G(SCH_1):PAGE59
  BP33    GND @T6G_MB_LIB.T6G(SCH_1):GND     I1 @T6G_MB_LIB.T6G(SCH_1):PAGE59
  BP35    GND @T6G_MB_LIB.T6G(SCH_1):GND     I1 @T6G_MB_LIB.T6G(SCH_1):PAGE59
  BP37    GND @T6G_MB_LIB.T6G(SCH_1):GND     I1 @T6G_MB_LIB.T6G(SCH_1):PAGE59
  BP40    GND @T6G_MB_LIB.T6G(SCH_1):GND     I1 @T6G_MB_LIB.T6G(SCH_1):PAGE59
  BP42    GND @T6G_MB_LIB.T6G(SCH_1):GND     I1 @T6G_MB_LIB.T6G(SCH_1):PAGE59
  BP44    GND @T6G_MB_LIB.T6G(SCH_1):GND     I1 @T6G_MB_LIB.T6G(SCH_1):PAGE59
  BP46    GND @T6G_MB_LIB.T6G(SCH_1):GND     I1 @T6G_MB_LIB.T6G(SCH_1):PAGE59
  BP48    GND @T6G_MB_LIB.T6G(SCH_1):GND     I1 @T6G_MB_LIB.T6G(SCH_1):PAGE59
  BP50    GND @T6G_MB_LIB.T6G(SCH_1):GND     I1 @T6G_MB_LIB.T6G(SCH_1):PAGE59
  BP52    GND @T6G_MB_LIB.T6G(SCH_1):GND     I1 @T6G_MB_LIB.T6G(SCH_1):PAGE59
  BP54    GND @T6G_MB_LIB.T6G(SCH_1):GND     I1 @T6G_MB_LIB.T6G(SCH_1):PAGE59
  BP57    GND @T6G_MB_LIB.T6G(SCH_1):GND     I1 @T6G_MB_LIB.T6G(SCH_1):PAGE59
  BP59    GND @T6G_MB_LIB.T6G(SCH_1):GND     I1 @T6G_MB_LIB.T6G(SCH_1):PAGE59
  BP61    GND @T6G_MB_LIB.T6G(SCH_1):GND     I1 @T6G_MB_LIB.T6G(SCH_1):PAGE59
  BP64    GND @T6G_MB_LIB.T6G(SCH_1):GND     I1 @T6G_MB_LIB.T6G(SCH_1):PAGE59
  BP66    GND @T6G_MB_LIB.T6G(SCH_1):GND     I1 @T6G_MB_LIB.T6G(SCH_1):PAGE59
  BP68    GND @T6G_MB_LIB.T6G(SCH_1):GND     I1 @T6G_MB_LIB.T6G(SCH_1):PAGE59
  BP71    GND @T6G_MB_LIB.T6G(SCH_1):GND     I1 @T6G_MB_LIB.T6G(SCH_1):PAGE59
  BP73    GND @T6G_MB_LIB.T6G(SCH_1):GND     I1 @T6G_MB_LIB.T6G(SCH_1):PAGE59
   BR1    GND @T6G_MB_LIB.T6G(SCH_1):GND     I1 @T6G_MB_LIB.T6G(SCH_1):PAGE59
   BR3    GND @T6G_MB_LIB.T6G(SCH_1):GND     I1 @T6G_MB_LIB.T6G(SCH_1):PAGE59
   BR6    GND @T6G_MB_LIB.T6G(SCH_1):GND     I1 @T6G_MB_LIB.T6G(SCH_1):PAGE59
   BR7    GND @T6G_MB_LIB.T6G(SCH_1):GND     I1 @T6G_MB_LIB.T6G(SCH_1):PAGE59
   BR8    GND @T6G_MB_LIB.T6G(SCH_1):GND     I1 @T6G_MB_LIB.T6G(SCH_1):PAGE59
  BR10    GND @T6G_MB_LIB.T6G(SCH_1):GND     I1 @T6G_MB_LIB.T6G(SCH_1):PAGE59
  BR13    GND @T6G_MB_LIB.T6G(SCH_1):GND     I1 @T6G_MB_LIB.T6G(SCH_1):PAGE59
  BR14    GND @T6G_MB_LIB.T6G(SCH_1):GND     I1 @T6G_MB_LIB.T6G(SCH_1):PAGE59
  BR15    GND @T6G_MB_LIB.T6G(SCH_1):GND     I1 @T6G_MB_LIB.T6G(SCH_1):PAGE59
  BR17    GND @T6G_MB_LIB.T6G(SCH_1):GND     I1 @T6G_MB_LIB.T6G(SCH_1):PAGE59
  BR20    GND @T6G_MB_LIB.T6G(SCH_1):GND     I1 @T6G_MB_LIB.T6G(SCH_1):PAGE59
  BR21    GND @T6G_MB_LIB.T6G(SCH_1):GND     I1 @T6G_MB_LIB.T6G(SCH_1):PAGE59
  BR22    GND @T6G_MB_LIB.T6G(SCH_1):GND     I1 @T6G_MB_LIB.T6G(SCH_1):PAGE59
  BR24    GND @T6G_MB_LIB.T6G(SCH_1):GND     I1 @T6G_MB_LIB.T6G(SCH_1):PAGE59
  BR26    GND @T6G_MB_LIB.T6G(SCH_1):GND     I1 @T6G_MB_LIB.T6G(SCH_1):PAGE59
  BR28    GND @T6G_MB_LIB.T6G(SCH_1):GND     I1 @T6G_MB_LIB.T6G(SCH_1):PAGE59
  BR30    GND @T6G_MB_LIB.T6G(SCH_1):GND     I1 @T6G_MB_LIB.T6G(SCH_1):PAGE59
  BR32    GND @T6G_MB_LIB.T6G(SCH_1):GND     I1 @T6G_MB_LIB.T6G(SCH_1):PAGE59
  BR34    GND @T6G_MB_LIB.T6G(SCH_1):GND     I1 @T6G_MB_LIB.T6G(SCH_1):PAGE59
  BR36    GND @T6G_MB_LIB.T6G(SCH_1):GND     I1 @T6G_MB_LIB.T6G(SCH_1):PAGE59
  BR41    GND @T6G_MB_LIB.T6G(SCH_1):GND     I1 @T6G_MB_LIB.T6G(SCH_1):PAGE59
  BR43    GND @T6G_MB_LIB.T6G(SCH_1):GND     I1 @T6G_MB_LIB.T6G(SCH_1):PAGE59
  BR45    GND @T6G_MB_LIB.T6G(SCH_1):GND     I1 @T6G_MB_LIB.T6G(SCH_1):PAGE59
  BR47    GND @T6G_MB_LIB.T6G(SCH_1):GND     I1 @T6G_MB_LIB.T6G(SCH_1):PAGE59
  BR49    GND @T6G_MB_LIB.T6G(SCH_1):GND     I1 @T6G_MB_LIB.T6G(SCH_1):PAGE59
  BR51    GND @T6G_MB_LIB.T6G(SCH_1):GND     I1 @T6G_MB_LIB.T6G(SCH_1):PAGE59
  BR55    GND @T6G_MB_LIB.T6G(SCH_1):GND     I1 @T6G_MB_LIB.T6G(SCH_1):PAGE59
  BR56    GND @T6G_MB_LIB.T6G(SCH_1):GND     I1 @T6G_MB_LIB.T6G(SCH_1):PAGE59
  BR59    GND @T6G_MB_LIB.T6G(SCH_1):GND     I1 @T6G_MB_LIB.T6G(SCH_1):PAGE59
  BR61    GND @T6G_MB_LIB.T6G(SCH_1):GND     I1 @T6G_MB_LIB.T6G(SCH_1):PAGE59
  BR62    GND @T6G_MB_LIB.T6G(SCH_1):GND     I1 @T6G_MB_LIB.T6G(SCH_1):PAGE59
  BR63    GND @T6G_MB_LIB.T6G(SCH_1):GND     I1 @T6G_MB_LIB.T6G(SCH_1):PAGE59
  BR66    GND @T6G_MB_LIB.T6G(SCH_1):GND     I1 @T6G_MB_LIB.T6G(SCH_1):PAGE59
  BR68    GND @T6G_MB_LIB.T6G(SCH_1):GND     I1 @T6G_MB_LIB.T6G(SCH_1):PAGE59
  BR69    GND @T6G_MB_LIB.T6G(SCH_1):GND     I1 @T6G_MB_LIB.T6G(SCH_1):PAGE59
  BR70    GND @T6G_MB_LIB.T6G(SCH_1):GND     I1 @T6G_MB_LIB.T6G(SCH_1):PAGE59
  BR73    GND @T6G_MB_LIB.T6G(SCH_1):GND     I1 @T6G_MB_LIB.T6G(SCH_1):PAGE59
  BR75    GND @T6G_MB_LIB.T6G(SCH_1):GND     I1 @T6G_MB_LIB.T6G(SCH_1):PAGE59
   BT3    GND @T6G_MB_LIB.T6G(SCH_1):GND     I1 @T6G_MB_LIB.T6G(SCH_1):PAGE59
   BT4    GND @T6G_MB_LIB.T6G(SCH_1):GND     I1 @T6G_MB_LIB.T6G(SCH_1):PAGE59
   BT5    GND @T6G_MB_LIB.T6G(SCH_1):GND     I1 @T6G_MB_LIB.T6G(SCH_1):PAGE59
   BT7    GND @T6G_MB_LIB.T6G(SCH_1):GND     I1 @T6G_MB_LIB.T6G(SCH_1):PAGE59
   BT8    GND @T6G_MB_LIB.T6G(SCH_1):GND     I1 @T6G_MB_LIB.T6G(SCH_1):PAGE59
  BT10    GND @T6G_MB_LIB.T6G(SCH_1):GND     I1 @T6G_MB_LIB.T6G(SCH_1):PAGE59
  BT11    GND @T6G_MB_LIB.T6G(SCH_1):GND     I1 @T6G_MB_LIB.T6G(SCH_1):PAGE59
  BT12    GND @T6G_MB_LIB.T6G(SCH_1):GND     I1 @T6G_MB_LIB.T6G(SCH_1):PAGE59
  BT14    GND @T6G_MB_LIB.T6G(SCH_1):GND     I1 @T6G_MB_LIB.T6G(SCH_1):PAGE59
  BT15    GND @T6G_MB_LIB.T6G(SCH_1):GND     I1 @T6G_MB_LIB.T6G(SCH_1):PAGE59
  BT17    GND @T6G_MB_LIB.T6G(SCH_1):GND     I1 @T6G_MB_LIB.T6G(SCH_1):PAGE59
  BT18    GND @T6G_MB_LIB.T6G(SCH_1):GND     I1 @T6G_MB_LIB.T6G(SCH_1):PAGE59
  BT19    GND @T6G_MB_LIB.T6G(SCH_1):GND     I1 @T6G_MB_LIB.T6G(SCH_1):PAGE59
  BT21    GND @T6G_MB_LIB.T6G(SCH_1):GND     I1 @T6G_MB_LIB.T6G(SCH_1):PAGE59
  BT22    GND @T6G_MB_LIB.T6G(SCH_1):GND     I1 @T6G_MB_LIB.T6G(SCH_1):PAGE59
  BT25    GND @T6G_MB_LIB.T6G(SCH_1):GND     I1 @T6G_MB_LIB.T6G(SCH_1):PAGE59
  BT28    GND @T6G_MB_LIB.T6G(SCH_1):GND     I1 @T6G_MB_LIB.T6G(SCH_1):PAGE59
  BT31    GND @T6G_MB_LIB.T6G(SCH_1):GND     I1 @T6G_MB_LIB.T6G(SCH_1):PAGE59
  BT34    GND @T6G_MB_LIB.T6G(SCH_1):GND     I1 @T6G_MB_LIB.T6G(SCH_1):PAGE59
  BT37    GND @T6G_MB_LIB.T6G(SCH_1):GND     I1 @T6G_MB_LIB.T6G(SCH_1):PAGE59
  BT39    GND @T6G_MB_LIB.T6G(SCH_1):GND     I1 @T6G_MB_LIB.T6G(SCH_1):PAGE59
  BT42    GND @T6G_MB_LIB.T6G(SCH_1):GND     I1 @T6G_MB_LIB.T6G(SCH_1):PAGE59
  BT45    GND @T6G_MB_LIB.T6G(SCH_1):GND     I1 @T6G_MB_LIB.T6G(SCH_1):PAGE59
  BT48    GND @T6G_MB_LIB.T6G(SCH_1):GND     I1 @T6G_MB_LIB.T6G(SCH_1):PAGE59
  BT51    GND @T6G_MB_LIB.T6G(SCH_1):GND     I1 @T6G_MB_LIB.T6G(SCH_1):PAGE59
  BT54    GND @T6G_MB_LIB.T6G(SCH_1):GND     I1 @T6G_MB_LIB.T6G(SCH_1):PAGE59
  BT55    GND @T6G_MB_LIB.T6G(SCH_1):GND     I1 @T6G_MB_LIB.T6G(SCH_1):PAGE59
  BT57    GND @T6G_MB_LIB.T6G(SCH_1):GND     I1 @T6G_MB_LIB.T6G(SCH_1):PAGE59
  BT58    GND @T6G_MB_LIB.T6G(SCH_1):GND     I1 @T6G_MB_LIB.T6G(SCH_1):PAGE59
  BT59    GND @T6G_MB_LIB.T6G(SCH_1):GND     I1 @T6G_MB_LIB.T6G(SCH_1):PAGE59
  BT61    GND @T6G_MB_LIB.T6G(SCH_1):GND     I1 @T6G_MB_LIB.T6G(SCH_1):PAGE59
  BT62    GND @T6G_MB_LIB.T6G(SCH_1):GND     I1 @T6G_MB_LIB.T6G(SCH_1):PAGE59
  BT64    GND @T6G_MB_LIB.T6G(SCH_1):GND     I1 @T6G_MB_LIB.T6G(SCH_1):PAGE59
  BT65    GND @T6G_MB_LIB.T6G(SCH_1):GND     I1 @T6G_MB_LIB.T6G(SCH_1):PAGE59
  BT66    GND @T6G_MB_LIB.T6G(SCH_1):GND     I1 @T6G_MB_LIB.T6G(SCH_1):PAGE59
  BT68    GND @T6G_MB_LIB.T6G(SCH_1):GND     I1 @T6G_MB_LIB.T6G(SCH_1):PAGE59
  BT69    GND @T6G_MB_LIB.T6G(SCH_1):GND     I1 @T6G_MB_LIB.T6G(SCH_1):PAGE59
  BT71    GND @T6G_MB_LIB.T6G(SCH_1):GND     I1 @T6G_MB_LIB.T6G(SCH_1):PAGE59
  BT72    GND @T6G_MB_LIB.T6G(SCH_1):GND     I1 @T6G_MB_LIB.T6G(SCH_1):PAGE59
  BT73    GND @T6G_MB_LIB.T6G(SCH_1):GND     I1 @T6G_MB_LIB.T6G(SCH_1):PAGE59
   BU1    GND @T6G_MB_LIB.T6G(SCH_1):GND     I1 @T6G_MB_LIB.T6G(SCH_1):PAGE59
   BU4    GND @T6G_MB_LIB.T6G(SCH_1):GND     I1 @T6G_MB_LIB.T6G(SCH_1):PAGE59
   BU6    GND @T6G_MB_LIB.T6G(SCH_1):GND     I1 @T6G_MB_LIB.T6G(SCH_1):PAGE59
   BU8    GND @T6G_MB_LIB.T6G(SCH_1):GND     I1 @T6G_MB_LIB.T6G(SCH_1):PAGE59
  BU11    GND @T6G_MB_LIB.T6G(SCH_1):GND     I1 @T6G_MB_LIB.T6G(SCH_1):PAGE59
  BU13    GND @T6G_MB_LIB.T6G(SCH_1):GND     I1 @T6G_MB_LIB.T6G(SCH_1):PAGE59
  BU15    GND @T6G_MB_LIB.T6G(SCH_1):GND     I1 @T6G_MB_LIB.T6G(SCH_1):PAGE59
  BU18    GND @T6G_MB_LIB.T6G(SCH_1):GND     I1 @T6G_MB_LIB.T6G(SCH_1):PAGE59
  BU20    GND @T6G_MB_LIB.T6G(SCH_1):GND     I1 @T6G_MB_LIB.T6G(SCH_1):PAGE59
  BU22    GND @T6G_MB_LIB.T6G(SCH_1):GND     I1 @T6G_MB_LIB.T6G(SCH_1):PAGE59
  BU25    GND @T6G_MB_LIB.T6G(SCH_1):GND     I1 @T6G_MB_LIB.T6G(SCH_1):PAGE59
  BU28    GND @T6G_MB_LIB.T6G(SCH_1):GND     I1 @T6G_MB_LIB.T6G(SCH_1):PAGE59
  BU31    GND @T6G_MB_LIB.T6G(SCH_1):GND     I1 @T6G_MB_LIB.T6G(SCH_1):PAGE59
  BU34    GND @T6G_MB_LIB.T6G(SCH_1):GND     I1 @T6G_MB_LIB.T6G(SCH_1):PAGE59
  BU35    GND @T6G_MB_LIB.T6G(SCH_1):GND     I1 @T6G_MB_LIB.T6G(SCH_1):PAGE59
  BU36    GND @T6G_MB_LIB.T6G(SCH_1):GND     I1 @T6G_MB_LIB.T6G(SCH_1):PAGE59
  BU40    GND @T6G_MB_LIB.T6G(SCH_1):GND     I1 @T6G_MB_LIB.T6G(SCH_1):PAGE59
  BU41    GND @T6G_MB_LIB.T6G(SCH_1):GND     I1 @T6G_MB_LIB.T6G(SCH_1):PAGE59
  BU42    GND @T6G_MB_LIB.T6G(SCH_1):GND     I1 @T6G_MB_LIB.T6G(SCH_1):PAGE59
  BU45    GND @T6G_MB_LIB.T6G(SCH_1):GND     I1 @T6G_MB_LIB.T6G(SCH_1):PAGE59
  BU48    GND @T6G_MB_LIB.T6G(SCH_1):GND     I1 @T6G_MB_LIB.T6G(SCH_1):PAGE59
  BU51    GND @T6G_MB_LIB.T6G(SCH_1):GND     I1 @T6G_MB_LIB.T6G(SCH_1):PAGE59
  BU54    GND @T6G_MB_LIB.T6G(SCH_1):GND     I1 @T6G_MB_LIB.T6G(SCH_1):PAGE59
  BU56    GND @T6G_MB_LIB.T6G(SCH_1):GND     I1 @T6G_MB_LIB.T6G(SCH_1):PAGE59
  BU58    GND @T6G_MB_LIB.T6G(SCH_1):GND     I1 @T6G_MB_LIB.T6G(SCH_1):PAGE59
  BU61    GND @T6G_MB_LIB.T6G(SCH_1):GND     I1 @T6G_MB_LIB.T6G(SCH_1):PAGE59
  BU63    GND @T6G_MB_LIB.T6G(SCH_1):GND     I1 @T6G_MB_LIB.T6G(SCH_1):PAGE59
  BU65    GND @T6G_MB_LIB.T6G(SCH_1):GND     I1 @T6G_MB_LIB.T6G(SCH_1):PAGE59
  BU68    GND @T6G_MB_LIB.T6G(SCH_1):GND     I1 @T6G_MB_LIB.T6G(SCH_1):PAGE59
  BU70    GND @T6G_MB_LIB.T6G(SCH_1):GND     I1 @T6G_MB_LIB.T6G(SCH_1):PAGE59
  BU72    GND @T6G_MB_LIB.T6G(SCH_1):GND     I1 @T6G_MB_LIB.T6G(SCH_1):PAGE59
  BU75    GND @T6G_MB_LIB.T6G(SCH_1):GND     I1 @T6G_MB_LIB.T6G(SCH_1):PAGE59
   BV3    GND @T6G_MB_LIB.T6G(SCH_1):GND     I1 @T6G_MB_LIB.T6G(SCH_1):PAGE59
   BV8    GND @T6G_MB_LIB.T6G(SCH_1):GND     I1 @T6G_MB_LIB.T6G(SCH_1):PAGE59
  BV10    GND @T6G_MB_LIB.T6G(SCH_1):GND     I1 @T6G_MB_LIB.T6G(SCH_1):PAGE59
  BV15    GND @T6G_MB_LIB.T6G(SCH_1):GND     I1 @T6G_MB_LIB.T6G(SCH_1):PAGE59
  BV17    GND @T6G_MB_LIB.T6G(SCH_1):GND     I1 @T6G_MB_LIB.T6G(SCH_1):PAGE59
  BV23    GND @T6G_MB_LIB.T6G(SCH_1):GND     I1 @T6G_MB_LIB.T6G(SCH_1):PAGE59
  BV24    GND @T6G_MB_LIB.T6G(SCH_1):GND     I1 @T6G_MB_LIB.T6G(SCH_1):PAGE59
  BV25    GND @T6G_MB_LIB.T6G(SCH_1):GND     I1 @T6G_MB_LIB.T6G(SCH_1):PAGE59
  BV26    GND @T6G_MB_LIB.T6G(SCH_1):GND     I1 @T6G_MB_LIB.T6G(SCH_1):PAGE59
  BV27    GND @T6G_MB_LIB.T6G(SCH_1):GND     I1 @T6G_MB_LIB.T6G(SCH_1):PAGE59
  BV28    GND @T6G_MB_LIB.T6G(SCH_1):GND     I1 @T6G_MB_LIB.T6G(SCH_1):PAGE59
  BV29    GND @T6G_MB_LIB.T6G(SCH_1):GND     I1 @T6G_MB_LIB.T6G(SCH_1):PAGE59
  BV30    GND @T6G_MB_LIB.T6G(SCH_1):GND     I1 @T6G_MB_LIB.T6G(SCH_1):PAGE59
  BV31    GND @T6G_MB_LIB.T6G(SCH_1):GND     I1 @T6G_MB_LIB.T6G(SCH_1):PAGE59
  BV32    GND @T6G_MB_LIB.T6G(SCH_1):GND     I1 @T6G_MB_LIB.T6G(SCH_1):PAGE59
  BV33    GND @T6G_MB_LIB.T6G(SCH_1):GND     I1 @T6G_MB_LIB.T6G(SCH_1):PAGE59
  BV34    GND @T6G_MB_LIB.T6G(SCH_1):GND     I1 @T6G_MB_LIB.T6G(SCH_1):PAGE59
  BV39    GND @T6G_MB_LIB.T6G(SCH_1):GND     I1 @T6G_MB_LIB.T6G(SCH_1):PAGE59
  BV43    GND @T6G_MB_LIB.T6G(SCH_1):GND     I1 @T6G_MB_LIB.T6G(SCH_1):PAGE59
  BV44    GND @T6G_MB_LIB.T6G(SCH_1):GND     I1 @T6G_MB_LIB.T6G(SCH_1):PAGE59
  BV45    GND @T6G_MB_LIB.T6G(SCH_1):GND     I1 @T6G_MB_LIB.T6G(SCH_1):PAGE59
   BW9 M_L_CPU1_SB_DQS_DN<9> @T6G_MB_LIB.T6G(SCH_1):M_L_CPU1_SB_DQS_DN(9)   I159 @T6G_MB_LIB.T6G(SCH_1):PAGE48
  CF11 M_L_CPU1_SB_DQS_DP<5> @T6G_MB_LIB.T6G(SCH_1):M_L_CPU1_SB_DQS_DP(5)   I159 @T6G_MB_LIB.T6G(SCH_1):PAGE48
   CF9 M_L_CPU1_SB_DQ<4> @T6G_MB_LIB.T6G(SCH_1):M_L_CPU1_SB_DQ(4)   I159 @T6G_MB_LIB.T6G(SCH_1):PAGE48
  BH11 M_L_CPU1_SB_CA<1> @T6G_MB_LIB.T6G(SCH_1):M_L_CPU1_SB_CA(1)   I159 @T6G_MB_LIB.T6G(SCH_1):PAGE48
   AB9 M_L_CPU1_SA_DQ<22> @T6G_MB_LIB.T6G(SCH_1):M_L_CPU1_SA_DQ(22)   I159 @T6G_MB_LIB.T6G(SCH_1):PAGE48
   N10 M_L_CPU1_SA_DQ<11> @T6G_MB_LIB.T6G(SCH_1):M_L_CPU1_SA_DQ(11)   I159 @T6G_MB_LIB.T6G(SCH_1):PAGE48
   K11 M_L_CPU1_SA_DQ<5> @T6G_MB_LIB.T6G(SCH_1):M_L_CPU1_SA_DQ(5)   I159 @T6G_MB_LIB.T6G(SCH_1):PAGE48
   AK9 M_L_CPU1_SA_CB<2> @T6G_MB_LIB.T6G(SCH_1):M_L_CPU1_SA_CB(2)   I159 @T6G_MB_LIB.T6G(SCH_1):PAGE48
  AY11 M_L_CPU1_SA_CA<2> @T6G_MB_LIB.T6G(SCH_1):M_L_CPU1_SA_CA(2)   I159 @T6G_MB_LIB.T6G(SCH_1):PAGE48
  AU10 M_L_CPU1_RESET_N @T6G_MB_LIB.T6G(SCH_1):M_L_CPU1_RESET_N   I159 @T6G_MB_LIB.T6G(SCH_1):PAGE48
  CM11 M_L_CPU1_SB_DQS_DP<6> @T6G_MB_LIB.T6G(SCH_1):M_L_CPU1_SB_DQS_DP(6)   I159 @T6G_MB_LIB.T6G(SCH_1):PAGE48
  CG10 M_L_CPU1_SB_DQ<5> @T6G_MB_LIB.T6G(SCH_1):M_L_CPU1_SB_DQ(5)   I159 @T6G_MB_LIB.T6G(SCH_1):PAGE48
   BH9 M_L_CPU1_SB_CA<2> @T6G_MB_LIB.T6G(SCH_1):M_L_CPU1_SB_CA(2)   I159 @T6G_MB_LIB.T6G(SCH_1):PAGE48
  BM11 M_L_CPU1_SB_CS_N<0> @T6G_MB_LIB.T6G(SCH_1):M_L_CPU1_SB_CS_N(0)   I159 @T6G_MB_LIB.T6G(SCH_1):PAGE48
  AC10 M_L_CPU1_SA_DQ<23> @T6G_MB_LIB.T6G(SCH_1):M_L_CPU1_SA_DQ(23)   I159 @T6G_MB_LIB.T6G(SCH_1):PAGE48
    R9 M_L_CPU1_SA_DQ<12> @T6G_MB_LIB.T6G(SCH_1):M_L_CPU1_SA_DQ(12)   I159 @T6G_MB_LIB.T6G(SCH_1):PAGE48
    K9 M_L_CPU1_SA_DQ<6> @T6G_MB_LIB.T6G(SCH_1):M_L_CPU1_SA_DQ(6)   I159 @T6G_MB_LIB.T6G(SCH_1):PAGE48
  AL10 M_L_CPU1_SA_CB<3> @T6G_MB_LIB.T6G(SCH_1):M_L_CPU1_SA_CB(3)   I159 @T6G_MB_LIB.T6G(SCH_1):PAGE48
  BA10 M_L_CPU1_SA_CA<3> @T6G_MB_LIB.T6G(SCH_1):M_L_CPU1_SA_CA(3)   I159 @T6G_MB_LIB.T6G(SCH_1):PAGE48
  CV11 M_L_CPU1_SB_DQS_DP<7> @T6G_MB_LIB.T6G(SCH_1):M_L_CPU1_SB_DQS_DP(7)   I159 @T6G_MB_LIB.T6G(SCH_1):PAGE48
   CG9 M_L_CPU1_SB_DQ<6> @T6G_MB_LIB.T6G(SCH_1):M_L_CPU1_SB_DQ(6)   I159 @T6G_MB_LIB.T6G(SCH_1):PAGE48
   BJ9 M_L_CPU1_SB_CA<3> @T6G_MB_LIB.T6G(SCH_1):M_L_CPU1_SB_CA(3)   I159 @T6G_MB_LIB.T6G(SCH_1):PAGE48
   BL9     NC     NC   I159 @T6G_MB_LIB.T6G(SCH_1):PAGE48
   BN9 M_L_CPU1_SB_CS_N<1> @T6G_MB_LIB.T6G(SCH_1):M_L_CPU1_SB_CS_N(1)   I159 @T6G_MB_LIB.T6G(SCH_1):PAGE48
    H9 M_L_CPU1_SA_DQS_DN<0> @T6G_MB_LIB.T6G(SCH_1):M_L_CPU1_SA_DQS_DN(0)   I159 @T6G_MB_LIB.T6G(SCH_1):PAGE48
   AC9 M_L_CPU1_SA_DQ<24> @T6G_MB_LIB.T6G(SCH_1):M_L_CPU1_SA_DQ(24)   I159 @T6G_MB_LIB.T6G(SCH_1):PAGE48
   T11 M_L_CPU1_SA_DQ<13> @T6G_MB_LIB.T6G(SCH_1):M_L_CPU1_SA_DQ(13)   I159 @T6G_MB_LIB.T6G(SCH_1):PAGE48
   L10 M_L_CPU1_SA_DQ<7> @T6G_MB_LIB.T6G(SCH_1):M_L_CPU1_SA_DQ(7)   I159 @T6G_MB_LIB.T6G(SCH_1):PAGE48
   AN9 M_L_CPU1_SA_CB<4> @T6G_MB_LIB.T6G(SCH_1):M_L_CPU1_SA_CB(4)   I159 @T6G_MB_LIB.T6G(SCH_1):PAGE48
   BA9 M_L_CPU1_SA_CA<4> @T6G_MB_LIB.T6G(SCH_1):M_L_CPU1_SA_CA(4)   I159 @T6G_MB_LIB.T6G(SCH_1):PAGE48
  DD11 M_L_CPU1_SB_DQS_DP<8> @T6G_MB_LIB.T6G(SCH_1):M_L_CPU1_SB_DQS_DP(8)   I159 @T6G_MB_LIB.T6G(SCH_1):PAGE48
   DE9 M_L_CPU1_SB_DQ<30> @T6G_MB_LIB.T6G(SCH_1):M_L_CPU1_SB_DQ(30)   I159 @T6G_MB_LIB.T6G(SCH_1):PAGE48
  CH11 M_L_CPU1_SB_DQ<7> @T6G_MB_LIB.T6G(SCH_1):M_L_CPU1_SB_DQ(7)   I159 @T6G_MB_LIB.T6G(SCH_1):PAGE48
  BJ10 M_L_CPU1_SB_CA<4> @T6G_MB_LIB.T6G(SCH_1):M_L_CPU1_SB_CA(4)   I159 @T6G_MB_LIB.T6G(SCH_1):PAGE48
   BM9     NC     NC   I159 @T6G_MB_LIB.T6G(SCH_1):PAGE48
    P9 M_L_CPU1_SA_DQS_DN<1> @T6G_MB_LIB.T6G(SCH_1):M_L_CPU1_SA_DQS_DN(1)   I159 @T6G_MB_LIB.T6G(SCH_1):PAGE48
  AD11 M_L_CPU1_SA_DQ<25> @T6G_MB_LIB.T6G(SCH_1):M_L_CPU1_SA_DQ(25)   I159 @T6G_MB_LIB.T6G(SCH_1):PAGE48
    T9 M_L_CPU1_SA_DQ<14> @T6G_MB_LIB.T6G(SCH_1):M_L_CPU1_SA_DQ(14)   I159 @T6G_MB_LIB.T6G(SCH_1):PAGE48
    L9 M_L_CPU1_SA_DQ<8> @T6G_MB_LIB.T6G(SCH_1):M_L_CPU1_SA_DQ(8)   I159 @T6G_MB_LIB.T6G(SCH_1):PAGE48
  AP11 M_L_CPU1_SA_CB<5> @T6G_MB_LIB.T6G(SCH_1):M_L_CPU1_SA_CB(5)   I159 @T6G_MB_LIB.T6G(SCH_1):PAGE48
   BB9 M_L_CPU1_SA_CA<5> @T6G_MB_LIB.T6G(SCH_1):M_L_CPU1_SA_CA(5)   I159 @T6G_MB_LIB.T6G(SCH_1):PAGE48
   BV9 M_L_CPU1_SB_DQS_DP<9> @T6G_MB_LIB.T6G(SCH_1):M_L_CPU1_SB_DQS_DP(9)   I159 @T6G_MB_LIB.T6G(SCH_1):PAGE48
   DF9 M_L_CPU1_SB_DQ<31> @T6G_MB_LIB.T6G(SCH_1):M_L_CPU1_SB_DQ(31)   I159 @T6G_MB_LIB.T6G(SCH_1):PAGE48
   CV9 M_L_CPU1_SB_DQ<20> @T6G_MB_LIB.T6G(SCH_1):M_L_CPU1_SB_DQ(20)   I159 @T6G_MB_LIB.T6G(SCH_1):PAGE48
   CH9 M_L_CPU1_SB_DQ<8> @T6G_MB_LIB.T6G(SCH_1):M_L_CPU1_SB_DQ(8)   I159 @T6G_MB_LIB.T6G(SCH_1):PAGE48
   BY9 M_L_CPU1_SB_CB<0> @T6G_MB_LIB.T6G(SCH_1):M_L_CPU1_SB_CB(0)   I159 @T6G_MB_LIB.T6G(SCH_1):PAGE48
  BK11 M_L_CPU1_SB_CA<5> @T6G_MB_LIB.T6G(SCH_1):M_L_CPU1_SB_CA(5)   I159 @T6G_MB_LIB.T6G(SCH_1):PAGE48
    Y9 M_L_CPU1_SA_DQS_DN<2> @T6G_MB_LIB.T6G(SCH_1):M_L_CPU1_SA_DQS_DN(2)   I159 @T6G_MB_LIB.T6G(SCH_1):PAGE48
   AD9 M_L_CPU1_SA_DQ<26> @T6G_MB_LIB.T6G(SCH_1):M_L_CPU1_SA_DQ(26)   I159 @T6G_MB_LIB.T6G(SCH_1):PAGE48
   U10 M_L_CPU1_SA_DQ<15> @T6G_MB_LIB.T6G(SCH_1):M_L_CPU1_SA_DQ(15)   I159 @T6G_MB_LIB.T6G(SCH_1):PAGE48
   M11 M_L_CPU1_SA_DQ<9> @T6G_MB_LIB.T6G(SCH_1):M_L_CPU1_SA_DQ(9)   I159 @T6G_MB_LIB.T6G(SCH_1):PAGE48
   AP9 M_L_CPU1_SA_CB<6> @T6G_MB_LIB.T6G(SCH_1):M_L_CPU1_SA_CB(6)   I159 @T6G_MB_LIB.T6G(SCH_1):PAGE48
  BB11 M_L_CPU1_SA_CA<6> @T6G_MB_LIB.T6G(SCH_1):M_L_CPU1_SA_CA(6)   I159 @T6G_MB_LIB.T6G(SCH_1):PAGE48
  BN10 M_L_CPU1_SA_RSP<0> @T6G_MB_LIB.T6G(SCH_1):M_L_CPU1_SA_RSP(0)   I159 @T6G_MB_LIB.T6G(SCH_1):PAGE48
  CW10 M_L_CPU1_SB_DQ<21> @T6G_MB_LIB.T6G(SCH_1):M_L_CPU1_SB_DQ(21)   I159 @T6G_MB_LIB.T6G(SCH_1):PAGE48
   CJ9 M_L_CPU1_SB_DQ<10> @T6G_MB_LIB.T6G(SCH_1):M_L_CPU1_SB_DQ(10)   I159 @T6G_MB_LIB.T6G(SCH_1):PAGE48
  CJ10 M_L_CPU1_SB_DQ<9> @T6G_MB_LIB.T6G(SCH_1):M_L_CPU1_SB_DQ(9)   I159 @T6G_MB_LIB.T6G(SCH_1):PAGE48
  CA10 M_L_CPU1_SB_CB<1> @T6G_MB_LIB.T6G(SCH_1):M_L_CPU1_SB_CB(1)   I159 @T6G_MB_LIB.T6G(SCH_1):PAGE48
   BK9 M_L_CPU1_SB_CA<6> @T6G_MB_LIB.T6G(SCH_1):M_L_CPU1_SB_CA(6)   I159 @T6G_MB_LIB.T6G(SCH_1):PAGE48
   AF9 M_L_CPU1_SA_DQS_DN<3> @T6G_MB_LIB.T6G(SCH_1):M_L_CPU1_SA_DQS_DN(3)   I159 @T6G_MB_LIB.T6G(SCH_1):PAGE48
  AE10 M_L_CPU1_SA_DQ<27> @T6G_MB_LIB.T6G(SCH_1):M_L_CPU1_SA_DQ(27)   I159 @T6G_MB_LIB.T6G(SCH_1):PAGE48
    U9 M_L_CPU1_SA_DQ<16> @T6G_MB_LIB.T6G(SCH_1):M_L_CPU1_SA_DQ(16)   I159 @T6G_MB_LIB.T6G(SCH_1):PAGE48
  AR10 M_L_CPU1_SA_CB<7> @T6G_MB_LIB.T6G(SCH_1):M_L_CPU1_SA_CB(7)   I159 @T6G_MB_LIB.T6G(SCH_1):PAGE48
  BP11     NC     NC   I159 @T6G_MB_LIB.T6G(SCH_1):PAGE48
  AT11 M_L_CPU1_ALERT_R_N @T6G_MB_LIB.T6G(SCH_1):M_L_CPU1_ALERT_R_N   I159 @T6G_MB_LIB.T6G(SCH_1):PAGE48
   CW9 M_L_CPU1_SB_DQ<22> @T6G_MB_LIB.T6G(SCH_1):M_L_CPU1_SB_DQ(22)   I159 @T6G_MB_LIB.T6G(SCH_1):PAGE48
  CK11 M_L_CPU1_SB_DQ<11> @T6G_MB_LIB.T6G(SCH_1):M_L_CPU1_SB_DQ(11)   I159 @T6G_MB_LIB.T6G(SCH_1):PAGE48
   CA9 M_L_CPU1_SB_CB<2> @T6G_MB_LIB.T6G(SCH_1):M_L_CPU1_SB_CB(2)   I159 @T6G_MB_LIB.T6G(SCH_1):PAGE48
   AM9 M_L_CPU1_SA_DQS_DN<4> @T6G_MB_LIB.T6G(SCH_1):M_L_CPU1_SA_DQS_DN(4)   I159 @T6G_MB_LIB.T6G(SCH_1):PAGE48
    G9 M_L_CPU1_SA_DQS_DP<0> @T6G_MB_LIB.T6G(SCH_1):M_L_CPU1_SA_DQS_DP(0)   I159 @T6G_MB_LIB.T6G(SCH_1):PAGE48
   AG9 M_L_CPU1_SA_DQ<28> @T6G_MB_LIB.T6G(SCH_1):M_L_CPU1_SA_DQ(28)   I159 @T6G_MB_LIB.T6G(SCH_1):PAGE48
   V11 M_L_CPU1_SA_DQ<17> @T6G_MB_LIB.T6G(SCH_1):M_L_CPU1_SA_DQ(17)   I159 @T6G_MB_LIB.T6G(SCH_1):PAGE48
  CY11 M_L_CPU1_SB_DQ<23> @T6G_MB_LIB.T6G(SCH_1):M_L_CPU1_SB_DQ(23)   I159 @T6G_MB_LIB.T6G(SCH_1):PAGE48
   CM9 M_L_CPU1_SB_DQ<12> @T6G_MB_LIB.T6G(SCH_1):M_L_CPU1_SB_DQ(12)   I159 @T6G_MB_LIB.T6G(SCH_1):PAGE48
  CB11 M_L_CPU1_SB_CB<3> @T6G_MB_LIB.T6G(SCH_1):M_L_CPU1_SB_CB(3)   I159 @T6G_MB_LIB.T6G(SCH_1):PAGE48
   H11 M_L_CPU1_SA_DQS_DN<5> @T6G_MB_LIB.T6G(SCH_1):M_L_CPU1_SA_DQS_DN(5)   I159 @T6G_MB_LIB.T6G(SCH_1):PAGE48
    N9 M_L_CPU1_SA_DQS_DP<1> @T6G_MB_LIB.T6G(SCH_1):M_L_CPU1_SA_DQS_DP(1)   I159 @T6G_MB_LIB.T6G(SCH_1):PAGE48
  AH11 M_L_CPU1_SA_DQ<29> @T6G_MB_LIB.T6G(SCH_1):M_L_CPU1_SA_DQ(29)   I159 @T6G_MB_LIB.T6G(SCH_1):PAGE48
    V9 M_L_CPU1_SA_DQ<18> @T6G_MB_LIB.T6G(SCH_1):M_L_CPU1_SA_DQ(18)   I159 @T6G_MB_LIB.T6G(SCH_1):PAGE48
   BC9 M_L_CPU1_CLK_DP<0> @T6G_MB_LIB.T6G(SCH_1):M_L_CPU1_CLK_DP(0)   I159 @T6G_MB_LIB.T6G(SCH_1):PAGE48
   CE9 M_L_CPU1_SB_DQS_DN<0> @T6G_MB_LIB.T6G(SCH_1):M_L_CPU1_SB_DQS_DN(0)   I159 @T6G_MB_LIB.T6G(SCH_1):PAGE48
   CY9 M_L_CPU1_SB_DQ<24> @T6G_MB_LIB.T6G(SCH_1):M_L_CPU1_SB_DQ(24)   I159 @T6G_MB_LIB.T6G(SCH_1):PAGE48
  CN10 M_L_CPU1_SB_DQ<13> @T6G_MB_LIB.T6G(SCH_1):M_L_CPU1_SB_DQ(13)   I159 @T6G_MB_LIB.T6G(SCH_1):PAGE48
   BT9 M_L_CPU1_SB_CB<4> @T6G_MB_LIB.T6G(SCH_1):M_L_CPU1_SB_CB(4)   I159 @T6G_MB_LIB.T6G(SCH_1):PAGE48
   P11 M_L_CPU1_SA_DQS_DN<6> @T6G_MB_LIB.T6G(SCH_1):M_L_CPU1_SA_DQS_DN(6)   I159 @T6G_MB_LIB.T6G(SCH_1):PAGE48
    W9 M_L_CPU1_SA_DQS_DP<2> @T6G_MB_LIB.T6G(SCH_1):M_L_CPU1_SA_DQS_DP(2)   I159 @T6G_MB_LIB.T6G(SCH_1):PAGE48
   W10 M_L_CPU1_SA_DQ<19> @T6G_MB_LIB.T6G(SCH_1):M_L_CPU1_SA_DQ(19)   I159 @T6G_MB_LIB.T6G(SCH_1):PAGE48
   BF9     NC     NC   I159 @T6G_MB_LIB.T6G(SCH_1):PAGE48
   CL9 M_L_CPU1_SB_DQS_DN<1> @T6G_MB_LIB.T6G(SCH_1):M_L_CPU1_SB_DQS_DN(1)   I159 @T6G_MB_LIB.T6G(SCH_1):PAGE48
  DA10 M_L_CPU1_SB_DQ<25> @T6G_MB_LIB.T6G(SCH_1):M_L_CPU1_SB_DQ(25)   I159 @T6G_MB_LIB.T6G(SCH_1):PAGE48
   CN9 M_L_CPU1_SB_DQ<14> @T6G_MB_LIB.T6G(SCH_1):M_L_CPU1_SB_DQ(14)   I159 @T6G_MB_LIB.T6G(SCH_1):PAGE48
  BU10 M_L_CPU1_SB_CB<5> @T6G_MB_LIB.T6G(SCH_1):M_L_CPU1_SB_CB(5)   I159 @T6G_MB_LIB.T6G(SCH_1):PAGE48
   Y11 M_L_CPU1_SA_DQS_DN<7> @T6G_MB_LIB.T6G(SCH_1):M_L_CPU1_SA_DQS_DN(7)   I159 @T6G_MB_LIB.T6G(SCH_1):PAGE48
   AE9 M_L_CPU1_SA_DQS_DP<3> @T6G_MB_LIB.T6G(SCH_1):M_L_CPU1_SA_DQS_DP(3)   I159 @T6G_MB_LIB.T6G(SCH_1):PAGE48
   CU9 M_L_CPU1_SB_DQS_DN<2> @T6G_MB_LIB.T6G(SCH_1):M_L_CPU1_SB_DQS_DN(2)   I159 @T6G_MB_LIB.T6G(SCH_1):PAGE48
   DA9 M_L_CPU1_SB_DQ<26> @T6G_MB_LIB.T6G(SCH_1):M_L_CPU1_SB_DQ(26)   I159 @T6G_MB_LIB.T6G(SCH_1):PAGE48
  CP11 M_L_CPU1_SB_DQ<15> @T6G_MB_LIB.T6G(SCH_1):M_L_CPU1_SB_DQ(15)   I159 @T6G_MB_LIB.T6G(SCH_1):PAGE48
   BU9 M_L_CPU1_SB_CB<6> @T6G_MB_LIB.T6G(SCH_1):M_L_CPU1_SB_CB(6)   I159 @T6G_MB_LIB.T6G(SCH_1):PAGE48
   BP9 M_L_CPU1_SB_RSP<0> @T6G_MB_LIB.T6G(SCH_1):M_L_CPU1_SB_RSP(0)   I159 @T6G_MB_LIB.T6G(SCH_1):PAGE48
  AF11 M_L_CPU1_SA_DQS_DN<8> @T6G_MB_LIB.T6G(SCH_1):M_L_CPU1_SA_DQS_DN(8)   I159 @T6G_MB_LIB.T6G(SCH_1):PAGE48
   AL9 M_L_CPU1_SA_DQS_DP<4> @T6G_MB_LIB.T6G(SCH_1):M_L_CPU1_SA_DQS_DP(4)   I159 @T6G_MB_LIB.T6G(SCH_1):PAGE48
   DC9 M_L_CPU1_SB_DQS_DN<3> @T6G_MB_LIB.T6G(SCH_1):M_L_CPU1_SB_DQS_DN(3)   I159 @T6G_MB_LIB.T6G(SCH_1):PAGE48
  DB11 M_L_CPU1_SB_DQ<27> @T6G_MB_LIB.T6G(SCH_1):M_L_CPU1_SB_DQ(27)   I159 @T6G_MB_LIB.T6G(SCH_1):PAGE48
   CP9 M_L_CPU1_SB_DQ<16> @T6G_MB_LIB.T6G(SCH_1):M_L_CPU1_SB_DQ(16)   I159 @T6G_MB_LIB.T6G(SCH_1):PAGE48
  BV11 M_L_CPU1_SB_CB<7> @T6G_MB_LIB.T6G(SCH_1):M_L_CPU1_SB_CB(7)   I159 @T6G_MB_LIB.T6G(SCH_1):PAGE48
   BR9     NC     NC   I159 @T6G_MB_LIB.T6G(SCH_1):PAGE48
  BC10 M_L_CPU1_SA_PAR @T6G_MB_LIB.T6G(SCH_1):M_L_CPU1_SA_PAR   I159 @T6G_MB_LIB.T6G(SCH_1):PAGE48
  AM11 M_L_CPU1_SA_DQS_DN<9> @T6G_MB_LIB.T6G(SCH_1):M_L_CPU1_SA_DQS_DN(9)   I159 @T6G_MB_LIB.T6G(SCH_1):PAGE48
   J10 M_L_CPU1_SA_DQS_DP<5> @T6G_MB_LIB.T6G(SCH_1):M_L_CPU1_SA_DQS_DP(5)   I159 @T6G_MB_LIB.T6G(SCH_1):PAGE48
   BD9 M_L_CPU1_CLK_DN<0> @T6G_MB_LIB.T6G(SCH_1):M_L_CPU1_CLK_DN(0)   I159 @T6G_MB_LIB.T6G(SCH_1):PAGE48
  BL10 M_L_CPU1_SB_PAR @T6G_MB_LIB.T6G(SCH_1):M_L_CPU1_SB_PAR   I159 @T6G_MB_LIB.T6G(SCH_1):PAGE48
  BW10 M_L_CPU1_SB_DQS_DN<4> @T6G_MB_LIB.T6G(SCH_1):M_L_CPU1_SB_DQS_DN(4)   I159 @T6G_MB_LIB.T6G(SCH_1):PAGE48
   CD9 M_L_CPU1_SB_DQS_DP<0> @T6G_MB_LIB.T6G(SCH_1):M_L_CPU1_SB_DQS_DP(0)   I159 @T6G_MB_LIB.T6G(SCH_1):PAGE48
   DD9 M_L_CPU1_SB_DQ<28> @T6G_MB_LIB.T6G(SCH_1):M_L_CPU1_SB_DQ(28)   I159 @T6G_MB_LIB.T6G(SCH_1):PAGE48
  CR10 M_L_CPU1_SB_DQ<17> @T6G_MB_LIB.T6G(SCH_1):M_L_CPU1_SB_DQ(17)   I159 @T6G_MB_LIB.T6G(SCH_1):PAGE48
   R10 M_L_CPU1_SA_DQS_DP<6> @T6G_MB_LIB.T6G(SCH_1):M_L_CPU1_SA_DQS_DP(6)   I159 @T6G_MB_LIB.T6G(SCH_1):PAGE48
    E9 M_L_CPU1_SA_DQ<0> @T6G_MB_LIB.T6G(SCH_1):M_L_CPU1_SA_DQ(0)   I159 @T6G_MB_LIB.T6G(SCH_1):PAGE48
   AU9 M_L_CPU1_SA_CS_N<0> @T6G_MB_LIB.T6G(SCH_1):M_L_CPU1_SA_CS_N(0)   I159 @T6G_MB_LIB.T6G(SCH_1):PAGE48
   BG9     NC     NC   I159 @T6G_MB_LIB.T6G(SCH_1):PAGE48
  CE10 M_L_CPU1_SB_DQS_DN<5> @T6G_MB_LIB.T6G(SCH_1):M_L_CPU1_SB_DQS_DN(5)   I159 @T6G_MB_LIB.T6G(SCH_1):PAGE48
   CK9 M_L_CPU1_SB_DQS_DP<1> @T6G_MB_LIB.T6G(SCH_1):M_L_CPU1_SB_DQS_DP(1)   I159 @T6G_MB_LIB.T6G(SCH_1):PAGE48
  DE10 M_L_CPU1_SB_DQ<29> @T6G_MB_LIB.T6G(SCH_1):M_L_CPU1_SB_DQ(29)   I159 @T6G_MB_LIB.T6G(SCH_1):PAGE48
   CR9 M_L_CPU1_SB_DQ<18> @T6G_MB_LIB.T6G(SCH_1):M_L_CPU1_SB_DQ(18)   I159 @T6G_MB_LIB.T6G(SCH_1):PAGE48
   CB9 M_L_CPU1_SB_DQ<0> @T6G_MB_LIB.T6G(SCH_1):M_L_CPU1_SB_DQ(0)   I159 @T6G_MB_LIB.T6G(SCH_1):PAGE48
  AA10 M_L_CPU1_SA_DQS_DP<7> @T6G_MB_LIB.T6G(SCH_1):M_L_CPU1_SA_DQS_DP(7)   I159 @T6G_MB_LIB.T6G(SCH_1):PAGE48
   F11 M_L_CPU1_SA_DQ<1> @T6G_MB_LIB.T6G(SCH_1):M_L_CPU1_SA_DQ(1)   I159 @T6G_MB_LIB.T6G(SCH_1):PAGE48
   AV9     NC     NC   I159 @T6G_MB_LIB.T6G(SCH_1):PAGE48
  AV11 M_L_CPU1_SA_CS_N<1> @T6G_MB_LIB.T6G(SCH_1):M_L_CPU1_SA_CS_N(1)   I159 @T6G_MB_LIB.T6G(SCH_1):PAGE48
  CL10 M_L_CPU1_SB_DQS_DN<6> @T6G_MB_LIB.T6G(SCH_1):M_L_CPU1_SB_DQS_DN(6)   I159 @T6G_MB_LIB.T6G(SCH_1):PAGE48
   CT9 M_L_CPU1_SB_DQS_DP<2> @T6G_MB_LIB.T6G(SCH_1):M_L_CPU1_SB_DQS_DP(2)   I159 @T6G_MB_LIB.T6G(SCH_1):PAGE48
  CT11 M_L_CPU1_SB_DQ<19> @T6G_MB_LIB.T6G(SCH_1):M_L_CPU1_SB_DQ(19)   I159 @T6G_MB_LIB.T6G(SCH_1):PAGE48
  CC10 M_L_CPU1_SB_DQ<1> @T6G_MB_LIB.T6G(SCH_1):M_L_CPU1_SB_DQ(1)   I159 @T6G_MB_LIB.T6G(SCH_1):PAGE48
  AG10 M_L_CPU1_SA_DQS_DP<8> @T6G_MB_LIB.T6G(SCH_1):M_L_CPU1_SA_DQS_DP(8)   I159 @T6G_MB_LIB.T6G(SCH_1):PAGE48
   AH9 M_L_CPU1_SA_DQ<30> @T6G_MB_LIB.T6G(SCH_1):M_L_CPU1_SA_DQ(30)   I159 @T6G_MB_LIB.T6G(SCH_1):PAGE48
    F9 M_L_CPU1_SA_DQ<2> @T6G_MB_LIB.T6G(SCH_1):M_L_CPU1_SA_DQ(2)   I159 @T6G_MB_LIB.T6G(SCH_1):PAGE48
  AW10     NC     NC   I159 @T6G_MB_LIB.T6G(SCH_1):PAGE48
  CU10 M_L_CPU1_SB_DQS_DN<7> @T6G_MB_LIB.T6G(SCH_1):M_L_CPU1_SB_DQS_DN(7)   I159 @T6G_MB_LIB.T6G(SCH_1):PAGE48
   DB9 M_L_CPU1_SB_DQS_DP<3> @T6G_MB_LIB.T6G(SCH_1):M_L_CPU1_SB_DQS_DP(3)   I159 @T6G_MB_LIB.T6G(SCH_1):PAGE48
   CC9 M_L_CPU1_SB_DQ<2> @T6G_MB_LIB.T6G(SCH_1):M_L_CPU1_SB_DQ(2)   I159 @T6G_MB_LIB.T6G(SCH_1):PAGE48
  AN10 M_L_CPU1_SA_DQS_DP<9> @T6G_MB_LIB.T6G(SCH_1):M_L_CPU1_SA_DQS_DP(9)   I159 @T6G_MB_LIB.T6G(SCH_1):PAGE48
  AJ10 M_L_CPU1_SA_DQ<31> @T6G_MB_LIB.T6G(SCH_1):M_L_CPU1_SA_DQ(31)   I159 @T6G_MB_LIB.T6G(SCH_1):PAGE48
   AA9 M_L_CPU1_SA_DQ<20> @T6G_MB_LIB.T6G(SCH_1):M_L_CPU1_SA_DQ(20)   I159 @T6G_MB_LIB.T6G(SCH_1):PAGE48
   G10 M_L_CPU1_SA_DQ<3> @T6G_MB_LIB.T6G(SCH_1):M_L_CPU1_SA_DQ(3)   I159 @T6G_MB_LIB.T6G(SCH_1):PAGE48
   AJ9 M_L_CPU1_SA_CB<0> @T6G_MB_LIB.T6G(SCH_1):M_L_CPU1_SA_CB(0)   I159 @T6G_MB_LIB.T6G(SCH_1):PAGE48
   AW9 M_L_CPU1_SA_CA<0> @T6G_MB_LIB.T6G(SCH_1):M_L_CPU1_SA_CA(0)   I159 @T6G_MB_LIB.T6G(SCH_1):PAGE48
  DC10 M_L_CPU1_SB_DQS_DN<8> @T6G_MB_LIB.T6G(SCH_1):M_L_CPU1_SB_DQS_DN(8)   I159 @T6G_MB_LIB.T6G(SCH_1):PAGE48
  BY11 M_L_CPU1_SB_DQS_DP<4> @T6G_MB_LIB.T6G(SCH_1):M_L_CPU1_SB_DQS_DP(4)   I159 @T6G_MB_LIB.T6G(SCH_1):PAGE48
  CD11 M_L_CPU1_SB_DQ<3> @T6G_MB_LIB.T6G(SCH_1):M_L_CPU1_SB_DQ(3)   I159 @T6G_MB_LIB.T6G(SCH_1):PAGE48
  BG10 M_L_CPU1_SB_CA<0> @T6G_MB_LIB.T6G(SCH_1):M_L_CPU1_SB_CA(0)   I159 @T6G_MB_LIB.T6G(SCH_1):PAGE48
  AB11 M_L_CPU1_SA_DQ<21> @T6G_MB_LIB.T6G(SCH_1):M_L_CPU1_SA_DQ(21)   I159 @T6G_MB_LIB.T6G(SCH_1):PAGE48
    M9 M_L_CPU1_SA_DQ<10> @T6G_MB_LIB.T6G(SCH_1):M_L_CPU1_SA_DQ(10)   I159 @T6G_MB_LIB.T6G(SCH_1):PAGE48
    J9 M_L_CPU1_SA_DQ<4> @T6G_MB_LIB.T6G(SCH_1):M_L_CPU1_SA_DQ(4)   I159 @T6G_MB_LIB.T6G(SCH_1):PAGE48
  AK11 M_L_CPU1_SA_CB<1> @T6G_MB_LIB.T6G(SCH_1):M_L_CPU1_SA_CB(1)   I159 @T6G_MB_LIB.T6G(SCH_1):PAGE48
   AY9 M_L_CPU1_SA_CA<1> @T6G_MB_LIB.T6G(SCH_1):M_L_CPU1_SA_CA(1)   I159 @T6G_MB_LIB.T6G(SCH_1):PAGE48
  BF11 TP_M_L_CPU1_SA_TEST39L @T6G_MB_LIB.T6G(SCH_1):TP_M_L_CPU1_SA_TEST39L   I159 @T6G_MB_LIB.T6G(SCH_1):PAGE48
   CL7 M_K_CPU1_SB_DQS_DN<6> @T6G_MB_LIB.T6G(SCH_1):M_K_CPU1_SB_DQS_DN(6)   I159 @T6G_MB_LIB.T6G(SCH_1):PAGE47
   CT6 M_K_CPU1_SB_DQS_DP<2> @T6G_MB_LIB.T6G(SCH_1):M_K_CPU1_SB_DQS_DP(2)   I159 @T6G_MB_LIB.T6G(SCH_1):PAGE47
   CT7 M_K_CPU1_SB_DQ<19> @T6G_MB_LIB.T6G(SCH_1):M_K_CPU1_SB_DQ(19)   I159 @T6G_MB_LIB.T6G(SCH_1):PAGE47
   BG7 M_K_CPU1_SB_CA<0> @T6G_MB_LIB.T6G(SCH_1):M_K_CPU1_SB_CA(0)   I159 @T6G_MB_LIB.T6G(SCH_1):PAGE47
   AG7 M_K_CPU1_SA_DQS_DP<8> @T6G_MB_LIB.T6G(SCH_1):M_K_CPU1_SA_DQS_DP(8)   I159 @T6G_MB_LIB.T6G(SCH_1):PAGE47
   AH6 M_K_CPU1_SA_DQ<30> @T6G_MB_LIB.T6G(SCH_1):M_K_CPU1_SA_DQ(30)   I159 @T6G_MB_LIB.T6G(SCH_1):PAGE47
   AY6 M_K_CPU1_SA_CA<1> @T6G_MB_LIB.T6G(SCH_1):M_K_CPU1_SA_CA(1)   I159 @T6G_MB_LIB.T6G(SCH_1):PAGE47
   AV6     NC     NC   I159 @T6G_MB_LIB.T6G(SCH_1):PAGE47
   AV7 M_K_CPU1_SA_CS_N<1> @T6G_MB_LIB.T6G(SCH_1):M_K_CPU1_SA_CS_N(1)   I159 @T6G_MB_LIB.T6G(SCH_1):PAGE47
   CU7 M_K_CPU1_SB_DQS_DN<7> @T6G_MB_LIB.T6G(SCH_1):M_K_CPU1_SB_DQS_DN(7)   I159 @T6G_MB_LIB.T6G(SCH_1):PAGE47
   DB6 M_K_CPU1_SB_DQS_DP<3> @T6G_MB_LIB.T6G(SCH_1):M_K_CPU1_SB_DQS_DP(3)   I159 @T6G_MB_LIB.T6G(SCH_1):PAGE47
   BH7 M_K_CPU1_SB_CA<1> @T6G_MB_LIB.T6G(SCH_1):M_K_CPU1_SB_CA(1)   I159 @T6G_MB_LIB.T6G(SCH_1):PAGE47
   AN7 M_K_CPU1_SA_DQS_DP<9> @T6G_MB_LIB.T6G(SCH_1):M_K_CPU1_SA_DQS_DP(9)   I159 @T6G_MB_LIB.T6G(SCH_1):PAGE47
   AJ7 M_K_CPU1_SA_DQ<31> @T6G_MB_LIB.T6G(SCH_1):M_K_CPU1_SA_DQ(31)   I159 @T6G_MB_LIB.T6G(SCH_1):PAGE47
   AA5 M_K_CPU1_SA_DQ<20> @T6G_MB_LIB.T6G(SCH_1):M_K_CPU1_SA_DQ(20)   I159 @T6G_MB_LIB.T6G(SCH_1):PAGE47
   AJ5 M_K_CPU1_SA_CB<0> @T6G_MB_LIB.T6G(SCH_1):M_K_CPU1_SA_CB(0)   I159 @T6G_MB_LIB.T6G(SCH_1):PAGE47
   AY7 M_K_CPU1_SA_CA<2> @T6G_MB_LIB.T6G(SCH_1):M_K_CPU1_SA_CA(2)   I159 @T6G_MB_LIB.T6G(SCH_1):PAGE47
   AW7     NC     NC   I159 @T6G_MB_LIB.T6G(SCH_1):PAGE47
   BC5 M_K_CPU1_CLK_DP<0> @T6G_MB_LIB.T6G(SCH_1):M_K_CPU1_CLK_DP(0)   I159 @T6G_MB_LIB.T6G(SCH_1):PAGE47
   DC7 M_K_CPU1_SB_DQS_DN<8> @T6G_MB_LIB.T6G(SCH_1):M_K_CPU1_SB_DQS_DN(8)   I159 @T6G_MB_LIB.T6G(SCH_1):PAGE47
   BY7 M_K_CPU1_SB_DQS_DP<4> @T6G_MB_LIB.T6G(SCH_1):M_K_CPU1_SB_DQS_DP(4)   I159 @T6G_MB_LIB.T6G(SCH_1):PAGE47
   BH6 M_K_CPU1_SB_CA<2> @T6G_MB_LIB.T6G(SCH_1):M_K_CPU1_SB_CA(2)   I159 @T6G_MB_LIB.T6G(SCH_1):PAGE47
   AB7 M_K_CPU1_SA_DQ<21> @T6G_MB_LIB.T6G(SCH_1):M_K_CPU1_SA_DQ(21)   I159 @T6G_MB_LIB.T6G(SCH_1):PAGE47
    M6 M_K_CPU1_SA_DQ<10> @T6G_MB_LIB.T6G(SCH_1):M_K_CPU1_SA_DQ(10)   I159 @T6G_MB_LIB.T6G(SCH_1):PAGE47
   AK7 M_K_CPU1_SA_CB<1> @T6G_MB_LIB.T6G(SCH_1):M_K_CPU1_SA_CB(1)   I159 @T6G_MB_LIB.T6G(SCH_1):PAGE47
   BA7 M_K_CPU1_SA_CA<3> @T6G_MB_LIB.T6G(SCH_1):M_K_CPU1_SA_CA(3)   I159 @T6G_MB_LIB.T6G(SCH_1):PAGE47
   BF6     NC     NC   I159 @T6G_MB_LIB.T6G(SCH_1):PAGE47
   BW5 M_K_CPU1_SB_DQS_DN<9> @T6G_MB_LIB.T6G(SCH_1):M_K_CPU1_SB_DQS_DN(9)   I159 @T6G_MB_LIB.T6G(SCH_1):PAGE47
   CF7 M_K_CPU1_SB_DQS_DP<5> @T6G_MB_LIB.T6G(SCH_1):M_K_CPU1_SB_DQS_DP(5)   I159 @T6G_MB_LIB.T6G(SCH_1):PAGE47
   BJ5 M_K_CPU1_SB_CA<3> @T6G_MB_LIB.T6G(SCH_1):M_K_CPU1_SB_CA(3)   I159 @T6G_MB_LIB.T6G(SCH_1):PAGE47
   AB6 M_K_CPU1_SA_DQ<22> @T6G_MB_LIB.T6G(SCH_1):M_K_CPU1_SA_DQ(22)   I159 @T6G_MB_LIB.T6G(SCH_1):PAGE47
    N7 M_K_CPU1_SA_DQ<11> @T6G_MB_LIB.T6G(SCH_1):M_K_CPU1_SA_DQ(11)   I159 @T6G_MB_LIB.T6G(SCH_1):PAGE47
   AK6 M_K_CPU1_SA_CB<2> @T6G_MB_LIB.T6G(SCH_1):M_K_CPU1_SA_CB(2)   I159 @T6G_MB_LIB.T6G(SCH_1):PAGE47
   BA5 M_K_CPU1_SA_CA<4> @T6G_MB_LIB.T6G(SCH_1):M_K_CPU1_SA_CA(4)   I159 @T6G_MB_LIB.T6G(SCH_1):PAGE47
   AU7 M_K_CPU1_RESET_N @T6G_MB_LIB.T6G(SCH_1):M_K_CPU1_RESET_N   I159 @T6G_MB_LIB.T6G(SCH_1):PAGE47
   CM7 M_K_CPU1_SB_DQS_DP<6> @T6G_MB_LIB.T6G(SCH_1):M_K_CPU1_SB_DQS_DP(6)   I159 @T6G_MB_LIB.T6G(SCH_1):PAGE47
   BJ7 M_K_CPU1_SB_CA<4> @T6G_MB_LIB.T6G(SCH_1):M_K_CPU1_SB_CA(4)   I159 @T6G_MB_LIB.T6G(SCH_1):PAGE47
   AC7 M_K_CPU1_SA_DQ<23> @T6G_MB_LIB.T6G(SCH_1):M_K_CPU1_SA_DQ(23)   I159 @T6G_MB_LIB.T6G(SCH_1):PAGE47
    R5 M_K_CPU1_SA_DQ<12> @T6G_MB_LIB.T6G(SCH_1):M_K_CPU1_SA_DQ(12)   I159 @T6G_MB_LIB.T6G(SCH_1):PAGE47
   AL7 M_K_CPU1_SA_CB<3> @T6G_MB_LIB.T6G(SCH_1):M_K_CPU1_SA_CB(3)   I159 @T6G_MB_LIB.T6G(SCH_1):PAGE47
   BB6 M_K_CPU1_SA_CA<5> @T6G_MB_LIB.T6G(SCH_1):M_K_CPU1_SA_CA(5)   I159 @T6G_MB_LIB.T6G(SCH_1):PAGE47
   CV7 M_K_CPU1_SB_DQS_DP<7> @T6G_MB_LIB.T6G(SCH_1):M_K_CPU1_SB_DQS_DP(7)   I159 @T6G_MB_LIB.T6G(SCH_1):PAGE47
   BK7 M_K_CPU1_SB_CA<5> @T6G_MB_LIB.T6G(SCH_1):M_K_CPU1_SB_CA(5)   I159 @T6G_MB_LIB.T6G(SCH_1):PAGE47
   BM7 M_K_CPU1_SB_CS_N<0> @T6G_MB_LIB.T6G(SCH_1):M_K_CPU1_SB_CS_N(0)   I159 @T6G_MB_LIB.T6G(SCH_1):PAGE47
    H6 M_K_CPU1_SA_DQS_DN<0> @T6G_MB_LIB.T6G(SCH_1):M_K_CPU1_SA_DQS_DN(0)   I159 @T6G_MB_LIB.T6G(SCH_1):PAGE47
   AC5 M_K_CPU1_SA_DQ<24> @T6G_MB_LIB.T6G(SCH_1):M_K_CPU1_SA_DQ(24)   I159 @T6G_MB_LIB.T6G(SCH_1):PAGE47
    T7 M_K_CPU1_SA_DQ<13> @T6G_MB_LIB.T6G(SCH_1):M_K_CPU1_SA_DQ(13)   I159 @T6G_MB_LIB.T6G(SCH_1):PAGE47
   AN5 M_K_CPU1_SA_CB<4> @T6G_MB_LIB.T6G(SCH_1):M_K_CPU1_SA_CB(4)   I159 @T6G_MB_LIB.T6G(SCH_1):PAGE47
   BB7 M_K_CPU1_SA_CA<6> @T6G_MB_LIB.T6G(SCH_1):M_K_CPU1_SA_CA(6)   I159 @T6G_MB_LIB.T6G(SCH_1):PAGE47
   BD6 M_K_CPU1_CLK_DN<0> @T6G_MB_LIB.T6G(SCH_1):M_K_CPU1_CLK_DN(0)   I159 @T6G_MB_LIB.T6G(SCH_1):PAGE47
   DD7 M_K_CPU1_SB_DQS_DP<8> @T6G_MB_LIB.T6G(SCH_1):M_K_CPU1_SB_DQS_DP(8)   I159 @T6G_MB_LIB.T6G(SCH_1):PAGE47
   DE5 M_K_CPU1_SB_DQ<30> @T6G_MB_LIB.T6G(SCH_1):M_K_CPU1_SB_DQ(30)   I159 @T6G_MB_LIB.T6G(SCH_1):PAGE47
   BK6 M_K_CPU1_SB_CA<6> @T6G_MB_LIB.T6G(SCH_1):M_K_CPU1_SB_CA(6)   I159 @T6G_MB_LIB.T6G(SCH_1):PAGE47
   BL5     NC     NC   I159 @T6G_MB_LIB.T6G(SCH_1):PAGE47
   BN5 M_K_CPU1_SB_CS_N<1> @T6G_MB_LIB.T6G(SCH_1):M_K_CPU1_SB_CS_N(1)   I159 @T6G_MB_LIB.T6G(SCH_1):PAGE47
    P6 M_K_CPU1_SA_DQS_DN<1> @T6G_MB_LIB.T6G(SCH_1):M_K_CPU1_SA_DQS_DN(1)   I159 @T6G_MB_LIB.T6G(SCH_1):PAGE47
   AD7 M_K_CPU1_SA_DQ<25> @T6G_MB_LIB.T6G(SCH_1):M_K_CPU1_SA_DQ(25)   I159 @T6G_MB_LIB.T6G(SCH_1):PAGE47
    T6 M_K_CPU1_SA_DQ<14> @T6G_MB_LIB.T6G(SCH_1):M_K_CPU1_SA_DQ(14)   I159 @T6G_MB_LIB.T6G(SCH_1):PAGE47
    E5 M_K_CPU1_SA_DQ<0> @T6G_MB_LIB.T6G(SCH_1):M_K_CPU1_SA_DQ(0)   I159 @T6G_MB_LIB.T6G(SCH_1):PAGE47
   AP7 M_K_CPU1_SA_CB<5> @T6G_MB_LIB.T6G(SCH_1):M_K_CPU1_SA_CB(5)   I159 @T6G_MB_LIB.T6G(SCH_1):PAGE47
   BG5     NC     NC   I159 @T6G_MB_LIB.T6G(SCH_1):PAGE47
   BV6 M_K_CPU1_SB_DQS_DP<9> @T6G_MB_LIB.T6G(SCH_1):M_K_CPU1_SB_DQS_DP(9)   I159 @T6G_MB_LIB.T6G(SCH_1):PAGE47
   DF7 M_K_CPU1_SB_DQ<31> @T6G_MB_LIB.T6G(SCH_1):M_K_CPU1_SB_DQ(31)   I159 @T6G_MB_LIB.T6G(SCH_1):PAGE47
   CV6 M_K_CPU1_SB_DQ<20> @T6G_MB_LIB.T6G(SCH_1):M_K_CPU1_SB_DQ(20)   I159 @T6G_MB_LIB.T6G(SCH_1):PAGE47
   CB6 M_K_CPU1_SB_DQ<0> @T6G_MB_LIB.T6G(SCH_1):M_K_CPU1_SB_DQ(0)   I159 @T6G_MB_LIB.T6G(SCH_1):PAGE47
   BY6 M_K_CPU1_SB_CB<0> @T6G_MB_LIB.T6G(SCH_1):M_K_CPU1_SB_CB(0)   I159 @T6G_MB_LIB.T6G(SCH_1):PAGE47
   BM6     NC     NC   I159 @T6G_MB_LIB.T6G(SCH_1):PAGE47
    Y6 M_K_CPU1_SA_DQS_DN<2> @T6G_MB_LIB.T6G(SCH_1):M_K_CPU1_SA_DQS_DN(2)   I159 @T6G_MB_LIB.T6G(SCH_1):PAGE47
   AD6 M_K_CPU1_SA_DQ<26> @T6G_MB_LIB.T6G(SCH_1):M_K_CPU1_SA_DQ(26)   I159 @T6G_MB_LIB.T6G(SCH_1):PAGE47
    U7 M_K_CPU1_SA_DQ<15> @T6G_MB_LIB.T6G(SCH_1):M_K_CPU1_SA_DQ(15)   I159 @T6G_MB_LIB.T6G(SCH_1):PAGE47
    F7 M_K_CPU1_SA_DQ<1> @T6G_MB_LIB.T6G(SCH_1):M_K_CPU1_SA_DQ(1)   I159 @T6G_MB_LIB.T6G(SCH_1):PAGE47
   AP6 M_K_CPU1_SA_CB<6> @T6G_MB_LIB.T6G(SCH_1):M_K_CPU1_SA_CB(6)   I159 @T6G_MB_LIB.T6G(SCH_1):PAGE47
   CW7 M_K_CPU1_SB_DQ<21> @T6G_MB_LIB.T6G(SCH_1):M_K_CPU1_SB_DQ(21)   I159 @T6G_MB_LIB.T6G(SCH_1):PAGE47
   CJ5 M_K_CPU1_SB_DQ<10> @T6G_MB_LIB.T6G(SCH_1):M_K_CPU1_SB_DQ(10)   I159 @T6G_MB_LIB.T6G(SCH_1):PAGE47
   CC7 M_K_CPU1_SB_DQ<1> @T6G_MB_LIB.T6G(SCH_1):M_K_CPU1_SB_DQ(1)   I159 @T6G_MB_LIB.T6G(SCH_1):PAGE47
   CA7 M_K_CPU1_SB_CB<1> @T6G_MB_LIB.T6G(SCH_1):M_K_CPU1_SB_CB(1)   I159 @T6G_MB_LIB.T6G(SCH_1):PAGE47
   AF6 M_K_CPU1_SA_DQS_DN<3> @T6G_MB_LIB.T6G(SCH_1):M_K_CPU1_SA_DQS_DN(3)   I159 @T6G_MB_LIB.T6G(SCH_1):PAGE47
   AE7 M_K_CPU1_SA_DQ<27> @T6G_MB_LIB.T6G(SCH_1):M_K_CPU1_SA_DQ(27)   I159 @T6G_MB_LIB.T6G(SCH_1):PAGE47
    U5 M_K_CPU1_SA_DQ<16> @T6G_MB_LIB.T6G(SCH_1):M_K_CPU1_SA_DQ(16)   I159 @T6G_MB_LIB.T6G(SCH_1):PAGE47
    F6 M_K_CPU1_SA_DQ<2> @T6G_MB_LIB.T6G(SCH_1):M_K_CPU1_SA_DQ(2)   I159 @T6G_MB_LIB.T6G(SCH_1):PAGE47
   AR7 M_K_CPU1_SA_CB<7> @T6G_MB_LIB.T6G(SCH_1):M_K_CPU1_SA_CB(7)   I159 @T6G_MB_LIB.T6G(SCH_1):PAGE47
   BN7 M_K_CPU1_SA_RSP<0> @T6G_MB_LIB.T6G(SCH_1):M_K_CPU1_SA_RSP(0)   I159 @T6G_MB_LIB.T6G(SCH_1):PAGE47
   AT7 M_K_CPU1_ALERT_R_N @T6G_MB_LIB.T6G(SCH_1):M_K_CPU1_ALERT_R_N   I159 @T6G_MB_LIB.T6G(SCH_1):PAGE47
   CW5 M_K_CPU1_SB_DQ<22> @T6G_MB_LIB.T6G(SCH_1):M_K_CPU1_SB_DQ(22)   I159 @T6G_MB_LIB.T6G(SCH_1):PAGE47
   CK7 M_K_CPU1_SB_DQ<11> @T6G_MB_LIB.T6G(SCH_1):M_K_CPU1_SB_DQ(11)   I159 @T6G_MB_LIB.T6G(SCH_1):PAGE47
   CC5 M_K_CPU1_SB_DQ<2> @T6G_MB_LIB.T6G(SCH_1):M_K_CPU1_SB_DQ(2)   I159 @T6G_MB_LIB.T6G(SCH_1):PAGE47
   CA5 M_K_CPU1_SB_CB<2> @T6G_MB_LIB.T6G(SCH_1):M_K_CPU1_SB_CB(2)   I159 @T6G_MB_LIB.T6G(SCH_1):PAGE47
   AM6 M_K_CPU1_SA_DQS_DN<4> @T6G_MB_LIB.T6G(SCH_1):M_K_CPU1_SA_DQS_DN(4)   I159 @T6G_MB_LIB.T6G(SCH_1):PAGE47
    G5 M_K_CPU1_SA_DQS_DP<0> @T6G_MB_LIB.T6G(SCH_1):M_K_CPU1_SA_DQS_DP(0)   I159 @T6G_MB_LIB.T6G(SCH_1):PAGE47
   AG5 M_K_CPU1_SA_DQ<28> @T6G_MB_LIB.T6G(SCH_1):M_K_CPU1_SA_DQ(28)   I159 @T6G_MB_LIB.T6G(SCH_1):PAGE47
    V7 M_K_CPU1_SA_DQ<17> @T6G_MB_LIB.T6G(SCH_1):M_K_CPU1_SA_DQ(17)   I159 @T6G_MB_LIB.T6G(SCH_1):PAGE47
    G7 M_K_CPU1_SA_DQ<3> @T6G_MB_LIB.T6G(SCH_1):M_K_CPU1_SA_DQ(3)   I159 @T6G_MB_LIB.T6G(SCH_1):PAGE47
   BP7     NC     NC   I159 @T6G_MB_LIB.T6G(SCH_1):PAGE47
   CY7 M_K_CPU1_SB_DQ<23> @T6G_MB_LIB.T6G(SCH_1):M_K_CPU1_SB_DQ(23)   I159 @T6G_MB_LIB.T6G(SCH_1):PAGE47
   CM6 M_K_CPU1_SB_DQ<12> @T6G_MB_LIB.T6G(SCH_1):M_K_CPU1_SB_DQ(12)   I159 @T6G_MB_LIB.T6G(SCH_1):PAGE47
   CD7 M_K_CPU1_SB_DQ<3> @T6G_MB_LIB.T6G(SCH_1):M_K_CPU1_SB_DQ(3)   I159 @T6G_MB_LIB.T6G(SCH_1):PAGE47
   CB7 M_K_CPU1_SB_CB<3> @T6G_MB_LIB.T6G(SCH_1):M_K_CPU1_SB_CB(3)   I159 @T6G_MB_LIB.T6G(SCH_1):PAGE47
    H7 M_K_CPU1_SA_DQS_DN<5> @T6G_MB_LIB.T6G(SCH_1):M_K_CPU1_SA_DQS_DN(5)   I159 @T6G_MB_LIB.T6G(SCH_1):PAGE47
    N5 M_K_CPU1_SA_DQS_DP<1> @T6G_MB_LIB.T6G(SCH_1):M_K_CPU1_SA_DQS_DP(1)   I159 @T6G_MB_LIB.T6G(SCH_1):PAGE47
   AH7 M_K_CPU1_SA_DQ<29> @T6G_MB_LIB.T6G(SCH_1):M_K_CPU1_SA_DQ(29)   I159 @T6G_MB_LIB.T6G(SCH_1):PAGE47
    V6 M_K_CPU1_SA_DQ<18> @T6G_MB_LIB.T6G(SCH_1):M_K_CPU1_SA_DQ(18)   I159 @T6G_MB_LIB.T6G(SCH_1):PAGE47
    J5 M_K_CPU1_SA_DQ<4> @T6G_MB_LIB.T6G(SCH_1):M_K_CPU1_SA_DQ(4)   I159 @T6G_MB_LIB.T6G(SCH_1):PAGE47
   CE5 M_K_CPU1_SB_DQS_DN<0> @T6G_MB_LIB.T6G(SCH_1):M_K_CPU1_SB_DQS_DN(0)   I159 @T6G_MB_LIB.T6G(SCH_1):PAGE47
   CY6 M_K_CPU1_SB_DQ<24> @T6G_MB_LIB.T6G(SCH_1):M_K_CPU1_SB_DQ(24)   I159 @T6G_MB_LIB.T6G(SCH_1):PAGE47
   CN7 M_K_CPU1_SB_DQ<13> @T6G_MB_LIB.T6G(SCH_1):M_K_CPU1_SB_DQ(13)   I159 @T6G_MB_LIB.T6G(SCH_1):PAGE47
   CF6 M_K_CPU1_SB_DQ<4> @T6G_MB_LIB.T6G(SCH_1):M_K_CPU1_SB_DQ(4)   I159 @T6G_MB_LIB.T6G(SCH_1):PAGE47
   BT6 M_K_CPU1_SB_CB<4> @T6G_MB_LIB.T6G(SCH_1):M_K_CPU1_SB_CB(4)   I159 @T6G_MB_LIB.T6G(SCH_1):PAGE47
    P7 M_K_CPU1_SA_DQS_DN<6> @T6G_MB_LIB.T6G(SCH_1):M_K_CPU1_SA_DQS_DN(6)   I159 @T6G_MB_LIB.T6G(SCH_1):PAGE47
    W5 M_K_CPU1_SA_DQS_DP<2> @T6G_MB_LIB.T6G(SCH_1):M_K_CPU1_SA_DQS_DP(2)   I159 @T6G_MB_LIB.T6G(SCH_1):PAGE47
    W7 M_K_CPU1_SA_DQ<19> @T6G_MB_LIB.T6G(SCH_1):M_K_CPU1_SA_DQ(19)   I159 @T6G_MB_LIB.T6G(SCH_1):PAGE47
    K7 M_K_CPU1_SA_DQ<5> @T6G_MB_LIB.T6G(SCH_1):M_K_CPU1_SA_DQ(5)   I159 @T6G_MB_LIB.T6G(SCH_1):PAGE47
   CL5 M_K_CPU1_SB_DQS_DN<1> @T6G_MB_LIB.T6G(SCH_1):M_K_CPU1_SB_DQS_DN(1)   I159 @T6G_MB_LIB.T6G(SCH_1):PAGE47
   DA7 M_K_CPU1_SB_DQ<25> @T6G_MB_LIB.T6G(SCH_1):M_K_CPU1_SB_DQ(25)   I159 @T6G_MB_LIB.T6G(SCH_1):PAGE47
   CN5 M_K_CPU1_SB_DQ<14> @T6G_MB_LIB.T6G(SCH_1):M_K_CPU1_SB_DQ(14)   I159 @T6G_MB_LIB.T6G(SCH_1):PAGE47
   CG7 M_K_CPU1_SB_DQ<5> @T6G_MB_LIB.T6G(SCH_1):M_K_CPU1_SB_DQ(5)   I159 @T6G_MB_LIB.T6G(SCH_1):PAGE47
   BU7 M_K_CPU1_SB_CB<5> @T6G_MB_LIB.T6G(SCH_1):M_K_CPU1_SB_CB(5)   I159 @T6G_MB_LIB.T6G(SCH_1):PAGE47
   BC7 M_K_CPU1_SA_PAR @T6G_MB_LIB.T6G(SCH_1):M_K_CPU1_SA_PAR   I159 @T6G_MB_LIB.T6G(SCH_1):PAGE47
    Y7 M_K_CPU1_SA_DQS_DN<7> @T6G_MB_LIB.T6G(SCH_1):M_K_CPU1_SA_DQS_DN(7)   I159 @T6G_MB_LIB.T6G(SCH_1):PAGE47
   AE5 M_K_CPU1_SA_DQS_DP<3> @T6G_MB_LIB.T6G(SCH_1):M_K_CPU1_SA_DQS_DP(3)   I159 @T6G_MB_LIB.T6G(SCH_1):PAGE47
    K6 M_K_CPU1_SA_DQ<6> @T6G_MB_LIB.T6G(SCH_1):M_K_CPU1_SA_DQ(6)   I159 @T6G_MB_LIB.T6G(SCH_1):PAGE47
   BL7 M_K_CPU1_SB_PAR @T6G_MB_LIB.T6G(SCH_1):M_K_CPU1_SB_PAR   I159 @T6G_MB_LIB.T6G(SCH_1):PAGE47
   CU5 M_K_CPU1_SB_DQS_DN<2> @T6G_MB_LIB.T6G(SCH_1):M_K_CPU1_SB_DQS_DN(2)   I159 @T6G_MB_LIB.T6G(SCH_1):PAGE47
   DA5 M_K_CPU1_SB_DQ<26> @T6G_MB_LIB.T6G(SCH_1):M_K_CPU1_SB_DQ(26)   I159 @T6G_MB_LIB.T6G(SCH_1):PAGE47
   CP7 M_K_CPU1_SB_DQ<15> @T6G_MB_LIB.T6G(SCH_1):M_K_CPU1_SB_DQ(15)   I159 @T6G_MB_LIB.T6G(SCH_1):PAGE47
   CG5 M_K_CPU1_SB_DQ<6> @T6G_MB_LIB.T6G(SCH_1):M_K_CPU1_SB_DQ(6)   I159 @T6G_MB_LIB.T6G(SCH_1):PAGE47
   BU5 M_K_CPU1_SB_CB<6> @T6G_MB_LIB.T6G(SCH_1):M_K_CPU1_SB_CB(6)   I159 @T6G_MB_LIB.T6G(SCH_1):PAGE47
   AF7 M_K_CPU1_SA_DQS_DN<8> @T6G_MB_LIB.T6G(SCH_1):M_K_CPU1_SA_DQS_DN(8)   I159 @T6G_MB_LIB.T6G(SCH_1):PAGE47
   AL5 M_K_CPU1_SA_DQS_DP<4> @T6G_MB_LIB.T6G(SCH_1):M_K_CPU1_SA_DQS_DP(4)   I159 @T6G_MB_LIB.T6G(SCH_1):PAGE47
    L7 M_K_CPU1_SA_DQ<7> @T6G_MB_LIB.T6G(SCH_1):M_K_CPU1_SA_DQ(7)   I159 @T6G_MB_LIB.T6G(SCH_1):PAGE47
   DC5 M_K_CPU1_SB_DQS_DN<3> @T6G_MB_LIB.T6G(SCH_1):M_K_CPU1_SB_DQS_DN(3)   I159 @T6G_MB_LIB.T6G(SCH_1):PAGE47
   DB7 M_K_CPU1_SB_DQ<27> @T6G_MB_LIB.T6G(SCH_1):M_K_CPU1_SB_DQ(27)   I159 @T6G_MB_LIB.T6G(SCH_1):PAGE47
   CP6 M_K_CPU1_SB_DQ<16> @T6G_MB_LIB.T6G(SCH_1):M_K_CPU1_SB_DQ(16)   I159 @T6G_MB_LIB.T6G(SCH_1):PAGE47
   CH7 M_K_CPU1_SB_DQ<7> @T6G_MB_LIB.T6G(SCH_1):M_K_CPU1_SB_DQ(7)   I159 @T6G_MB_LIB.T6G(SCH_1):PAGE47
   BV7 M_K_CPU1_SB_CB<7> @T6G_MB_LIB.T6G(SCH_1):M_K_CPU1_SB_CB(7)   I159 @T6G_MB_LIB.T6G(SCH_1):PAGE47
   BP6 M_K_CPU1_SB_RSP<0> @T6G_MB_LIB.T6G(SCH_1):M_K_CPU1_SB_RSP(0)   I159 @T6G_MB_LIB.T6G(SCH_1):PAGE47
   AM7 M_K_CPU1_SA_DQS_DN<9> @T6G_MB_LIB.T6G(SCH_1):M_K_CPU1_SA_DQS_DN(9)   I159 @T6G_MB_LIB.T6G(SCH_1):PAGE47
    J7 M_K_CPU1_SA_DQS_DP<5> @T6G_MB_LIB.T6G(SCH_1):M_K_CPU1_SA_DQS_DP(5)   I159 @T6G_MB_LIB.T6G(SCH_1):PAGE47
    L5 M_K_CPU1_SA_DQ<8> @T6G_MB_LIB.T6G(SCH_1):M_K_CPU1_SA_DQ(8)   I159 @T6G_MB_LIB.T6G(SCH_1):PAGE47
   BW7 M_K_CPU1_SB_DQS_DN<4> @T6G_MB_LIB.T6G(SCH_1):M_K_CPU1_SB_DQS_DN(4)   I159 @T6G_MB_LIB.T6G(SCH_1):PAGE47
   CD6 M_K_CPU1_SB_DQS_DP<0> @T6G_MB_LIB.T6G(SCH_1):M_K_CPU1_SB_DQS_DP(0)   I159 @T6G_MB_LIB.T6G(SCH_1):PAGE47
   DD6 M_K_CPU1_SB_DQ<28> @T6G_MB_LIB.T6G(SCH_1):M_K_CPU1_SB_DQ(28)   I159 @T6G_MB_LIB.T6G(SCH_1):PAGE47
   CR7 M_K_CPU1_SB_DQ<17> @T6G_MB_LIB.T6G(SCH_1):M_K_CPU1_SB_DQ(17)   I159 @T6G_MB_LIB.T6G(SCH_1):PAGE47
   CH6 M_K_CPU1_SB_DQ<8> @T6G_MB_LIB.T6G(SCH_1):M_K_CPU1_SB_DQ(8)   I159 @T6G_MB_LIB.T6G(SCH_1):PAGE47
   BR5     NC     NC   I159 @T6G_MB_LIB.T6G(SCH_1):PAGE47
    R7 M_K_CPU1_SA_DQS_DP<6> @T6G_MB_LIB.T6G(SCH_1):M_K_CPU1_SA_DQS_DP(6)   I159 @T6G_MB_LIB.T6G(SCH_1):PAGE47
    M7 M_K_CPU1_SA_DQ<9> @T6G_MB_LIB.T6G(SCH_1):M_K_CPU1_SA_DQ(9)   I159 @T6G_MB_LIB.T6G(SCH_1):PAGE47
   CE7 M_K_CPU1_SB_DQS_DN<5> @T6G_MB_LIB.T6G(SCH_1):M_K_CPU1_SB_DQS_DN(5)   I159 @T6G_MB_LIB.T6G(SCH_1):PAGE47
   CK6 M_K_CPU1_SB_DQS_DP<1> @T6G_MB_LIB.T6G(SCH_1):M_K_CPU1_SB_DQS_DP(1)   I159 @T6G_MB_LIB.T6G(SCH_1):PAGE47
   DE7 M_K_CPU1_SB_DQ<29> @T6G_MB_LIB.T6G(SCH_1):M_K_CPU1_SB_DQ(29)   I159 @T6G_MB_LIB.T6G(SCH_1):PAGE47
   CR5 M_K_CPU1_SB_DQ<18> @T6G_MB_LIB.T6G(SCH_1):M_K_CPU1_SB_DQ(18)   I159 @T6G_MB_LIB.T6G(SCH_1):PAGE47
   CJ7 M_K_CPU1_SB_DQ<9> @T6G_MB_LIB.T6G(SCH_1):M_K_CPU1_SB_DQ(9)   I159 @T6G_MB_LIB.T6G(SCH_1):PAGE47
   AA7 M_K_CPU1_SA_DQS_DP<7> @T6G_MB_LIB.T6G(SCH_1):M_K_CPU1_SA_DQS_DP(7)   I159 @T6G_MB_LIB.T6G(SCH_1):PAGE47
   AW5 M_K_CPU1_SA_CA<0> @T6G_MB_LIB.T6G(SCH_1):M_K_CPU1_SA_CA(0)   I159 @T6G_MB_LIB.T6G(SCH_1):PAGE47
   AU5 M_K_CPU1_SA_CS_N<0> @T6G_MB_LIB.T6G(SCH_1):M_K_CPU1_SA_CS_N(0)   I159 @T6G_MB_LIB.T6G(SCH_1):PAGE47
   BF7 TP_M_K_CPU1_SA_TEST39K @T6G_MB_LIB.T6G(SCH_1):TP_M_K_CPU1_SA_TEST39K   I159 @T6G_MB_LIB.T6G(SCH_1):PAGE47
  BV46    GND @T6G_MB_LIB.T6G(SCH_1):GND     I2 @T6G_MB_LIB.T6G(SCH_1):PAGE59
  BV47    GND @T6G_MB_LIB.T6G(SCH_1):GND     I2 @T6G_MB_LIB.T6G(SCH_1):PAGE59
  BV48    GND @T6G_MB_LIB.T6G(SCH_1):GND     I2 @T6G_MB_LIB.T6G(SCH_1):PAGE59
  BV49    GND @T6G_MB_LIB.T6G(SCH_1):GND     I2 @T6G_MB_LIB.T6G(SCH_1):PAGE59
  BV50    GND @T6G_MB_LIB.T6G(SCH_1):GND     I2 @T6G_MB_LIB.T6G(SCH_1):PAGE59
  BV51    GND @T6G_MB_LIB.T6G(SCH_1):GND     I2 @T6G_MB_LIB.T6G(SCH_1):PAGE59
  BV52    GND @T6G_MB_LIB.T6G(SCH_1):GND     I2 @T6G_MB_LIB.T6G(SCH_1):PAGE59
  BV53    GND @T6G_MB_LIB.T6G(SCH_1):GND     I2 @T6G_MB_LIB.T6G(SCH_1):PAGE59
  BV59    GND @T6G_MB_LIB.T6G(SCH_1):GND     I2 @T6G_MB_LIB.T6G(SCH_1):PAGE59
  BV61    GND @T6G_MB_LIB.T6G(SCH_1):GND     I2 @T6G_MB_LIB.T6G(SCH_1):PAGE59
  BV66    GND @T6G_MB_LIB.T6G(SCH_1):GND     I2 @T6G_MB_LIB.T6G(SCH_1):PAGE59
  BV68    GND @T6G_MB_LIB.T6G(SCH_1):GND     I2 @T6G_MB_LIB.T6G(SCH_1):PAGE59
  BV73    GND @T6G_MB_LIB.T6G(SCH_1):GND     I2 @T6G_MB_LIB.T6G(SCH_1):PAGE59
   BW1    GND @T6G_MB_LIB.T6G(SCH_1):GND     I2 @T6G_MB_LIB.T6G(SCH_1):PAGE59
   BW4    GND @T6G_MB_LIB.T6G(SCH_1):GND     I2 @T6G_MB_LIB.T6G(SCH_1):PAGE59
   BW6    GND @T6G_MB_LIB.T6G(SCH_1):GND     I2 @T6G_MB_LIB.T6G(SCH_1):PAGE59
   BW8    GND @T6G_MB_LIB.T6G(SCH_1):GND     I2 @T6G_MB_LIB.T6G(SCH_1):PAGE59
  BW11    GND @T6G_MB_LIB.T6G(SCH_1):GND     I2 @T6G_MB_LIB.T6G(SCH_1):PAGE59
  BW13    GND @T6G_MB_LIB.T6G(SCH_1):GND     I2 @T6G_MB_LIB.T6G(SCH_1):PAGE59
  BW15    GND @T6G_MB_LIB.T6G(SCH_1):GND     I2 @T6G_MB_LIB.T6G(SCH_1):PAGE59
  BW18    GND @T6G_MB_LIB.T6G(SCH_1):GND     I2 @T6G_MB_LIB.T6G(SCH_1):PAGE59
  BW20    GND @T6G_MB_LIB.T6G(SCH_1):GND     I2 @T6G_MB_LIB.T6G(SCH_1):PAGE59
  BW22    GND @T6G_MB_LIB.T6G(SCH_1):GND     I2 @T6G_MB_LIB.T6G(SCH_1):PAGE59
  BW28    GND @T6G_MB_LIB.T6G(SCH_1):GND     I2 @T6G_MB_LIB.T6G(SCH_1):PAGE59
  BW31    GND @T6G_MB_LIB.T6G(SCH_1):GND     I2 @T6G_MB_LIB.T6G(SCH_1):PAGE59
  BW34    GND @T6G_MB_LIB.T6G(SCH_1):GND     I2 @T6G_MB_LIB.T6G(SCH_1):PAGE59
  BW42    GND @T6G_MB_LIB.T6G(SCH_1):GND     I2 @T6G_MB_LIB.T6G(SCH_1):PAGE59
  BW45    GND @T6G_MB_LIB.T6G(SCH_1):GND     I2 @T6G_MB_LIB.T6G(SCH_1):PAGE59
  BW48    GND @T6G_MB_LIB.T6G(SCH_1):GND     I2 @T6G_MB_LIB.T6G(SCH_1):PAGE59
  BW51    GND @T6G_MB_LIB.T6G(SCH_1):GND     I2 @T6G_MB_LIB.T6G(SCH_1):PAGE59
  BW54    GND @T6G_MB_LIB.T6G(SCH_1):GND     I2 @T6G_MB_LIB.T6G(SCH_1):PAGE59
  BW56    GND @T6G_MB_LIB.T6G(SCH_1):GND     I2 @T6G_MB_LIB.T6G(SCH_1):PAGE59
  BW58    GND @T6G_MB_LIB.T6G(SCH_1):GND     I2 @T6G_MB_LIB.T6G(SCH_1):PAGE59
  BW61    GND @T6G_MB_LIB.T6G(SCH_1):GND     I2 @T6G_MB_LIB.T6G(SCH_1):PAGE59
  BW63    GND @T6G_MB_LIB.T6G(SCH_1):GND     I2 @T6G_MB_LIB.T6G(SCH_1):PAGE59
  BW65    GND @T6G_MB_LIB.T6G(SCH_1):GND     I2 @T6G_MB_LIB.T6G(SCH_1):PAGE59
  BW68    GND @T6G_MB_LIB.T6G(SCH_1):GND     I2 @T6G_MB_LIB.T6G(SCH_1):PAGE59
  BW70    GND @T6G_MB_LIB.T6G(SCH_1):GND     I2 @T6G_MB_LIB.T6G(SCH_1):PAGE59
  BW72    GND @T6G_MB_LIB.T6G(SCH_1):GND     I2 @T6G_MB_LIB.T6G(SCH_1):PAGE59
  BW75    GND @T6G_MB_LIB.T6G(SCH_1):GND     I2 @T6G_MB_LIB.T6G(SCH_1):PAGE59
   BY3    GND @T6G_MB_LIB.T6G(SCH_1):GND     I2 @T6G_MB_LIB.T6G(SCH_1):PAGE59
   BY5    GND @T6G_MB_LIB.T6G(SCH_1):GND     I2 @T6G_MB_LIB.T6G(SCH_1):PAGE59
   BY8    GND @T6G_MB_LIB.T6G(SCH_1):GND     I2 @T6G_MB_LIB.T6G(SCH_1):PAGE59
  BY10    GND @T6G_MB_LIB.T6G(SCH_1):GND     I2 @T6G_MB_LIB.T6G(SCH_1):PAGE59
  BY12    GND @T6G_MB_LIB.T6G(SCH_1):GND     I2 @T6G_MB_LIB.T6G(SCH_1):PAGE59
  BY15    GND @T6G_MB_LIB.T6G(SCH_1):GND     I2 @T6G_MB_LIB.T6G(SCH_1):PAGE59
  BY17    GND @T6G_MB_LIB.T6G(SCH_1):GND     I2 @T6G_MB_LIB.T6G(SCH_1):PAGE59
  BY19    GND @T6G_MB_LIB.T6G(SCH_1):GND     I2 @T6G_MB_LIB.T6G(SCH_1):PAGE59
  BY22    GND @T6G_MB_LIB.T6G(SCH_1):GND     I2 @T6G_MB_LIB.T6G(SCH_1):PAGE59
  BY25    GND @T6G_MB_LIB.T6G(SCH_1):GND     I2 @T6G_MB_LIB.T6G(SCH_1):PAGE59
  BY28    GND @T6G_MB_LIB.T6G(SCH_1):GND     I2 @T6G_MB_LIB.T6G(SCH_1):PAGE59
  BY31    GND @T6G_MB_LIB.T6G(SCH_1):GND     I2 @T6G_MB_LIB.T6G(SCH_1):PAGE59
  BY34    GND @T6G_MB_LIB.T6G(SCH_1):GND     I2 @T6G_MB_LIB.T6G(SCH_1):PAGE59
  BY37    GND @T6G_MB_LIB.T6G(SCH_1):GND     I2 @T6G_MB_LIB.T6G(SCH_1):PAGE59
  BY39    GND @T6G_MB_LIB.T6G(SCH_1):GND     I2 @T6G_MB_LIB.T6G(SCH_1):PAGE59
  BY42    GND @T6G_MB_LIB.T6G(SCH_1):GND     I2 @T6G_MB_LIB.T6G(SCH_1):PAGE59
  BY45    GND @T6G_MB_LIB.T6G(SCH_1):GND     I2 @T6G_MB_LIB.T6G(SCH_1):PAGE59
  BY48    GND @T6G_MB_LIB.T6G(SCH_1):GND     I2 @T6G_MB_LIB.T6G(SCH_1):PAGE59
  BY51    GND @T6G_MB_LIB.T6G(SCH_1):GND     I2 @T6G_MB_LIB.T6G(SCH_1):PAGE59
  BY54    GND @T6G_MB_LIB.T6G(SCH_1):GND     I2 @T6G_MB_LIB.T6G(SCH_1):PAGE59
  BY57    GND @T6G_MB_LIB.T6G(SCH_1):GND     I2 @T6G_MB_LIB.T6G(SCH_1):PAGE59
  BY59    GND @T6G_MB_LIB.T6G(SCH_1):GND     I2 @T6G_MB_LIB.T6G(SCH_1):PAGE59
  BY61    GND @T6G_MB_LIB.T6G(SCH_1):GND     I2 @T6G_MB_LIB.T6G(SCH_1):PAGE59
  BY64    GND @T6G_MB_LIB.T6G(SCH_1):GND     I2 @T6G_MB_LIB.T6G(SCH_1):PAGE59
  BY66    GND @T6G_MB_LIB.T6G(SCH_1):GND     I2 @T6G_MB_LIB.T6G(SCH_1):PAGE59
  BY68    GND @T6G_MB_LIB.T6G(SCH_1):GND     I2 @T6G_MB_LIB.T6G(SCH_1):PAGE59
  BY71    GND @T6G_MB_LIB.T6G(SCH_1):GND     I2 @T6G_MB_LIB.T6G(SCH_1):PAGE59
  BY73    GND @T6G_MB_LIB.T6G(SCH_1):GND     I2 @T6G_MB_LIB.T6G(SCH_1):PAGE59
   CA1    GND @T6G_MB_LIB.T6G(SCH_1):GND     I2 @T6G_MB_LIB.T6G(SCH_1):PAGE59
   CA6    GND @T6G_MB_LIB.T6G(SCH_1):GND     I2 @T6G_MB_LIB.T6G(SCH_1):PAGE59
   CA8    GND @T6G_MB_LIB.T6G(SCH_1):GND     I2 @T6G_MB_LIB.T6G(SCH_1):PAGE59
  CA13    GND @T6G_MB_LIB.T6G(SCH_1):GND     I2 @T6G_MB_LIB.T6G(SCH_1):PAGE59
  CA15    GND @T6G_MB_LIB.T6G(SCH_1):GND     I2 @T6G_MB_LIB.T6G(SCH_1):PAGE59
  CA20    GND @T6G_MB_LIB.T6G(SCH_1):GND     I2 @T6G_MB_LIB.T6G(SCH_1):PAGE59
  CA22    GND @T6G_MB_LIB.T6G(SCH_1):GND     I2 @T6G_MB_LIB.T6G(SCH_1):PAGE59
  CA25    GND @T6G_MB_LIB.T6G(SCH_1):GND     I2 @T6G_MB_LIB.T6G(SCH_1):PAGE59
  CA28    GND @T6G_MB_LIB.T6G(SCH_1):GND     I2 @T6G_MB_LIB.T6G(SCH_1):PAGE59
  CA31    GND @T6G_MB_LIB.T6G(SCH_1):GND     I2 @T6G_MB_LIB.T6G(SCH_1):PAGE59
  CA34    GND @T6G_MB_LIB.T6G(SCH_1):GND     I2 @T6G_MB_LIB.T6G(SCH_1):PAGE59
  CA35    GND @T6G_MB_LIB.T6G(SCH_1):GND     I2 @T6G_MB_LIB.T6G(SCH_1):PAGE59
  CA36    GND @T6G_MB_LIB.T6G(SCH_1):GND     I2 @T6G_MB_LIB.T6G(SCH_1):PAGE59
  CA40    GND @T6G_MB_LIB.T6G(SCH_1):GND     I2 @T6G_MB_LIB.T6G(SCH_1):PAGE59
  CA41    GND @T6G_MB_LIB.T6G(SCH_1):GND     I2 @T6G_MB_LIB.T6G(SCH_1):PAGE59
  CA42    GND @T6G_MB_LIB.T6G(SCH_1):GND     I2 @T6G_MB_LIB.T6G(SCH_1):PAGE59
  CA45    GND @T6G_MB_LIB.T6G(SCH_1):GND     I2 @T6G_MB_LIB.T6G(SCH_1):PAGE59
  CA48    GND @T6G_MB_LIB.T6G(SCH_1):GND     I2 @T6G_MB_LIB.T6G(SCH_1):PAGE59
  CA51    GND @T6G_MB_LIB.T6G(SCH_1):GND     I2 @T6G_MB_LIB.T6G(SCH_1):PAGE59
  CA54    GND @T6G_MB_LIB.T6G(SCH_1):GND     I2 @T6G_MB_LIB.T6G(SCH_1):PAGE59
  CA56    GND @T6G_MB_LIB.T6G(SCH_1):GND     I2 @T6G_MB_LIB.T6G(SCH_1):PAGE59
  CA61    GND @T6G_MB_LIB.T6G(SCH_1):GND     I2 @T6G_MB_LIB.T6G(SCH_1):PAGE59
  CA63    GND @T6G_MB_LIB.T6G(SCH_1):GND     I2 @T6G_MB_LIB.T6G(SCH_1):PAGE59
  CA68    GND @T6G_MB_LIB.T6G(SCH_1):GND     I2 @T6G_MB_LIB.T6G(SCH_1):PAGE59
  CA70    GND @T6G_MB_LIB.T6G(SCH_1):GND     I2 @T6G_MB_LIB.T6G(SCH_1):PAGE59
  CA75    GND @T6G_MB_LIB.T6G(SCH_1):GND     I2 @T6G_MB_LIB.T6G(SCH_1):PAGE59
   CB3    GND @T6G_MB_LIB.T6G(SCH_1):GND     I2 @T6G_MB_LIB.T6G(SCH_1):PAGE59
   CB5    GND @T6G_MB_LIB.T6G(SCH_1):GND     I2 @T6G_MB_LIB.T6G(SCH_1):PAGE59
   CB8    GND @T6G_MB_LIB.T6G(SCH_1):GND     I2 @T6G_MB_LIB.T6G(SCH_1):PAGE59
  CB10    GND @T6G_MB_LIB.T6G(SCH_1):GND     I2 @T6G_MB_LIB.T6G(SCH_1):PAGE59
  CB12    GND @T6G_MB_LIB.T6G(SCH_1):GND     I2 @T6G_MB_LIB.T6G(SCH_1):PAGE59
  CB15    GND @T6G_MB_LIB.T6G(SCH_1):GND     I2 @T6G_MB_LIB.T6G(SCH_1):PAGE59
  CB17    GND @T6G_MB_LIB.T6G(SCH_1):GND     I2 @T6G_MB_LIB.T6G(SCH_1):PAGE59
  CB19    GND @T6G_MB_LIB.T6G(SCH_1):GND     I2 @T6G_MB_LIB.T6G(SCH_1):PAGE59
  CB23    GND @T6G_MB_LIB.T6G(SCH_1):GND     I2 @T6G_MB_LIB.T6G(SCH_1):PAGE59
  CB24    GND @T6G_MB_LIB.T6G(SCH_1):GND     I2 @T6G_MB_LIB.T6G(SCH_1):PAGE59
  CB25    GND @T6G_MB_LIB.T6G(SCH_1):GND     I2 @T6G_MB_LIB.T6G(SCH_1):PAGE59
  CB26    GND @T6G_MB_LIB.T6G(SCH_1):GND     I2 @T6G_MB_LIB.T6G(SCH_1):PAGE59
  CB27    GND @T6G_MB_LIB.T6G(SCH_1):GND     I2 @T6G_MB_LIB.T6G(SCH_1):PAGE59
  CB28    GND @T6G_MB_LIB.T6G(SCH_1):GND     I2 @T6G_MB_LIB.T6G(SCH_1):PAGE59
  CB29    GND @T6G_MB_LIB.T6G(SCH_1):GND     I2 @T6G_MB_LIB.T6G(SCH_1):PAGE59
  CB30    GND @T6G_MB_LIB.T6G(SCH_1):GND     I2 @T6G_MB_LIB.T6G(SCH_1):PAGE59
  CB31    GND @T6G_MB_LIB.T6G(SCH_1):GND     I2 @T6G_MB_LIB.T6G(SCH_1):PAGE59
  CB32    GND @T6G_MB_LIB.T6G(SCH_1):GND     I2 @T6G_MB_LIB.T6G(SCH_1):PAGE59
  CB33    GND @T6G_MB_LIB.T6G(SCH_1):GND     I2 @T6G_MB_LIB.T6G(SCH_1):PAGE59
  CB34    GND @T6G_MB_LIB.T6G(SCH_1):GND     I2 @T6G_MB_LIB.T6G(SCH_1):PAGE59
  CB37    GND @T6G_MB_LIB.T6G(SCH_1):GND     I2 @T6G_MB_LIB.T6G(SCH_1):PAGE59
  CB39    GND @T6G_MB_LIB.T6G(SCH_1):GND     I2 @T6G_MB_LIB.T6G(SCH_1):PAGE59
  CB42    GND @T6G_MB_LIB.T6G(SCH_1):GND     I2 @T6G_MB_LIB.T6G(SCH_1):PAGE59
  CB43    GND @T6G_MB_LIB.T6G(SCH_1):GND     I2 @T6G_MB_LIB.T6G(SCH_1):PAGE59
  CB45    GND @T6G_MB_LIB.T6G(SCH_1):GND     I2 @T6G_MB_LIB.T6G(SCH_1):PAGE59
  CB46    GND @T6G_MB_LIB.T6G(SCH_1):GND     I2 @T6G_MB_LIB.T6G(SCH_1):PAGE59
  CB47    GND @T6G_MB_LIB.T6G(SCH_1):GND     I2 @T6G_MB_LIB.T6G(SCH_1):PAGE59
  CB48    GND @T6G_MB_LIB.T6G(SCH_1):GND     I2 @T6G_MB_LIB.T6G(SCH_1):PAGE59
  CB49    GND @T6G_MB_LIB.T6G(SCH_1):GND     I2 @T6G_MB_LIB.T6G(SCH_1):PAGE59
  CB50    GND @T6G_MB_LIB.T6G(SCH_1):GND     I2 @T6G_MB_LIB.T6G(SCH_1):PAGE59
  CB51    GND @T6G_MB_LIB.T6G(SCH_1):GND     I2 @T6G_MB_LIB.T6G(SCH_1):PAGE59
  CB52    GND @T6G_MB_LIB.T6G(SCH_1):GND     I2 @T6G_MB_LIB.T6G(SCH_1):PAGE59
  CB53    GND @T6G_MB_LIB.T6G(SCH_1):GND     I2 @T6G_MB_LIB.T6G(SCH_1):PAGE59
  CB57    GND @T6G_MB_LIB.T6G(SCH_1):GND     I2 @T6G_MB_LIB.T6G(SCH_1):PAGE59
  CB59    GND @T6G_MB_LIB.T6G(SCH_1):GND     I2 @T6G_MB_LIB.T6G(SCH_1):PAGE59
  CB61    GND @T6G_MB_LIB.T6G(SCH_1):GND     I2 @T6G_MB_LIB.T6G(SCH_1):PAGE59
  CB64    GND @T6G_MB_LIB.T6G(SCH_1):GND     I2 @T6G_MB_LIB.T6G(SCH_1):PAGE59
  CB66    GND @T6G_MB_LIB.T6G(SCH_1):GND     I2 @T6G_MB_LIB.T6G(SCH_1):PAGE59
  CB68    GND @T6G_MB_LIB.T6G(SCH_1):GND     I2 @T6G_MB_LIB.T6G(SCH_1):PAGE59
  CB71    GND @T6G_MB_LIB.T6G(SCH_1):GND     I2 @T6G_MB_LIB.T6G(SCH_1):PAGE59
  CB73    GND @T6G_MB_LIB.T6G(SCH_1):GND     I2 @T6G_MB_LIB.T6G(SCH_1):PAGE59
   CC1    GND @T6G_MB_LIB.T6G(SCH_1):GND     I2 @T6G_MB_LIB.T6G(SCH_1):PAGE59
   CC4    GND @T6G_MB_LIB.T6G(SCH_1):GND     I2 @T6G_MB_LIB.T6G(SCH_1):PAGE59
   CC6    GND @T6G_MB_LIB.T6G(SCH_1):GND     I2 @T6G_MB_LIB.T6G(SCH_1):PAGE59
   CC8    GND @T6G_MB_LIB.T6G(SCH_1):GND     I2 @T6G_MB_LIB.T6G(SCH_1):PAGE59
  CC11    GND @T6G_MB_LIB.T6G(SCH_1):GND     I2 @T6G_MB_LIB.T6G(SCH_1):PAGE59
  CC13    GND @T6G_MB_LIB.T6G(SCH_1):GND     I2 @T6G_MB_LIB.T6G(SCH_1):PAGE59
  CC15    GND @T6G_MB_LIB.T6G(SCH_1):GND     I2 @T6G_MB_LIB.T6G(SCH_1):PAGE59
  CC18    GND @T6G_MB_LIB.T6G(SCH_1):GND     I2 @T6G_MB_LIB.T6G(SCH_1):PAGE59
  CC20    GND @T6G_MB_LIB.T6G(SCH_1):GND     I2 @T6G_MB_LIB.T6G(SCH_1):PAGE59
  CC25    GND @T6G_MB_LIB.T6G(SCH_1):GND     I2 @T6G_MB_LIB.T6G(SCH_1):PAGE59
  CC28    GND @T6G_MB_LIB.T6G(SCH_1):GND     I2 @T6G_MB_LIB.T6G(SCH_1):PAGE59
  CC31    GND @T6G_MB_LIB.T6G(SCH_1):GND     I2 @T6G_MB_LIB.T6G(SCH_1):PAGE59
  CC34    GND @T6G_MB_LIB.T6G(SCH_1):GND     I2 @T6G_MB_LIB.T6G(SCH_1):PAGE59
  CC42    GND @T6G_MB_LIB.T6G(SCH_1):GND     I2 @T6G_MB_LIB.T6G(SCH_1):PAGE59
  CC45    GND @T6G_MB_LIB.T6G(SCH_1):GND     I2 @T6G_MB_LIB.T6G(SCH_1):PAGE59
  CC48    GND @T6G_MB_LIB.T6G(SCH_1):GND     I2 @T6G_MB_LIB.T6G(SCH_1):PAGE59
  CC51    GND @T6G_MB_LIB.T6G(SCH_1):GND     I2 @T6G_MB_LIB.T6G(SCH_1):PAGE59
  CC54    GND @T6G_MB_LIB.T6G(SCH_1):GND     I2 @T6G_MB_LIB.T6G(SCH_1):PAGE59
  CC56    GND @T6G_MB_LIB.T6G(SCH_1):GND     I2 @T6G_MB_LIB.T6G(SCH_1):PAGE59
  CC58    GND @T6G_MB_LIB.T6G(SCH_1):GND     I2 @T6G_MB_LIB.T6G(SCH_1):PAGE59
  CC61    GND @T6G_MB_LIB.T6G(SCH_1):GND     I2 @T6G_MB_LIB.T6G(SCH_1):PAGE59
  CC63    GND @T6G_MB_LIB.T6G(SCH_1):GND     I2 @T6G_MB_LIB.T6G(SCH_1):PAGE59
  CC65    GND @T6G_MB_LIB.T6G(SCH_1):GND     I2 @T6G_MB_LIB.T6G(SCH_1):PAGE59
  CC68    GND @T6G_MB_LIB.T6G(SCH_1):GND     I2 @T6G_MB_LIB.T6G(SCH_1):PAGE59
  CC70    GND @T6G_MB_LIB.T6G(SCH_1):GND     I2 @T6G_MB_LIB.T6G(SCH_1):PAGE59
  CC72    GND @T6G_MB_LIB.T6G(SCH_1):GND     I2 @T6G_MB_LIB.T6G(SCH_1):PAGE59
  CC75    GND @T6G_MB_LIB.T6G(SCH_1):GND     I2 @T6G_MB_LIB.T6G(SCH_1):PAGE59
   CD3    GND @T6G_MB_LIB.T6G(SCH_1):GND     I2 @T6G_MB_LIB.T6G(SCH_1):PAGE59
   CD8    GND @T6G_MB_LIB.T6G(SCH_1):GND     I2 @T6G_MB_LIB.T6G(SCH_1):PAGE59
  CD10    GND @T6G_MB_LIB.T6G(SCH_1):GND     I2 @T6G_MB_LIB.T6G(SCH_1):PAGE59
  CD15    GND @T6G_MB_LIB.T6G(SCH_1):GND     I2 @T6G_MB_LIB.T6G(SCH_1):PAGE59
  CD17    GND @T6G_MB_LIB.T6G(SCH_1):GND     I2 @T6G_MB_LIB.T6G(SCH_1):PAGE59
  CD22    GND @T6G_MB_LIB.T6G(SCH_1):GND     I2 @T6G_MB_LIB.T6G(SCH_1):PAGE59
  CD25    GND @T6G_MB_LIB.T6G(SCH_1):GND     I2 @T6G_MB_LIB.T6G(SCH_1):PAGE59
  CD28    GND @T6G_MB_LIB.T6G(SCH_1):GND     I2 @T6G_MB_LIB.T6G(SCH_1):PAGE59
  CD31    GND @T6G_MB_LIB.T6G(SCH_1):GND     I2 @T6G_MB_LIB.T6G(SCH_1):PAGE59
  CD34    GND @T6G_MB_LIB.T6G(SCH_1):GND     I2 @T6G_MB_LIB.T6G(SCH_1):PAGE59
  CD37    GND @T6G_MB_LIB.T6G(SCH_1):GND     I2 @T6G_MB_LIB.T6G(SCH_1):PAGE59
  CD39    GND @T6G_MB_LIB.T6G(SCH_1):GND     I2 @T6G_MB_LIB.T6G(SCH_1):PAGE59
  CD42    GND @T6G_MB_LIB.T6G(SCH_1):GND     I2 @T6G_MB_LIB.T6G(SCH_1):PAGE59
  CD45    GND @T6G_MB_LIB.T6G(SCH_1):GND     I2 @T6G_MB_LIB.T6G(SCH_1):PAGE59
  CD48    GND @T6G_MB_LIB.T6G(SCH_1):GND     I2 @T6G_MB_LIB.T6G(SCH_1):PAGE59
  CD51    GND @T6G_MB_LIB.T6G(SCH_1):GND     I2 @T6G_MB_LIB.T6G(SCH_1):PAGE59
  CD54    GND @T6G_MB_LIB.T6G(SCH_1):GND     I2 @T6G_MB_LIB.T6G(SCH_1):PAGE59
  CD59    GND @T6G_MB_LIB.T6G(SCH_1):GND     I2 @T6G_MB_LIB.T6G(SCH_1):PAGE59
  CD61    GND @T6G_MB_LIB.T6G(SCH_1):GND     I2 @T6G_MB_LIB.T6G(SCH_1):PAGE59
  CD66    GND @T6G_MB_LIB.T6G(SCH_1):GND     I2 @T6G_MB_LIB.T6G(SCH_1):PAGE59
  CD68    GND @T6G_MB_LIB.T6G(SCH_1):GND     I2 @T6G_MB_LIB.T6G(SCH_1):PAGE59
  CD73    GND @T6G_MB_LIB.T6G(SCH_1):GND     I2 @T6G_MB_LIB.T6G(SCH_1):PAGE59
   CE1    GND @T6G_MB_LIB.T6G(SCH_1):GND     I2 @T6G_MB_LIB.T6G(SCH_1):PAGE59
   CE4    GND @T6G_MB_LIB.T6G(SCH_1):GND     I2 @T6G_MB_LIB.T6G(SCH_1):PAGE59
   CE6    GND @T6G_MB_LIB.T6G(SCH_1):GND     I2 @T6G_MB_LIB.T6G(SCH_1):PAGE59
   CE8    GND @T6G_MB_LIB.T6G(SCH_1):GND     I2 @T6G_MB_LIB.T6G(SCH_1):PAGE59
  CE11    GND @T6G_MB_LIB.T6G(SCH_1):GND     I2 @T6G_MB_LIB.T6G(SCH_1):PAGE59
  CE13    GND @T6G_MB_LIB.T6G(SCH_1):GND     I2 @T6G_MB_LIB.T6G(SCH_1):PAGE59
  CE15    GND @T6G_MB_LIB.T6G(SCH_1):GND     I2 @T6G_MB_LIB.T6G(SCH_1):PAGE59
  CE18    GND @T6G_MB_LIB.T6G(SCH_1):GND     I2 @T6G_MB_LIB.T6G(SCH_1):PAGE59
  CE20    GND @T6G_MB_LIB.T6G(SCH_1):GND     I2 @T6G_MB_LIB.T6G(SCH_1):PAGE59
  CE22    GND @T6G_MB_LIB.T6G(SCH_1):GND     I2 @T6G_MB_LIB.T6G(SCH_1):PAGE59
  CE25    GND @T6G_MB_LIB.T6G(SCH_1):GND     I2 @T6G_MB_LIB.T6G(SCH_1):PAGE59
  CE28    GND @T6G_MB_LIB.T6G(SCH_1):GND     I2 @T6G_MB_LIB.T6G(SCH_1):PAGE59
  CE31    GND @T6G_MB_LIB.T6G(SCH_1):GND     I2 @T6G_MB_LIB.T6G(SCH_1):PAGE59
  CE34    GND @T6G_MB_LIB.T6G(SCH_1):GND     I2 @T6G_MB_LIB.T6G(SCH_1):PAGE59
  CE35    GND @T6G_MB_LIB.T6G(SCH_1):GND     I2 @T6G_MB_LIB.T6G(SCH_1):PAGE59
  CE36    GND @T6G_MB_LIB.T6G(SCH_1):GND     I2 @T6G_MB_LIB.T6G(SCH_1):PAGE59
  CE40    GND @T6G_MB_LIB.T6G(SCH_1):GND     I2 @T6G_MB_LIB.T6G(SCH_1):PAGE59
  CE41    GND @T6G_MB_LIB.T6G(SCH_1):GND     I2 @T6G_MB_LIB.T6G(SCH_1):PAGE59
  CE42    GND @T6G_MB_LIB.T6G(SCH_1):GND     I2 @T6G_MB_LIB.T6G(SCH_1):PAGE59
  CE45    GND @T6G_MB_LIB.T6G(SCH_1):GND     I2 @T6G_MB_LIB.T6G(SCH_1):PAGE59
  CE48    GND @T6G_MB_LIB.T6G(SCH_1):GND     I2 @T6G_MB_LIB.T6G(SCH_1):PAGE59
  CE51    GND @T6G_MB_LIB.T6G(SCH_1):GND     I2 @T6G_MB_LIB.T6G(SCH_1):PAGE59
  CE54    GND @T6G_MB_LIB.T6G(SCH_1):GND     I2 @T6G_MB_LIB.T6G(SCH_1):PAGE59
  CE56    GND @T6G_MB_LIB.T6G(SCH_1):GND     I2 @T6G_MB_LIB.T6G(SCH_1):PAGE59
  CE58    GND @T6G_MB_LIB.T6G(SCH_1):GND     I2 @T6G_MB_LIB.T6G(SCH_1):PAGE59
  CE61    GND @T6G_MB_LIB.T6G(SCH_1):GND     I2 @T6G_MB_LIB.T6G(SCH_1):PAGE59
  CE63    GND @T6G_MB_LIB.T6G(SCH_1):GND     I2 @T6G_MB_LIB.T6G(SCH_1):PAGE59
  CE65    GND @T6G_MB_LIB.T6G(SCH_1):GND     I2 @T6G_MB_LIB.T6G(SCH_1):PAGE59
  CE68    GND @T6G_MB_LIB.T6G(SCH_1):GND     I2 @T6G_MB_LIB.T6G(SCH_1):PAGE59
  CE70    GND @T6G_MB_LIB.T6G(SCH_1):GND     I2 @T6G_MB_LIB.T6G(SCH_1):PAGE59
  CE72    GND @T6G_MB_LIB.T6G(SCH_1):GND     I2 @T6G_MB_LIB.T6G(SCH_1):PAGE59
  CE75    GND @T6G_MB_LIB.T6G(SCH_1):GND     I2 @T6G_MB_LIB.T6G(SCH_1):PAGE59
   CF3    GND @T6G_MB_LIB.T6G(SCH_1):GND     I2 @T6G_MB_LIB.T6G(SCH_1):PAGE59
   CF5    GND @T6G_MB_LIB.T6G(SCH_1):GND     I2 @T6G_MB_LIB.T6G(SCH_1):PAGE59
   CF8    GND @T6G_MB_LIB.T6G(SCH_1):GND     I2 @T6G_MB_LIB.T6G(SCH_1):PAGE59
  CF10    GND @T6G_MB_LIB.T6G(SCH_1):GND     I2 @T6G_MB_LIB.T6G(SCH_1):PAGE59
  CF12    GND @T6G_MB_LIB.T6G(SCH_1):GND     I2 @T6G_MB_LIB.T6G(SCH_1):PAGE59
  CF15    GND @T6G_MB_LIB.T6G(SCH_1):GND     I2 @T6G_MB_LIB.T6G(SCH_1):PAGE59
  CF17    GND @T6G_MB_LIB.T6G(SCH_1):GND     I2 @T6G_MB_LIB.T6G(SCH_1):PAGE59
  CF19    GND @T6G_MB_LIB.T6G(SCH_1):GND     I2 @T6G_MB_LIB.T6G(SCH_1):PAGE59
  CF23    GND @T6G_MB_LIB.T6G(SCH_1):GND     I2 @T6G_MB_LIB.T6G(SCH_1):PAGE59
  CF24    GND @T6G_MB_LIB.T6G(SCH_1):GND     I2 @T6G_MB_LIB.T6G(SCH_1):PAGE59
  CF25    GND @T6G_MB_LIB.T6G(SCH_1):GND     I2 @T6G_MB_LIB.T6G(SCH_1):PAGE59
  CF26    GND @T6G_MB_LIB.T6G(SCH_1):GND     I2 @T6G_MB_LIB.T6G(SCH_1):PAGE59
  CF27    GND @T6G_MB_LIB.T6G(SCH_1):GND     I2 @T6G_MB_LIB.T6G(SCH_1):PAGE59
  CF28    GND @T6G_MB_LIB.T6G(SCH_1):GND     I2 @T6G_MB_LIB.T6G(SCH_1):PAGE59
  CF29    GND @T6G_MB_LIB.T6G(SCH_1):GND     I2 @T6G_MB_LIB.T6G(SCH_1):PAGE59
  CF30    GND @T6G_MB_LIB.T6G(SCH_1):GND     I2 @T6G_MB_LIB.T6G(SCH_1):PAGE59
  CF31    GND @T6G_MB_LIB.T6G(SCH_1):GND     I2 @T6G_MB_LIB.T6G(SCH_1):PAGE59
  CF32    GND @T6G_MB_LIB.T6G(SCH_1):GND     I2 @T6G_MB_LIB.T6G(SCH_1):PAGE59
  CF33    GND @T6G_MB_LIB.T6G(SCH_1):GND     I2 @T6G_MB_LIB.T6G(SCH_1):PAGE59
  CN56    GND @T6G_MB_LIB.T6G(SCH_1):GND     I3 @T6G_MB_LIB.T6G(SCH_1):PAGE59
  CN20    GND @T6G_MB_LIB.T6G(SCH_1):GND     I3 @T6G_MB_LIB.T6G(SCH_1):PAGE59
  CM61    GND @T6G_MB_LIB.T6G(SCH_1):GND     I3 @T6G_MB_LIB.T6G(SCH_1):PAGE59
  CM34    GND @T6G_MB_LIB.T6G(SCH_1):GND     I3 @T6G_MB_LIB.T6G(SCH_1):PAGE59
  CK33    GND @T6G_MB_LIB.T6G(SCH_1):GND     I3 @T6G_MB_LIB.T6G(SCH_1):PAGE59
  CK15    GND @T6G_MB_LIB.T6G(SCH_1):GND     I3 @T6G_MB_LIB.T6G(SCH_1):PAGE59
  CJ58    GND @T6G_MB_LIB.T6G(SCH_1):GND     I3 @T6G_MB_LIB.T6G(SCH_1):PAGE59
  CJ20    GND @T6G_MB_LIB.T6G(SCH_1):GND     I3 @T6G_MB_LIB.T6G(SCH_1):PAGE59
  CH68    GND @T6G_MB_LIB.T6G(SCH_1):GND     I3 @T6G_MB_LIB.T6G(SCH_1):PAGE59
  CH39    GND @T6G_MB_LIB.T6G(SCH_1):GND     I3 @T6G_MB_LIB.T6G(SCH_1):PAGE59
  CH10    GND @T6G_MB_LIB.T6G(SCH_1):GND     I3 @T6G_MB_LIB.T6G(SCH_1):PAGE59
  CN22    GND @T6G_MB_LIB.T6G(SCH_1):GND     I3 @T6G_MB_LIB.T6G(SCH_1):PAGE59
  CM64    GND @T6G_MB_LIB.T6G(SCH_1):GND     I3 @T6G_MB_LIB.T6G(SCH_1):PAGE59
  CM37    GND @T6G_MB_LIB.T6G(SCH_1):GND     I3 @T6G_MB_LIB.T6G(SCH_1):PAGE59
  CM24    GND @T6G_MB_LIB.T6G(SCH_1):GND     I3 @T6G_MB_LIB.T6G(SCH_1):PAGE59
  CK17    GND @T6G_MB_LIB.T6G(SCH_1):GND     I3 @T6G_MB_LIB.T6G(SCH_1):PAGE59
  CJ61    GND @T6G_MB_LIB.T6G(SCH_1):GND     I3 @T6G_MB_LIB.T6G(SCH_1):PAGE59
  CJ23    GND @T6G_MB_LIB.T6G(SCH_1):GND     I3 @T6G_MB_LIB.T6G(SCH_1):PAGE59
  CH71    GND @T6G_MB_LIB.T6G(SCH_1):GND     I3 @T6G_MB_LIB.T6G(SCH_1):PAGE59
  CH42    GND @T6G_MB_LIB.T6G(SCH_1):GND     I3 @T6G_MB_LIB.T6G(SCH_1):PAGE59
  CH12    GND @T6G_MB_LIB.T6G(SCH_1):GND     I3 @T6G_MB_LIB.T6G(SCH_1):PAGE59
  CM66    GND @T6G_MB_LIB.T6G(SCH_1):GND     I3 @T6G_MB_LIB.T6G(SCH_1):PAGE59
  CM39    GND @T6G_MB_LIB.T6G(SCH_1):GND     I3 @T6G_MB_LIB.T6G(SCH_1):PAGE59
  CM25    GND @T6G_MB_LIB.T6G(SCH_1):GND     I3 @T6G_MB_LIB.T6G(SCH_1):PAGE59
  CL75    GND @T6G_MB_LIB.T6G(SCH_1):GND     I3 @T6G_MB_LIB.T6G(SCH_1):PAGE59
  CJ63    GND @T6G_MB_LIB.T6G(SCH_1):GND     I3 @T6G_MB_LIB.T6G(SCH_1):PAGE59
  CJ31    GND @T6G_MB_LIB.T6G(SCH_1):GND     I3 @T6G_MB_LIB.T6G(SCH_1):PAGE59
  CH73    GND @T6G_MB_LIB.T6G(SCH_1):GND     I3 @T6G_MB_LIB.T6G(SCH_1):PAGE59
  CH45    GND @T6G_MB_LIB.T6G(SCH_1):GND     I3 @T6G_MB_LIB.T6G(SCH_1):PAGE59
  CH15    GND @T6G_MB_LIB.T6G(SCH_1):GND     I3 @T6G_MB_LIB.T6G(SCH_1):PAGE59
  CM42    GND @T6G_MB_LIB.T6G(SCH_1):GND     I3 @T6G_MB_LIB.T6G(SCH_1):PAGE59
  CM26    GND @T6G_MB_LIB.T6G(SCH_1):GND     I3 @T6G_MB_LIB.T6G(SCH_1):PAGE59
   CM3    GND @T6G_MB_LIB.T6G(SCH_1):GND     I3 @T6G_MB_LIB.T6G(SCH_1):PAGE59
  CL51    GND @T6G_MB_LIB.T6G(SCH_1):GND     I3 @T6G_MB_LIB.T6G(SCH_1):PAGE59
  CJ34    GND @T6G_MB_LIB.T6G(SCH_1):GND     I3 @T6G_MB_LIB.T6G(SCH_1):PAGE59
   CJ1    GND @T6G_MB_LIB.T6G(SCH_1):GND     I3 @T6G_MB_LIB.T6G(SCH_1):PAGE59
  CH48    GND @T6G_MB_LIB.T6G(SCH_1):GND     I3 @T6G_MB_LIB.T6G(SCH_1):PAGE59
  CH17    GND @T6G_MB_LIB.T6G(SCH_1):GND     I3 @T6G_MB_LIB.T6G(SCH_1):PAGE59
  CM43    GND @T6G_MB_LIB.T6G(SCH_1):GND     I3 @T6G_MB_LIB.T6G(SCH_1):PAGE59
  CM27    GND @T6G_MB_LIB.T6G(SCH_1):GND     I3 @T6G_MB_LIB.T6G(SCH_1):PAGE59
   CM5    GND @T6G_MB_LIB.T6G(SCH_1):GND     I3 @T6G_MB_LIB.T6G(SCH_1):PAGE59
  CL54    GND @T6G_MB_LIB.T6G(SCH_1):GND     I3 @T6G_MB_LIB.T6G(SCH_1):PAGE59
  CL28    GND @T6G_MB_LIB.T6G(SCH_1):GND     I3 @T6G_MB_LIB.T6G(SCH_1):PAGE59
   CJ4    GND @T6G_MB_LIB.T6G(SCH_1):GND     I3 @T6G_MB_LIB.T6G(SCH_1):PAGE59
  CH51    GND @T6G_MB_LIB.T6G(SCH_1):GND     I3 @T6G_MB_LIB.T6G(SCH_1):PAGE59
  CH19    GND @T6G_MB_LIB.T6G(SCH_1):GND     I3 @T6G_MB_LIB.T6G(SCH_1):PAGE59
  CF34    GND @T6G_MB_LIB.T6G(SCH_1):GND     I3 @T6G_MB_LIB.T6G(SCH_1):PAGE59
  CF37    GND @T6G_MB_LIB.T6G(SCH_1):GND     I3 @T6G_MB_LIB.T6G(SCH_1):PAGE59
  CF39    GND @T6G_MB_LIB.T6G(SCH_1):GND     I3 @T6G_MB_LIB.T6G(SCH_1):PAGE59
  CF42    GND @T6G_MB_LIB.T6G(SCH_1):GND     I3 @T6G_MB_LIB.T6G(SCH_1):PAGE59
  CF43    GND @T6G_MB_LIB.T6G(SCH_1):GND     I3 @T6G_MB_LIB.T6G(SCH_1):PAGE59
  CF44    GND @T6G_MB_LIB.T6G(SCH_1):GND     I3 @T6G_MB_LIB.T6G(SCH_1):PAGE59
  CF45    GND @T6G_MB_LIB.T6G(SCH_1):GND     I3 @T6G_MB_LIB.T6G(SCH_1):PAGE59
  CF47    GND @T6G_MB_LIB.T6G(SCH_1):GND     I3 @T6G_MB_LIB.T6G(SCH_1):PAGE59
  CF48    GND @T6G_MB_LIB.T6G(SCH_1):GND     I3 @T6G_MB_LIB.T6G(SCH_1):PAGE59
  CF49    GND @T6G_MB_LIB.T6G(SCH_1):GND     I3 @T6G_MB_LIB.T6G(SCH_1):PAGE59
  CF50    GND @T6G_MB_LIB.T6G(SCH_1):GND     I3 @T6G_MB_LIB.T6G(SCH_1):PAGE59
  CF51    GND @T6G_MB_LIB.T6G(SCH_1):GND     I3 @T6G_MB_LIB.T6G(SCH_1):PAGE59
  CF52    GND @T6G_MB_LIB.T6G(SCH_1):GND     I3 @T6G_MB_LIB.T6G(SCH_1):PAGE59
  CF53    GND @T6G_MB_LIB.T6G(SCH_1):GND     I3 @T6G_MB_LIB.T6G(SCH_1):PAGE59
  CF57    GND @T6G_MB_LIB.T6G(SCH_1):GND     I3 @T6G_MB_LIB.T6G(SCH_1):PAGE59
  CF59    GND @T6G_MB_LIB.T6G(SCH_1):GND     I3 @T6G_MB_LIB.T6G(SCH_1):PAGE59
  CF61    GND @T6G_MB_LIB.T6G(SCH_1):GND     I3 @T6G_MB_LIB.T6G(SCH_1):PAGE59
  CF64    GND @T6G_MB_LIB.T6G(SCH_1):GND     I3 @T6G_MB_LIB.T6G(SCH_1):PAGE59
  CF66    GND @T6G_MB_LIB.T6G(SCH_1):GND     I3 @T6G_MB_LIB.T6G(SCH_1):PAGE59
  CF68    GND @T6G_MB_LIB.T6G(SCH_1):GND     I3 @T6G_MB_LIB.T6G(SCH_1):PAGE59
  CF71    GND @T6G_MB_LIB.T6G(SCH_1):GND     I3 @T6G_MB_LIB.T6G(SCH_1):PAGE59
  CF73    GND @T6G_MB_LIB.T6G(SCH_1):GND     I3 @T6G_MB_LIB.T6G(SCH_1):PAGE59
   CG1    GND @T6G_MB_LIB.T6G(SCH_1):GND     I3 @T6G_MB_LIB.T6G(SCH_1):PAGE59
   CG6    GND @T6G_MB_LIB.T6G(SCH_1):GND     I3 @T6G_MB_LIB.T6G(SCH_1):PAGE59
   CG8    GND @T6G_MB_LIB.T6G(SCH_1):GND     I3 @T6G_MB_LIB.T6G(SCH_1):PAGE59
  CG13    GND @T6G_MB_LIB.T6G(SCH_1):GND     I3 @T6G_MB_LIB.T6G(SCH_1):PAGE59
  CG15    GND @T6G_MB_LIB.T6G(SCH_1):GND     I3 @T6G_MB_LIB.T6G(SCH_1):PAGE59
  CG20    GND @T6G_MB_LIB.T6G(SCH_1):GND     I3 @T6G_MB_LIB.T6G(SCH_1):PAGE59
  CG22    GND @T6G_MB_LIB.T6G(SCH_1):GND     I3 @T6G_MB_LIB.T6G(SCH_1):PAGE59
  CG25    GND @T6G_MB_LIB.T6G(SCH_1):GND     I3 @T6G_MB_LIB.T6G(SCH_1):PAGE59
  CG28    GND @T6G_MB_LIB.T6G(SCH_1):GND     I3 @T6G_MB_LIB.T6G(SCH_1):PAGE59
  CG31    GND @T6G_MB_LIB.T6G(SCH_1):GND     I3 @T6G_MB_LIB.T6G(SCH_1):PAGE59
  CG34    GND @T6G_MB_LIB.T6G(SCH_1):GND     I3 @T6G_MB_LIB.T6G(SCH_1):PAGE59
  CG45    GND @T6G_MB_LIB.T6G(SCH_1):GND     I3 @T6G_MB_LIB.T6G(SCH_1):PAGE59
  CG48    GND @T6G_MB_LIB.T6G(SCH_1):GND     I3 @T6G_MB_LIB.T6G(SCH_1):PAGE59
  CG51    GND @T6G_MB_LIB.T6G(SCH_1):GND     I3 @T6G_MB_LIB.T6G(SCH_1):PAGE59
  CG54    GND @T6G_MB_LIB.T6G(SCH_1):GND     I3 @T6G_MB_LIB.T6G(SCH_1):PAGE59
  CG56    GND @T6G_MB_LIB.T6G(SCH_1):GND     I3 @T6G_MB_LIB.T6G(SCH_1):PAGE59
  CG61    GND @T6G_MB_LIB.T6G(SCH_1):GND     I3 @T6G_MB_LIB.T6G(SCH_1):PAGE59
  CG63    GND @T6G_MB_LIB.T6G(SCH_1):GND     I3 @T6G_MB_LIB.T6G(SCH_1):PAGE59
  CG68    GND @T6G_MB_LIB.T6G(SCH_1):GND     I3 @T6G_MB_LIB.T6G(SCH_1):PAGE59
  CG70    GND @T6G_MB_LIB.T6G(SCH_1):GND     I3 @T6G_MB_LIB.T6G(SCH_1):PAGE59
  CG75    GND @T6G_MB_LIB.T6G(SCH_1):GND     I3 @T6G_MB_LIB.T6G(SCH_1):PAGE59
   CH3    GND @T6G_MB_LIB.T6G(SCH_1):GND     I3 @T6G_MB_LIB.T6G(SCH_1):PAGE59
   CH5    GND @T6G_MB_LIB.T6G(SCH_1):GND     I3 @T6G_MB_LIB.T6G(SCH_1):PAGE59
   CH8    GND @T6G_MB_LIB.T6G(SCH_1):GND     I3 @T6G_MB_LIB.T6G(SCH_1):PAGE59
  CH22    GND @T6G_MB_LIB.T6G(SCH_1):GND     I3 @T6G_MB_LIB.T6G(SCH_1):PAGE59
  CH25    GND @T6G_MB_LIB.T6G(SCH_1):GND     I3 @T6G_MB_LIB.T6G(SCH_1):PAGE59
  CH28    GND @T6G_MB_LIB.T6G(SCH_1):GND     I3 @T6G_MB_LIB.T6G(SCH_1):PAGE59
  CH31    GND @T6G_MB_LIB.T6G(SCH_1):GND     I3 @T6G_MB_LIB.T6G(SCH_1):PAGE59
  CH34    GND @T6G_MB_LIB.T6G(SCH_1):GND     I3 @T6G_MB_LIB.T6G(SCH_1):PAGE59
  CH37    GND @T6G_MB_LIB.T6G(SCH_1):GND     I3 @T6G_MB_LIB.T6G(SCH_1):PAGE59
  CH54    GND @T6G_MB_LIB.T6G(SCH_1):GND     I3 @T6G_MB_LIB.T6G(SCH_1):PAGE59
  CH57    GND @T6G_MB_LIB.T6G(SCH_1):GND     I3 @T6G_MB_LIB.T6G(SCH_1):PAGE59
  CH59    GND @T6G_MB_LIB.T6G(SCH_1):GND     I3 @T6G_MB_LIB.T6G(SCH_1):PAGE59
  CH61    GND @T6G_MB_LIB.T6G(SCH_1):GND     I3 @T6G_MB_LIB.T6G(SCH_1):PAGE59
  CH64    GND @T6G_MB_LIB.T6G(SCH_1):GND     I3 @T6G_MB_LIB.T6G(SCH_1):PAGE59
  CH66    GND @T6G_MB_LIB.T6G(SCH_1):GND     I3 @T6G_MB_LIB.T6G(SCH_1):PAGE59
   CJ6    GND @T6G_MB_LIB.T6G(SCH_1):GND     I3 @T6G_MB_LIB.T6G(SCH_1):PAGE59
   CJ8    GND @T6G_MB_LIB.T6G(SCH_1):GND     I3 @T6G_MB_LIB.T6G(SCH_1):PAGE59
  CJ11    GND @T6G_MB_LIB.T6G(SCH_1):GND     I3 @T6G_MB_LIB.T6G(SCH_1):PAGE59
  CJ13    GND @T6G_MB_LIB.T6G(SCH_1):GND     I3 @T6G_MB_LIB.T6G(SCH_1):PAGE59
  CJ15    GND @T6G_MB_LIB.T6G(SCH_1):GND     I3 @T6G_MB_LIB.T6G(SCH_1):PAGE59
  CJ18    GND @T6G_MB_LIB.T6G(SCH_1):GND     I3 @T6G_MB_LIB.T6G(SCH_1):PAGE59
  CJ35    GND @T6G_MB_LIB.T6G(SCH_1):GND     I3 @T6G_MB_LIB.T6G(SCH_1):PAGE59
  CJ36    GND @T6G_MB_LIB.T6G(SCH_1):GND     I3 @T6G_MB_LIB.T6G(SCH_1):PAGE59
  CJ40    GND @T6G_MB_LIB.T6G(SCH_1):GND     I3 @T6G_MB_LIB.T6G(SCH_1):PAGE59
  CJ41    GND @T6G_MB_LIB.T6G(SCH_1):GND     I3 @T6G_MB_LIB.T6G(SCH_1):PAGE59
  CJ42    GND @T6G_MB_LIB.T6G(SCH_1):GND     I3 @T6G_MB_LIB.T6G(SCH_1):PAGE59
  CJ45    GND @T6G_MB_LIB.T6G(SCH_1):GND     I3 @T6G_MB_LIB.T6G(SCH_1):PAGE59
  CJ56    GND @T6G_MB_LIB.T6G(SCH_1):GND     I3 @T6G_MB_LIB.T6G(SCH_1):PAGE59
  CJ65    GND @T6G_MB_LIB.T6G(SCH_1):GND     I3 @T6G_MB_LIB.T6G(SCH_1):PAGE59
  CJ68    GND @T6G_MB_LIB.T6G(SCH_1):GND     I3 @T6G_MB_LIB.T6G(SCH_1):PAGE59
  CJ70    GND @T6G_MB_LIB.T6G(SCH_1):GND     I3 @T6G_MB_LIB.T6G(SCH_1):PAGE59
  CJ72    GND @T6G_MB_LIB.T6G(SCH_1):GND     I3 @T6G_MB_LIB.T6G(SCH_1):PAGE59
  CJ75    GND @T6G_MB_LIB.T6G(SCH_1):GND     I3 @T6G_MB_LIB.T6G(SCH_1):PAGE59
   CK3    GND @T6G_MB_LIB.T6G(SCH_1):GND     I3 @T6G_MB_LIB.T6G(SCH_1):PAGE59
   CK8    GND @T6G_MB_LIB.T6G(SCH_1):GND     I3 @T6G_MB_LIB.T6G(SCH_1):PAGE59
  CK22    GND @T6G_MB_LIB.T6G(SCH_1):GND     I3 @T6G_MB_LIB.T6G(SCH_1):PAGE59
  CK23    GND @T6G_MB_LIB.T6G(SCH_1):GND     I3 @T6G_MB_LIB.T6G(SCH_1):PAGE59
  CK24    GND @T6G_MB_LIB.T6G(SCH_1):GND     I3 @T6G_MB_LIB.T6G(SCH_1):PAGE59
  CK25    GND @T6G_MB_LIB.T6G(SCH_1):GND     I3 @T6G_MB_LIB.T6G(SCH_1):PAGE59
  CK26    GND @T6G_MB_LIB.T6G(SCH_1):GND     I3 @T6G_MB_LIB.T6G(SCH_1):PAGE59
  CK27    GND @T6G_MB_LIB.T6G(SCH_1):GND     I3 @T6G_MB_LIB.T6G(SCH_1):PAGE59
  CK28    GND @T6G_MB_LIB.T6G(SCH_1):GND     I3 @T6G_MB_LIB.T6G(SCH_1):PAGE59
  CK32    GND @T6G_MB_LIB.T6G(SCH_1):GND     I3 @T6G_MB_LIB.T6G(SCH_1):PAGE59
  CK34    GND @T6G_MB_LIB.T6G(SCH_1):GND     I3 @T6G_MB_LIB.T6G(SCH_1):PAGE59
  CK37    GND @T6G_MB_LIB.T6G(SCH_1):GND     I3 @T6G_MB_LIB.T6G(SCH_1):PAGE59
  CK39    GND @T6G_MB_LIB.T6G(SCH_1):GND     I3 @T6G_MB_LIB.T6G(SCH_1):PAGE59
  CK42    GND @T6G_MB_LIB.T6G(SCH_1):GND     I3 @T6G_MB_LIB.T6G(SCH_1):PAGE59
  CK43    GND @T6G_MB_LIB.T6G(SCH_1):GND     I3 @T6G_MB_LIB.T6G(SCH_1):PAGE59
  CK44    GND @T6G_MB_LIB.T6G(SCH_1):GND     I3 @T6G_MB_LIB.T6G(SCH_1):PAGE59
  CK45    GND @T6G_MB_LIB.T6G(SCH_1):GND     I3 @T6G_MB_LIB.T6G(SCH_1):PAGE59
  CK48    GND @T6G_MB_LIB.T6G(SCH_1):GND     I3 @T6G_MB_LIB.T6G(SCH_1):PAGE59
  CK49    GND @T6G_MB_LIB.T6G(SCH_1):GND     I3 @T6G_MB_LIB.T6G(SCH_1):PAGE59
  CK50    GND @T6G_MB_LIB.T6G(SCH_1):GND     I3 @T6G_MB_LIB.T6G(SCH_1):PAGE59
  CK51    GND @T6G_MB_LIB.T6G(SCH_1):GND     I3 @T6G_MB_LIB.T6G(SCH_1):PAGE59
  CK52    GND @T6G_MB_LIB.T6G(SCH_1):GND     I3 @T6G_MB_LIB.T6G(SCH_1):PAGE59
  CK53    GND @T6G_MB_LIB.T6G(SCH_1):GND     I3 @T6G_MB_LIB.T6G(SCH_1):PAGE59
  CK54    GND @T6G_MB_LIB.T6G(SCH_1):GND     I3 @T6G_MB_LIB.T6G(SCH_1):PAGE59
  CK59    GND @T6G_MB_LIB.T6G(SCH_1):GND     I3 @T6G_MB_LIB.T6G(SCH_1):PAGE59
  CK61    GND @T6G_MB_LIB.T6G(SCH_1):GND     I3 @T6G_MB_LIB.T6G(SCH_1):PAGE59
  CK66    GND @T6G_MB_LIB.T6G(SCH_1):GND     I3 @T6G_MB_LIB.T6G(SCH_1):PAGE59
  CK68    GND @T6G_MB_LIB.T6G(SCH_1):GND     I3 @T6G_MB_LIB.T6G(SCH_1):PAGE59
  CK73    GND @T6G_MB_LIB.T6G(SCH_1):GND     I3 @T6G_MB_LIB.T6G(SCH_1):PAGE59
   CL1    GND @T6G_MB_LIB.T6G(SCH_1):GND     I3 @T6G_MB_LIB.T6G(SCH_1):PAGE59
   CL4    GND @T6G_MB_LIB.T6G(SCH_1):GND     I3 @T6G_MB_LIB.T6G(SCH_1):PAGE59
   CL6    GND @T6G_MB_LIB.T6G(SCH_1):GND     I3 @T6G_MB_LIB.T6G(SCH_1):PAGE59
   CL8    GND @T6G_MB_LIB.T6G(SCH_1):GND     I3 @T6G_MB_LIB.T6G(SCH_1):PAGE59
  CL11    GND @T6G_MB_LIB.T6G(SCH_1):GND     I3 @T6G_MB_LIB.T6G(SCH_1):PAGE59
  CL13    GND @T6G_MB_LIB.T6G(SCH_1):GND     I3 @T6G_MB_LIB.T6G(SCH_1):PAGE59
  CL15    GND @T6G_MB_LIB.T6G(SCH_1):GND     I3 @T6G_MB_LIB.T6G(SCH_1):PAGE59
  CL18    GND @T6G_MB_LIB.T6G(SCH_1):GND     I3 @T6G_MB_LIB.T6G(SCH_1):PAGE59
  CL20    GND @T6G_MB_LIB.T6G(SCH_1):GND     I3 @T6G_MB_LIB.T6G(SCH_1):PAGE59
  CL22    GND @T6G_MB_LIB.T6G(SCH_1):GND     I3 @T6G_MB_LIB.T6G(SCH_1):PAGE59
  CL25    GND @T6G_MB_LIB.T6G(SCH_1):GND     I3 @T6G_MB_LIB.T6G(SCH_1):PAGE59
  CL31    GND @T6G_MB_LIB.T6G(SCH_1):GND     I3 @T6G_MB_LIB.T6G(SCH_1):PAGE59
  CL34    GND @T6G_MB_LIB.T6G(SCH_1):GND     I3 @T6G_MB_LIB.T6G(SCH_1):PAGE59
  CL35    GND @T6G_MB_LIB.T6G(SCH_1):GND     I3 @T6G_MB_LIB.T6G(SCH_1):PAGE59
  CL36    GND @T6G_MB_LIB.T6G(SCH_1):GND     I3 @T6G_MB_LIB.T6G(SCH_1):PAGE59
  CL40    GND @T6G_MB_LIB.T6G(SCH_1):GND     I3 @T6G_MB_LIB.T6G(SCH_1):PAGE59
  CL41    GND @T6G_MB_LIB.T6G(SCH_1):GND     I3 @T6G_MB_LIB.T6G(SCH_1):PAGE59
  CL42    GND @T6G_MB_LIB.T6G(SCH_1):GND     I3 @T6G_MB_LIB.T6G(SCH_1):PAGE59
  CL45    GND @T6G_MB_LIB.T6G(SCH_1):GND     I3 @T6G_MB_LIB.T6G(SCH_1):PAGE59
  CL48    GND @T6G_MB_LIB.T6G(SCH_1):GND     I3 @T6G_MB_LIB.T6G(SCH_1):PAGE59
  CL56    GND @T6G_MB_LIB.T6G(SCH_1):GND     I3 @T6G_MB_LIB.T6G(SCH_1):PAGE59
  CL58    GND @T6G_MB_LIB.T6G(SCH_1):GND     I3 @T6G_MB_LIB.T6G(SCH_1):PAGE59
  CL61    GND @T6G_MB_LIB.T6G(SCH_1):GND     I3 @T6G_MB_LIB.T6G(SCH_1):PAGE59
  CL63    GND @T6G_MB_LIB.T6G(SCH_1):GND     I3 @T6G_MB_LIB.T6G(SCH_1):PAGE59
  CL65    GND @T6G_MB_LIB.T6G(SCH_1):GND     I3 @T6G_MB_LIB.T6G(SCH_1):PAGE59
  CL68    GND @T6G_MB_LIB.T6G(SCH_1):GND     I3 @T6G_MB_LIB.T6G(SCH_1):PAGE59
  CL70    GND @T6G_MB_LIB.T6G(SCH_1):GND     I3 @T6G_MB_LIB.T6G(SCH_1):PAGE59
  CL72    GND @T6G_MB_LIB.T6G(SCH_1):GND     I3 @T6G_MB_LIB.T6G(SCH_1):PAGE59
   CM8    GND @T6G_MB_LIB.T6G(SCH_1):GND     I3 @T6G_MB_LIB.T6G(SCH_1):PAGE59
  CM10    GND @T6G_MB_LIB.T6G(SCH_1):GND     I3 @T6G_MB_LIB.T6G(SCH_1):PAGE59
  CM12    GND @T6G_MB_LIB.T6G(SCH_1):GND     I3 @T6G_MB_LIB.T6G(SCH_1):PAGE59
  CM15    GND @T6G_MB_LIB.T6G(SCH_1):GND     I3 @T6G_MB_LIB.T6G(SCH_1):PAGE59
  CM17    GND @T6G_MB_LIB.T6G(SCH_1):GND     I3 @T6G_MB_LIB.T6G(SCH_1):PAGE59
  CM19    GND @T6G_MB_LIB.T6G(SCH_1):GND     I3 @T6G_MB_LIB.T6G(SCH_1):PAGE59
  CM23    GND @T6G_MB_LIB.T6G(SCH_1):GND     I3 @T6G_MB_LIB.T6G(SCH_1):PAGE59
  CM28    GND @T6G_MB_LIB.T6G(SCH_1):GND     I3 @T6G_MB_LIB.T6G(SCH_1):PAGE59
  CM29    GND @T6G_MB_LIB.T6G(SCH_1):GND     I3 @T6G_MB_LIB.T6G(SCH_1):PAGE59
  CM30    GND @T6G_MB_LIB.T6G(SCH_1):GND     I3 @T6G_MB_LIB.T6G(SCH_1):PAGE59
  CM31    GND @T6G_MB_LIB.T6G(SCH_1):GND     I3 @T6G_MB_LIB.T6G(SCH_1):PAGE59
  CM32    GND @T6G_MB_LIB.T6G(SCH_1):GND     I3 @T6G_MB_LIB.T6G(SCH_1):PAGE59
  CM33    GND @T6G_MB_LIB.T6G(SCH_1):GND     I3 @T6G_MB_LIB.T6G(SCH_1):PAGE59
  CM44    GND @T6G_MB_LIB.T6G(SCH_1):GND     I3 @T6G_MB_LIB.T6G(SCH_1):PAGE59
  CM45    GND @T6G_MB_LIB.T6G(SCH_1):GND     I3 @T6G_MB_LIB.T6G(SCH_1):PAGE59
  CM46    GND @T6G_MB_LIB.T6G(SCH_1):GND     I3 @T6G_MB_LIB.T6G(SCH_1):PAGE59
  CM47    GND @T6G_MB_LIB.T6G(SCH_1):GND     I3 @T6G_MB_LIB.T6G(SCH_1):PAGE59
  CM48    GND @T6G_MB_LIB.T6G(SCH_1):GND     I3 @T6G_MB_LIB.T6G(SCH_1):PAGE59
  CM49    GND @T6G_MB_LIB.T6G(SCH_1):GND     I3 @T6G_MB_LIB.T6G(SCH_1):PAGE59
  CM51    GND @T6G_MB_LIB.T6G(SCH_1):GND     I3 @T6G_MB_LIB.T6G(SCH_1):PAGE59
  CM52    GND @T6G_MB_LIB.T6G(SCH_1):GND     I3 @T6G_MB_LIB.T6G(SCH_1):PAGE59
  CM53    GND @T6G_MB_LIB.T6G(SCH_1):GND     I3 @T6G_MB_LIB.T6G(SCH_1):PAGE59
  CM57    GND @T6G_MB_LIB.T6G(SCH_1):GND     I3 @T6G_MB_LIB.T6G(SCH_1):PAGE59
  CM59    GND @T6G_MB_LIB.T6G(SCH_1):GND     I3 @T6G_MB_LIB.T6G(SCH_1):PAGE59
  CM68    GND @T6G_MB_LIB.T6G(SCH_1):GND     I3 @T6G_MB_LIB.T6G(SCH_1):PAGE59
  CM71    GND @T6G_MB_LIB.T6G(SCH_1):GND     I3 @T6G_MB_LIB.T6G(SCH_1):PAGE59
  CM73    GND @T6G_MB_LIB.T6G(SCH_1):GND     I3 @T6G_MB_LIB.T6G(SCH_1):PAGE59
   CN1    GND @T6G_MB_LIB.T6G(SCH_1):GND     I3 @T6G_MB_LIB.T6G(SCH_1):PAGE59
   CN6    GND @T6G_MB_LIB.T6G(SCH_1):GND     I3 @T6G_MB_LIB.T6G(SCH_1):PAGE59
   CN8    GND @T6G_MB_LIB.T6G(SCH_1):GND     I3 @T6G_MB_LIB.T6G(SCH_1):PAGE59
  CN13    GND @T6G_MB_LIB.T6G(SCH_1):GND     I3 @T6G_MB_LIB.T6G(SCH_1):PAGE59
  CN15    GND @T6G_MB_LIB.T6G(SCH_1):GND     I3 @T6G_MB_LIB.T6G(SCH_1):PAGE59
  CN25    GND @T6G_MB_LIB.T6G(SCH_1):GND     I3 @T6G_MB_LIB.T6G(SCH_1):PAGE59
  CN28    GND @T6G_MB_LIB.T6G(SCH_1):GND     I3 @T6G_MB_LIB.T6G(SCH_1):PAGE59
  CN31    GND @T6G_MB_LIB.T6G(SCH_1):GND     I3 @T6G_MB_LIB.T6G(SCH_1):PAGE59
  CN34    GND @T6G_MB_LIB.T6G(SCH_1):GND     I3 @T6G_MB_LIB.T6G(SCH_1):PAGE59
  CN42    GND @T6G_MB_LIB.T6G(SCH_1):GND     I3 @T6G_MB_LIB.T6G(SCH_1):PAGE59
  CN45    GND @T6G_MB_LIB.T6G(SCH_1):GND     I3 @T6G_MB_LIB.T6G(SCH_1):PAGE59
  CN48    GND @T6G_MB_LIB.T6G(SCH_1):GND     I3 @T6G_MB_LIB.T6G(SCH_1):PAGE59
  CN51    GND @T6G_MB_LIB.T6G(SCH_1):GND     I3 @T6G_MB_LIB.T6G(SCH_1):PAGE59
  CN61    GND @T6G_MB_LIB.T6G(SCH_1):GND     I3 @T6G_MB_LIB.T6G(SCH_1):PAGE59
  CN63    GND @T6G_MB_LIB.T6G(SCH_1):GND     I3 @T6G_MB_LIB.T6G(SCH_1):PAGE59
  CN68    GND @T6G_MB_LIB.T6G(SCH_1):GND     I3 @T6G_MB_LIB.T6G(SCH_1):PAGE59
  CN70    GND @T6G_MB_LIB.T6G(SCH_1):GND     I3 @T6G_MB_LIB.T6G(SCH_1):PAGE59
  CN75    GND @T6G_MB_LIB.T6G(SCH_1):GND     I3 @T6G_MB_LIB.T6G(SCH_1):PAGE59
   CP3    GND @T6G_MB_LIB.T6G(SCH_1):GND     I3 @T6G_MB_LIB.T6G(SCH_1):PAGE59
   CP5    GND @T6G_MB_LIB.T6G(SCH_1):GND     I3 @T6G_MB_LIB.T6G(SCH_1):PAGE59
   CP8    GND @T6G_MB_LIB.T6G(SCH_1):GND     I3 @T6G_MB_LIB.T6G(SCH_1):PAGE59
  CP10    GND @T6G_MB_LIB.T6G(SCH_1):GND     I3 @T6G_MB_LIB.T6G(SCH_1):PAGE59
  CP12    GND @T6G_MB_LIB.T6G(SCH_1):GND     I3 @T6G_MB_LIB.T6G(SCH_1):PAGE59
  CP15    GND @T6G_MB_LIB.T6G(SCH_1):GND     I3 @T6G_MB_LIB.T6G(SCH_1):PAGE59
  CP17    GND @T6G_MB_LIB.T6G(SCH_1):GND     I3 @T6G_MB_LIB.T6G(SCH_1):PAGE59
  CP19    GND @T6G_MB_LIB.T6G(SCH_1):GND     I3 @T6G_MB_LIB.T6G(SCH_1):PAGE59
  CP22    GND @T6G_MB_LIB.T6G(SCH_1):GND     I4 @T6G_MB_LIB.T6G(SCH_1):PAGE59
  CP42    GND @T6G_MB_LIB.T6G(SCH_1):GND     I4 @T6G_MB_LIB.T6G(SCH_1):PAGE59
  CP45    GND @T6G_MB_LIB.T6G(SCH_1):GND     I4 @T6G_MB_LIB.T6G(SCH_1):PAGE59
  CP48    GND @T6G_MB_LIB.T6G(SCH_1):GND     I4 @T6G_MB_LIB.T6G(SCH_1):PAGE59
  CP51    GND @T6G_MB_LIB.T6G(SCH_1):GND     I4 @T6G_MB_LIB.T6G(SCH_1):PAGE59
  CP54    GND @T6G_MB_LIB.T6G(SCH_1):GND     I4 @T6G_MB_LIB.T6G(SCH_1):PAGE59
  CP71    GND @T6G_MB_LIB.T6G(SCH_1):GND     I4 @T6G_MB_LIB.T6G(SCH_1):PAGE59
  CP73    GND @T6G_MB_LIB.T6G(SCH_1):GND     I4 @T6G_MB_LIB.T6G(SCH_1):PAGE59
   CR1    GND @T6G_MB_LIB.T6G(SCH_1):GND     I4 @T6G_MB_LIB.T6G(SCH_1):PAGE59
   CR4    GND @T6G_MB_LIB.T6G(SCH_1):GND     I4 @T6G_MB_LIB.T6G(SCH_1):PAGE59
   CR6    GND @T6G_MB_LIB.T6G(SCH_1):GND     I4 @T6G_MB_LIB.T6G(SCH_1):PAGE59
  CR22    GND @T6G_MB_LIB.T6G(SCH_1):GND     I4 @T6G_MB_LIB.T6G(SCH_1):PAGE59
  CR25    GND @T6G_MB_LIB.T6G(SCH_1):GND     I4 @T6G_MB_LIB.T6G(SCH_1):PAGE59
  CR28    GND @T6G_MB_LIB.T6G(SCH_1):GND     I4 @T6G_MB_LIB.T6G(SCH_1):PAGE59
  CR31    GND @T6G_MB_LIB.T6G(SCH_1):GND     I4 @T6G_MB_LIB.T6G(SCH_1):PAGE59
  CR34    GND @T6G_MB_LIB.T6G(SCH_1):GND     I4 @T6G_MB_LIB.T6G(SCH_1):PAGE59
  CR48    GND @T6G_MB_LIB.T6G(SCH_1):GND     I4 @T6G_MB_LIB.T6G(SCH_1):PAGE59
  CR51    GND @T6G_MB_LIB.T6G(SCH_1):GND     I4 @T6G_MB_LIB.T6G(SCH_1):PAGE59
  CR54    GND @T6G_MB_LIB.T6G(SCH_1):GND     I4 @T6G_MB_LIB.T6G(SCH_1):PAGE59
  CR56    GND @T6G_MB_LIB.T6G(SCH_1):GND     I4 @T6G_MB_LIB.T6G(SCH_1):PAGE59
  CR58    GND @T6G_MB_LIB.T6G(SCH_1):GND     I4 @T6G_MB_LIB.T6G(SCH_1):PAGE59
  CR75    GND @T6G_MB_LIB.T6G(SCH_1):GND     I4 @T6G_MB_LIB.T6G(SCH_1):PAGE59
   CT3    GND @T6G_MB_LIB.T6G(SCH_1):GND     I4 @T6G_MB_LIB.T6G(SCH_1):PAGE59
   CT8    GND @T6G_MB_LIB.T6G(SCH_1):GND     I4 @T6G_MB_LIB.T6G(SCH_1):PAGE59
  CT10    GND @T6G_MB_LIB.T6G(SCH_1):GND     I4 @T6G_MB_LIB.T6G(SCH_1):PAGE59
  CT15    GND @T6G_MB_LIB.T6G(SCH_1):GND     I4 @T6G_MB_LIB.T6G(SCH_1):PAGE59
  CT48    GND @T6G_MB_LIB.T6G(SCH_1):GND     I4 @T6G_MB_LIB.T6G(SCH_1):PAGE59
  CT73    GND @T6G_MB_LIB.T6G(SCH_1):GND     I4 @T6G_MB_LIB.T6G(SCH_1):PAGE59
   CU1    GND @T6G_MB_LIB.T6G(SCH_1):GND     I4 @T6G_MB_LIB.T6G(SCH_1):PAGE59
  CU22    GND @T6G_MB_LIB.T6G(SCH_1):GND     I4 @T6G_MB_LIB.T6G(SCH_1):PAGE59
  CU25    GND @T6G_MB_LIB.T6G(SCH_1):GND     I4 @T6G_MB_LIB.T6G(SCH_1):PAGE59
  CU28    GND @T6G_MB_LIB.T6G(SCH_1):GND     I4 @T6G_MB_LIB.T6G(SCH_1):PAGE59
  CU56    GND @T6G_MB_LIB.T6G(SCH_1):GND     I4 @T6G_MB_LIB.T6G(SCH_1):PAGE59
  CU61    GND @T6G_MB_LIB.T6G(SCH_1):GND     I4 @T6G_MB_LIB.T6G(SCH_1):PAGE59
  CU63    GND @T6G_MB_LIB.T6G(SCH_1):GND     I4 @T6G_MB_LIB.T6G(SCH_1):PAGE59
   CV5    GND @T6G_MB_LIB.T6G(SCH_1):GND     I4 @T6G_MB_LIB.T6G(SCH_1):PAGE59
   CV8    GND @T6G_MB_LIB.T6G(SCH_1):GND     I4 @T6G_MB_LIB.T6G(SCH_1):PAGE59
  CV10    GND @T6G_MB_LIB.T6G(SCH_1):GND     I4 @T6G_MB_LIB.T6G(SCH_1):PAGE59
  CV12    GND @T6G_MB_LIB.T6G(SCH_1):GND     I4 @T6G_MB_LIB.T6G(SCH_1):PAGE59
  CV15    GND @T6G_MB_LIB.T6G(SCH_1):GND     I4 @T6G_MB_LIB.T6G(SCH_1):PAGE59
  CV34    GND @T6G_MB_LIB.T6G(SCH_1):GND     I4 @T6G_MB_LIB.T6G(SCH_1):PAGE59
  CV37    GND @T6G_MB_LIB.T6G(SCH_1):GND     I4 @T6G_MB_LIB.T6G(SCH_1):PAGE59
  CV39    GND @T6G_MB_LIB.T6G(SCH_1):GND     I4 @T6G_MB_LIB.T6G(SCH_1):PAGE59
  CV42    GND @T6G_MB_LIB.T6G(SCH_1):GND     I4 @T6G_MB_LIB.T6G(SCH_1):PAGE59
  CV45    GND @T6G_MB_LIB.T6G(SCH_1):GND     I4 @T6G_MB_LIB.T6G(SCH_1):PAGE59
  CV64    GND @T6G_MB_LIB.T6G(SCH_1):GND     I4 @T6G_MB_LIB.T6G(SCH_1):PAGE59
  CV66    GND @T6G_MB_LIB.T6G(SCH_1):GND     I4 @T6G_MB_LIB.T6G(SCH_1):PAGE59
  CV68    GND @T6G_MB_LIB.T6G(SCH_1):GND     I4 @T6G_MB_LIB.T6G(SCH_1):PAGE59
  CV71    GND @T6G_MB_LIB.T6G(SCH_1):GND     I4 @T6G_MB_LIB.T6G(SCH_1):PAGE59
  CV73    GND @T6G_MB_LIB.T6G(SCH_1):GND     I4 @T6G_MB_LIB.T6G(SCH_1):PAGE59
  CW22    GND @T6G_MB_LIB.T6G(SCH_1):GND     I4 @T6G_MB_LIB.T6G(SCH_1):PAGE59
  CW25    GND @T6G_MB_LIB.T6G(SCH_1):GND     I4 @T6G_MB_LIB.T6G(SCH_1):PAGE59
  CW28    GND @T6G_MB_LIB.T6G(SCH_1):GND     I4 @T6G_MB_LIB.T6G(SCH_1):PAGE59
  CW31    GND @T6G_MB_LIB.T6G(SCH_1):GND     I4 @T6G_MB_LIB.T6G(SCH_1):PAGE59
  CW34    GND @T6G_MB_LIB.T6G(SCH_1):GND     I4 @T6G_MB_LIB.T6G(SCH_1):PAGE59
  CY32    GND @T6G_MB_LIB.T6G(SCH_1):GND     I4 @T6G_MB_LIB.T6G(SCH_1):PAGE59
  CY47    GND @T6G_MB_LIB.T6G(SCH_1):GND     I4 @T6G_MB_LIB.T6G(SCH_1):PAGE59
  CY48    GND @T6G_MB_LIB.T6G(SCH_1):GND     I4 @T6G_MB_LIB.T6G(SCH_1):PAGE59
  CY64    GND @T6G_MB_LIB.T6G(SCH_1):GND     I4 @T6G_MB_LIB.T6G(SCH_1):PAGE59
  CY66    GND @T6G_MB_LIB.T6G(SCH_1):GND     I4 @T6G_MB_LIB.T6G(SCH_1):PAGE59
  CY68    GND @T6G_MB_LIB.T6G(SCH_1):GND     I4 @T6G_MB_LIB.T6G(SCH_1):PAGE59
  DA13    GND @T6G_MB_LIB.T6G(SCH_1):GND     I4 @T6G_MB_LIB.T6G(SCH_1):PAGE59
  DA15    GND @T6G_MB_LIB.T6G(SCH_1):GND     I4 @T6G_MB_LIB.T6G(SCH_1):PAGE59
  DA18    GND @T6G_MB_LIB.T6G(SCH_1):GND     I4 @T6G_MB_LIB.T6G(SCH_1):PAGE59
  DA20    GND @T6G_MB_LIB.T6G(SCH_1):GND     I4 @T6G_MB_LIB.T6G(SCH_1):PAGE59
  DA45    GND @T6G_MB_LIB.T6G(SCH_1):GND     I4 @T6G_MB_LIB.T6G(SCH_1):PAGE59
  DA48    GND @T6G_MB_LIB.T6G(SCH_1):GND     I4 @T6G_MB_LIB.T6G(SCH_1):PAGE59
  DA51    GND @T6G_MB_LIB.T6G(SCH_1):GND     I4 @T6G_MB_LIB.T6G(SCH_1):PAGE59
  DA54    GND @T6G_MB_LIB.T6G(SCH_1):GND     I4 @T6G_MB_LIB.T6G(SCH_1):PAGE59
  CP25    GND @T6G_MB_LIB.T6G(SCH_1):GND     I4 @T6G_MB_LIB.T6G(SCH_1):PAGE59
  CP28    GND @T6G_MB_LIB.T6G(SCH_1):GND     I4 @T6G_MB_LIB.T6G(SCH_1):PAGE59
  CP31    GND @T6G_MB_LIB.T6G(SCH_1):GND     I4 @T6G_MB_LIB.T6G(SCH_1):PAGE59
  CP34    GND @T6G_MB_LIB.T6G(SCH_1):GND     I4 @T6G_MB_LIB.T6G(SCH_1):PAGE59
  CP37    GND @T6G_MB_LIB.T6G(SCH_1):GND     I4 @T6G_MB_LIB.T6G(SCH_1):PAGE59
  CP39    GND @T6G_MB_LIB.T6G(SCH_1):GND     I4 @T6G_MB_LIB.T6G(SCH_1):PAGE59
  CP57    GND @T6G_MB_LIB.T6G(SCH_1):GND     I4 @T6G_MB_LIB.T6G(SCH_1):PAGE59
  CP59    GND @T6G_MB_LIB.T6G(SCH_1):GND     I4 @T6G_MB_LIB.T6G(SCH_1):PAGE59
  CP61    GND @T6G_MB_LIB.T6G(SCH_1):GND     I4 @T6G_MB_LIB.T6G(SCH_1):PAGE59
  CP64    GND @T6G_MB_LIB.T6G(SCH_1):GND     I4 @T6G_MB_LIB.T6G(SCH_1):PAGE59
  CP66    GND @T6G_MB_LIB.T6G(SCH_1):GND     I4 @T6G_MB_LIB.T6G(SCH_1):PAGE59
  CP68    GND @T6G_MB_LIB.T6G(SCH_1):GND     I4 @T6G_MB_LIB.T6G(SCH_1):PAGE59
   CR8    GND @T6G_MB_LIB.T6G(SCH_1):GND     I4 @T6G_MB_LIB.T6G(SCH_1):PAGE59
  CR11    GND @T6G_MB_LIB.T6G(SCH_1):GND     I4 @T6G_MB_LIB.T6G(SCH_1):PAGE59
  CR13    GND @T6G_MB_LIB.T6G(SCH_1):GND     I4 @T6G_MB_LIB.T6G(SCH_1):PAGE59
  CR15    GND @T6G_MB_LIB.T6G(SCH_1):GND     I4 @T6G_MB_LIB.T6G(SCH_1):PAGE59
  CR18    GND @T6G_MB_LIB.T6G(SCH_1):GND     I4 @T6G_MB_LIB.T6G(SCH_1):PAGE59
  CR20    GND @T6G_MB_LIB.T6G(SCH_1):GND     I4 @T6G_MB_LIB.T6G(SCH_1):PAGE59
  CR35    GND @T6G_MB_LIB.T6G(SCH_1):GND     I4 @T6G_MB_LIB.T6G(SCH_1):PAGE59
  CR36    GND @T6G_MB_LIB.T6G(SCH_1):GND     I4 @T6G_MB_LIB.T6G(SCH_1):PAGE59
  CR40    GND @T6G_MB_LIB.T6G(SCH_1):GND     I4 @T6G_MB_LIB.T6G(SCH_1):PAGE59
  CR41    GND @T6G_MB_LIB.T6G(SCH_1):GND     I4 @T6G_MB_LIB.T6G(SCH_1):PAGE59
  CR42    GND @T6G_MB_LIB.T6G(SCH_1):GND     I4 @T6G_MB_LIB.T6G(SCH_1):PAGE59
  CR45    GND @T6G_MB_LIB.T6G(SCH_1):GND     I4 @T6G_MB_LIB.T6G(SCH_1):PAGE59
  CR61    GND @T6G_MB_LIB.T6G(SCH_1):GND     I4 @T6G_MB_LIB.T6G(SCH_1):PAGE59
  CR63    GND @T6G_MB_LIB.T6G(SCH_1):GND     I4 @T6G_MB_LIB.T6G(SCH_1):PAGE59
  CR65    GND @T6G_MB_LIB.T6G(SCH_1):GND     I4 @T6G_MB_LIB.T6G(SCH_1):PAGE59
  CR68    GND @T6G_MB_LIB.T6G(SCH_1):GND     I4 @T6G_MB_LIB.T6G(SCH_1):PAGE59
  CR70    GND @T6G_MB_LIB.T6G(SCH_1):GND     I4 @T6G_MB_LIB.T6G(SCH_1):PAGE59
  CR72    GND @T6G_MB_LIB.T6G(SCH_1):GND     I4 @T6G_MB_LIB.T6G(SCH_1):PAGE59
  CT17    GND @T6G_MB_LIB.T6G(SCH_1):GND     I4 @T6G_MB_LIB.T6G(SCH_1):PAGE59
  CT23    GND @T6G_MB_LIB.T6G(SCH_1):GND     I4 @T6G_MB_LIB.T6G(SCH_1):PAGE59
  CT24    GND @T6G_MB_LIB.T6G(SCH_1):GND     I4 @T6G_MB_LIB.T6G(SCH_1):PAGE59
  CT25    GND @T6G_MB_LIB.T6G(SCH_1):GND     I4 @T6G_MB_LIB.T6G(SCH_1):PAGE59
  CT26    GND @T6G_MB_LIB.T6G(SCH_1):GND     I4 @T6G_MB_LIB.T6G(SCH_1):PAGE59
  CT27    GND @T6G_MB_LIB.T6G(SCH_1):GND     I4 @T6G_MB_LIB.T6G(SCH_1):PAGE59
  CT28    GND @T6G_MB_LIB.T6G(SCH_1):GND     I4 @T6G_MB_LIB.T6G(SCH_1):PAGE59
  CT29    GND @T6G_MB_LIB.T6G(SCH_1):GND     I4 @T6G_MB_LIB.T6G(SCH_1):PAGE59
  CT30    GND @T6G_MB_LIB.T6G(SCH_1):GND     I4 @T6G_MB_LIB.T6G(SCH_1):PAGE59
  CT31    GND @T6G_MB_LIB.T6G(SCH_1):GND     I4 @T6G_MB_LIB.T6G(SCH_1):PAGE59
  CT32    GND @T6G_MB_LIB.T6G(SCH_1):GND     I4 @T6G_MB_LIB.T6G(SCH_1):PAGE59
  CT33    GND @T6G_MB_LIB.T6G(SCH_1):GND     I4 @T6G_MB_LIB.T6G(SCH_1):PAGE59
  CT34    GND @T6G_MB_LIB.T6G(SCH_1):GND     I4 @T6G_MB_LIB.T6G(SCH_1):PAGE59
  CT37    GND @T6G_MB_LIB.T6G(SCH_1):GND     I4 @T6G_MB_LIB.T6G(SCH_1):PAGE59
  CT39    GND @T6G_MB_LIB.T6G(SCH_1):GND     I4 @T6G_MB_LIB.T6G(SCH_1):PAGE59
  CT42    GND @T6G_MB_LIB.T6G(SCH_1):GND     I4 @T6G_MB_LIB.T6G(SCH_1):PAGE59
  CT43    GND @T6G_MB_LIB.T6G(SCH_1):GND     I4 @T6G_MB_LIB.T6G(SCH_1):PAGE59
  CT44    GND @T6G_MB_LIB.T6G(SCH_1):GND     I4 @T6G_MB_LIB.T6G(SCH_1):PAGE59
  CT45    GND @T6G_MB_LIB.T6G(SCH_1):GND     I4 @T6G_MB_LIB.T6G(SCH_1):PAGE59
  CT46    GND @T6G_MB_LIB.T6G(SCH_1):GND     I4 @T6G_MB_LIB.T6G(SCH_1):PAGE59
  CT47    GND @T6G_MB_LIB.T6G(SCH_1):GND     I4 @T6G_MB_LIB.T6G(SCH_1):PAGE59
  CT49    GND @T6G_MB_LIB.T6G(SCH_1):GND     I4 @T6G_MB_LIB.T6G(SCH_1):PAGE59
  CT50    GND @T6G_MB_LIB.T6G(SCH_1):GND     I4 @T6G_MB_LIB.T6G(SCH_1):PAGE59
  CT51    GND @T6G_MB_LIB.T6G(SCH_1):GND     I4 @T6G_MB_LIB.T6G(SCH_1):PAGE59
  CT53    GND @T6G_MB_LIB.T6G(SCH_1):GND     I4 @T6G_MB_LIB.T6G(SCH_1):PAGE59
  CT59    GND @T6G_MB_LIB.T6G(SCH_1):GND     I4 @T6G_MB_LIB.T6G(SCH_1):PAGE59
  CT61    GND @T6G_MB_LIB.T6G(SCH_1):GND     I4 @T6G_MB_LIB.T6G(SCH_1):PAGE59
  CT66    GND @T6G_MB_LIB.T6G(SCH_1):GND     I4 @T6G_MB_LIB.T6G(SCH_1):PAGE59
  CT68    GND @T6G_MB_LIB.T6G(SCH_1):GND     I4 @T6G_MB_LIB.T6G(SCH_1):PAGE59
   CU4    GND @T6G_MB_LIB.T6G(SCH_1):GND     I4 @T6G_MB_LIB.T6G(SCH_1):PAGE59
   CU6    GND @T6G_MB_LIB.T6G(SCH_1):GND     I4 @T6G_MB_LIB.T6G(SCH_1):PAGE59
   CU8    GND @T6G_MB_LIB.T6G(SCH_1):GND     I4 @T6G_MB_LIB.T6G(SCH_1):PAGE59
  CU11    GND @T6G_MB_LIB.T6G(SCH_1):GND     I4 @T6G_MB_LIB.T6G(SCH_1):PAGE59
  CU13    GND @T6G_MB_LIB.T6G(SCH_1):GND     I4 @T6G_MB_LIB.T6G(SCH_1):PAGE59
  CU15    GND @T6G_MB_LIB.T6G(SCH_1):GND     I4 @T6G_MB_LIB.T6G(SCH_1):PAGE59
  CU18    GND @T6G_MB_LIB.T6G(SCH_1):GND     I4 @T6G_MB_LIB.T6G(SCH_1):PAGE59
  CU20    GND @T6G_MB_LIB.T6G(SCH_1):GND     I4 @T6G_MB_LIB.T6G(SCH_1):PAGE59
  CU31    GND @T6G_MB_LIB.T6G(SCH_1):GND     I4 @T6G_MB_LIB.T6G(SCH_1):PAGE59
  CU34    GND @T6G_MB_LIB.T6G(SCH_1):GND     I4 @T6G_MB_LIB.T6G(SCH_1):PAGE59
  CU42    GND @T6G_MB_LIB.T6G(SCH_1):GND     I4 @T6G_MB_LIB.T6G(SCH_1):PAGE59
  CU45    GND @T6G_MB_LIB.T6G(SCH_1):GND     I4 @T6G_MB_LIB.T6G(SCH_1):PAGE59
  CU48    GND @T6G_MB_LIB.T6G(SCH_1):GND     I4 @T6G_MB_LIB.T6G(SCH_1):PAGE59
  CU51    GND @T6G_MB_LIB.T6G(SCH_1):GND     I4 @T6G_MB_LIB.T6G(SCH_1):PAGE59
  CU54    GND @T6G_MB_LIB.T6G(SCH_1):GND     I4 @T6G_MB_LIB.T6G(SCH_1):PAGE59
  CU65    GND @T6G_MB_LIB.T6G(SCH_1):GND     I4 @T6G_MB_LIB.T6G(SCH_1):PAGE59
  CU68    GND @T6G_MB_LIB.T6G(SCH_1):GND     I4 @T6G_MB_LIB.T6G(SCH_1):PAGE59
  CU70    GND @T6G_MB_LIB.T6G(SCH_1):GND     I4 @T6G_MB_LIB.T6G(SCH_1):PAGE59
  CU72    GND @T6G_MB_LIB.T6G(SCH_1):GND     I4 @T6G_MB_LIB.T6G(SCH_1):PAGE59
  CU75    GND @T6G_MB_LIB.T6G(SCH_1):GND     I4 @T6G_MB_LIB.T6G(SCH_1):PAGE59
   CV3    GND @T6G_MB_LIB.T6G(SCH_1):GND     I4 @T6G_MB_LIB.T6G(SCH_1):PAGE59
  CV17    GND @T6G_MB_LIB.T6G(SCH_1):GND     I4 @T6G_MB_LIB.T6G(SCH_1):PAGE59
  CV19    GND @T6G_MB_LIB.T6G(SCH_1):GND     I4 @T6G_MB_LIB.T6G(SCH_1):PAGE59
  CV22    GND @T6G_MB_LIB.T6G(SCH_1):GND     I4 @T6G_MB_LIB.T6G(SCH_1):PAGE59
  CV25    GND @T6G_MB_LIB.T6G(SCH_1):GND     I4 @T6G_MB_LIB.T6G(SCH_1):PAGE59
  CV28    GND @T6G_MB_LIB.T6G(SCH_1):GND     I4 @T6G_MB_LIB.T6G(SCH_1):PAGE59
  CV31    GND @T6G_MB_LIB.T6G(SCH_1):GND     I4 @T6G_MB_LIB.T6G(SCH_1):PAGE59
  CV48    GND @T6G_MB_LIB.T6G(SCH_1):GND     I4 @T6G_MB_LIB.T6G(SCH_1):PAGE59
  CV51    GND @T6G_MB_LIB.T6G(SCH_1):GND     I4 @T6G_MB_LIB.T6G(SCH_1):PAGE59
  CV54    GND @T6G_MB_LIB.T6G(SCH_1):GND     I4 @T6G_MB_LIB.T6G(SCH_1):PAGE59
  CV57    GND @T6G_MB_LIB.T6G(SCH_1):GND     I4 @T6G_MB_LIB.T6G(SCH_1):PAGE59
  CV59    GND @T6G_MB_LIB.T6G(SCH_1):GND     I4 @T6G_MB_LIB.T6G(SCH_1):PAGE59
  CV61    GND @T6G_MB_LIB.T6G(SCH_1):GND     I4 @T6G_MB_LIB.T6G(SCH_1):PAGE59
   CW1    GND @T6G_MB_LIB.T6G(SCH_1):GND     I4 @T6G_MB_LIB.T6G(SCH_1):PAGE59
   CW6    GND @T6G_MB_LIB.T6G(SCH_1):GND     I4 @T6G_MB_LIB.T6G(SCH_1):PAGE59
   CW8    GND @T6G_MB_LIB.T6G(SCH_1):GND     I4 @T6G_MB_LIB.T6G(SCH_1):PAGE59
  CW13    GND @T6G_MB_LIB.T6G(SCH_1):GND     I4 @T6G_MB_LIB.T6G(SCH_1):PAGE59
  CW15    GND @T6G_MB_LIB.T6G(SCH_1):GND     I4 @T6G_MB_LIB.T6G(SCH_1):PAGE59
  CW20    GND @T6G_MB_LIB.T6G(SCH_1):GND     I4 @T6G_MB_LIB.T6G(SCH_1):PAGE59
  CW35    GND @T6G_MB_LIB.T6G(SCH_1):GND     I4 @T6G_MB_LIB.T6G(SCH_1):PAGE59
  CW36    GND @T6G_MB_LIB.T6G(SCH_1):GND     I4 @T6G_MB_LIB.T6G(SCH_1):PAGE59
  CW40    GND @T6G_MB_LIB.T6G(SCH_1):GND     I4 @T6G_MB_LIB.T6G(SCH_1):PAGE59
  CW41    GND @T6G_MB_LIB.T6G(SCH_1):GND     I4 @T6G_MB_LIB.T6G(SCH_1):PAGE59
  CW42    GND @T6G_MB_LIB.T6G(SCH_1):GND     I4 @T6G_MB_LIB.T6G(SCH_1):PAGE59
  CW45    GND @T6G_MB_LIB.T6G(SCH_1):GND     I4 @T6G_MB_LIB.T6G(SCH_1):PAGE59
  CW48    GND @T6G_MB_LIB.T6G(SCH_1):GND     I4 @T6G_MB_LIB.T6G(SCH_1):PAGE59
  CW51    GND @T6G_MB_LIB.T6G(SCH_1):GND     I4 @T6G_MB_LIB.T6G(SCH_1):PAGE59
  CW54    GND @T6G_MB_LIB.T6G(SCH_1):GND     I4 @T6G_MB_LIB.T6G(SCH_1):PAGE59
  CW56    GND @T6G_MB_LIB.T6G(SCH_1):GND     I4 @T6G_MB_LIB.T6G(SCH_1):PAGE59
  CW61    GND @T6G_MB_LIB.T6G(SCH_1):GND     I4 @T6G_MB_LIB.T6G(SCH_1):PAGE59
  CW63    GND @T6G_MB_LIB.T6G(SCH_1):GND     I4 @T6G_MB_LIB.T6G(SCH_1):PAGE59
  CW68    GND @T6G_MB_LIB.T6G(SCH_1):GND     I4 @T6G_MB_LIB.T6G(SCH_1):PAGE59
  CW70    GND @T6G_MB_LIB.T6G(SCH_1):GND     I4 @T6G_MB_LIB.T6G(SCH_1):PAGE59
  CW75    GND @T6G_MB_LIB.T6G(SCH_1):GND     I4 @T6G_MB_LIB.T6G(SCH_1):PAGE59
   CY3    GND @T6G_MB_LIB.T6G(SCH_1):GND     I4 @T6G_MB_LIB.T6G(SCH_1):PAGE59
   CY5    GND @T6G_MB_LIB.T6G(SCH_1):GND     I4 @T6G_MB_LIB.T6G(SCH_1):PAGE59
   CY8    GND @T6G_MB_LIB.T6G(SCH_1):GND     I4 @T6G_MB_LIB.T6G(SCH_1):PAGE59
  CY10    GND @T6G_MB_LIB.T6G(SCH_1):GND     I4 @T6G_MB_LIB.T6G(SCH_1):PAGE59
  CY12    GND @T6G_MB_LIB.T6G(SCH_1):GND     I4 @T6G_MB_LIB.T6G(SCH_1):PAGE59
  CY15    GND @T6G_MB_LIB.T6G(SCH_1):GND     I4 @T6G_MB_LIB.T6G(SCH_1):PAGE59
  CY17    GND @T6G_MB_LIB.T6G(SCH_1):GND     I4 @T6G_MB_LIB.T6G(SCH_1):PAGE59
  CY19    GND @T6G_MB_LIB.T6G(SCH_1):GND     I4 @T6G_MB_LIB.T6G(SCH_1):PAGE59
  CY23    GND @T6G_MB_LIB.T6G(SCH_1):GND     I4 @T6G_MB_LIB.T6G(SCH_1):PAGE59
  CY24    GND @T6G_MB_LIB.T6G(SCH_1):GND     I4 @T6G_MB_LIB.T6G(SCH_1):PAGE59
  CY25    GND @T6G_MB_LIB.T6G(SCH_1):GND     I4 @T6G_MB_LIB.T6G(SCH_1):PAGE59
  CY26    GND @T6G_MB_LIB.T6G(SCH_1):GND     I4 @T6G_MB_LIB.T6G(SCH_1):PAGE59
  CY27    GND @T6G_MB_LIB.T6G(SCH_1):GND     I4 @T6G_MB_LIB.T6G(SCH_1):PAGE59
  CY28    GND @T6G_MB_LIB.T6G(SCH_1):GND     I4 @T6G_MB_LIB.T6G(SCH_1):PAGE59
  CY29    GND @T6G_MB_LIB.T6G(SCH_1):GND     I4 @T6G_MB_LIB.T6G(SCH_1):PAGE59
  CY30    GND @T6G_MB_LIB.T6G(SCH_1):GND     I4 @T6G_MB_LIB.T6G(SCH_1):PAGE59
  CY31    GND @T6G_MB_LIB.T6G(SCH_1):GND     I4 @T6G_MB_LIB.T6G(SCH_1):PAGE59
  CY33    GND @T6G_MB_LIB.T6G(SCH_1):GND     I4 @T6G_MB_LIB.T6G(SCH_1):PAGE59
  CY34    GND @T6G_MB_LIB.T6G(SCH_1):GND     I4 @T6G_MB_LIB.T6G(SCH_1):PAGE59
  CY37    GND @T6G_MB_LIB.T6G(SCH_1):GND     I4 @T6G_MB_LIB.T6G(SCH_1):PAGE59
  CY39    GND @T6G_MB_LIB.T6G(SCH_1):GND     I4 @T6G_MB_LIB.T6G(SCH_1):PAGE59
  CY42    GND @T6G_MB_LIB.T6G(SCH_1):GND     I4 @T6G_MB_LIB.T6G(SCH_1):PAGE59
  CY43    GND @T6G_MB_LIB.T6G(SCH_1):GND     I4 @T6G_MB_LIB.T6G(SCH_1):PAGE59
  CY44    GND @T6G_MB_LIB.T6G(SCH_1):GND     I4 @T6G_MB_LIB.T6G(SCH_1):PAGE59
  CY45    GND @T6G_MB_LIB.T6G(SCH_1):GND     I4 @T6G_MB_LIB.T6G(SCH_1):PAGE59
  CY46    GND @T6G_MB_LIB.T6G(SCH_1):GND     I4 @T6G_MB_LIB.T6G(SCH_1):PAGE59
  CY49    GND @T6G_MB_LIB.T6G(SCH_1):GND     I4 @T6G_MB_LIB.T6G(SCH_1):PAGE59
  CY50    GND @T6G_MB_LIB.T6G(SCH_1):GND     I4 @T6G_MB_LIB.T6G(SCH_1):PAGE59
  CY51    GND @T6G_MB_LIB.T6G(SCH_1):GND     I4 @T6G_MB_LIB.T6G(SCH_1):PAGE59
  CY52    GND @T6G_MB_LIB.T6G(SCH_1):GND     I4 @T6G_MB_LIB.T6G(SCH_1):PAGE59
  CY53    GND @T6G_MB_LIB.T6G(SCH_1):GND     I4 @T6G_MB_LIB.T6G(SCH_1):PAGE59
  CY59    GND @T6G_MB_LIB.T6G(SCH_1):GND     I4 @T6G_MB_LIB.T6G(SCH_1):PAGE59
  CY61    GND @T6G_MB_LIB.T6G(SCH_1):GND     I4 @T6G_MB_LIB.T6G(SCH_1):PAGE59
  CY71    GND @T6G_MB_LIB.T6G(SCH_1):GND     I4 @T6G_MB_LIB.T6G(SCH_1):PAGE59
  CY73    GND @T6G_MB_LIB.T6G(SCH_1):GND     I4 @T6G_MB_LIB.T6G(SCH_1):PAGE59
   DA1    GND @T6G_MB_LIB.T6G(SCH_1):GND     I4 @T6G_MB_LIB.T6G(SCH_1):PAGE59
   DA4    GND @T6G_MB_LIB.T6G(SCH_1):GND     I4 @T6G_MB_LIB.T6G(SCH_1):PAGE59
   DA6    GND @T6G_MB_LIB.T6G(SCH_1):GND     I4 @T6G_MB_LIB.T6G(SCH_1):PAGE59
   DA8    GND @T6G_MB_LIB.T6G(SCH_1):GND     I4 @T6G_MB_LIB.T6G(SCH_1):PAGE59
  DA11    GND @T6G_MB_LIB.T6G(SCH_1):GND     I4 @T6G_MB_LIB.T6G(SCH_1):PAGE59
  DA22    GND @T6G_MB_LIB.T6G(SCH_1):GND     I4 @T6G_MB_LIB.T6G(SCH_1):PAGE59
  DA25    GND @T6G_MB_LIB.T6G(SCH_1):GND     I4 @T6G_MB_LIB.T6G(SCH_1):PAGE59
  DA28    GND @T6G_MB_LIB.T6G(SCH_1):GND     I4 @T6G_MB_LIB.T6G(SCH_1):PAGE59
  DA31    GND @T6G_MB_LIB.T6G(SCH_1):GND     I4 @T6G_MB_LIB.T6G(SCH_1):PAGE59
  DA34    GND @T6G_MB_LIB.T6G(SCH_1):GND     I4 @T6G_MB_LIB.T6G(SCH_1):PAGE59
  DA42    GND @T6G_MB_LIB.T6G(SCH_1):GND     I4 @T6G_MB_LIB.T6G(SCH_1):PAGE59
  DA58    GND @T6G_MB_LIB.T6G(SCH_1):GND     I4 @T6G_MB_LIB.T6G(SCH_1):PAGE59
  DA61    GND @T6G_MB_LIB.T6G(SCH_1):GND     I4 @T6G_MB_LIB.T6G(SCH_1):PAGE59
  DA63    GND @T6G_MB_LIB.T6G(SCH_1):GND     I4 @T6G_MB_LIB.T6G(SCH_1):PAGE59
  DA65    GND @T6G_MB_LIB.T6G(SCH_1):GND     I4 @T6G_MB_LIB.T6G(SCH_1):PAGE59
  DA68    GND @T6G_MB_LIB.T6G(SCH_1):GND     I4 @T6G_MB_LIB.T6G(SCH_1):PAGE59
  DA70    GND @T6G_MB_LIB.T6G(SCH_1):GND     I4 @T6G_MB_LIB.T6G(SCH_1):PAGE59
  DB15    GND @T6G_MB_LIB.T6G(SCH_1):GND     I3 @T6G_MB_LIB.T6G(SCH_1):PAGE60
  DB17    GND @T6G_MB_LIB.T6G(SCH_1):GND     I3 @T6G_MB_LIB.T6G(SCH_1):PAGE60
  DB22    GND @T6G_MB_LIB.T6G(SCH_1):GND     I3 @T6G_MB_LIB.T6G(SCH_1):PAGE60
  DB25    GND @T6G_MB_LIB.T6G(SCH_1):GND     I3 @T6G_MB_LIB.T6G(SCH_1):PAGE60
  DB48    GND @T6G_MB_LIB.T6G(SCH_1):GND     I3 @T6G_MB_LIB.T6G(SCH_1):PAGE60
  DB51    GND @T6G_MB_LIB.T6G(SCH_1):GND     I3 @T6G_MB_LIB.T6G(SCH_1):PAGE60
  DB54    GND @T6G_MB_LIB.T6G(SCH_1):GND     I3 @T6G_MB_LIB.T6G(SCH_1):PAGE60
  DB59    GND @T6G_MB_LIB.T6G(SCH_1):GND     I3 @T6G_MB_LIB.T6G(SCH_1):PAGE60
  DC13    GND @T6G_MB_LIB.T6G(SCH_1):GND     I3 @T6G_MB_LIB.T6G(SCH_1):PAGE60
  DC15    GND @T6G_MB_LIB.T6G(SCH_1):GND     I3 @T6G_MB_LIB.T6G(SCH_1):PAGE60
  DC45    GND @T6G_MB_LIB.T6G(SCH_1):GND     I3 @T6G_MB_LIB.T6G(SCH_1):PAGE60
  DC48    GND @T6G_MB_LIB.T6G(SCH_1):GND     I3 @T6G_MB_LIB.T6G(SCH_1):PAGE60
  DC51    GND @T6G_MB_LIB.T6G(SCH_1):GND     I3 @T6G_MB_LIB.T6G(SCH_1):PAGE60
  DC70    GND @T6G_MB_LIB.T6G(SCH_1):GND     I3 @T6G_MB_LIB.T6G(SCH_1):PAGE60
  DC72    GND @T6G_MB_LIB.T6G(SCH_1):GND     I3 @T6G_MB_LIB.T6G(SCH_1):PAGE60
  DC75    GND @T6G_MB_LIB.T6G(SCH_1):GND     I3 @T6G_MB_LIB.T6G(SCH_1):PAGE60
   DD3    GND @T6G_MB_LIB.T6G(SCH_1):GND     I3 @T6G_MB_LIB.T6G(SCH_1):PAGE60
  DD23    GND @T6G_MB_LIB.T6G(SCH_1):GND     I3 @T6G_MB_LIB.T6G(SCH_1):PAGE60
  DD24    GND @T6G_MB_LIB.T6G(SCH_1):GND     I3 @T6G_MB_LIB.T6G(SCH_1):PAGE60
  DD26    GND @T6G_MB_LIB.T6G(SCH_1):GND     I3 @T6G_MB_LIB.T6G(SCH_1):PAGE60
  DD27    GND @T6G_MB_LIB.T6G(SCH_1):GND     I3 @T6G_MB_LIB.T6G(SCH_1):PAGE60
  DD39    GND @T6G_MB_LIB.T6G(SCH_1):GND     I3 @T6G_MB_LIB.T6G(SCH_1):PAGE60
  DD40    GND @T6G_MB_LIB.T6G(SCH_1):GND     I3 @T6G_MB_LIB.T6G(SCH_1):PAGE60
  DD41    GND @T6G_MB_LIB.T6G(SCH_1):GND     I3 @T6G_MB_LIB.T6G(SCH_1):PAGE60
  DD43    GND @T6G_MB_LIB.T6G(SCH_1):GND     I3 @T6G_MB_LIB.T6G(SCH_1):PAGE60
  DD57    GND @T6G_MB_LIB.T6G(SCH_1):GND     I3 @T6G_MB_LIB.T6G(SCH_1):PAGE60
  DD59    GND @T6G_MB_LIB.T6G(SCH_1):GND     I3 @T6G_MB_LIB.T6G(SCH_1):PAGE60
  DD61    GND @T6G_MB_LIB.T6G(SCH_1):GND     I3 @T6G_MB_LIB.T6G(SCH_1):PAGE60
  DD64    GND @T6G_MB_LIB.T6G(SCH_1):GND     I3 @T6G_MB_LIB.T6G(SCH_1):PAGE60
  DE13    GND @T6G_MB_LIB.T6G(SCH_1):GND     I3 @T6G_MB_LIB.T6G(SCH_1):PAGE60
  DE15    GND @T6G_MB_LIB.T6G(SCH_1):GND     I3 @T6G_MB_LIB.T6G(SCH_1):PAGE60
  DE20    GND @T6G_MB_LIB.T6G(SCH_1):GND     I3 @T6G_MB_LIB.T6G(SCH_1):PAGE60
  DE23    GND @T6G_MB_LIB.T6G(SCH_1):GND     I3 @T6G_MB_LIB.T6G(SCH_1):PAGE60
  DE70    GND @T6G_MB_LIB.T6G(SCH_1):GND     I3 @T6G_MB_LIB.T6G(SCH_1):PAGE60
  DE75    GND @T6G_MB_LIB.T6G(SCH_1):GND     I3 @T6G_MB_LIB.T6G(SCH_1):PAGE60
   DF3    GND @T6G_MB_LIB.T6G(SCH_1):GND     I3 @T6G_MB_LIB.T6G(SCH_1):PAGE60
   DF4    GND @T6G_MB_LIB.T6G(SCH_1):GND     I3 @T6G_MB_LIB.T6G(SCH_1):PAGE60
  DF15    GND @T6G_MB_LIB.T6G(SCH_1):GND     I3 @T6G_MB_LIB.T6G(SCH_1):PAGE60
  DF17    GND @T6G_MB_LIB.T6G(SCH_1):GND     I3 @T6G_MB_LIB.T6G(SCH_1):PAGE60
  DF18    GND @T6G_MB_LIB.T6G(SCH_1):GND     I3 @T6G_MB_LIB.T6G(SCH_1):PAGE60
  DF19    GND @T6G_MB_LIB.T6G(SCH_1):GND     I3 @T6G_MB_LIB.T6G(SCH_1):PAGE60
  DF43    GND @T6G_MB_LIB.T6G(SCH_1):GND     I3 @T6G_MB_LIB.T6G(SCH_1):PAGE60
  DF53    GND @T6G_MB_LIB.T6G(SCH_1):GND     I3 @T6G_MB_LIB.T6G(SCH_1):PAGE60
  DF54    GND @T6G_MB_LIB.T6G(SCH_1):GND     I3 @T6G_MB_LIB.T6G(SCH_1):PAGE60
  DF66    GND @T6G_MB_LIB.T6G(SCH_1):GND     I3 @T6G_MB_LIB.T6G(SCH_1):PAGE60
  DF68    GND @T6G_MB_LIB.T6G(SCH_1):GND     I3 @T6G_MB_LIB.T6G(SCH_1):PAGE60
  DF70    GND @T6G_MB_LIB.T6G(SCH_1):GND     I3 @T6G_MB_LIB.T6G(SCH_1):PAGE60
   DG8    GND @T6G_MB_LIB.T6G(SCH_1):GND     I3 @T6G_MB_LIB.T6G(SCH_1):PAGE60
   DG9    GND @T6G_MB_LIB.T6G(SCH_1):GND     I3 @T6G_MB_LIB.T6G(SCH_1):PAGE60
  DG13    GND @T6G_MB_LIB.T6G(SCH_1):GND     I3 @T6G_MB_LIB.T6G(SCH_1):PAGE60
  DG14    GND @T6G_MB_LIB.T6G(SCH_1):GND     I3 @T6G_MB_LIB.T6G(SCH_1):PAGE60
  DG30    GND @T6G_MB_LIB.T6G(SCH_1):GND     I3 @T6G_MB_LIB.T6G(SCH_1):PAGE60
  DG33    GND @T6G_MB_LIB.T6G(SCH_1):GND     I3 @T6G_MB_LIB.T6G(SCH_1):PAGE60
  DG41    GND @T6G_MB_LIB.T6G(SCH_1):GND     I3 @T6G_MB_LIB.T6G(SCH_1):PAGE60
  DG43    GND @T6G_MB_LIB.T6G(SCH_1):GND     I3 @T6G_MB_LIB.T6G(SCH_1):PAGE60
  DG61    GND @T6G_MB_LIB.T6G(SCH_1):GND     I3 @T6G_MB_LIB.T6G(SCH_1):PAGE60
  DG62    GND @T6G_MB_LIB.T6G(SCH_1):GND     I3 @T6G_MB_LIB.T6G(SCH_1):PAGE60
  DG63    GND @T6G_MB_LIB.T6G(SCH_1):GND     I3 @T6G_MB_LIB.T6G(SCH_1):PAGE60
  DG65    GND @T6G_MB_LIB.T6G(SCH_1):GND     I3 @T6G_MB_LIB.T6G(SCH_1):PAGE60
   DH5    GND @T6G_MB_LIB.T6G(SCH_1):GND     I3 @T6G_MB_LIB.T6G(SCH_1):PAGE60
  DH11    GND @T6G_MB_LIB.T6G(SCH_1):GND     I3 @T6G_MB_LIB.T6G(SCH_1):PAGE60
  DH18    GND @T6G_MB_LIB.T6G(SCH_1):GND     I3 @T6G_MB_LIB.T6G(SCH_1):PAGE60
  DH37    GND @T6G_MB_LIB.T6G(SCH_1):GND     I3 @T6G_MB_LIB.T6G(SCH_1):PAGE60
  DH61    GND @T6G_MB_LIB.T6G(SCH_1):GND     I3 @T6G_MB_LIB.T6G(SCH_1):PAGE60
  DH63    GND @T6G_MB_LIB.T6G(SCH_1):GND     I3 @T6G_MB_LIB.T6G(SCH_1):PAGE60
  DH64    GND @T6G_MB_LIB.T6G(SCH_1):GND     I3 @T6G_MB_LIB.T6G(SCH_1):PAGE60
  DH66    GND @T6G_MB_LIB.T6G(SCH_1):GND     I3 @T6G_MB_LIB.T6G(SCH_1):PAGE60
  DA72    GND @T6G_MB_LIB.T6G(SCH_1):GND     I3 @T6G_MB_LIB.T6G(SCH_1):PAGE60
  DA75    GND @T6G_MB_LIB.T6G(SCH_1):GND     I3 @T6G_MB_LIB.T6G(SCH_1):PAGE60
   DB3    GND @T6G_MB_LIB.T6G(SCH_1):GND     I3 @T6G_MB_LIB.T6G(SCH_1):PAGE60
   DB8    GND @T6G_MB_LIB.T6G(SCH_1):GND     I3 @T6G_MB_LIB.T6G(SCH_1):PAGE60
  DB10    GND @T6G_MB_LIB.T6G(SCH_1):GND     I3 @T6G_MB_LIB.T6G(SCH_1):PAGE60
  DB28    GND @T6G_MB_LIB.T6G(SCH_1):GND     I3 @T6G_MB_LIB.T6G(SCH_1):PAGE60
  DB31    GND @T6G_MB_LIB.T6G(SCH_1):GND     I3 @T6G_MB_LIB.T6G(SCH_1):PAGE60
  DB34    GND @T6G_MB_LIB.T6G(SCH_1):GND     I3 @T6G_MB_LIB.T6G(SCH_1):PAGE60
  DB37    GND @T6G_MB_LIB.T6G(SCH_1):GND     I3 @T6G_MB_LIB.T6G(SCH_1):PAGE60
  DB39    GND @T6G_MB_LIB.T6G(SCH_1):GND     I3 @T6G_MB_LIB.T6G(SCH_1):PAGE60
  DB42    GND @T6G_MB_LIB.T6G(SCH_1):GND     I3 @T6G_MB_LIB.T6G(SCH_1):PAGE60
  DB45    GND @T6G_MB_LIB.T6G(SCH_1):GND     I3 @T6G_MB_LIB.T6G(SCH_1):PAGE60
  DB61    GND @T6G_MB_LIB.T6G(SCH_1):GND     I3 @T6G_MB_LIB.T6G(SCH_1):PAGE60
  DB66    GND @T6G_MB_LIB.T6G(SCH_1):GND     I3 @T6G_MB_LIB.T6G(SCH_1):PAGE60
  DB68    GND @T6G_MB_LIB.T6G(SCH_1):GND     I3 @T6G_MB_LIB.T6G(SCH_1):PAGE60
  DB73    GND @T6G_MB_LIB.T6G(SCH_1):GND     I3 @T6G_MB_LIB.T6G(SCH_1):PAGE60
   DC1    GND @T6G_MB_LIB.T6G(SCH_1):GND     I3 @T6G_MB_LIB.T6G(SCH_1):PAGE60
   DC4    GND @T6G_MB_LIB.T6G(SCH_1):GND     I3 @T6G_MB_LIB.T6G(SCH_1):PAGE60
   DC6    GND @T6G_MB_LIB.T6G(SCH_1):GND     I3 @T6G_MB_LIB.T6G(SCH_1):PAGE60
   DC8    GND @T6G_MB_LIB.T6G(SCH_1):GND     I3 @T6G_MB_LIB.T6G(SCH_1):PAGE60
  DC11    GND @T6G_MB_LIB.T6G(SCH_1):GND     I3 @T6G_MB_LIB.T6G(SCH_1):PAGE60
  DC18    GND @T6G_MB_LIB.T6G(SCH_1):GND     I3 @T6G_MB_LIB.T6G(SCH_1):PAGE60
  DC20    GND @T6G_MB_LIB.T6G(SCH_1):GND     I3 @T6G_MB_LIB.T6G(SCH_1):PAGE60
  DC22    GND @T6G_MB_LIB.T6G(SCH_1):GND     I3 @T6G_MB_LIB.T6G(SCH_1):PAGE60
  DC25    GND @T6G_MB_LIB.T6G(SCH_1):GND     I3 @T6G_MB_LIB.T6G(SCH_1):PAGE60
  DC28    GND @T6G_MB_LIB.T6G(SCH_1):GND     I3 @T6G_MB_LIB.T6G(SCH_1):PAGE60
  DC31    GND @T6G_MB_LIB.T6G(SCH_1):GND     I3 @T6G_MB_LIB.T6G(SCH_1):PAGE60
  DC34    GND @T6G_MB_LIB.T6G(SCH_1):GND     I3 @T6G_MB_LIB.T6G(SCH_1):PAGE60
  DC42    GND @T6G_MB_LIB.T6G(SCH_1):GND     I3 @T6G_MB_LIB.T6G(SCH_1):PAGE60
  DC54    GND @T6G_MB_LIB.T6G(SCH_1):GND     I3 @T6G_MB_LIB.T6G(SCH_1):PAGE60
  DC56    GND @T6G_MB_LIB.T6G(SCH_1):GND     I3 @T6G_MB_LIB.T6G(SCH_1):PAGE60
  DC58    GND @T6G_MB_LIB.T6G(SCH_1):GND     I3 @T6G_MB_LIB.T6G(SCH_1):PAGE60
  DC61    GND @T6G_MB_LIB.T6G(SCH_1):GND     I3 @T6G_MB_LIB.T6G(SCH_1):PAGE60
  DC63    GND @T6G_MB_LIB.T6G(SCH_1):GND     I3 @T6G_MB_LIB.T6G(SCH_1):PAGE60
  DC65    GND @T6G_MB_LIB.T6G(SCH_1):GND     I3 @T6G_MB_LIB.T6G(SCH_1):PAGE60
  DC68    GND @T6G_MB_LIB.T6G(SCH_1):GND     I3 @T6G_MB_LIB.T6G(SCH_1):PAGE60
   DD5    GND @T6G_MB_LIB.T6G(SCH_1):GND     I3 @T6G_MB_LIB.T6G(SCH_1):PAGE60
   DD8    GND @T6G_MB_LIB.T6G(SCH_1):GND     I3 @T6G_MB_LIB.T6G(SCH_1):PAGE60
  DD10    GND @T6G_MB_LIB.T6G(SCH_1):GND     I3 @T6G_MB_LIB.T6G(SCH_1):PAGE60
  DD12    GND @T6G_MB_LIB.T6G(SCH_1):GND     I3 @T6G_MB_LIB.T6G(SCH_1):PAGE60
  DD15    GND @T6G_MB_LIB.T6G(SCH_1):GND     I3 @T6G_MB_LIB.T6G(SCH_1):PAGE60
  DD17    GND @T6G_MB_LIB.T6G(SCH_1):GND     I3 @T6G_MB_LIB.T6G(SCH_1):PAGE60
  DD19    GND @T6G_MB_LIB.T6G(SCH_1):GND     I3 @T6G_MB_LIB.T6G(SCH_1):PAGE60
  DD29    GND @T6G_MB_LIB.T6G(SCH_1):GND     I3 @T6G_MB_LIB.T6G(SCH_1):PAGE60
  DD30    GND @T6G_MB_LIB.T6G(SCH_1):GND     I3 @T6G_MB_LIB.T6G(SCH_1):PAGE60
  DD32    GND @T6G_MB_LIB.T6G(SCH_1):GND     I3 @T6G_MB_LIB.T6G(SCH_1):PAGE60
  DD33    GND @T6G_MB_LIB.T6G(SCH_1):GND     I3 @T6G_MB_LIB.T6G(SCH_1):PAGE60
  DD35    GND @T6G_MB_LIB.T6G(SCH_1):GND     I3 @T6G_MB_LIB.T6G(SCH_1):PAGE60
  DD36    GND @T6G_MB_LIB.T6G(SCH_1):GND     I3 @T6G_MB_LIB.T6G(SCH_1):PAGE60
  DD37    GND @T6G_MB_LIB.T6G(SCH_1):GND     I3 @T6G_MB_LIB.T6G(SCH_1):PAGE60
  DD44    GND @T6G_MB_LIB.T6G(SCH_1):GND     I3 @T6G_MB_LIB.T6G(SCH_1):PAGE60
  DD46    GND @T6G_MB_LIB.T6G(SCH_1):GND     I3 @T6G_MB_LIB.T6G(SCH_1):PAGE60
  DD47    GND @T6G_MB_LIB.T6G(SCH_1):GND     I3 @T6G_MB_LIB.T6G(SCH_1):PAGE60
  DD49    GND @T6G_MB_LIB.T6G(SCH_1):GND     I3 @T6G_MB_LIB.T6G(SCH_1):PAGE60
  DD50    GND @T6G_MB_LIB.T6G(SCH_1):GND     I3 @T6G_MB_LIB.T6G(SCH_1):PAGE60
  DD52    GND @T6G_MB_LIB.T6G(SCH_1):GND     I3 @T6G_MB_LIB.T6G(SCH_1):PAGE60
  DD53    GND @T6G_MB_LIB.T6G(SCH_1):GND     I3 @T6G_MB_LIB.T6G(SCH_1):PAGE60
  DD66    GND @T6G_MB_LIB.T6G(SCH_1):GND     I3 @T6G_MB_LIB.T6G(SCH_1):PAGE60
  DD68    GND @T6G_MB_LIB.T6G(SCH_1):GND     I3 @T6G_MB_LIB.T6G(SCH_1):PAGE60
  DD71    GND @T6G_MB_LIB.T6G(SCH_1):GND     I3 @T6G_MB_LIB.T6G(SCH_1):PAGE60
  DD73    GND @T6G_MB_LIB.T6G(SCH_1):GND     I3 @T6G_MB_LIB.T6G(SCH_1):PAGE60
   DE1    GND @T6G_MB_LIB.T6G(SCH_1):GND     I3 @T6G_MB_LIB.T6G(SCH_1):PAGE60
   DE6    GND @T6G_MB_LIB.T6G(SCH_1):GND     I3 @T6G_MB_LIB.T6G(SCH_1):PAGE60
   DE8    GND @T6G_MB_LIB.T6G(SCH_1):GND     I3 @T6G_MB_LIB.T6G(SCH_1):PAGE60
  DE26    GND @T6G_MB_LIB.T6G(SCH_1):GND     I3 @T6G_MB_LIB.T6G(SCH_1):PAGE60
  DE29    GND @T6G_MB_LIB.T6G(SCH_1):GND     I3 @T6G_MB_LIB.T6G(SCH_1):PAGE60
  DE33    GND @T6G_MB_LIB.T6G(SCH_1):GND     I3 @T6G_MB_LIB.T6G(SCH_1):PAGE60
  DE56    GND @T6G_MB_LIB.T6G(SCH_1):GND     I3 @T6G_MB_LIB.T6G(SCH_1):PAGE60
  DE61    GND @T6G_MB_LIB.T6G(SCH_1):GND     I3 @T6G_MB_LIB.T6G(SCH_1):PAGE60
  DE63    GND @T6G_MB_LIB.T6G(SCH_1):GND     I3 @T6G_MB_LIB.T6G(SCH_1):PAGE60
  DE68    GND @T6G_MB_LIB.T6G(SCH_1):GND     I3 @T6G_MB_LIB.T6G(SCH_1):PAGE60
   DF5    GND @T6G_MB_LIB.T6G(SCH_1):GND     I3 @T6G_MB_LIB.T6G(SCH_1):PAGE60
   DF6    GND @T6G_MB_LIB.T6G(SCH_1):GND     I3 @T6G_MB_LIB.T6G(SCH_1):PAGE60
   DF8    GND @T6G_MB_LIB.T6G(SCH_1):GND     I3 @T6G_MB_LIB.T6G(SCH_1):PAGE60
  DF10    GND @T6G_MB_LIB.T6G(SCH_1):GND     I3 @T6G_MB_LIB.T6G(SCH_1):PAGE60
  DF11    GND @T6G_MB_LIB.T6G(SCH_1):GND     I3 @T6G_MB_LIB.T6G(SCH_1):PAGE60
  DF12    GND @T6G_MB_LIB.T6G(SCH_1):GND     I3 @T6G_MB_LIB.T6G(SCH_1):PAGE60
  DF13    GND @T6G_MB_LIB.T6G(SCH_1):GND     I3 @T6G_MB_LIB.T6G(SCH_1):PAGE60
  DF20    GND @T6G_MB_LIB.T6G(SCH_1):GND     I3 @T6G_MB_LIB.T6G(SCH_1):PAGE60
  DF22    GND @T6G_MB_LIB.T6G(SCH_1):GND     I3 @T6G_MB_LIB.T6G(SCH_1):PAGE60
  DF23    GND @T6G_MB_LIB.T6G(SCH_1):GND     I3 @T6G_MB_LIB.T6G(SCH_1):PAGE60
  DF26    GND @T6G_MB_LIB.T6G(SCH_1):GND     I3 @T6G_MB_LIB.T6G(SCH_1):PAGE60
  DF29    GND @T6G_MB_LIB.T6G(SCH_1):GND     I3 @T6G_MB_LIB.T6G(SCH_1):PAGE60
  DF32    GND @T6G_MB_LIB.T6G(SCH_1):GND     I3 @T6G_MB_LIB.T6G(SCH_1):PAGE60
  DF35    GND @T6G_MB_LIB.T6G(SCH_1):GND     I3 @T6G_MB_LIB.T6G(SCH_1):PAGE60
  DF37    GND @T6G_MB_LIB.T6G(SCH_1):GND     I3 @T6G_MB_LIB.T6G(SCH_1):PAGE60
  DF39    GND @T6G_MB_LIB.T6G(SCH_1):GND     I3 @T6G_MB_LIB.T6G(SCH_1):PAGE60
  DF42    GND @T6G_MB_LIB.T6G(SCH_1):GND     I3 @T6G_MB_LIB.T6G(SCH_1):PAGE60
  DF44    GND @T6G_MB_LIB.T6G(SCH_1):GND     I3 @T6G_MB_LIB.T6G(SCH_1):PAGE60
  DF45    GND @T6G_MB_LIB.T6G(SCH_1):GND     I3 @T6G_MB_LIB.T6G(SCH_1):PAGE60
  DF46    GND @T6G_MB_LIB.T6G(SCH_1):GND     I3 @T6G_MB_LIB.T6G(SCH_1):PAGE60
  DF47    GND @T6G_MB_LIB.T6G(SCH_1):GND     I3 @T6G_MB_LIB.T6G(SCH_1):PAGE60
  DF48    GND @T6G_MB_LIB.T6G(SCH_1):GND     I3 @T6G_MB_LIB.T6G(SCH_1):PAGE60
  DF49    GND @T6G_MB_LIB.T6G(SCH_1):GND     I3 @T6G_MB_LIB.T6G(SCH_1):PAGE60
  DF50    GND @T6G_MB_LIB.T6G(SCH_1):GND     I3 @T6G_MB_LIB.T6G(SCH_1):PAGE60
  DF51    GND @T6G_MB_LIB.T6G(SCH_1):GND     I3 @T6G_MB_LIB.T6G(SCH_1):PAGE60
  DF52    GND @T6G_MB_LIB.T6G(SCH_1):GND     I3 @T6G_MB_LIB.T6G(SCH_1):PAGE60
  DF56    GND @T6G_MB_LIB.T6G(SCH_1):GND     I3 @T6G_MB_LIB.T6G(SCH_1):PAGE60
  DF57    GND @T6G_MB_LIB.T6G(SCH_1):GND     I3 @T6G_MB_LIB.T6G(SCH_1):PAGE60
  DF58    GND @T6G_MB_LIB.T6G(SCH_1):GND     I3 @T6G_MB_LIB.T6G(SCH_1):PAGE60
  DF59    GND @T6G_MB_LIB.T6G(SCH_1):GND     I3 @T6G_MB_LIB.T6G(SCH_1):PAGE60
  DF61    GND @T6G_MB_LIB.T6G(SCH_1):GND     I3 @T6G_MB_LIB.T6G(SCH_1):PAGE60
  DF63    GND @T6G_MB_LIB.T6G(SCH_1):GND     I3 @T6G_MB_LIB.T6G(SCH_1):PAGE60
  DF64    GND @T6G_MB_LIB.T6G(SCH_1):GND     I3 @T6G_MB_LIB.T6G(SCH_1):PAGE60
  DF65    GND @T6G_MB_LIB.T6G(SCH_1):GND     I3 @T6G_MB_LIB.T6G(SCH_1):PAGE60
  DF71    GND @T6G_MB_LIB.T6G(SCH_1):GND     I3 @T6G_MB_LIB.T6G(SCH_1):PAGE60
  DF72    GND @T6G_MB_LIB.T6G(SCH_1):GND     I3 @T6G_MB_LIB.T6G(SCH_1):PAGE60
  DF73    GND @T6G_MB_LIB.T6G(SCH_1):GND     I3 @T6G_MB_LIB.T6G(SCH_1):PAGE60
   DG1    GND @T6G_MB_LIB.T6G(SCH_1):GND     I3 @T6G_MB_LIB.T6G(SCH_1):PAGE60
   DG2    GND @T6G_MB_LIB.T6G(SCH_1):GND     I3 @T6G_MB_LIB.T6G(SCH_1):PAGE60
   DG6    GND @T6G_MB_LIB.T6G(SCH_1):GND     I3 @T6G_MB_LIB.T6G(SCH_1):PAGE60
   DG7    GND @T6G_MB_LIB.T6G(SCH_1):GND     I3 @T6G_MB_LIB.T6G(SCH_1):PAGE60
  DG15    GND @T6G_MB_LIB.T6G(SCH_1):GND     I3 @T6G_MB_LIB.T6G(SCH_1):PAGE60
  DG16    GND @T6G_MB_LIB.T6G(SCH_1):GND     I3 @T6G_MB_LIB.T6G(SCH_1):PAGE60
  DG18    GND @T6G_MB_LIB.T6G(SCH_1):GND     I3 @T6G_MB_LIB.T6G(SCH_1):PAGE60
  DG20    GND @T6G_MB_LIB.T6G(SCH_1):GND     I3 @T6G_MB_LIB.T6G(SCH_1):PAGE60
  DG21    GND @T6G_MB_LIB.T6G(SCH_1):GND     I3 @T6G_MB_LIB.T6G(SCH_1):PAGE60
  DG24    GND @T6G_MB_LIB.T6G(SCH_1):GND     I3 @T6G_MB_LIB.T6G(SCH_1):PAGE60
  DG27    GND @T6G_MB_LIB.T6G(SCH_1):GND     I3 @T6G_MB_LIB.T6G(SCH_1):PAGE60
  DG46    GND @T6G_MB_LIB.T6G(SCH_1):GND     I3 @T6G_MB_LIB.T6G(SCH_1):PAGE60
  DG49    GND @T6G_MB_LIB.T6G(SCH_1):GND     I3 @T6G_MB_LIB.T6G(SCH_1):PAGE60
  DG52    GND @T6G_MB_LIB.T6G(SCH_1):GND     I3 @T6G_MB_LIB.T6G(SCH_1):PAGE60
  DG55    GND @T6G_MB_LIB.T6G(SCH_1):GND     I3 @T6G_MB_LIB.T6G(SCH_1):PAGE60
  DG56    GND @T6G_MB_LIB.T6G(SCH_1):GND     I3 @T6G_MB_LIB.T6G(SCH_1):PAGE60
  DG59    GND @T6G_MB_LIB.T6G(SCH_1):GND     I3 @T6G_MB_LIB.T6G(SCH_1):PAGE60
  DG60    GND @T6G_MB_LIB.T6G(SCH_1):GND     I3 @T6G_MB_LIB.T6G(SCH_1):PAGE60
  DG66    GND @T6G_MB_LIB.T6G(SCH_1):GND     I3 @T6G_MB_LIB.T6G(SCH_1):PAGE60
  DG67    GND @T6G_MB_LIB.T6G(SCH_1):GND     I3 @T6G_MB_LIB.T6G(SCH_1):PAGE60
  DG68    GND @T6G_MB_LIB.T6G(SCH_1):GND     I3 @T6G_MB_LIB.T6G(SCH_1):PAGE60
  DG69    GND @T6G_MB_LIB.T6G(SCH_1):GND     I3 @T6G_MB_LIB.T6G(SCH_1):PAGE60
  DG70    GND @T6G_MB_LIB.T6G(SCH_1):GND     I3 @T6G_MB_LIB.T6G(SCH_1):PAGE60
  DG74    GND @T6G_MB_LIB.T6G(SCH_1):GND     I3 @T6G_MB_LIB.T6G(SCH_1):PAGE60
  DG75    GND @T6G_MB_LIB.T6G(SCH_1):GND     I3 @T6G_MB_LIB.T6G(SCH_1):PAGE60
  DH39    GND @T6G_MB_LIB.T6G(SCH_1):GND     I3 @T6G_MB_LIB.T6G(SCH_1):PAGE60
  DH43    GND @T6G_MB_LIB.T6G(SCH_1):GND     I3 @T6G_MB_LIB.T6G(SCH_1):PAGE60
  DH46    GND @T6G_MB_LIB.T6G(SCH_1):GND     I3 @T6G_MB_LIB.T6G(SCH_1):PAGE60
  DH49    GND @T6G_MB_LIB.T6G(SCH_1):GND     I3 @T6G_MB_LIB.T6G(SCH_1):PAGE60
  DH52    GND @T6G_MB_LIB.T6G(SCH_1):GND     I3 @T6G_MB_LIB.T6G(SCH_1):PAGE60
  DH55    GND @T6G_MB_LIB.T6G(SCH_1):GND     I3 @T6G_MB_LIB.T6G(SCH_1):PAGE60
  DH59    GND @T6G_MB_LIB.T6G(SCH_1):GND     I3 @T6G_MB_LIB.T6G(SCH_1):PAGE60
  DH68    GND @T6G_MB_LIB.T6G(SCH_1):GND     I3 @T6G_MB_LIB.T6G(SCH_1):PAGE60
  DH70    GND @T6G_MB_LIB.T6G(SCH_1):GND     I3 @T6G_MB_LIB.T6G(SCH_1):PAGE60
   DJ7    GND @T6G_MB_LIB.T6G(SCH_1):GND     I3 @T6G_MB_LIB.T6G(SCH_1):PAGE60
  DJ15    GND @T6G_MB_LIB.T6G(SCH_1):GND     I3 @T6G_MB_LIB.T6G(SCH_1):PAGE60
  DJ19    GND @T6G_MB_LIB.T6G(SCH_1):GND     I3 @T6G_MB_LIB.T6G(SCH_1):PAGE60
  DJ43    GND @T6G_MB_LIB.T6G(SCH_1):GND     I3 @T6G_MB_LIB.T6G(SCH_1):PAGE60
  DJ49    GND @T6G_MB_LIB.T6G(SCH_1):GND     I3 @T6G_MB_LIB.T6G(SCH_1):PAGE60
  DJ59    GND @T6G_MB_LIB.T6G(SCH_1):GND     I3 @T6G_MB_LIB.T6G(SCH_1):PAGE60
  DJ61    GND @T6G_MB_LIB.T6G(SCH_1):GND     I3 @T6G_MB_LIB.T6G(SCH_1):PAGE60
  DJ63    GND @T6G_MB_LIB.T6G(SCH_1):GND     I3 @T6G_MB_LIB.T6G(SCH_1):PAGE60
  DJ66    GND @T6G_MB_LIB.T6G(SCH_1):GND     I3 @T6G_MB_LIB.T6G(SCH_1):PAGE60
  DJ68    GND @T6G_MB_LIB.T6G(SCH_1):GND     I3 @T6G_MB_LIB.T6G(SCH_1):PAGE60
  DJ73    GND @T6G_MB_LIB.T6G(SCH_1):GND     I3 @T6G_MB_LIB.T6G(SCH_1):PAGE60
  CY57    GND @T6G_MB_LIB.T6G(SCH_1):GND     I3 @T6G_MB_LIB.T6G(SCH_1):PAGE60
  CK31    GND @T6G_MB_LIB.T6G(SCH_1):GND     I3 @T6G_MB_LIB.T6G(SCH_1):PAGE60
  CB44    GND @T6G_MB_LIB.T6G(SCH_1):GND     I3 @T6G_MB_LIB.T6G(SCH_1):PAGE60
  AM37    GND @T6G_MB_LIB.T6G(SCH_1):GND     I3 @T6G_MB_LIB.T6G(SCH_1):PAGE60
   K23    GND @T6G_MB_LIB.T6G(SCH_1):GND     I3 @T6G_MB_LIB.T6G(SCH_1):PAGE60
  CN54    GND @T6G_MB_LIB.T6G(SCH_1):GND     I3 @T6G_MB_LIB.T6G(SCH_1):PAGE60
  CK10    GND @T6G_MB_LIB.T6G(SCH_1):GND     I3 @T6G_MB_LIB.T6G(SCH_1):PAGE60
  AA72    GND @T6G_MB_LIB.T6G(SCH_1):GND     I3 @T6G_MB_LIB.T6G(SCH_1):PAGE60
  AJ13    GND @T6G_MB_LIB.T6G(SCH_1):GND     I3 @T6G_MB_LIB.T6G(SCH_1):PAGE60
  AD31    GND @T6G_MB_LIB.T6G(SCH_1):GND     I3 @T6G_MB_LIB.T6G(SCH_1):PAGE60
  AA42    GND @T6G_MB_LIB.T6G(SCH_1):GND     I3 @T6G_MB_LIB.T6G(SCH_1):PAGE60
   V27    GND @T6G_MB_LIB.T6G(SCH_1):GND     I3 @T6G_MB_LIB.T6G(SCH_1):PAGE60
  CF46    GND @T6G_MB_LIB.T6G(SCH_1):GND     I3 @T6G_MB_LIB.T6G(SCH_1):PAGE60
  CC22    GND @T6G_MB_LIB.T6G(SCH_1):GND     I3 @T6G_MB_LIB.T6G(SCH_1):PAGE60
  AN20    GND @T6G_MB_LIB.T6G(SCH_1):GND     I3 @T6G_MB_LIB.T6G(SCH_1):PAGE60
   P68    GND @T6G_MB_LIB.T6G(SCH_1):GND     I3 @T6G_MB_LIB.T6G(SCH_1):PAGE60
   P25    GND @T6G_MB_LIB.T6G(SCH_1):GND     I3 @T6G_MB_LIB.T6G(SCH_1):PAGE60
  CU58    GND @T6G_MB_LIB.T6G(SCH_1):GND     I3 @T6G_MB_LIB.T6G(SCH_1):PAGE60
  BW25    GND @T6G_MB_LIB.T6G(SCH_1):GND     I3 @T6G_MB_LIB.T6G(SCH_1):PAGE60
  AH33    GND @T6G_MB_LIB.T6G(SCH_1):GND     I3 @T6G_MB_LIB.T6G(SCH_1):PAGE60
   AE4    GND @T6G_MB_LIB.T6G(SCH_1):GND     I3 @T6G_MB_LIB.T6G(SCH_1):PAGE60
  CG42    GND @T6G_MB_LIB.T6G(SCH_1):GND     I3 @T6G_MB_LIB.T6G(SCH_1):PAGE60
  DA56    GND @T6G_MB_LIB.T6G(SCH_1):GND     I3 @T6G_MB_LIB.T6G(SCH_1):PAGE60
   K59    GND @T6G_MB_LIB.T6G(SCH_1):GND     I3 @T6G_MB_LIB.T6G(SCH_1):PAGE60
  CM50    GND @T6G_MB_LIB.T6G(SCH_1):GND     I3 @T6G_MB_LIB.T6G(SCH_1):PAGE60
  CT52    GND @T6G_MB_LIB.T6G(SCH_1):GND     I3 @T6G_MB_LIB.T6G(SCH_1):PAGE60
  BV42    GND @T6G_MB_LIB.T6G(SCH_1):GND     I3 @T6G_MB_LIB.T6G(SCH_1):PAGE60
   V68    GND @T6G_MB_LIB.T6G(SCH_1):GND     I3 @T6G_MB_LIB.T6G(SCH_1):PAGE60

 U27 PCA9617ADP-PCA9617ADP,SMLF,IC,AL009617K02
     5 TP_U27_EN @T6G_MB_LIB.T6G(SCH_1):TP_U27_EN    I18 @T6G_MB_LIB.T6G(SCH_1):PAGE34
     1 PVDD18_S5_P0 @T6G_MB_LIB.T6G(SCH_1):PVDD18_S5_P0    I18 @T6G_MB_LIB.T6G(SCH_1):PAGE34
     8 P3V3_AUX @T6G_MB_LIB.T6G(SCH_1):P3V3_AUX    I18 @T6G_MB_LIB.T6G(SCH_1):PAGE34
     2 SMB_CPU0_4_SCL @T6G_MB_LIB.T6G(SCH_1):SMB_CPU0_4_SCL    I18 @T6G_MB_LIB.T6G(SCH_1):PAGE34
     3 SMB_CPU0_4_SDA @T6G_MB_LIB.T6G(SCH_1):SMB_CPU0_4_SDA    I18 @T6G_MB_LIB.T6G(SCH_1):PAGE34
     6 SMB_CPU0_4_XLTR_SDA @T6G_MB_LIB.T6G(SCH_1):SMB_CPU0_4_XLTR_SDA    I18 @T6G_MB_LIB.T6G(SCH_1):PAGE34
     7 SMB_CPU0_4_XLTR_SCL @T6G_MB_LIB.T6G(SCH_1):SMB_CPU0_4_XLTR_SCL    I18 @T6G_MB_LIB.T6G(SCH_1):PAGE34
     4    GND @T6G_MB_LIB.T6G(SCH_1):GND    I18 @T6G_MB_LIB.T6G(SCH_1):PAGE34

 U28 SN74LVC1G07DBVR_SMLF-SN74LVC1G07DBVR,IC,AL1G0007024
     2 HP_LVC3_OCP_V3_1_P12V_R_PWRGD @T6G_MB_LIB.T6G(SCH_1):HP_LVC3_OCP_V3_1_P12V_R_PWRGD    I51 @T6G_MB_LIB.T6G(SCH_1):PAGE340
     4 P12V_OCP_V3_1_PLD_R_PWRGD @T6G_MB_LIB.T6G(SCH_1):P12V_OCP_V3_1_PLD_R_PWRGD    I51 @T6G_MB_LIB.T6G(SCH_1):PAGE340
     1     NC     NC    I51 @T6G_MB_LIB.T6G(SCH_1):PAGE340
     5 P3V3_AUX @T6G_MB_LIB.T6G(SCH_1):P3V3_AUX    I51 @T6G_MB_LIB.T6G(SCH_1):PAGE340
     3    GND @T6G_MB_LIB.T6G(SCH_1):GND    I51 @T6G_MB_LIB.T6G(SCH_1):PAGE340

 U29 SN74LVC2G07DCKR_SMLF-SN74LVC2G07DCKR,IC,AL002G07006
     1 PWRGD_CPU0_PWROK @T6G_MB_LIB.T6G(SCH_1):PWRGD_CPU0_PWROK    I15 @T6G_MB_LIB.T6G(SCH_1):PAGE77
     3 PWRGD_CPU0_PWROK @T6G_MB_LIB.T6G(SCH_1):PWRGD_CPU0_PWROK    I15 @T6G_MB_LIB.T6G(SCH_1):PAGE77
     6 PVDDCR_CPU0_P0_RESET_N @T6G_MB_LIB.T6G(SCH_1):PVDDCR_CPU0_P0_RESET_N    I15 @T6G_MB_LIB.T6G(SCH_1):PAGE77
     4 PVDDCR_CPU1_P0_RESET_N @T6G_MB_LIB.T6G(SCH_1):PVDDCR_CPU1_P0_RESET_N    I15 @T6G_MB_LIB.T6G(SCH_1):PAGE77
     2    GND @T6G_MB_LIB.T6G(SCH_1):GND    I15 @T6G_MB_LIB.T6G(SCH_1):PAGE77
     5 P1V8_AUX @T6G_MB_LIB.T6G(SCH_1):P1V8_AUX    I15 @T6G_MB_LIB.T6G(SCH_1):PAGE77

 U30 SN74LVC1G07DBVR_SMLF-SN74LVC1G07DBVR,IC,AL1G0007024
     2 OCP_V3_1_P3V3_R2_PWRGD @T6G_MB_LIB.T6G(SCH_1):OCP_V3_1_P3V3_R2_PWRGD    I66 @T6G_MB_LIB.T6G(SCH_1):PAGE340
     4 OCP_V3_1_P3V3_PLD_PWRGD @T6G_MB_LIB.T6G(SCH_1):OCP_V3_1_P3V3_PLD_PWRGD    I66 @T6G_MB_LIB.T6G(SCH_1):PAGE340
     1     NC     NC    I66 @T6G_MB_LIB.T6G(SCH_1):PAGE340
     5 P3V3_AUX @T6G_MB_LIB.T6G(SCH_1):P3V3_AUX    I66 @T6G_MB_LIB.T6G(SCH_1):PAGE340
     3    GND @T6G_MB_LIB.T6G(SCH_1):GND    I66 @T6G_MB_LIB.T6G(SCH_1):PAGE340

 U31 74LVC1G08W57-74LVC1G08W5-7,SMLF,IC,AL1G0008020
     1 P12V_OCP_V3_2_EN_R3 @T6G_MB_LIB.T6G(SCH_1):P12V_OCP_V3_2_EN_R3    I31 @T6G_MB_LIB.T6G(SCH_1):PAGE257
     2 HP_LVC3_OCP_V3_2_PRSNT2 @T6G_MB_LIB.T6G(SCH_1):HP_LVC3_OCP_V3_2_PRSNT2    I31 @T6G_MB_LIB.T6G(SCH_1):PAGE257
     3    GND @T6G_MB_LIB.T6G(SCH_1):GND    I31 @T6G_MB_LIB.T6G(SCH_1):PAGE257
     4 P12V_OCP_V3_2_BUF_EN @T6G_MB_LIB.T6G(SCH_1):P12V_OCP_V3_2_BUF_EN    I31 @T6G_MB_LIB.T6G(SCH_1):PAGE257
     5 P3V3_AUX @T6G_MB_LIB.T6G(SCH_1):P3V3_AUX    I31 @T6G_MB_LIB.T6G(SCH_1):PAGE257

 U32 MOSFET_N_SMLF-BSS138K,BSS138K,IC,BAM138K0000
     G HP_LVC3_OCP_V3_2_PRSNT2_N @T6G_MB_LIB.T6G(SCH_1):HP_LVC3_OCP_V3_2_PRSNT2_N    I24 @T6G_MB_LIB.T6G(SCH_1):PAGE257
     D HP_LVC3_OCP_V3_2_PRSNT2 @T6G_MB_LIB.T6G(SCH_1):HP_LVC3_OCP_V3_2_PRSNT2    I24 @T6G_MB_LIB.T6G(SCH_1):PAGE257
     S    GND @T6G_MB_LIB.T6G(SCH_1):GND    I24 @T6G_MB_LIB.T6G(SCH_1):PAGE257

 U33 SN74LVC1G07DBVR_SMLF-SN74LVC1G07DBVR,IC,AL1G0007024
     2 HP_LVC3_OCP_V3_2_P12V_R_PWRGD @T6G_MB_LIB.T6G(SCH_1):HP_LVC3_OCP_V3_2_P12V_R_PWRGD    I64 @T6G_MB_LIB.T6G(SCH_1):PAGE257
     4 P12V_OCP_V3_2_PLD_R_PWRGD @T6G_MB_LIB.T6G(SCH_1):P12V_OCP_V3_2_PLD_R_PWRGD    I64 @T6G_MB_LIB.T6G(SCH_1):PAGE257
     1     NC     NC    I64 @T6G_MB_LIB.T6G(SCH_1):PAGE257
     5 P3V3_AUX @T6G_MB_LIB.T6G(SCH_1):P3V3_AUX    I64 @T6G_MB_LIB.T6G(SCH_1):PAGE257
     3    GND @T6G_MB_LIB.T6G(SCH_1):GND    I64 @T6G_MB_LIB.T6G(SCH_1):PAGE257

 U34 SN74LVC1G07DBVR_SMLF-SN74LVC1G07DBVR,IC,AL1G0007024
     2 OCP_V3_2_P3V3_R2_PWRGD @T6G_MB_LIB.T6G(SCH_1):OCP_V3_2_P3V3_R2_PWRGD    I45 @T6G_MB_LIB.T6G(SCH_1):PAGE257
     4 OCP_V3_2_P3V3_PLD_PWRGD @T6G_MB_LIB.T6G(SCH_1):OCP_V3_2_P3V3_PLD_PWRGD    I45 @T6G_MB_LIB.T6G(SCH_1):PAGE257
     1     NC     NC    I45 @T6G_MB_LIB.T6G(SCH_1):PAGE257
     5 P3V3_AUX @T6G_MB_LIB.T6G(SCH_1):P3V3_AUX    I45 @T6G_MB_LIB.T6G(SCH_1):PAGE257
     3    GND @T6G_MB_LIB.T6G(SCH_1):GND    I45 @T6G_MB_LIB.T6G(SCH_1):PAGE257

 U35 74LVC1G08W57-74LVC1G08W5-7,SMLF,IC,AL1G0008020
     1 RST_PERST_OCP_V3_2_R_N @T6G_MB_LIB.T6G(SCH_1):RST_PERST_OCP_V3_2_R_N    I63 @T6G_MB_LIB.T6G(SCH_1):PAGE257
     2 HP_LVC3_OCP_V3_2_PWRGD @T6G_MB_LIB.T6G(SCH_1):HP_LVC3_OCP_V3_2_PWRGD    I63 @T6G_MB_LIB.T6G(SCH_1):PAGE257
     3    GND @T6G_MB_LIB.T6G(SCH_1):GND    I63 @T6G_MB_LIB.T6G(SCH_1):PAGE257
     4 RST_PERST_OCP_V3_2_BUF_R_N @T6G_MB_LIB.T6G(SCH_1):RST_PERST_OCP_V3_2_BUF_R_N    I63 @T6G_MB_LIB.T6G(SCH_1):PAGE257
     5 P3V3_AUX @T6G_MB_LIB.T6G(SCH_1):P3V3_AUX    I63 @T6G_MB_LIB.T6G(SCH_1):PAGE257

 U36 TCA9548APWR-TCA9548APWR,SMLF,IC,AL009548K02
     1 PCA9548_PCIE3_ADDR0 @T6G_MB_LIB.T6G(SCH_1):PCA9548_PCIE3_ADDR0    I33 @T6G_MB_LIB.T6G(SCH_1):PAGE252
     2 PCA9548_PCIE3_ADDR1 @T6G_MB_LIB.T6G(SCH_1):PCA9548_PCIE3_ADDR1    I33 @T6G_MB_LIB.T6G(SCH_1):PAGE252
     3 PU_RST_SMB_PCIE0_N @T6G_MB_LIB.T6G(SCH_1):PU_RST_SMB_PCIE0_N    I33 @T6G_MB_LIB.T6G(SCH_1):PAGE252
     4 SMB_USB_CPU0_HUB1_SDA_R @T6G_MB_LIB.T6G(SCH_1):SMB_USB_CPU0_HUB1_SDA_R    I33 @T6G_MB_LIB.T6G(SCH_1):PAGE252
     5 SMB_USB_CPU0_HUB1_SCL_R @T6G_MB_LIB.T6G(SCH_1):SMB_USB_CPU0_HUB1_SCL_R    I33 @T6G_MB_LIB.T6G(SCH_1):PAGE252
     6 SMB_IOEXP_3V3AUX_SDA_R @T6G_MB_LIB.T6G(SCH_1):SMB_IOEXP_3V3AUX_SDA_R    I33 @T6G_MB_LIB.T6G(SCH_1):PAGE252
     7 SMB_IOEXP_3V3AUX_SCL_R @T6G_MB_LIB.T6G(SCH_1):SMB_IOEXP_3V3AUX_SCL_R    I33 @T6G_MB_LIB.T6G(SCH_1):PAGE252
     8 SMB_PCIE0_3V3AUX_SDA_R3 @T6G_MB_LIB.T6G(SCH_1):SMB_PCIE0_3V3AUX_SDA_R3    I33 @T6G_MB_LIB.T6G(SCH_1):PAGE252
     9 SMB_PCIE0_3V3AUX_SCL_R3 @T6G_MB_LIB.T6G(SCH_1):SMB_PCIE0_3V3AUX_SCL_R3    I33 @T6G_MB_LIB.T6G(SCH_1):PAGE252
    10 SMB_PCIE0_3V3AUX_SDA_R5 @T6G_MB_LIB.T6G(SCH_1):SMB_PCIE0_3V3AUX_SDA_R5    I33 @T6G_MB_LIB.T6G(SCH_1):PAGE252
    11 SMB_PCIE0_3V3AUX_SCL_R5 @T6G_MB_LIB.T6G(SCH_1):SMB_PCIE0_3V3AUX_SCL_R5    I33 @T6G_MB_LIB.T6G(SCH_1):PAGE252
    12    GND @T6G_MB_LIB.T6G(SCH_1):GND    I33 @T6G_MB_LIB.T6G(SCH_1):PAGE252
    24 P3V3_AUX @T6G_MB_LIB.T6G(SCH_1):P3V3_AUX    I33 @T6G_MB_LIB.T6G(SCH_1):PAGE252
    23 SMB_PCIE0_3V3AUX_SDA_R @T6G_MB_LIB.T6G(SCH_1):SMB_PCIE0_3V3AUX_SDA_R    I33 @T6G_MB_LIB.T6G(SCH_1):PAGE252
    22 SMB_PCIE0_3V3AUX_SCL_R @T6G_MB_LIB.T6G(SCH_1):SMB_PCIE0_3V3AUX_SCL_R    I33 @T6G_MB_LIB.T6G(SCH_1):PAGE252
    21 PCA9548_PCIE3_ADDR2 @T6G_MB_LIB.T6G(SCH_1):PCA9548_PCIE3_ADDR2    I33 @T6G_MB_LIB.T6G(SCH_1):PAGE252
    20     NC     NC    I33 @T6G_MB_LIB.T6G(SCH_1):PAGE252
    19     NC     NC    I33 @T6G_MB_LIB.T6G(SCH_1):PAGE252
    18 SMB_INA230_3V3AUX_SCL_R @T6G_MB_LIB.T6G(SCH_1):SMB_INA230_3V3AUX_SCL_R    I33 @T6G_MB_LIB.T6G(SCH_1):PAGE252
    17 SMB_INA230_3V3AUX_SDA_R @T6G_MB_LIB.T6G(SCH_1):SMB_INA230_3V3AUX_SDA_R    I33 @T6G_MB_LIB.T6G(SCH_1):PAGE252
    16 SMB_FRU_3V3AUX_SCL_R @T6G_MB_LIB.T6G(SCH_1):SMB_FRU_3V3AUX_SCL_R    I33 @T6G_MB_LIB.T6G(SCH_1):PAGE252
    15 SMB_FRU_3V3AUX_SDA_R @T6G_MB_LIB.T6G(SCH_1):SMB_FRU_3V3AUX_SDA_R    I33 @T6G_MB_LIB.T6G(SCH_1):PAGE252
    14 SMB_BMC_SWB_SCL_R4 @T6G_MB_LIB.T6G(SCH_1):SMB_BMC_SWB_SCL_R4    I33 @T6G_MB_LIB.T6G(SCH_1):PAGE252
    13 SMB_BMC_SWB_SDA_R4 @T6G_MB_LIB.T6G(SCH_1):SMB_BMC_SWB_SDA_R4    I33 @T6G_MB_LIB.T6G(SCH_1):PAGE252

 U37 74LVC1G32GW_SMLF-74LVC1G32GW,IC,ALVC1G32007
     1 HP_LVC3_OCP_V3_2_PWRGD_R1 @T6G_MB_LIB.T6G(SCH_1):HP_LVC3_OCP_V3_2_PWRGD_R1    I40 @T6G_MB_LIB.T6G(SCH_1):PAGE257
     2 FM_OCP_V3_2_AUX_PWR_R_EN @T6G_MB_LIB.T6G(SCH_1):FM_OCP_V3_2_AUX_PWR_R_EN    I40 @T6G_MB_LIB.T6G(SCH_1):PAGE257
     4 OCP_V3_2_AUX_PWR_EN_R2 @T6G_MB_LIB.T6G(SCH_1):OCP_V3_2_AUX_PWR_EN_R2    I40 @T6G_MB_LIB.T6G(SCH_1):PAGE257
     5 P3V3_AUX @T6G_MB_LIB.T6G(SCH_1):P3V3_AUX    I40 @T6G_MB_LIB.T6G(SCH_1):PAGE257
     3    GND @T6G_MB_LIB.T6G(SCH_1):GND    I40 @T6G_MB_LIB.T6G(SCH_1):PAGE257

 U38 SN74LVC1G11DCKR-SN74LVC1G11DCKR,SMLF,IC,ALLVC1G1000
     1 PWRGD_P12V_MEM_CPU0_R @T6G_MB_LIB.T6G(SCH_1):PWRGD_P12V_MEM_CPU0_R     I8 @T6G_MB_LIB.T6G(SCH_1):PAGE264
     3 PWRGD_P12V_MEM_CPU1_R @T6G_MB_LIB.T6G(SCH_1):PWRGD_P12V_MEM_CPU1_R     I8 @T6G_MB_LIB.T6G(SCH_1):PAGE264
     6 PU_U38_6 @T6G_MB_LIB.T6G(SCH_1):PU_U38_6     I8 @T6G_MB_LIB.T6G(SCH_1):PAGE264
     5 P1V8_AUX @T6G_MB_LIB.T6G(SCH_1):P1V8_AUX     I8 @T6G_MB_LIB.T6G(SCH_1):PAGE264
     4 PWRGD_P12V_MEM @T6G_MB_LIB.T6G(SCH_1):PWRGD_P12V_MEM     I8 @T6G_MB_LIB.T6G(SCH_1):PAGE264
     2    GND @T6G_MB_LIB.T6G(SCH_1):GND     I8 @T6G_MB_LIB.T6G(SCH_1):PAGE264

 U39 TCA9548APWR-TCA9548APWR,SMLF,IC,AL009548K02
     1 PCA9548_PCIE0_ADDR0 @T6G_MB_LIB.T6G(SCH_1):PCA9548_PCIE0_ADDR0    I74 @T6G_MB_LIB.T6G(SCH_1):PAGE251
     2 PCA9548_PCIE0_ADDR1 @T6G_MB_LIB.T6G(SCH_1):PCA9548_PCIE0_ADDR1    I74 @T6G_MB_LIB.T6G(SCH_1):PAGE251
     3 PU_RST_SMB_PCIE2_N @T6G_MB_LIB.T6G(SCH_1):PU_RST_SMB_PCIE2_N    I74 @T6G_MB_LIB.T6G(SCH_1):PAGE251
     4 SMB_VR_3V3AUX_SDA_R6 @T6G_MB_LIB.T6G(SCH_1):SMB_VR_3V3AUX_SDA_R6    I74 @T6G_MB_LIB.T6G(SCH_1):PAGE251
     5 SMB_VR_3V3AUX_SCL_R6 @T6G_MB_LIB.T6G(SCH_1):SMB_VR_3V3AUX_SCL_R6    I74 @T6G_MB_LIB.T6G(SCH_1):PAGE251
     6 SMB_LM75_0_3V3AUX_SDA_R @T6G_MB_LIB.T6G(SCH_1):SMB_LM75_0_3V3AUX_SDA_R    I74 @T6G_MB_LIB.T6G(SCH_1):PAGE251
     7 SMB_LM75_0_3V3AUX_SCL_R @T6G_MB_LIB.T6G(SCH_1):SMB_LM75_0_3V3AUX_SCL_R    I74 @T6G_MB_LIB.T6G(SCH_1):PAGE251
     8 SMB_LM75_1_3V3AUX_SDA_R @T6G_MB_LIB.T6G(SCH_1):SMB_LM75_1_3V3AUX_SDA_R    I74 @T6G_MB_LIB.T6G(SCH_1):PAGE251
     9 SMB_LM75_1_3V3AUX_SCL_R @T6G_MB_LIB.T6G(SCH_1):SMB_LM75_1_3V3AUX_SCL_R    I74 @T6G_MB_LIB.T6G(SCH_1):PAGE251
    10 SMB_LM75_2_3V3AUX_SDA_R @T6G_MB_LIB.T6G(SCH_1):SMB_LM75_2_3V3AUX_SDA_R    I74 @T6G_MB_LIB.T6G(SCH_1):PAGE251
    11 SMB_LM75_2_3V3AUX_SCL_R @T6G_MB_LIB.T6G(SCH_1):SMB_LM75_2_3V3AUX_SCL_R    I74 @T6G_MB_LIB.T6G(SCH_1):PAGE251
    12    GND @T6G_MB_LIB.T6G(SCH_1):GND    I74 @T6G_MB_LIB.T6G(SCH_1):PAGE251
    24 P3V3_AUX @T6G_MB_LIB.T6G(SCH_1):P3V3_AUX    I74 @T6G_MB_LIB.T6G(SCH_1):PAGE251
    23 SMB_VR_SENSOR_3V3AUX_SDA_R @T6G_MB_LIB.T6G(SCH_1):SMB_VR_SENSOR_3V3AUX_SDA_R    I74 @T6G_MB_LIB.T6G(SCH_1):PAGE251
    22 SMB_VR_SENSOR_3V3AUX_SCL_R @T6G_MB_LIB.T6G(SCH_1):SMB_VR_SENSOR_3V3AUX_SCL_R    I74 @T6G_MB_LIB.T6G(SCH_1):PAGE251
    21 PCA9548_PCIE0_ADDR2 @T6G_MB_LIB.T6G(SCH_1):PCA9548_PCIE0_ADDR2    I74 @T6G_MB_LIB.T6G(SCH_1):PAGE251
    20     NC     NC    I74 @T6G_MB_LIB.T6G(SCH_1):PAGE251
    19     NC     NC    I74 @T6G_MB_LIB.T6G(SCH_1):PAGE251
    18 SMB_ADC_SCL @T6G_MB_LIB.T6G(SCH_1):SMB_ADC_SCL    I74 @T6G_MB_LIB.T6G(SCH_1):PAGE251
    17 SMB_ADC_SDA @T6G_MB_LIB.T6G(SCH_1):SMB_ADC_SDA    I74 @T6G_MB_LIB.T6G(SCH_1):PAGE251
    16 SMB_P12V_HSC_SCL_R @T6G_MB_LIB.T6G(SCH_1):SMB_P12V_HSC_SCL_R    I74 @T6G_MB_LIB.T6G(SCH_1):PAGE251
    15 SMB_P12V_HSC_SDA_R @T6G_MB_LIB.T6G(SCH_1):SMB_P12V_HSC_SDA_R    I74 @T6G_MB_LIB.T6G(SCH_1):PAGE251
    14 SMB_LM75_3_3V3AUX_SCL_R @T6G_MB_LIB.T6G(SCH_1):SMB_LM75_3_3V3AUX_SCL_R    I74 @T6G_MB_LIB.T6G(SCH_1):PAGE251
    13 SMB_LM75_3_3V3AUX_SDA_R @T6G_MB_LIB.T6G(SCH_1):SMB_LM75_3_3V3AUX_SDA_R    I74 @T6G_MB_LIB.T6G(SCH_1):PAGE251

 U40 SN74LVC2G07DCKR_SMLF-SN74LVC2G07DCKR,IC,AL002G07006
     1 PWRGD_CPU1_PWROK @T6G_MB_LIB.T6G(SCH_1):PWRGD_CPU1_PWROK    I21 @T6G_MB_LIB.T6G(SCH_1):PAGE77
     3 PWRGD_CPU1_PWROK @T6G_MB_LIB.T6G(SCH_1):PWRGD_CPU1_PWROK    I21 @T6G_MB_LIB.T6G(SCH_1):PAGE77
     6 PVDDCR_CPU0_P1_RESET_N @T6G_MB_LIB.T6G(SCH_1):PVDDCR_CPU0_P1_RESET_N    I21 @T6G_MB_LIB.T6G(SCH_1):PAGE77
     4 PVDDCR_CPU1_P1_RESET_N @T6G_MB_LIB.T6G(SCH_1):PVDDCR_CPU1_P1_RESET_N    I21 @T6G_MB_LIB.T6G(SCH_1):PAGE77
     2    GND @T6G_MB_LIB.T6G(SCH_1):GND    I21 @T6G_MB_LIB.T6G(SCH_1):PAGE77
     5 P1V8_AUX @T6G_MB_LIB.T6G(SCH_1):P1V8_AUX    I21 @T6G_MB_LIB.T6G(SCH_1):PAGE77

 U41 PI3CSW12ZUAEX-PI3CSW12ZUAEX,SMLF,IC,AL3CSW12000
     1 SMB_RT_CPU1_P3_ROM_MUX_1D_SCL @T6G_MB_LIB.T6G(SCH_1):SMB_RT_CPU1_P3_ROM_MUX_1D_SCL    I46 @T6G_MB_LIB.T6G(SCH_1):PAGE376
     3 SMB_RT_CPU1_P3_ROM_MUX_2D_SCL @T6G_MB_LIB.T6G(SCH_1):SMB_RT_CPU1_P3_ROM_MUX_2D_SCL    I46 @T6G_MB_LIB.T6G(SCH_1):PAGE376
     4 SMB_RT_CPU1_P3_ROM_MUX_2D_SDA @T6G_MB_LIB.T6G(SCH_1):SMB_RT_CPU1_P3_ROM_MUX_2D_SDA    I46 @T6G_MB_LIB.T6G(SCH_1):PAGE376
     7 SMB_RT_CPU1_P3_ROM_R_SDA @T6G_MB_LIB.T6G(SCH_1):SMB_RT_CPU1_P3_ROM_R_SDA    I46 @T6G_MB_LIB.T6G(SCH_1):PAGE376
     6 RT_ROM_MUX3_OE_N @T6G_MB_LIB.T6G(SCH_1):RT_ROM_MUX3_OE_N    I46 @T6G_MB_LIB.T6G(SCH_1):PAGE376
     9 FM_SMB_RT_ROM_MUX3_SEL @T6G_MB_LIB.T6G(SCH_1):FM_SMB_RT_ROM_MUX3_SEL    I46 @T6G_MB_LIB.T6G(SCH_1):PAGE376
    10 P3V3_AUX @T6G_MB_LIB.T6G(SCH_1):P3V3_AUX    I46 @T6G_MB_LIB.T6G(SCH_1):PAGE376
     2 SMB_RT_CPU1_P3_ROM_MUX_1D_SDA @T6G_MB_LIB.T6G(SCH_1):SMB_RT_CPU1_P3_ROM_MUX_1D_SDA    I46 @T6G_MB_LIB.T6G(SCH_1):PAGE376
     5    GND @T6G_MB_LIB.T6G(SCH_1):GND    I46 @T6G_MB_LIB.T6G(SCH_1):PAGE376
     8 SMB_RT_CPU1_P3_ROM_R_SCL @T6G_MB_LIB.T6G(SCH_1):SMB_RT_CPU1_P3_ROM_R_SCL    I46 @T6G_MB_LIB.T6G(SCH_1):PAGE376

 U42 PI3CSW12ZUAEX-PI3CSW12ZUAEX,SMLF,IC,AL3CSW12000
     1 SMB_RT_CPU1_P1_ROM_MUX_1D_SCL @T6G_MB_LIB.T6G(SCH_1):SMB_RT_CPU1_P1_ROM_MUX_1D_SCL    I31 @T6G_MB_LIB.T6G(SCH_1):PAGE376
     3 SMB_RT_CPU1_P1_ROM_MUX_2D_SCL @T6G_MB_LIB.T6G(SCH_1):SMB_RT_CPU1_P1_ROM_MUX_2D_SCL    I31 @T6G_MB_LIB.T6G(SCH_1):PAGE376
     4 SMB_RT_CPU1_P1_ROM_MUX_2D_SDA @T6G_MB_LIB.T6G(SCH_1):SMB_RT_CPU1_P1_ROM_MUX_2D_SDA    I31 @T6G_MB_LIB.T6G(SCH_1):PAGE376
     7 SMB_RT_CPU1_P1_ROM_R_SDA @T6G_MB_LIB.T6G(SCH_1):SMB_RT_CPU1_P1_ROM_R_SDA    I31 @T6G_MB_LIB.T6G(SCH_1):PAGE376
     6 RT_ROM_MUX2_OE_N @T6G_MB_LIB.T6G(SCH_1):RT_ROM_MUX2_OE_N    I31 @T6G_MB_LIB.T6G(SCH_1):PAGE376
     9 FM_SMB_RT_ROM_MUX2_SEL @T6G_MB_LIB.T6G(SCH_1):FM_SMB_RT_ROM_MUX2_SEL    I31 @T6G_MB_LIB.T6G(SCH_1):PAGE376
    10 P3V3_AUX @T6G_MB_LIB.T6G(SCH_1):P3V3_AUX    I31 @T6G_MB_LIB.T6G(SCH_1):PAGE376
     2 SMB_RT_CPU1_P1_ROM_MUX_1D_SDA @T6G_MB_LIB.T6G(SCH_1):SMB_RT_CPU1_P1_ROM_MUX_1D_SDA    I31 @T6G_MB_LIB.T6G(SCH_1):PAGE376
     5    GND @T6G_MB_LIB.T6G(SCH_1):GND    I31 @T6G_MB_LIB.T6G(SCH_1):PAGE376
     8 SMB_RT_CPU1_P1_ROM_R_SCL @T6G_MB_LIB.T6G(SCH_1):SMB_RT_CPU1_P1_ROM_R_SCL    I31 @T6G_MB_LIB.T6G(SCH_1):PAGE376

 U43 PI3CSW12ZUAEX-PI3CSW12ZUAEX,SMLF,IC,AL3CSW12000
     1 SMB_RT_CPU1_P2_ROM_MUX_1D_SCL @T6G_MB_LIB.T6G(SCH_1):SMB_RT_CPU1_P2_ROM_MUX_1D_SCL    I61 @T6G_MB_LIB.T6G(SCH_1):PAGE376
     3 SMB_RT_CPU1_P2_ROM_MUX_2D_SCL @T6G_MB_LIB.T6G(SCH_1):SMB_RT_CPU1_P2_ROM_MUX_2D_SCL    I61 @T6G_MB_LIB.T6G(SCH_1):PAGE376
     4 SMB_RT_CPU1_P2_ROM_MUX_2D_SDA @T6G_MB_LIB.T6G(SCH_1):SMB_RT_CPU1_P2_ROM_MUX_2D_SDA    I61 @T6G_MB_LIB.T6G(SCH_1):PAGE376
     7 SMB_RT_CPU1_P2_ROM_R_SDA @T6G_MB_LIB.T6G(SCH_1):SMB_RT_CPU1_P2_ROM_R_SDA    I61 @T6G_MB_LIB.T6G(SCH_1):PAGE376
     6 RT_ROM_MUX4_OE_N @T6G_MB_LIB.T6G(SCH_1):RT_ROM_MUX4_OE_N    I61 @T6G_MB_LIB.T6G(SCH_1):PAGE376
     9 FM_SMB_RT_ROM_MUX4_SEL @T6G_MB_LIB.T6G(SCH_1):FM_SMB_RT_ROM_MUX4_SEL    I61 @T6G_MB_LIB.T6G(SCH_1):PAGE376
    10 P3V3_AUX @T6G_MB_LIB.T6G(SCH_1):P3V3_AUX    I61 @T6G_MB_LIB.T6G(SCH_1):PAGE376
     2 SMB_RT_CPU1_P2_ROM_MUX_1D_SDA @T6G_MB_LIB.T6G(SCH_1):SMB_RT_CPU1_P2_ROM_MUX_1D_SDA    I61 @T6G_MB_LIB.T6G(SCH_1):PAGE376
     5    GND @T6G_MB_LIB.T6G(SCH_1):GND    I61 @T6G_MB_LIB.T6G(SCH_1):PAGE376
     8 SMB_RT_CPU1_P2_ROM_R_SCL @T6G_MB_LIB.T6G(SCH_1):SMB_RT_CPU1_P2_ROM_R_SCL    I61 @T6G_MB_LIB.T6G(SCH_1):PAGE376

 U44 74LVC1G17GW-74LVC1G17GW,SMLF,IC,AL1G0017K01
     5 P3V3_E1S_0 @T6G_MB_LIB.T6G(SCH_1):P3V3_E1S_0    I97 @T6G_MB_LIB.T6G(SCH_1):PAGE297
     2 FM_LED_ACTIVE_E1S_0_R @T6G_MB_LIB.T6G(SCH_1):FM_LED_ACTIVE_E1S_0_R    I97 @T6G_MB_LIB.T6G(SCH_1):PAGE297
     3    GND @T6G_MB_LIB.T6G(SCH_1):GND    I97 @T6G_MB_LIB.T6G(SCH_1):PAGE297
     4 FM_LED_ACTIVE_E1S_0_R_BUF @T6G_MB_LIB.T6G(SCH_1):FM_LED_ACTIVE_E1S_0_R_BUF    I97 @T6G_MB_LIB.T6G(SCH_1):PAGE297
     1     NC     NC    I97 @T6G_MB_LIB.T6G(SCH_1):PAGE297

 U45 PI3CSW12ZUAEX-PI3CSW12ZUAEX,SMLF,IC,AL3CSW12000
     1 SMB_RT_CPU1_P0_ROM_MUX_1D_SCL @T6G_MB_LIB.T6G(SCH_1):SMB_RT_CPU1_P0_ROM_MUX_1D_SCL    I22 @T6G_MB_LIB.T6G(SCH_1):PAGE376
     3 SMB_RT_CPU1_P0_ROM_MUX_2D_SCL @T6G_MB_LIB.T6G(SCH_1):SMB_RT_CPU1_P0_ROM_MUX_2D_SCL    I22 @T6G_MB_LIB.T6G(SCH_1):PAGE376
     4 SMB_RT_CPU1_P0_ROM_MUX_2D_SDA @T6G_MB_LIB.T6G(SCH_1):SMB_RT_CPU1_P0_ROM_MUX_2D_SDA    I22 @T6G_MB_LIB.T6G(SCH_1):PAGE376
     7 SMB_RT_CPU1_P0_ROM_R_SDA @T6G_MB_LIB.T6G(SCH_1):SMB_RT_CPU1_P0_ROM_R_SDA    I22 @T6G_MB_LIB.T6G(SCH_1):PAGE376
     6 RT_ROM_MUX1_OE_N @T6G_MB_LIB.T6G(SCH_1):RT_ROM_MUX1_OE_N    I22 @T6G_MB_LIB.T6G(SCH_1):PAGE376
     9 FM_SMB_RT_ROM_MUX1_SEL @T6G_MB_LIB.T6G(SCH_1):FM_SMB_RT_ROM_MUX1_SEL    I22 @T6G_MB_LIB.T6G(SCH_1):PAGE376
    10 P3V3_AUX @T6G_MB_LIB.T6G(SCH_1):P3V3_AUX    I22 @T6G_MB_LIB.T6G(SCH_1):PAGE376
     2 SMB_RT_CPU1_P0_ROM_MUX_1D_SDA @T6G_MB_LIB.T6G(SCH_1):SMB_RT_CPU1_P0_ROM_MUX_1D_SDA    I22 @T6G_MB_LIB.T6G(SCH_1):PAGE376
     5    GND @T6G_MB_LIB.T6G(SCH_1):GND    I22 @T6G_MB_LIB.T6G(SCH_1):PAGE376
     8 SMB_RT_CPU1_P0_ROM_R_SCL @T6G_MB_LIB.T6G(SCH_1):SMB_RT_CPU1_P0_ROM_R_SCL    I22 @T6G_MB_LIB.T6G(SCH_1):PAGE376

 U46 PI3CSW12ZUAEX-PI3CSW12ZUAEX,SMLF,IC,AL3CSW12000
     1 SMB_RT_CPU0_P3_ROM_MUX_1D_SCL @T6G_MB_LIB.T6G(SCH_1):SMB_RT_CPU0_P3_ROM_MUX_1D_SCL   I108 @T6G_MB_LIB.T6G(SCH_1):PAGE376
     3 SMB_RT_CPU0_P3_ROM_MUX_2D_SCL @T6G_MB_LIB.T6G(SCH_1):SMB_RT_CPU0_P3_ROM_MUX_2D_SCL   I108 @T6G_MB_LIB.T6G(SCH_1):PAGE376
     4 SMB_RT_CPU0_P3_ROM_MUX_2D_SDA @T6G_MB_LIB.T6G(SCH_1):SMB_RT_CPU0_P3_ROM_MUX_2D_SDA   I108 @T6G_MB_LIB.T6G(SCH_1):PAGE376
     7 SMB_RT_CPU0_P3_ROM_R_SDA @T6G_MB_LIB.T6G(SCH_1):SMB_RT_CPU0_P3_ROM_R_SDA   I108 @T6G_MB_LIB.T6G(SCH_1):PAGE376
     6 RT_ROM_MUX7_OE_N @T6G_MB_LIB.T6G(SCH_1):RT_ROM_MUX7_OE_N   I108 @T6G_MB_LIB.T6G(SCH_1):PAGE376
     9 FM_SMB_RT_ROM_MUX7_SEL @T6G_MB_LIB.T6G(SCH_1):FM_SMB_RT_ROM_MUX7_SEL   I108 @T6G_MB_LIB.T6G(SCH_1):PAGE376
    10 P3V3_AUX @T6G_MB_LIB.T6G(SCH_1):P3V3_AUX   I108 @T6G_MB_LIB.T6G(SCH_1):PAGE376
     2 SMB_RT_CPU0_P3_ROM_MUX_1D_SDA @T6G_MB_LIB.T6G(SCH_1):SMB_RT_CPU0_P3_ROM_MUX_1D_SDA   I108 @T6G_MB_LIB.T6G(SCH_1):PAGE376
     5    GND @T6G_MB_LIB.T6G(SCH_1):GND   I108 @T6G_MB_LIB.T6G(SCH_1):PAGE376
     8 SMB_RT_CPU0_P3_ROM_R_SCL @T6G_MB_LIB.T6G(SCH_1):SMB_RT_CPU0_P3_ROM_R_SCL   I108 @T6G_MB_LIB.T6G(SCH_1):PAGE376

 U47 PI3CSW12ZUAEX-PI3CSW12ZUAEX,SMLF,IC,AL3CSW12000
     1 SMB_RT_CPU0_P2_ROM_MUX_1D_SCL @T6G_MB_LIB.T6G(SCH_1):SMB_RT_CPU0_P2_ROM_MUX_1D_SCL   I121 @T6G_MB_LIB.T6G(SCH_1):PAGE376
     3 SMB_RT_CPU0_P2_ROM_MUX_2D_SCL @T6G_MB_LIB.T6G(SCH_1):SMB_RT_CPU0_P2_ROM_MUX_2D_SCL   I121 @T6G_MB_LIB.T6G(SCH_1):PAGE376
     4 SMB_RT_CPU0_P2_ROM_MUX_2D_SDA @T6G_MB_LIB.T6G(SCH_1):SMB_RT_CPU0_P2_ROM_MUX_2D_SDA   I121 @T6G_MB_LIB.T6G(SCH_1):PAGE376
     7 SMB_RT_CPU0_P2_ROM_R_SDA @T6G_MB_LIB.T6G(SCH_1):SMB_RT_CPU0_P2_ROM_R_SDA   I121 @T6G_MB_LIB.T6G(SCH_1):PAGE376
     6 RT_ROM_MUX8_OE_N @T6G_MB_LIB.T6G(SCH_1):RT_ROM_MUX8_OE_N   I121 @T6G_MB_LIB.T6G(SCH_1):PAGE376
     9 FM_SMB_RT_ROM_MUX8_SEL @T6G_MB_LIB.T6G(SCH_1):FM_SMB_RT_ROM_MUX8_SEL   I121 @T6G_MB_LIB.T6G(SCH_1):PAGE376
    10 P3V3_AUX @T6G_MB_LIB.T6G(SCH_1):P3V3_AUX   I121 @T6G_MB_LIB.T6G(SCH_1):PAGE376
     2 SMB_RT_CPU0_P2_ROM_MUX_1D_SDA @T6G_MB_LIB.T6G(SCH_1):SMB_RT_CPU0_P2_ROM_MUX_1D_SDA   I121 @T6G_MB_LIB.T6G(SCH_1):PAGE376
     5    GND @T6G_MB_LIB.T6G(SCH_1):GND   I121 @T6G_MB_LIB.T6G(SCH_1):PAGE376
     8 SMB_RT_CPU0_P2_ROM_R_SCL @T6G_MB_LIB.T6G(SCH_1):SMB_RT_CPU0_P2_ROM_R_SCL   I121 @T6G_MB_LIB.T6G(SCH_1):PAGE376

 U48 PI3CSW12ZUAEX-PI3CSW12ZUAEX,SMLF,IC,AL3CSW12000
     1 SMB_RT_CPU0_P1_ROM_MUX_1D_SCL @T6G_MB_LIB.T6G(SCH_1):SMB_RT_CPU0_P1_ROM_MUX_1D_SCL    I76 @T6G_MB_LIB.T6G(SCH_1):PAGE376
     3 SMB_RT_CPU0_P1_ROM_MUX_2D_SCL @T6G_MB_LIB.T6G(SCH_1):SMB_RT_CPU0_P1_ROM_MUX_2D_SCL    I76 @T6G_MB_LIB.T6G(SCH_1):PAGE376
     4 SMB_RT_CPU0_P1_ROM_MUX_2D_SDA @T6G_MB_LIB.T6G(SCH_1):SMB_RT_CPU0_P1_ROM_MUX_2D_SDA    I76 @T6G_MB_LIB.T6G(SCH_1):PAGE376
     7 SMB_RT_CPU0_P1_ROM_R_SDA @T6G_MB_LIB.T6G(SCH_1):SMB_RT_CPU0_P1_ROM_R_SDA    I76 @T6G_MB_LIB.T6G(SCH_1):PAGE376
     6 RT_ROM_MUX6_OE_N @T6G_MB_LIB.T6G(SCH_1):RT_ROM_MUX6_OE_N    I76 @T6G_MB_LIB.T6G(SCH_1):PAGE376
     9 FM_SMB_RT_ROM_MUX6_SEL @T6G_MB_LIB.T6G(SCH_1):FM_SMB_RT_ROM_MUX6_SEL    I76 @T6G_MB_LIB.T6G(SCH_1):PAGE376
    10 P3V3_AUX @T6G_MB_LIB.T6G(SCH_1):P3V3_AUX    I76 @T6G_MB_LIB.T6G(SCH_1):PAGE376
     2 SMB_RT_CPU0_P1_ROM_MUX_1D_SDA @T6G_MB_LIB.T6G(SCH_1):SMB_RT_CPU0_P1_ROM_MUX_1D_SDA    I76 @T6G_MB_LIB.T6G(SCH_1):PAGE376
     5    GND @T6G_MB_LIB.T6G(SCH_1):GND    I76 @T6G_MB_LIB.T6G(SCH_1):PAGE376
     8 SMB_RT_CPU0_P1_ROM_R_SCL @T6G_MB_LIB.T6G(SCH_1):SMB_RT_CPU0_P1_ROM_R_SCL    I76 @T6G_MB_LIB.T6G(SCH_1):PAGE376

 U49 PI3CSW12ZUAEX-PI3CSW12ZUAEX,SMLF,IC,AL3CSW12000
     1 SMB_RT_CPU0_P0_ROM_MUX_1D_SCL @T6G_MB_LIB.T6G(SCH_1):SMB_RT_CPU0_P0_ROM_MUX_1D_SCL    I85 @T6G_MB_LIB.T6G(SCH_1):PAGE376
     3 SMB_RT_CPU0_P0_ROM_MUX_2D_SCL @T6G_MB_LIB.T6G(SCH_1):SMB_RT_CPU0_P0_ROM_MUX_2D_SCL    I85 @T6G_MB_LIB.T6G(SCH_1):PAGE376
     4 SMB_RT_CPU0_P0_ROM_MUX_2D_SDA @T6G_MB_LIB.T6G(SCH_1):SMB_RT_CPU0_P0_ROM_MUX_2D_SDA    I85 @T6G_MB_LIB.T6G(SCH_1):PAGE376
     7 SMB_RT_CPU0_P0_ROM_R_SDA @T6G_MB_LIB.T6G(SCH_1):SMB_RT_CPU0_P0_ROM_R_SDA    I85 @T6G_MB_LIB.T6G(SCH_1):PAGE376
     6 RT_ROM_MUX5_OE_N @T6G_MB_LIB.T6G(SCH_1):RT_ROM_MUX5_OE_N    I85 @T6G_MB_LIB.T6G(SCH_1):PAGE376
     9 FM_SMB_RT_ROM_MUX5_SEL @T6G_MB_LIB.T6G(SCH_1):FM_SMB_RT_ROM_MUX5_SEL    I85 @T6G_MB_LIB.T6G(SCH_1):PAGE376
    10 P3V3_AUX @T6G_MB_LIB.T6G(SCH_1):P3V3_AUX    I85 @T6G_MB_LIB.T6G(SCH_1):PAGE376
     2 SMB_RT_CPU0_P0_ROM_MUX_1D_SDA @T6G_MB_LIB.T6G(SCH_1):SMB_RT_CPU0_P0_ROM_MUX_1D_SDA    I85 @T6G_MB_LIB.T6G(SCH_1):PAGE376
     5    GND @T6G_MB_LIB.T6G(SCH_1):GND    I85 @T6G_MB_LIB.T6G(SCH_1):PAGE376
     8 SMB_RT_CPU0_P0_ROM_R_SCL @T6G_MB_LIB.T6G(SCH_1):SMB_RT_CPU0_P0_ROM_R_SCL    I85 @T6G_MB_LIB.T6G(SCH_1):PAGE376

 U50 MAX11617EEET-MAX11617EEE+T,SMLF,EMPTY,AL011617W00
     1 MAX11617_2_VREF_R @T6G_MB_LIB.T6G(SCH_1):MAX11617_2_VREF_R   I156 @T6G_MB_LIB.T6G(SCH_1):PAGE263
     2    GND @T6G_MB_LIB.T6G(SCH_1):GND   I156 @T6G_MB_LIB.T6G(SCH_1):PAGE263
     3    GND @T6G_MB_LIB.T6G(SCH_1):GND   I156 @T6G_MB_LIB.T6G(SCH_1):PAGE263
     4    GND @T6G_MB_LIB.T6G(SCH_1):GND   I156 @T6G_MB_LIB.T6G(SCH_1):PAGE263
     5 P5V_AUX_ADC_MAM @T6G_MB_LIB.T6G(SCH_1):P5V_AUX_ADC_MAM   I156 @T6G_MB_LIB.T6G(SCH_1):PAGE263
     6 P1V8_AUX_ADC_MAM @T6G_MB_LIB.T6G(SCH_1):P1V8_AUX_ADC_MAM   I156 @T6G_MB_LIB.T6G(SCH_1):PAGE263
     7 P1V2_AUX_ADC_MAM @T6G_MB_LIB.T6G(SCH_1):P1V2_AUX_ADC_MAM   I156 @T6G_MB_LIB.T6G(SCH_1):PAGE263
     8 P1V8_CPU0_RT_1D_ADC_MAM @T6G_MB_LIB.T6G(SCH_1):P1V8_CPU0_RT_1D_ADC_MAM   I156 @T6G_MB_LIB.T6G(SCH_1):PAGE263
     9 P1V8_CPU1_RT_1D_ADC_MAM @T6G_MB_LIB.T6G(SCH_1):P1V8_CPU1_RT_1D_ADC_MAM   I156 @T6G_MB_LIB.T6G(SCH_1):PAGE263
    10 PVDD_33_S5_ADC_MAM @T6G_MB_LIB.T6G(SCH_1):PVDD_33_S5_ADC_MAM   I156 @T6G_MB_LIB.T6G(SCH_1):PAGE263
    11 PVDD18_S5_P0_ADC_MAM @T6G_MB_LIB.T6G(SCH_1):PVDD18_S5_P0_ADC_MAM   I156 @T6G_MB_LIB.T6G(SCH_1):PAGE263
    12 PVDD18_S5_P1_ADC_MAM @T6G_MB_LIB.T6G(SCH_1):PVDD18_S5_P1_ADC_MAM   I156 @T6G_MB_LIB.T6G(SCH_1):PAGE263
    13 SMB_SEN_MAM_2_3V3AUX_SCL @T6G_MB_LIB.T6G(SCH_1):SMB_SEN_MAM_2_3V3AUX_SCL   I156 @T6G_MB_LIB.T6G(SCH_1):PAGE263
    14 SMB_SEN_MAM_2_3V3AUX_SDA @T6G_MB_LIB.T6G(SCH_1):SMB_SEN_MAM_2_3V3AUX_SDA   I156 @T6G_MB_LIB.T6G(SCH_1):PAGE263
    15    GND @T6G_MB_LIB.T6G(SCH_1):GND   I156 @T6G_MB_LIB.T6G(SCH_1):PAGE263
    16 P3V3_MAX11617_2_VDD @T6G_MB_LIB.T6G(SCH_1):P3V3_MAX11617_2_VDD   I156 @T6G_MB_LIB.T6G(SCH_1):PAGE263

 U51 ADC128D818CIMTXNOPB-ADC128D818CIMTX/NOPB,SMLF,IC,AA
     1 ADC128_2_VREF @T6G_MB_LIB.T6G(SCH_1):ADC128_2_VREF   I142 @T6G_MB_LIB.T6G(SCH_1):PAGE263
     5 P3V3_ADC128_2_VCC @T6G_MB_LIB.T6G(SCH_1):P3V3_ADC128_2_VCC   I142 @T6G_MB_LIB.T6G(SCH_1):PAGE263
     7 ADC128_2_A0 @T6G_MB_LIB.T6G(SCH_1):ADC128_2_A0   I142 @T6G_MB_LIB.T6G(SCH_1):PAGE263
     8 ADC128_2_A1 @T6G_MB_LIB.T6G(SCH_1):ADC128_2_A1   I142 @T6G_MB_LIB.T6G(SCH_1):PAGE263
     9 PVDD18_S5_P1_ADC_TIC @T6G_MB_LIB.T6G(SCH_1):PVDD18_S5_P1_ADC_TIC   I142 @T6G_MB_LIB.T6G(SCH_1):PAGE263
    10 PVDD18_S5_P0_ADC_TIC @T6G_MB_LIB.T6G(SCH_1):PVDD18_S5_P0_ADC_TIC   I142 @T6G_MB_LIB.T6G(SCH_1):PAGE263
    11 PVDD_33_S5_ADC_TIC @T6G_MB_LIB.T6G(SCH_1):PVDD_33_S5_ADC_TIC   I142 @T6G_MB_LIB.T6G(SCH_1):PAGE263
    12 P1V8_CPU1_RT_1D_ADC_TIC @T6G_MB_LIB.T6G(SCH_1):P1V8_CPU1_RT_1D_ADC_TIC   I142 @T6G_MB_LIB.T6G(SCH_1):PAGE263
    13 P1V8_CPU0_RT_1D_ADC_TIC @T6G_MB_LIB.T6G(SCH_1):P1V8_CPU0_RT_1D_ADC_TIC   I142 @T6G_MB_LIB.T6G(SCH_1):PAGE263
    14 P1V2_AUX_ADC_TIC @T6G_MB_LIB.T6G(SCH_1):P1V2_AUX_ADC_TIC   I142 @T6G_MB_LIB.T6G(SCH_1):PAGE263
    15 P1V8_AUX_ADC_TIC @T6G_MB_LIB.T6G(SCH_1):P1V8_AUX_ADC_TIC   I142 @T6G_MB_LIB.T6G(SCH_1):PAGE263
    16 P5V_AUX_ADC_TIC @T6G_MB_LIB.T6G(SCH_1):P5V_AUX_ADC_TIC   I142 @T6G_MB_LIB.T6G(SCH_1):PAGE263
     2 SMB_SEN_TIC_2_3V3AUX_SDA @T6G_MB_LIB.T6G(SCH_1):SMB_SEN_TIC_2_3V3AUX_SDA   I142 @T6G_MB_LIB.T6G(SCH_1):PAGE263
     3 SMB_SEN_TIC_2_3V3AUX_SCL @T6G_MB_LIB.T6G(SCH_1):SMB_SEN_TIC_2_3V3AUX_SCL   I142 @T6G_MB_LIB.T6G(SCH_1):PAGE263
     4    GND @T6G_MB_LIB.T6G(SCH_1):GND   I142 @T6G_MB_LIB.T6G(SCH_1):PAGE263
     6 TP_ADC128_2_INT @T6G_MB_LIB.T6G(SCH_1):TP_ADC128_2_INT   I142 @T6G_MB_LIB.T6G(SCH_1):PAGE263

 U52 ISL28022FRZT-ISL28022FRZ-T,SMLF,IC,AL028022003
     9 P3V3_AUX @T6G_MB_LIB.T6G(SCH_1):P3V3_AUX    I57 @T6G_MB_LIB.T6G(SCH_1):PAGE466
     1 INA230_8_A1 @T6G_MB_LIB.T6G(SCH_1):INA230_8_A1    I57 @T6G_MB_LIB.T6G(SCH_1):PAGE466
     2 INA230_8_A0 @T6G_MB_LIB.T6G(SCH_1):INA230_8_A0    I57 @T6G_MB_LIB.T6G(SCH_1):PAGE466
     5 SMB_INA230_8_3V3AUX_SCL_R1 @T6G_MB_LIB.T6G(SCH_1):SMB_INA230_8_3V3AUX_SCL_R1    I57 @T6G_MB_LIB.T6G(SCH_1):PAGE466
     4 SMB_INA230_8_3V3AUX_SDA_R1 @T6G_MB_LIB.T6G(SCH_1):SMB_INA230_8_3V3AUX_SDA_R1    I57 @T6G_MB_LIB.T6G(SCH_1):PAGE466
    11 P12V_E1S_0 @T6G_MB_LIB.T6G(SCH_1):P12V_E1S_0    I57 @T6G_MB_LIB.T6G(SCH_1):PAGE466
    13 VSENSE_P12V_INA230_8_INP @T6G_MB_LIB.T6G(SCH_1):VSENSE_P12V_INA230_8_INP    I57 @T6G_MB_LIB.T6G(SCH_1):PAGE466
    12 VSENSE_P12V_INA230_8_INN @T6G_MB_LIB.T6G(SCH_1):VSENSE_P12V_INA230_8_INN    I57 @T6G_MB_LIB.T6G(SCH_1):PAGE466
     3 P12V_E1S_0_ADC_ALERT_R @T6G_MB_LIB.T6G(SCH_1):P12V_E1S_0_ADC_ALERT_R    I57 @T6G_MB_LIB.T6G(SCH_1):PAGE466
     6 NC_INA230_8_NC0 @T6G_MB_LIB.T6G(SCH_1):NC_INA230_8_NC0    I57 @T6G_MB_LIB.T6G(SCH_1):PAGE466
     7 NC_INA230_8_NC1 @T6G_MB_LIB.T6G(SCH_1):NC_INA230_8_NC1    I57 @T6G_MB_LIB.T6G(SCH_1):PAGE466
     8 NC_INA230_8_NC2 @T6G_MB_LIB.T6G(SCH_1):NC_INA230_8_NC2    I57 @T6G_MB_LIB.T6G(SCH_1):PAGE466
    14 NC_INA230_8_NC3 @T6G_MB_LIB.T6G(SCH_1):NC_INA230_8_NC3    I57 @T6G_MB_LIB.T6G(SCH_1):PAGE466
    15 NC_INA230_8_NC4 @T6G_MB_LIB.T6G(SCH_1):NC_INA230_8_NC4    I57 @T6G_MB_LIB.T6G(SCH_1):PAGE466
    16 NC_INA230_8_NC5 @T6G_MB_LIB.T6G(SCH_1):NC_INA230_8_NC5    I57 @T6G_MB_LIB.T6G(SCH_1):PAGE466
    10    GND @T6G_MB_LIB.T6G(SCH_1):GND    I57 @T6G_MB_LIB.T6G(SCH_1):PAGE466
    TH    GND @T6G_MB_LIB.T6G(SCH_1):GND    I57 @T6G_MB_LIB.T6G(SCH_1):PAGE466

 U53 SN74AVC4T774PWR-SN74AVC4T774PWR,SMLF,IC,AL04T774K00
     1 PVDD18_S5_P0 @T6G_MB_LIB.T6G(SCH_1):PVDD18_S5_P0    I63 @T6G_MB_LIB.T6G(SCH_1):PAGE76
     2 PVDD18_S5_P0 @T6G_MB_LIB.T6G(SCH_1):PVDD18_S5_P0    I63 @T6G_MB_LIB.T6G(SCH_1):PAGE76
     3 SPI_CPU0_CS0_N @T6G_MB_LIB.T6G(SCH_1):SPI_CPU0_CS0_N    I63 @T6G_MB_LIB.T6G(SCH_1):PAGE76
     4 SPI_CPU0_CLK @T6G_MB_LIB.T6G(SCH_1):SPI_CPU0_CLK    I63 @T6G_MB_LIB.T6G(SCH_1):PAGE76
     5 SPI_CPU0_CS1_N @T6G_MB_LIB.T6G(SCH_1):SPI_CPU0_CS1_N    I63 @T6G_MB_LIB.T6G(SCH_1):PAGE76
     6 SPI_CPU0_TPM_CS_N @T6G_MB_LIB.T6G(SCH_1):SPI_CPU0_TPM_CS_N    I63 @T6G_MB_LIB.T6G(SCH_1):PAGE76
     7 PVDD18_S5_P0 @T6G_MB_LIB.T6G(SCH_1):PVDD18_S5_P0    I63 @T6G_MB_LIB.T6G(SCH_1):PAGE76
     8 PVDD18_S5_P0 @T6G_MB_LIB.T6G(SCH_1):PVDD18_S5_P0    I63 @T6G_MB_LIB.T6G(SCH_1):PAGE76
     9 ROM_SD_LS_OE @T6G_MB_LIB.T6G(SCH_1):ROM_SD_LS_OE    I63 @T6G_MB_LIB.T6G(SCH_1):PAGE76
    10    GND @T6G_MB_LIB.T6G(SCH_1):GND    I63 @T6G_MB_LIB.T6G(SCH_1):PAGE76
    11 SPI_CPU0_LVC3_R_TPM_CS_N @T6G_MB_LIB.T6G(SCH_1):SPI_CPU0_LVC3_R_TPM_CS_N    I63 @T6G_MB_LIB.T6G(SCH_1):PAGE76
    12 SPI_CPU0_LVC3_CS1_N @T6G_MB_LIB.T6G(SCH_1):SPI_CPU0_LVC3_CS1_N    I63 @T6G_MB_LIB.T6G(SCH_1):PAGE76
    13 SPI_CPU0_LVC3_CLK @T6G_MB_LIB.T6G(SCH_1):SPI_CPU0_LVC3_CLK    I63 @T6G_MB_LIB.T6G(SCH_1):PAGE76
    14 SPI_CPU0_LVC3_CS0_N @T6G_MB_LIB.T6G(SCH_1):SPI_CPU0_LVC3_CS0_N    I63 @T6G_MB_LIB.T6G(SCH_1):PAGE76
    15 P3V3_AUX @T6G_MB_LIB.T6G(SCH_1):P3V3_AUX    I63 @T6G_MB_LIB.T6G(SCH_1):PAGE76
    16 PVDD18_S5_P0 @T6G_MB_LIB.T6G(SCH_1):PVDD18_S5_P0    I63 @T6G_MB_LIB.T6G(SCH_1):PAGE76

 U54 PI4ULS3V304AZMAEX-PI4ULS3V304AZMAEX,SMLF,IC,AL0003A
     2 SPI_CPU0_R1_D3 @T6G_MB_LIB.T6G(SCH_1):SPI_CPU0_R1_D3    I67 @T6G_MB_LIB.T6G(SCH_1):PAGE76
     3 SPI_CPU0_R1_D2 @T6G_MB_LIB.T6G(SCH_1):SPI_CPU0_R1_D2    I67 @T6G_MB_LIB.T6G(SCH_1):PAGE76
     4 SPI_CPU0_R1_D0 @T6G_MB_LIB.T6G(SCH_1):SPI_CPU0_R1_D0    I67 @T6G_MB_LIB.T6G(SCH_1):PAGE76
    11 P3V3_AUX @T6G_MB_LIB.T6G(SCH_1):P3V3_AUX    I67 @T6G_MB_LIB.T6G(SCH_1):PAGE76
    12 ROM_LS_EN @T6G_MB_LIB.T6G(SCH_1):ROM_LS_EN    I67 @T6G_MB_LIB.T6G(SCH_1):PAGE76
     5 SPI_CPU0_R1_D1 @T6G_MB_LIB.T6G(SCH_1):SPI_CPU0_R1_D1    I67 @T6G_MB_LIB.T6G(SCH_1):PAGE76
     1 PVDD18_S5_P0 @T6G_MB_LIB.T6G(SCH_1):PVDD18_S5_P0    I67 @T6G_MB_LIB.T6G(SCH_1):PAGE76
    10 SPI_CPU0_LVC3_D3 @T6G_MB_LIB.T6G(SCH_1):SPI_CPU0_LVC3_D3    I67 @T6G_MB_LIB.T6G(SCH_1):PAGE76
     9 SPI_CPU0_LVC3_D2 @T6G_MB_LIB.T6G(SCH_1):SPI_CPU0_LVC3_D2    I67 @T6G_MB_LIB.T6G(SCH_1):PAGE76
     8 SPI_CPU0_LVC3_D0 @T6G_MB_LIB.T6G(SCH_1):SPI_CPU0_LVC3_D0    I67 @T6G_MB_LIB.T6G(SCH_1):PAGE76
     7 SPI_CPU0_LVC3_D1 @T6G_MB_LIB.T6G(SCH_1):SPI_CPU0_LVC3_D1    I67 @T6G_MB_LIB.T6G(SCH_1):PAGE76
     6    GND @T6G_MB_LIB.T6G(SCH_1):GND    I67 @T6G_MB_LIB.T6G(SCH_1):PAGE76

 U55 ISL28022FRZT-ISL28022FRZ-T,SMLF,IC,AL028022003
     9 P3V3_AUX @T6G_MB_LIB.T6G(SCH_1):P3V3_AUX    I28 @T6G_MB_LIB.T6G(SCH_1):PAGE466
     1 INA230_6_A1 @T6G_MB_LIB.T6G(SCH_1):INA230_6_A1    I28 @T6G_MB_LIB.T6G(SCH_1):PAGE466
     2 INA230_6_A0 @T6G_MB_LIB.T6G(SCH_1):INA230_6_A0    I28 @T6G_MB_LIB.T6G(SCH_1):PAGE466
     5 SMB_INA230_6_3V3AUX_SCL_R1 @T6G_MB_LIB.T6G(SCH_1):SMB_INA230_6_3V3AUX_SCL_R1    I28 @T6G_MB_LIB.T6G(SCH_1):PAGE466
     4 SMB_INA230_6_3V3AUX_SDA_R1 @T6G_MB_LIB.T6G(SCH_1):SMB_INA230_6_3V3AUX_SDA_R1    I28 @T6G_MB_LIB.T6G(SCH_1):PAGE466
    11 P12V_OCP_SFF @T6G_MB_LIB.T6G(SCH_1):P12V_OCP_SFF    I28 @T6G_MB_LIB.T6G(SCH_1):PAGE466
    13 VSENSE_P12V_INA230_6_INP @T6G_MB_LIB.T6G(SCH_1):VSENSE_P12V_INA230_6_INP    I28 @T6G_MB_LIB.T6G(SCH_1):PAGE466
    12 VSENSE_P12V_INA230_6_INN @T6G_MB_LIB.T6G(SCH_1):VSENSE_P12V_INA230_6_INN    I28 @T6G_MB_LIB.T6G(SCH_1):PAGE466
     3 P12V_OCP_SFF_ADC_ALERT_R @T6G_MB_LIB.T6G(SCH_1):P12V_OCP_SFF_ADC_ALERT_R    I28 @T6G_MB_LIB.T6G(SCH_1):PAGE466
     6 NC_INA230_6_NC0 @T6G_MB_LIB.T6G(SCH_1):NC_INA230_6_NC0    I28 @T6G_MB_LIB.T6G(SCH_1):PAGE466
     7 NC_INA230_6_NC1 @T6G_MB_LIB.T6G(SCH_1):NC_INA230_6_NC1    I28 @T6G_MB_LIB.T6G(SCH_1):PAGE466
     8 NC_INA230_6_NC2 @T6G_MB_LIB.T6G(SCH_1):NC_INA230_6_NC2    I28 @T6G_MB_LIB.T6G(SCH_1):PAGE466
    14 NC_INA230_6_NC3 @T6G_MB_LIB.T6G(SCH_1):NC_INA230_6_NC3    I28 @T6G_MB_LIB.T6G(SCH_1):PAGE466
    15 NC_INA230_6_NC4 @T6G_MB_LIB.T6G(SCH_1):NC_INA230_6_NC4    I28 @T6G_MB_LIB.T6G(SCH_1):PAGE466
    16 NC_INA230_6_NC5 @T6G_MB_LIB.T6G(SCH_1):NC_INA230_6_NC5    I28 @T6G_MB_LIB.T6G(SCH_1):PAGE466
    10    GND @T6G_MB_LIB.T6G(SCH_1):GND    I28 @T6G_MB_LIB.T6G(SCH_1):PAGE466
    TH    GND @T6G_MB_LIB.T6G(SCH_1):GND    I28 @T6G_MB_LIB.T6G(SCH_1):PAGE466

 U56 ISL28022FRZT-ISL28022FRZ-T,SMLF,IC,AL028022003
     9 P3V3_AUX @T6G_MB_LIB.T6G(SCH_1):P3V3_AUX    I29 @T6G_MB_LIB.T6G(SCH_1):PAGE466
     1 INA230_7_A1 @T6G_MB_LIB.T6G(SCH_1):INA230_7_A1    I29 @T6G_MB_LIB.T6G(SCH_1):PAGE466
     2 INA230_7_A0 @T6G_MB_LIB.T6G(SCH_1):INA230_7_A0    I29 @T6G_MB_LIB.T6G(SCH_1):PAGE466
     5 SMB_INA230_7_3V3AUX_SCL_R1 @T6G_MB_LIB.T6G(SCH_1):SMB_INA230_7_3V3AUX_SCL_R1    I29 @T6G_MB_LIB.T6G(SCH_1):PAGE466
     4 SMB_INA230_7_3V3AUX_SDA_R1 @T6G_MB_LIB.T6G(SCH_1):SMB_INA230_7_3V3AUX_SDA_R1    I29 @T6G_MB_LIB.T6G(SCH_1):PAGE466
    11 P12V_OCP_V3_2 @T6G_MB_LIB.T6G(SCH_1):P12V_OCP_V3_2    I29 @T6G_MB_LIB.T6G(SCH_1):PAGE466
    13 VSENSE_P12V_INA230_7_INP @T6G_MB_LIB.T6G(SCH_1):VSENSE_P12V_INA230_7_INP    I29 @T6G_MB_LIB.T6G(SCH_1):PAGE466
    12 VSENSE_P12V_INA230_7_INN @T6G_MB_LIB.T6G(SCH_1):VSENSE_P12V_INA230_7_INN    I29 @T6G_MB_LIB.T6G(SCH_1):PAGE466
     3 P12V_OCP_V3_2_ADC_ALERT_R @T6G_MB_LIB.T6G(SCH_1):P12V_OCP_V3_2_ADC_ALERT_R    I29 @T6G_MB_LIB.T6G(SCH_1):PAGE466
     6 NC_INA230_7_NC0 @T6G_MB_LIB.T6G(SCH_1):NC_INA230_7_NC0    I29 @T6G_MB_LIB.T6G(SCH_1):PAGE466
     7 NC_INA230_7_NC1 @T6G_MB_LIB.T6G(SCH_1):NC_INA230_7_NC1    I29 @T6G_MB_LIB.T6G(SCH_1):PAGE466
     8 NC_INA230_7_NC2 @T6G_MB_LIB.T6G(SCH_1):NC_INA230_7_NC2    I29 @T6G_MB_LIB.T6G(SCH_1):PAGE466
    14 NC_INA230_7_NC3 @T6G_MB_LIB.T6G(SCH_1):NC_INA230_7_NC3    I29 @T6G_MB_LIB.T6G(SCH_1):PAGE466
    15 NC_INA230_7_NC4 @T6G_MB_LIB.T6G(SCH_1):NC_INA230_7_NC4    I29 @T6G_MB_LIB.T6G(SCH_1):PAGE466
    16 NC_INA230_7_NC5 @T6G_MB_LIB.T6G(SCH_1):NC_INA230_7_NC5    I29 @T6G_MB_LIB.T6G(SCH_1):PAGE466
    10    GND @T6G_MB_LIB.T6G(SCH_1):GND    I29 @T6G_MB_LIB.T6G(SCH_1):PAGE466
    TH    GND @T6G_MB_LIB.T6G(SCH_1):GND    I29 @T6G_MB_LIB.T6G(SCH_1):PAGE466

 U57 SCHOTTKY_DUAL_12A_3C-BAT54CW,SMLF,EMPTY,BCBAT54CZ13
     2     NC     NC     I5 @T6G_MB_LIB.T6G(SCH_1):PAGE146
     1 P12V_AUX_DSC_VOL @T6G_MB_LIB.T6G(SCH_1):P12V_AUX_DSC_VOL     I5 @T6G_MB_LIB.T6G(SCH_1):PAGE146
     3 P12V_AUX_DSC_S1 @T6G_MB_LIB.T6G(SCH_1):P12V_AUX_DSC_S1     I5 @T6G_MB_LIB.T6G(SCH_1):PAGE146

 U58 74LVC2G07DW7-74LVC2G07DW-7,SMLF,IC,AL002G07003
     1 OCP_V3_2_PRSNT0_R_N @T6G_MB_LIB.T6G(SCH_1):OCP_V3_2_PRSNT0_R_N    I28 @T6G_MB_LIB.T6G(SCH_1):PAGE343
     3 OCP_V3_2_PRSNT1_R_N @T6G_MB_LIB.T6G(SCH_1):OCP_V3_2_PRSNT1_R_N    I28 @T6G_MB_LIB.T6G(SCH_1):PAGE343
     6 HP_LVC3_OCP_V3_2_PRSNT2_N_R @T6G_MB_LIB.T6G(SCH_1):HP_LVC3_OCP_V3_2_PRSNT2_N_R    I28 @T6G_MB_LIB.T6G(SCH_1):PAGE343
     4 HP_LVC3_OCP_V3_2_PRSNT2_N_R @T6G_MB_LIB.T6G(SCH_1):HP_LVC3_OCP_V3_2_PRSNT2_N_R    I28 @T6G_MB_LIB.T6G(SCH_1):PAGE343
     2    GND @T6G_MB_LIB.T6G(SCH_1):GND    I28 @T6G_MB_LIB.T6G(SCH_1):PAGE343
     5 P3V3_AUX @T6G_MB_LIB.T6G(SCH_1):P3V3_AUX    I28 @T6G_MB_LIB.T6G(SCH_1):PAGE343

 U59 74LVC2G07DW7-74LVC2G07DW-7,SMLF,IC,AL002G07003
     1 OCP_V3_2_PRSNT2_R_N @T6G_MB_LIB.T6G(SCH_1):OCP_V3_2_PRSNT2_R_N    I22 @T6G_MB_LIB.T6G(SCH_1):PAGE343
     3 OCP_V3_2_PRSNT3_R_N @T6G_MB_LIB.T6G(SCH_1):OCP_V3_2_PRSNT3_R_N    I22 @T6G_MB_LIB.T6G(SCH_1):PAGE343
     6 HP_LVC3_OCP_V3_2_PRSNT2_N_R @T6G_MB_LIB.T6G(SCH_1):HP_LVC3_OCP_V3_2_PRSNT2_N_R    I22 @T6G_MB_LIB.T6G(SCH_1):PAGE343
     4 HP_LVC3_OCP_V3_2_PRSNT2_N_R @T6G_MB_LIB.T6G(SCH_1):HP_LVC3_OCP_V3_2_PRSNT2_N_R    I22 @T6G_MB_LIB.T6G(SCH_1):PAGE343
     2    GND @T6G_MB_LIB.T6G(SCH_1):GND    I22 @T6G_MB_LIB.T6G(SCH_1):PAGE343
     5 P3V3_AUX @T6G_MB_LIB.T6G(SCH_1):P3V3_AUX    I22 @T6G_MB_LIB.T6G(SCH_1):PAGE343

 U60 SCHOTTKY_DUAL_12A_3C-BAT54CW,SMLF,EMPTY,BCBAT54CZ13
     2     NC     NC    I25 @T6G_MB_LIB.T6G(SCH_1):PAGE146
     1 P3V3_AUX_DSC_VOL @T6G_MB_LIB.T6G(SCH_1):P3V3_AUX_DSC_VOL    I25 @T6G_MB_LIB.T6G(SCH_1):PAGE146
     3 P3V3_AUX_DSC_S1 @T6G_MB_LIB.T6G(SCH_1):P3V3_AUX_DSC_S1    I25 @T6G_MB_LIB.T6G(SCH_1):PAGE146

 U64 M24128BWMN6TP-M24128-BWMN6TP,SMLF,IC,AKE30Z00613
     8 P3V3_AUX @T6G_MB_LIB.T6G(SCH_1):P3V3_AUX    I35 @T6G_MB_LIB.T6G(SCH_1):PAGE361
     7 PD_MB_FRU_WP @T6G_MB_LIB.T6G(SCH_1):PD_MB_FRU_WP    I35 @T6G_MB_LIB.T6G(SCH_1):PAGE361
     6 SMB_FRU_3V3AUX_R1_SCL @T6G_MB_LIB.T6G(SCH_1):SMB_FRU_3V3AUX_R1_SCL    I35 @T6G_MB_LIB.T6G(SCH_1):PAGE361
     5 SMB_FRU_3V3AUX_R1_SDA @T6G_MB_LIB.T6G(SCH_1):SMB_FRU_3V3AUX_R1_SDA    I35 @T6G_MB_LIB.T6G(SCH_1):PAGE361
     4    GND @T6G_MB_LIB.T6G(SCH_1):GND    I35 @T6G_MB_LIB.T6G(SCH_1):PAGE361
     3 MB_FRU_ADDR2 @T6G_MB_LIB.T6G(SCH_1):MB_FRU_ADDR2    I35 @T6G_MB_LIB.T6G(SCH_1):PAGE361
     2 MB_FRU_ADDR1 @T6G_MB_LIB.T6G(SCH_1):MB_FRU_ADDR1    I35 @T6G_MB_LIB.T6G(SCH_1):PAGE361
     1 MB_FRU_ADDR0 @T6G_MB_LIB.T6G(SCH_1):MB_FRU_ADDR0    I35 @T6G_MB_LIB.T6G(SCH_1):PAGE361

 U66 74LVC1G126SE7-74LVC1G126SE-7,SMLF,IC,AL1G0126009
     2 FM_OCP_SFF_PWR_GOOD @T6G_MB_LIB.T6G(SCH_1):FM_OCP_SFF_PWR_GOOD   I157 @T6G_MB_LIB.T6G(SCH_1):PAGE336
     4 FB_BMC_ISOLATE_R1 @T6G_MB_LIB.T6G(SCH_1):FB_BMC_ISOLATE_R1   I157 @T6G_MB_LIB.T6G(SCH_1):PAGE336
     5 P3V3_AUX @T6G_MB_LIB.T6G(SCH_1):P3V3_AUX   I157 @T6G_MB_LIB.T6G(SCH_1):PAGE336
     3    GND @T6G_MB_LIB.T6G(SCH_1):GND   I157 @T6G_MB_LIB.T6G(SCH_1):PAGE336
     1 OCP_SFF_AUX_PWR_EN_R1 @T6G_MB_LIB.T6G(SCH_1):OCP_SFF_AUX_PWR_EN_R1   I157 @T6G_MB_LIB.T6G(SCH_1):PAGE336

 U67 74CBTLV3126PW-74CBTLV3126PW,SMLF,IC,AL003126K08
     5 NCSI_BMC_RXD0_R @T6G_MB_LIB.T6G(SCH_1):NCSI_BMC_RXD0_R     I1 @T6G_MB_LIB.T6G(SCH_1):PAGE336
     8 NCSI_OCP_SFF_CRS_DV @T6G_MB_LIB.T6G(SCH_1):NCSI_OCP_SFF_CRS_DV     I1 @T6G_MB_LIB.T6G(SCH_1):PAGE336
     1 FB_BMC_ISOLATE @T6G_MB_LIB.T6G(SCH_1):FB_BMC_ISOLATE     I1 @T6G_MB_LIB.T6G(SCH_1):PAGE336
     4 FB_BMC_ISOLATE @T6G_MB_LIB.T6G(SCH_1):FB_BMC_ISOLATE     I1 @T6G_MB_LIB.T6G(SCH_1):PAGE336
     3 NCSI_OCP_SFF_RXD1 @T6G_MB_LIB.T6G(SCH_1):NCSI_OCP_SFF_RXD1     I1 @T6G_MB_LIB.T6G(SCH_1):PAGE336
     6 NCSI_OCP_SFF_RXD0 @T6G_MB_LIB.T6G(SCH_1):NCSI_OCP_SFF_RXD0     I1 @T6G_MB_LIB.T6G(SCH_1):PAGE336
     2 NCSI_BMC_RXD1_R @T6G_MB_LIB.T6G(SCH_1):NCSI_BMC_RXD1_R     I1 @T6G_MB_LIB.T6G(SCH_1):PAGE336
     7    GND @T6G_MB_LIB.T6G(SCH_1):GND     I1 @T6G_MB_LIB.T6G(SCH_1):PAGE336
     9 NCSI_BMC_CRS_DV_R @T6G_MB_LIB.T6G(SCH_1):NCSI_BMC_CRS_DV_R     I1 @T6G_MB_LIB.T6G(SCH_1):PAGE336
    10 FB_BMC_ISOLATE @T6G_MB_LIB.T6G(SCH_1):FB_BMC_ISOLATE     I1 @T6G_MB_LIB.T6G(SCH_1):PAGE336
    11 OCP_SFF_ISO1_RBT_ARB_IN @T6G_MB_LIB.T6G(SCH_1):OCP_SFF_ISO1_RBT_ARB_IN     I1 @T6G_MB_LIB.T6G(SCH_1):PAGE336
    12 OCP_SFF_RBT_ARB_IN_R @T6G_MB_LIB.T6G(SCH_1):OCP_SFF_RBT_ARB_IN_R     I1 @T6G_MB_LIB.T6G(SCH_1):PAGE336
    13 FB_BMC_ISOLATE @T6G_MB_LIB.T6G(SCH_1):FB_BMC_ISOLATE     I1 @T6G_MB_LIB.T6G(SCH_1):PAGE336
    14 P3V3_AUX @T6G_MB_LIB.T6G(SCH_1):P3V3_AUX     I1 @T6G_MB_LIB.T6G(SCH_1):PAGE336

 U75 74LVC1G17GW-74LVC1G17GW,SMLF,IC,AL1G0017K01
     5 P3V3_AUX @T6G_MB_LIB.T6G(SCH_1):P3V3_AUX    I64 @T6G_MB_LIB.T6G(SCH_1):PAGE337
     2 RST_PERST_OCP_SFF_BUF_N @T6G_MB_LIB.T6G(SCH_1):RST_PERST_OCP_SFF_BUF_N    I64 @T6G_MB_LIB.T6G(SCH_1):PAGE337
     3    GND @T6G_MB_LIB.T6G(SCH_1):GND    I64 @T6G_MB_LIB.T6G(SCH_1):PAGE337
     4 RST_PERST_OCP_SFF_BUF2_N @T6G_MB_LIB.T6G(SCH_1):RST_PERST_OCP_SFF_BUF2_N    I64 @T6G_MB_LIB.T6G(SCH_1):PAGE337
     1     NC     NC    I64 @T6G_MB_LIB.T6G(SCH_1):PAGE337

 U82 SN74LVC1G07DBVR_SMLF-SN74LVC1G07DBVR,IC,AL1G0007024
     2 BOOT_RDY_R1_N @T6G_MB_LIB.T6G(SCH_1):BOOT_RDY_R1_N    I26 @T6G_MB_LIB.T6G(SCH_1):PAGE143
     4 BOOT_RDY_BUF_R_LED @T6G_MB_LIB.T6G(SCH_1):BOOT_RDY_BUF_R_LED    I26 @T6G_MB_LIB.T6G(SCH_1):PAGE143
     1     NC     NC    I26 @T6G_MB_LIB.T6G(SCH_1):PAGE143
     5 P1V8_AUX @T6G_MB_LIB.T6G(SCH_1):P1V8_AUX    I26 @T6G_MB_LIB.T6G(SCH_1):PAGE143
     3    GND @T6G_MB_LIB.T6G(SCH_1):GND    I26 @T6G_MB_LIB.T6G(SCH_1):PAGE143

 U86 SN74LVC1G07DBVR_SMLF-SN74LVC1G07DBVR,IC,AL1G0007024
     2 FM_SMERR_LED_N @T6G_MB_LIB.T6G(SCH_1):FM_SMERR_LED_N    I31 @T6G_MB_LIB.T6G(SCH_1):PAGE143
     4 FM_SMERR_BUF_LED_N @T6G_MB_LIB.T6G(SCH_1):FM_SMERR_BUF_LED_N    I31 @T6G_MB_LIB.T6G(SCH_1):PAGE143
     1     NC     NC    I31 @T6G_MB_LIB.T6G(SCH_1):PAGE143
     5 P1V8_AUX @T6G_MB_LIB.T6G(SCH_1):P1V8_AUX    I31 @T6G_MB_LIB.T6G(SCH_1):PAGE143
     3    GND @T6G_MB_LIB.T6G(SCH_1):GND    I31 @T6G_MB_LIB.T6G(SCH_1):PAGE143

 U90 PI6CV304LE-PI6CV304LE,SMLF,IC,AL000304K01
     1 CLK_50M_RMII_R @T6G_MB_LIB.T6G(SCH_1):CLK_50M_RMII_R    I16 @T6G_MB_LIB.T6G(SCH_1):PAGE337
     2 CLK_50M_EN @T6G_MB_LIB.T6G(SCH_1):CLK_50M_EN    I16 @T6G_MB_LIB.T6G(SCH_1):PAGE337
     3 CLK_50M_BMC_MAC_R @T6G_MB_LIB.T6G(SCH_1):CLK_50M_BMC_MAC_R    I16 @T6G_MB_LIB.T6G(SCH_1):PAGE337
     5 CLK_50M_NCSI_OCP_1 @T6G_MB_LIB.T6G(SCH_1):CLK_50M_NCSI_OCP_1    I16 @T6G_MB_LIB.T6G(SCH_1):PAGE337
     7 CLK_50M_NCSI_OCP_2 @T6G_MB_LIB.T6G(SCH_1):CLK_50M_NCSI_OCP_2    I16 @T6G_MB_LIB.T6G(SCH_1):PAGE337
     8 TP_CLK_50M_Y3 @T6G_MB_LIB.T6G(SCH_1):TP_CLK_50M_Y3    I16 @T6G_MB_LIB.T6G(SCH_1):PAGE337
     6 P3V3_AUX @T6G_MB_LIB.T6G(SCH_1):P3V3_AUX    I16 @T6G_MB_LIB.T6G(SCH_1):PAGE337
     4    GND @T6G_MB_LIB.T6G(SCH_1):GND    I16 @T6G_MB_LIB.T6G(SCH_1):PAGE337

 U92 SN74LVC1G07DBVR_SMLF-SN74LVC1G07DBVR,IC,AL1G0007024
     2 SCM_IRQ_1V8_N @T6G_MB_LIB.T6G(SCH_1):SCM_IRQ_1V8_N    I26 @T6G_MB_LIB.T6G(SCH_1):PAGE83
     4 SCM_IRQ_R_N @T6G_MB_LIB.T6G(SCH_1):SCM_IRQ_R_N    I26 @T6G_MB_LIB.T6G(SCH_1):PAGE83
     1     NC     NC    I26 @T6G_MB_LIB.T6G(SCH_1):PAGE83
     5 P1V8_AUX @T6G_MB_LIB.T6G(SCH_1):P1V8_AUX    I26 @T6G_MB_LIB.T6G(SCH_1):PAGE83
     3    GND @T6G_MB_LIB.T6G(SCH_1):GND    I26 @T6G_MB_LIB.T6G(SCH_1):PAGE83

 U96 PCA9617ADP-PCA9617ADP,SMLF,IC,AL009617K02
     5 PU_U96_EN @T6G_MB_LIB.T6G(SCH_1):PU_U96_EN    I51 @T6G_MB_LIB.T6G(SCH_1):PAGE137
     1 PVDD18_S5_P0 @T6G_MB_LIB.T6G(SCH_1):PVDD18_S5_P0    I51 @T6G_MB_LIB.T6G(SCH_1):PAGE137
     8 P3V3_AUX @T6G_MB_LIB.T6G(SCH_1):P3V3_AUX    I51 @T6G_MB_LIB.T6G(SCH_1):PAGE137
     2 SMB_CPU0_CPU1_SEC_SCL_R1 @T6G_MB_LIB.T6G(SCH_1):SMB_CPU0_CPU1_SEC_SCL_R1    I51 @T6G_MB_LIB.T6G(SCH_1):PAGE137
     3 SMB_CPU0_CPU1_SEC_SDA_R1 @T6G_MB_LIB.T6G(SCH_1):SMB_CPU0_CPU1_SEC_SDA_R1    I51 @T6G_MB_LIB.T6G(SCH_1):PAGE137
     6 SMB_CPU0_CPU1_SEC_SDA @T6G_MB_LIB.T6G(SCH_1):SMB_CPU0_CPU1_SEC_SDA    I51 @T6G_MB_LIB.T6G(SCH_1):PAGE137
     7 SMB_CPU0_CPU1_SEC_SCL @T6G_MB_LIB.T6G(SCH_1):SMB_CPU0_CPU1_SEC_SCL    I51 @T6G_MB_LIB.T6G(SCH_1):PAGE137
     4    GND @T6G_MB_LIB.T6G(SCH_1):GND    I51 @T6G_MB_LIB.T6G(SCH_1):PAGE137

 U98 PCA9306DP1-PCA9306DP1,SMLF,IC,AL009306K04
     2 P1V8_AUX @T6G_MB_LIB.T6G(SCH_1):P1V8_AUX    I27 @T6G_MB_LIB.T6G(SCH_1):PAGE346
     3 SMB_M2_P1_1V8AUX_SCL_R @T6G_MB_LIB.T6G(SCH_1):SMB_M2_P1_1V8AUX_SCL_R    I27 @T6G_MB_LIB.T6G(SCH_1):PAGE346
     4 SMB_M2_P1_1V8AUX_SDA_R @T6G_MB_LIB.T6G(SCH_1):SMB_M2_P1_1V8AUX_SDA_R    I27 @T6G_MB_LIB.T6G(SCH_1):PAGE346
     5 SMB_SENSOR_M2_P1_3V3AUX_SDA @T6G_MB_LIB.T6G(SCH_1):SMB_SENSOR_M2_P1_3V3AUX_SDA    I27 @T6G_MB_LIB.T6G(SCH_1):PAGE346
     6 SMB_SENSOR_M2_P1_3V3AUX_SCL @T6G_MB_LIB.T6G(SCH_1):SMB_SENSOR_M2_P1_3V3AUX_SCL    I27 @T6G_MB_LIB.T6G(SCH_1):PAGE346
     7 SMB_PCIE_M2_0_EN @T6G_MB_LIB.T6G(SCH_1):SMB_PCIE_M2_0_EN    I27 @T6G_MB_LIB.T6G(SCH_1):PAGE346
     8 SMB_PCIE_M2_0_EN @T6G_MB_LIB.T6G(SCH_1):SMB_PCIE_M2_0_EN    I27 @T6G_MB_LIB.T6G(SCH_1):PAGE346
     1    GND @T6G_MB_LIB.T6G(SCH_1):GND    I27 @T6G_MB_LIB.T6G(SCH_1):PAGE346

 U99 SN74LVC1G07DBVR_SMLF-SN74LVC1G07DBVR,EMPTY,AL1G000A
     2 FW_RECOVERY_R @T6G_MB_LIB.T6G(SCH_1):FW_RECOVERY_R   I340 @T6G_MB_LIB.T6G(SCH_1):PAGE148
     4 SCM_JTAG_MUX_S1 @T6G_MB_LIB.T6G(SCH_1):SCM_JTAG_MUX_S1   I340 @T6G_MB_LIB.T6G(SCH_1):PAGE148
     1     NC     NC   I340 @T6G_MB_LIB.T6G(SCH_1):PAGE148
     5 P3V3_AUX @T6G_MB_LIB.T6G(SCH_1):P3V3_AUX   I340 @T6G_MB_LIB.T6G(SCH_1):PAGE148
     3    GND @T6G_MB_LIB.T6G(SCH_1):GND   I340 @T6G_MB_LIB.T6G(SCH_1):PAGE148

U100 RT9818C44GV-RT9818C-44GV,SMLF,IC,AL009818001
     3    P5V @T6G_MB_LIB.T6G(SCH_1):P5V    I77 @T6G_MB_LIB.T6G(SCH_1):PAGE273
     1 PWRGD_P5V_R @T6G_MB_LIB.T6G(SCH_1):PWRGD_P5V_R    I77 @T6G_MB_LIB.T6G(SCH_1):PAGE273
     2    GND @T6G_MB_LIB.T6G(SCH_1):GND    I77 @T6G_MB_LIB.T6G(SCH_1):PAGE273

U101 SN74LVC1G07DBVR_SMLF-SN74LVC1G07DBVR,IC,AL1G0007024
     2 FM_BIOS_POST_CMPLT_N @T6G_MB_LIB.T6G(SCH_1):FM_BIOS_POST_CMPLT_N    I55 @T6G_MB_LIB.T6G(SCH_1):PAGE34
     4 FM_BIOS_POST_CMPLT_BUF_R1_N @T6G_MB_LIB.T6G(SCH_1):FM_BIOS_POST_CMPLT_BUF_R1_N    I55 @T6G_MB_LIB.T6G(SCH_1):PAGE34
     1     NC     NC    I55 @T6G_MB_LIB.T6G(SCH_1):PAGE34
     5 PVDD18_S5_P0 @T6G_MB_LIB.T6G(SCH_1):PVDD18_S5_P0    I55 @T6G_MB_LIB.T6G(SCH_1):PAGE34
     3    GND @T6G_MB_LIB.T6G(SCH_1):GND    I55 @T6G_MB_LIB.T6G(SCH_1):PAGE34

U104 74LVC1G07GV-74LVC1G07GV,SMLF,IC,AL1G0007001
     5 P3V3_AUX @T6G_MB_LIB.T6G(SCH_1):P3V3_AUX    I38 @T6G_MB_LIB.T6G(SCH_1):PAGE337
     2 FM_SYS_THROTTLE_N @T6G_MB_LIB.T6G(SCH_1):FM_SYS_THROTTLE_N    I38 @T6G_MB_LIB.T6G(SCH_1):PAGE337
     3    GND @T6G_MB_LIB.T6G(SCH_1):GND    I38 @T6G_MB_LIB.T6G(SCH_1):PAGE337
     4 OCP_SFF_PWRBRK_BUFF_N @T6G_MB_LIB.T6G(SCH_1):OCP_SFF_PWRBRK_BUFF_N    I38 @T6G_MB_LIB.T6G(SCH_1):PAGE337
     1 NC_U104_NC1 @T6G_MB_LIB.T6G(SCH_1):NC_U104_NC1    I38 @T6G_MB_LIB.T6G(SCH_1):PAGE337

U105 PI3CSW12ZUAEX-PI3CSW12ZUAEX,SMLF,IC,AL3CSW12000
     1 I3C_0_SPD_DDRAF_CPU0_SCL @T6G_MB_LIB.T6G(SCH_1):I3C_0_SPD_DDRAF_CPU0_SCL    I47 @T6G_MB_LIB.T6G(SCH_1):PAGE136
     3 I3C_SCM_0_R_SCL @T6G_MB_LIB.T6G(SCH_1):I3C_SCM_0_R_SCL    I47 @T6G_MB_LIB.T6G(SCH_1):PAGE136
     4 I3C_SCM_0_R_SDA @T6G_MB_LIB.T6G(SCH_1):I3C_SCM_0_R_SDA    I47 @T6G_MB_LIB.T6G(SCH_1):PAGE136
     7 I3C_SPD_DDRAF_CPU0_LVC1_SDA @T6G_MB_LIB.T6G(SCH_1):I3C_SPD_DDRAF_CPU0_LVC1_SDA    I47 @T6G_MB_LIB.T6G(SCH_1):PAGE136
     6 FM_I3C_CPU0_MUX0_OE_N @T6G_MB_LIB.T6G(SCH_1):FM_I3C_CPU0_MUX0_OE_N    I47 @T6G_MB_LIB.T6G(SCH_1):PAGE136
     9 FM_I3C_CPU0_MUX0_SEL @T6G_MB_LIB.T6G(SCH_1):FM_I3C_CPU0_MUX0_SEL    I47 @T6G_MB_LIB.T6G(SCH_1):PAGE136
    10 P3V3_AUX @T6G_MB_LIB.T6G(SCH_1):P3V3_AUX    I47 @T6G_MB_LIB.T6G(SCH_1):PAGE136
     2 I3C_0_SPD_DDRAF_CPU0_SDA @T6G_MB_LIB.T6G(SCH_1):I3C_0_SPD_DDRAF_CPU0_SDA    I47 @T6G_MB_LIB.T6G(SCH_1):PAGE136
     5    GND @T6G_MB_LIB.T6G(SCH_1):GND    I47 @T6G_MB_LIB.T6G(SCH_1):PAGE136
     8 I3C_SPD_DDRAF_CPU0_LVC1_SCL @T6G_MB_LIB.T6G(SCH_1):I3C_SPD_DDRAF_CPU0_LVC1_SCL    I47 @T6G_MB_LIB.T6G(SCH_1):PAGE136

U106 PI3CSW12ZUAEX-PI3CSW12ZUAEX,SMLF,IC,AL3CSW12000
     1 I3C_1_SPD_DDRGL_CPU0_SCL @T6G_MB_LIB.T6G(SCH_1):I3C_1_SPD_DDRGL_CPU0_SCL    I54 @T6G_MB_LIB.T6G(SCH_1):PAGE136
     3 I3C_SCM_1_R_SCL @T6G_MB_LIB.T6G(SCH_1):I3C_SCM_1_R_SCL    I54 @T6G_MB_LIB.T6G(SCH_1):PAGE136
     4 I3C_SCM_1_R_SDA @T6G_MB_LIB.T6G(SCH_1):I3C_SCM_1_R_SDA    I54 @T6G_MB_LIB.T6G(SCH_1):PAGE136
     7 I3C_SPD_DDRGL_CPU0_LVC1_SDA @T6G_MB_LIB.T6G(SCH_1):I3C_SPD_DDRGL_CPU0_LVC1_SDA    I54 @T6G_MB_LIB.T6G(SCH_1):PAGE136
     6 FM_I3C_CPU0_MUX1_OE_N @T6G_MB_LIB.T6G(SCH_1):FM_I3C_CPU0_MUX1_OE_N    I54 @T6G_MB_LIB.T6G(SCH_1):PAGE136
     9 FM_I3C_CPU0_MUX1_SEL @T6G_MB_LIB.T6G(SCH_1):FM_I3C_CPU0_MUX1_SEL    I54 @T6G_MB_LIB.T6G(SCH_1):PAGE136
    10 P3V3_AUX @T6G_MB_LIB.T6G(SCH_1):P3V3_AUX    I54 @T6G_MB_LIB.T6G(SCH_1):PAGE136
     2 I3C_1_SPD_DDRGL_CPU0_SDA @T6G_MB_LIB.T6G(SCH_1):I3C_1_SPD_DDRGL_CPU0_SDA    I54 @T6G_MB_LIB.T6G(SCH_1):PAGE136
     5    GND @T6G_MB_LIB.T6G(SCH_1):GND    I54 @T6G_MB_LIB.T6G(SCH_1):PAGE136
     8 I3C_SPD_DDRGL_CPU0_LVC1_SCL @T6G_MB_LIB.T6G(SCH_1):I3C_SPD_DDRGL_CPU0_LVC1_SCL    I54 @T6G_MB_LIB.T6G(SCH_1):PAGE136

U107 PI3CSW12ZUAEX-PI3CSW12ZUAEX,SMLF,IC,AL3CSW12000
     1 I3C_0_SPD_DDRAF_CPU1_SCL @T6G_MB_LIB.T6G(SCH_1):I3C_0_SPD_DDRAF_CPU1_SCL    I63 @T6G_MB_LIB.T6G(SCH_1):PAGE136
     3 I3C_SCM_2_R_SCL @T6G_MB_LIB.T6G(SCH_1):I3C_SCM_2_R_SCL    I63 @T6G_MB_LIB.T6G(SCH_1):PAGE136
     4 I3C_SCM_2_R_SDA @T6G_MB_LIB.T6G(SCH_1):I3C_SCM_2_R_SDA    I63 @T6G_MB_LIB.T6G(SCH_1):PAGE136
     7 I3C_SPD_DDRAF_CPU1_LVC1_SDA @T6G_MB_LIB.T6G(SCH_1):I3C_SPD_DDRAF_CPU1_LVC1_SDA    I63 @T6G_MB_LIB.T6G(SCH_1):PAGE136
     6 FM_I3C_CPU1_MUX0_OE_N @T6G_MB_LIB.T6G(SCH_1):FM_I3C_CPU1_MUX0_OE_N    I63 @T6G_MB_LIB.T6G(SCH_1):PAGE136
     9 FM_I3C_CPU1_MUX0_SEL @T6G_MB_LIB.T6G(SCH_1):FM_I3C_CPU1_MUX0_SEL    I63 @T6G_MB_LIB.T6G(SCH_1):PAGE136
    10 P3V3_AUX @T6G_MB_LIB.T6G(SCH_1):P3V3_AUX    I63 @T6G_MB_LIB.T6G(SCH_1):PAGE136
     2 I3C_0_SPD_DDRAF_CPU1_SDA @T6G_MB_LIB.T6G(SCH_1):I3C_0_SPD_DDRAF_CPU1_SDA    I63 @T6G_MB_LIB.T6G(SCH_1):PAGE136
     5    GND @T6G_MB_LIB.T6G(SCH_1):GND    I63 @T6G_MB_LIB.T6G(SCH_1):PAGE136
     8 I3C_SPD_DDRAF_CPU1_LVC1_SCL @T6G_MB_LIB.T6G(SCH_1):I3C_SPD_DDRAF_CPU1_LVC1_SCL    I63 @T6G_MB_LIB.T6G(SCH_1):PAGE136

U108 PI3CSW12ZUAEX-PI3CSW12ZUAEX,SMLF,IC,AL3CSW12000
     1 I3C_1_SPD_DDRGL_CPU1_SCL @T6G_MB_LIB.T6G(SCH_1):I3C_1_SPD_DDRGL_CPU1_SCL    I68 @T6G_MB_LIB.T6G(SCH_1):PAGE136
     3 I3C_SCM_3_R_SCL @T6G_MB_LIB.T6G(SCH_1):I3C_SCM_3_R_SCL    I68 @T6G_MB_LIB.T6G(SCH_1):PAGE136
     4 I3C_SCM_3_R_SDA @T6G_MB_LIB.T6G(SCH_1):I3C_SCM_3_R_SDA    I68 @T6G_MB_LIB.T6G(SCH_1):PAGE136
     7 I3C_SPD_DDRGL_CPU1_LVC1_SDA @T6G_MB_LIB.T6G(SCH_1):I3C_SPD_DDRGL_CPU1_LVC1_SDA    I68 @T6G_MB_LIB.T6G(SCH_1):PAGE136
     6 FM_I3C_CPU1_MUX1_OE_N @T6G_MB_LIB.T6G(SCH_1):FM_I3C_CPU1_MUX1_OE_N    I68 @T6G_MB_LIB.T6G(SCH_1):PAGE136
     9 FM_I3C_CPU1_MUX1_SEL @T6G_MB_LIB.T6G(SCH_1):FM_I3C_CPU1_MUX1_SEL    I68 @T6G_MB_LIB.T6G(SCH_1):PAGE136
    10 P3V3_AUX @T6G_MB_LIB.T6G(SCH_1):P3V3_AUX    I68 @T6G_MB_LIB.T6G(SCH_1):PAGE136
     2 I3C_1_SPD_DDRGL_CPU1_SDA @T6G_MB_LIB.T6G(SCH_1):I3C_1_SPD_DDRGL_CPU1_SDA    I68 @T6G_MB_LIB.T6G(SCH_1):PAGE136
     5    GND @T6G_MB_LIB.T6G(SCH_1):GND    I68 @T6G_MB_LIB.T6G(SCH_1):PAGE136
     8 I3C_SPD_DDRGL_CPU1_LVC1_SCL @T6G_MB_LIB.T6G(SCH_1):I3C_SPD_DDRGL_CPU1_LVC1_SCL    I68 @T6G_MB_LIB.T6G(SCH_1):PAGE136

U116 SN74AVC4T774PWR-SN74AVC4T774PWR,SMLF,IC,AL04T774K00
     1 PVDD18_S5_P0 @T6G_MB_LIB.T6G(SCH_1):PVDD18_S5_P0   I117 @T6G_MB_LIB.T6G(SCH_1):PAGE141
     2    GND @T6G_MB_LIB.T6G(SCH_1):GND   I117 @T6G_MB_LIB.T6G(SCH_1):PAGE141
     3 UART_CPU0_SCM_UART1_TX @T6G_MB_LIB.T6G(SCH_1):UART_CPU0_SCM_UART1_TX   I117 @T6G_MB_LIB.T6G(SCH_1):PAGE141
     4 UART_CPU0_SCM_UART1_R_RX @T6G_MB_LIB.T6G(SCH_1):UART_CPU0_SCM_UART1_R_RX   I117 @T6G_MB_LIB.T6G(SCH_1):PAGE141
     5 UART_CPU0_UART0_TX @T6G_MB_LIB.T6G(SCH_1):UART_CPU0_UART0_TX   I117 @T6G_MB_LIB.T6G(SCH_1):PAGE141
     6 UART_CPU0_UART0_R_RX @T6G_MB_LIB.T6G(SCH_1):UART_CPU0_UART0_R_RX   I117 @T6G_MB_LIB.T6G(SCH_1):PAGE141
     7 PVDD18_S5_P0 @T6G_MB_LIB.T6G(SCH_1):PVDD18_S5_P0   I117 @T6G_MB_LIB.T6G(SCH_1):PAGE141
     8    GND @T6G_MB_LIB.T6G(SCH_1):GND   I117 @T6G_MB_LIB.T6G(SCH_1):PAGE141
     9 UART_LS_EN_N @T6G_MB_LIB.T6G(SCH_1):UART_LS_EN_N   I117 @T6G_MB_LIB.T6G(SCH_1):PAGE141
    10    GND @T6G_MB_LIB.T6G(SCH_1):GND   I117 @T6G_MB_LIB.T6G(SCH_1):PAGE141
    11 UART_CPU0_LVC3_UART0_R_RX @T6G_MB_LIB.T6G(SCH_1):UART_CPU0_LVC3_UART0_R_RX   I117 @T6G_MB_LIB.T6G(SCH_1):PAGE141
    12 UART_CPU0_LVC3_UART0_R_TX @T6G_MB_LIB.T6G(SCH_1):UART_CPU0_LVC3_UART0_R_TX   I117 @T6G_MB_LIB.T6G(SCH_1):PAGE141
    13 UART_CPU0_SCM_LVC3_UART1_R_RX @T6G_MB_LIB.T6G(SCH_1):UART_CPU0_SCM_LVC3_UART1_R_RX   I117 @T6G_MB_LIB.T6G(SCH_1):PAGE141
    14 UART_CPU0_SCM_LVC3_UART1_R_TX @T6G_MB_LIB.T6G(SCH_1):UART_CPU0_SCM_LVC3_UART1_R_TX   I117 @T6G_MB_LIB.T6G(SCH_1):PAGE141
    15 P3V3_AUX @T6G_MB_LIB.T6G(SCH_1):P3V3_AUX   I117 @T6G_MB_LIB.T6G(SCH_1):PAGE141
    16 PVDD18_S5_P0 @T6G_MB_LIB.T6G(SCH_1):PVDD18_S5_P0   I117 @T6G_MB_LIB.T6G(SCH_1):PAGE141

U124 SN74LVC1G07DBVR_SMLF-SN74LVC1G07DBVR,IC,AL1G0007024
     2 FM_JTAG_BMC_R_OE @T6G_MB_LIB.T6G(SCH_1):FM_JTAG_BMC_R_OE    I38 @T6G_MB_LIB.T6G(SCH_1):PAGE144
     4 JTAG_BMC_OE @T6G_MB_LIB.T6G(SCH_1):JTAG_BMC_OE    I38 @T6G_MB_LIB.T6G(SCH_1):PAGE144
     1     NC     NC    I38 @T6G_MB_LIB.T6G(SCH_1):PAGE144
     5 U124_VCC @T6G_MB_LIB.T6G(SCH_1):U124_VCC    I38 @T6G_MB_LIB.T6G(SCH_1):PAGE144
     3    GND @T6G_MB_LIB.T6G(SCH_1):GND    I38 @T6G_MB_LIB.T6G(SCH_1):PAGE144

U134 74LVC2G07DW7-74LVC2G07DW-7,SMLF,IC,AL002G07003
     1 RST_SMB_E1S_N @T6G_MB_LIB.T6G(SCH_1):RST_SMB_E1S_N     I4 @T6G_MB_LIB.T6G(SCH_1):PAGE297
     3 RST_SMB_E1S_N @T6G_MB_LIB.T6G(SCH_1):RST_SMB_E1S_N     I4 @T6G_MB_LIB.T6G(SCH_1):PAGE297
     6 RST_SMB_BUF_E1S_0_N @T6G_MB_LIB.T6G(SCH_1):RST_SMB_BUF_E1S_0_N     I4 @T6G_MB_LIB.T6G(SCH_1):PAGE297
     4 SMB_PCIE_E1S_ISO_EN_R2 @T6G_MB_LIB.T6G(SCH_1):SMB_PCIE_E1S_ISO_EN_R2     I4 @T6G_MB_LIB.T6G(SCH_1):PAGE297
     2    GND @T6G_MB_LIB.T6G(SCH_1):GND     I4 @T6G_MB_LIB.T6G(SCH_1):PAGE297
     5 P3V3_AUX @T6G_MB_LIB.T6G(SCH_1):P3V3_AUX     I4 @T6G_MB_LIB.T6G(SCH_1):PAGE297

U142 LT6700CS61TRPBF-LT6700CS6-1#TRPBF,SMLF,EMPTY,AL006A
     5 U142_VS @T6G_MB_LIB.T6G(SCH_1):U142_VS    I50 @T6G_MB_LIB.T6G(SCH_1):PAGE371
     4 A_HSC_HIGH @T6G_MB_LIB.T6G(SCH_1):A_HSC_HIGH    I50 @T6G_MB_LIB.T6G(SCH_1):PAGE371
     2    GND @T6G_MB_LIB.T6G(SCH_1):GND    I50 @T6G_MB_LIB.T6G(SCH_1):PAGE371
     1 A_HSC_LOW_GATE @T6G_MB_LIB.T6G(SCH_1):A_HSC_LOW_GATE    I50 @T6G_MB_LIB.T6G(SCH_1):PAGE371
     3 A_HSC_LOW @T6G_MB_LIB.T6G(SCH_1):A_HSC_LOW    I50 @T6G_MB_LIB.T6G(SCH_1):PAGE371
     6 HSC_D_OC @T6G_MB_LIB.T6G(SCH_1):HSC_D_OC    I50 @T6G_MB_LIB.T6G(SCH_1):PAGE371

U143 NCT7718W-NCT7718W,SMLF,IC,AL007718001
     1 P3V3_AUX @T6G_MB_LIB.T6G(SCH_1):P3V3_AUX     I8 @T6G_MB_LIB.T6G(SCH_1):PAGE371
     2 P12V_HSC_TEMP_D+ @T6G_MB_LIB.T6G(SCH_1):P12V_HSC_TEMP_D+     I8 @T6G_MB_LIB.T6G(SCH_1):PAGE371
     3 P12V_HSC_TEMP_D- @T6G_MB_LIB.T6G(SCH_1):P12V_HSC_TEMP_D-     I8 @T6G_MB_LIB.T6G(SCH_1):PAGE371
     4 P12V_HSC_T_CRIT_N @T6G_MB_LIB.T6G(SCH_1):P12V_HSC_T_CRIT_N     I8 @T6G_MB_LIB.T6G(SCH_1):PAGE371
     5    GND @T6G_MB_LIB.T6G(SCH_1):GND     I8 @T6G_MB_LIB.T6G(SCH_1):PAGE371
     6 P12V_HSC_TEMP_ALERT_N @T6G_MB_LIB.T6G(SCH_1):P12V_HSC_TEMP_ALERT_N     I8 @T6G_MB_LIB.T6G(SCH_1):PAGE371
     7 SMB_P12V_HSC_TEMP_SDA @T6G_MB_LIB.T6G(SCH_1):SMB_P12V_HSC_TEMP_SDA     I8 @T6G_MB_LIB.T6G(SCH_1):PAGE371
     8 SMB_P12V_HSC_TEMP_SCL @T6G_MB_LIB.T6G(SCH_1):SMB_P12V_HSC_TEMP_SCL     I8 @T6G_MB_LIB.T6G(SCH_1):PAGE371

U146 SN74AVC2T245RSWR-SN74AVC2T245RSWR,SMLF,IC,AL02T245A
     1    GND @T6G_MB_LIB.T6G(SCH_1):GND    I76 @T6G_MB_LIB.T6G(SCH_1):PAGE149
     2 JTAG_BMC_R_D_OE @T6G_MB_LIB.T6G(SCH_1):JTAG_BMC_R_D_OE    I76 @T6G_MB_LIB.T6G(SCH_1):PAGE149
     3    GND @T6G_MB_LIB.T6G(SCH_1):GND    I76 @T6G_MB_LIB.T6G(SCH_1):PAGE149
     4 JTAG_TDO_R1 @T6G_MB_LIB.T6G(SCH_1):JTAG_TDO_R1    I76 @T6G_MB_LIB.T6G(SCH_1):PAGE149
     5 JTAG_TDI_R @T6G_MB_LIB.T6G(SCH_1):JTAG_TDI_R    I76 @T6G_MB_LIB.T6G(SCH_1):PAGE149
     6 PVDD18_S5_P0 @T6G_MB_LIB.T6G(SCH_1):PVDD18_S5_P0    I76 @T6G_MB_LIB.T6G(SCH_1):PAGE149
     7 PVDD18_S5_P0 @T6G_MB_LIB.T6G(SCH_1):PVDD18_S5_P0    I76 @T6G_MB_LIB.T6G(SCH_1):PAGE149
     8 HDT_HDR_TDI @T6G_MB_LIB.T6G(SCH_1):HDT_HDR_TDI    I76 @T6G_MB_LIB.T6G(SCH_1):PAGE149
     9 HDT_HDR_TDO_R @T6G_MB_LIB.T6G(SCH_1):HDT_HDR_TDO_R    I76 @T6G_MB_LIB.T6G(SCH_1):PAGE149
    10 PVDD18_S5_P0 @T6G_MB_LIB.T6G(SCH_1):PVDD18_S5_P0    I76 @T6G_MB_LIB.T6G(SCH_1):PAGE149

U147 SN74AVC2T245RSWR-SN74AVC2T245RSWR,SMLF,IC,AL02T245A
     1    GND @T6G_MB_LIB.T6G(SCH_1):GND     I1 @T6G_MB_LIB.T6G(SCH_1):PAGE149
     2 JTAG_BMC_OE_N @T6G_MB_LIB.T6G(SCH_1):JTAG_BMC_OE_N     I1 @T6G_MB_LIB.T6G(SCH_1):PAGE149
     3    GND @T6G_MB_LIB.T6G(SCH_1):GND     I1 @T6G_MB_LIB.T6G(SCH_1):PAGE149
     4 JTAG_TDO_R1 @T6G_MB_LIB.T6G(SCH_1):JTAG_TDO_R1     I1 @T6G_MB_LIB.T6G(SCH_1):PAGE149
     5 JTAG_TDI_R @T6G_MB_LIB.T6G(SCH_1):JTAG_TDI_R     I1 @T6G_MB_LIB.T6G(SCH_1):PAGE149
     6 PVDD18_S5_P0 @T6G_MB_LIB.T6G(SCH_1):PVDD18_S5_P0     I1 @T6G_MB_LIB.T6G(SCH_1):PAGE149
     7 P3V3_AUX @T6G_MB_LIB.T6G(SCH_1):P3V3_AUX     I1 @T6G_MB_LIB.T6G(SCH_1):PAGE149
     8 JTAG_SCM_MUX_TDO @T6G_MB_LIB.T6G(SCH_1):JTAG_SCM_MUX_TDO     I1 @T6G_MB_LIB.T6G(SCH_1):PAGE149
     9 JTAG_SCM_MUX_TDI @T6G_MB_LIB.T6G(SCH_1):JTAG_SCM_MUX_TDI     I1 @T6G_MB_LIB.T6G(SCH_1):PAGE149
    10 P3V3_AUX @T6G_MB_LIB.T6G(SCH_1):P3V3_AUX     I1 @T6G_MB_LIB.T6G(SCH_1):PAGE149

U148 SN74AVC4T774PWR-SN74AVC4T774PWR,SMLF,IC,AL04T774K00
     1 P3V3_AUX @T6G_MB_LIB.T6G(SCH_1):P3V3_AUX    I34 @T6G_MB_LIB.T6G(SCH_1):PAGE149
     2 P3V3_AUX @T6G_MB_LIB.T6G(SCH_1):P3V3_AUX    I34 @T6G_MB_LIB.T6G(SCH_1):PAGE149
     3 JTAG_SCM_MUX_TCK @T6G_MB_LIB.T6G(SCH_1):JTAG_SCM_MUX_TCK    I34 @T6G_MB_LIB.T6G(SCH_1):PAGE149
     4 JTAG_SCM_MUX_TMS @T6G_MB_LIB.T6G(SCH_1):JTAG_SCM_MUX_TMS    I34 @T6G_MB_LIB.T6G(SCH_1):PAGE149
     5 JTAG_SCM_TRST_N @T6G_MB_LIB.T6G(SCH_1):JTAG_SCM_TRST_N    I34 @T6G_MB_LIB.T6G(SCH_1):PAGE149
     6 JTAG_SCM_DBREQ_N @T6G_MB_LIB.T6G(SCH_1):JTAG_SCM_DBREQ_N    I34 @T6G_MB_LIB.T6G(SCH_1):PAGE149
     7 P3V3_AUX @T6G_MB_LIB.T6G(SCH_1):P3V3_AUX    I34 @T6G_MB_LIB.T6G(SCH_1):PAGE149
     8 P3V3_AUX @T6G_MB_LIB.T6G(SCH_1):P3V3_AUX    I34 @T6G_MB_LIB.T6G(SCH_1):PAGE149
     9 JTAG_BMC_OE_N @T6G_MB_LIB.T6G(SCH_1):JTAG_BMC_OE_N    I34 @T6G_MB_LIB.T6G(SCH_1):PAGE149
    10    GND @T6G_MB_LIB.T6G(SCH_1):GND    I34 @T6G_MB_LIB.T6G(SCH_1):PAGE149
    11 JTAG_DBREQ_R_N @T6G_MB_LIB.T6G(SCH_1):JTAG_DBREQ_R_N    I34 @T6G_MB_LIB.T6G(SCH_1):PAGE149
    12 JTAG_TRST_R_N @T6G_MB_LIB.T6G(SCH_1):JTAG_TRST_R_N    I34 @T6G_MB_LIB.T6G(SCH_1):PAGE149
    13 JTAG_TMS_R @T6G_MB_LIB.T6G(SCH_1):JTAG_TMS_R    I34 @T6G_MB_LIB.T6G(SCH_1):PAGE149
    14 JTAG_TCK_R @T6G_MB_LIB.T6G(SCH_1):JTAG_TCK_R    I34 @T6G_MB_LIB.T6G(SCH_1):PAGE149
    15 PVDD18_S5_P0 @T6G_MB_LIB.T6G(SCH_1):PVDD18_S5_P0    I34 @T6G_MB_LIB.T6G(SCH_1):PAGE149
    16 P3V3_AUX @T6G_MB_LIB.T6G(SCH_1):P3V3_AUX    I34 @T6G_MB_LIB.T6G(SCH_1):PAGE149

U149 SN74AVC4T774PWR-SN74AVC4T774PWR,SMLF,IC,AL04T774K00
     1 PVDD18_S5_P0 @T6G_MB_LIB.T6G(SCH_1):PVDD18_S5_P0    I31 @T6G_MB_LIB.T6G(SCH_1):PAGE149
     2 PVDD18_S5_P0 @T6G_MB_LIB.T6G(SCH_1):PVDD18_S5_P0    I31 @T6G_MB_LIB.T6G(SCH_1):PAGE149
     3 HDT_HDR_TCK @T6G_MB_LIB.T6G(SCH_1):HDT_HDR_TCK    I31 @T6G_MB_LIB.T6G(SCH_1):PAGE149
     4 HDT_HDR_TMS @T6G_MB_LIB.T6G(SCH_1):HDT_HDR_TMS    I31 @T6G_MB_LIB.T6G(SCH_1):PAGE149
     5 HDT_HDR_TRST_N @T6G_MB_LIB.T6G(SCH_1):HDT_HDR_TRST_N    I31 @T6G_MB_LIB.T6G(SCH_1):PAGE149
     6 HDT_HDR_DBREQ_N @T6G_MB_LIB.T6G(SCH_1):HDT_HDR_DBREQ_N    I31 @T6G_MB_LIB.T6G(SCH_1):PAGE149
     7 PVDD18_S5_P0 @T6G_MB_LIB.T6G(SCH_1):PVDD18_S5_P0    I31 @T6G_MB_LIB.T6G(SCH_1):PAGE149
     8 PVDD18_S5_P0 @T6G_MB_LIB.T6G(SCH_1):PVDD18_S5_P0    I31 @T6G_MB_LIB.T6G(SCH_1):PAGE149
     9 JTAG_BMC_R_D_OE @T6G_MB_LIB.T6G(SCH_1):JTAG_BMC_R_D_OE    I31 @T6G_MB_LIB.T6G(SCH_1):PAGE149
    10    GND @T6G_MB_LIB.T6G(SCH_1):GND    I31 @T6G_MB_LIB.T6G(SCH_1):PAGE149
    11 JTAG_DBREQ_R_N @T6G_MB_LIB.T6G(SCH_1):JTAG_DBREQ_R_N    I31 @T6G_MB_LIB.T6G(SCH_1):PAGE149
    12 JTAG_TRST_R_N @T6G_MB_LIB.T6G(SCH_1):JTAG_TRST_R_N    I31 @T6G_MB_LIB.T6G(SCH_1):PAGE149
    13 JTAG_TMS_R @T6G_MB_LIB.T6G(SCH_1):JTAG_TMS_R    I31 @T6G_MB_LIB.T6G(SCH_1):PAGE149
    14 JTAG_TCK_R @T6G_MB_LIB.T6G(SCH_1):JTAG_TCK_R    I31 @T6G_MB_LIB.T6G(SCH_1):PAGE149
    15 PVDD18_S5_P0 @T6G_MB_LIB.T6G(SCH_1):PVDD18_S5_P0    I31 @T6G_MB_LIB.T6G(SCH_1):PAGE149
    16 PVDD18_S5_P0 @T6G_MB_LIB.T6G(SCH_1):PVDD18_S5_P0    I31 @T6G_MB_LIB.T6G(SCH_1):PAGE149

U150 SN74AVC4T774PWR-SN74AVC4T774PWR,SMLF,IC,AL04T774K00
     1 PVDD18_S5_P0 @T6G_MB_LIB.T6G(SCH_1):PVDD18_S5_P0     I8 @T6G_MB_LIB.T6G(SCH_1):PAGE150
     2 PVDD18_S5_P0 @T6G_MB_LIB.T6G(SCH_1):PVDD18_S5_P0     I8 @T6G_MB_LIB.T6G(SCH_1):PAGE150
     3 JTAG_TCK @T6G_MB_LIB.T6G(SCH_1):JTAG_TCK     I8 @T6G_MB_LIB.T6G(SCH_1):PAGE150
     4 JTAG_TMS @T6G_MB_LIB.T6G(SCH_1):JTAG_TMS     I8 @T6G_MB_LIB.T6G(SCH_1):PAGE150
     5 JTAG_TRST_N @T6G_MB_LIB.T6G(SCH_1):JTAG_TRST_N     I8 @T6G_MB_LIB.T6G(SCH_1):PAGE150
     6 JTAG_DBREQ_N @T6G_MB_LIB.T6G(SCH_1):JTAG_DBREQ_N     I8 @T6G_MB_LIB.T6G(SCH_1):PAGE150
     7 PVDD18_S5_P0 @T6G_MB_LIB.T6G(SCH_1):PVDD18_S5_P0     I8 @T6G_MB_LIB.T6G(SCH_1):PAGE150
     8 PVDD18_S5_P0 @T6G_MB_LIB.T6G(SCH_1):PVDD18_S5_P0     I8 @T6G_MB_LIB.T6G(SCH_1):PAGE150
     9 CPU0_JTAG_BUF_OE @T6G_MB_LIB.T6G(SCH_1):CPU0_JTAG_BUF_OE     I8 @T6G_MB_LIB.T6G(SCH_1):PAGE150
    10    GND @T6G_MB_LIB.T6G(SCH_1):GND     I8 @T6G_MB_LIB.T6G(SCH_1):PAGE150
    11 JTAG_P0_R_DBREQ_N @T6G_MB_LIB.T6G(SCH_1):JTAG_P0_R_DBREQ_N     I8 @T6G_MB_LIB.T6G(SCH_1):PAGE150
    12 JTAG_P0_R_TRST_N @T6G_MB_LIB.T6G(SCH_1):JTAG_P0_R_TRST_N     I8 @T6G_MB_LIB.T6G(SCH_1):PAGE150
    13 JTAG_P0_R_TMS @T6G_MB_LIB.T6G(SCH_1):JTAG_P0_R_TMS     I8 @T6G_MB_LIB.T6G(SCH_1):PAGE150
    14 JTAG_P0_R_TCK @T6G_MB_LIB.T6G(SCH_1):JTAG_P0_R_TCK     I8 @T6G_MB_LIB.T6G(SCH_1):PAGE150
    15 PVDD18_S5_P0 @T6G_MB_LIB.T6G(SCH_1):PVDD18_S5_P0     I8 @T6G_MB_LIB.T6G(SCH_1):PAGE150
    16 PVDD18_S5_P0 @T6G_MB_LIB.T6G(SCH_1):PVDD18_S5_P0     I8 @T6G_MB_LIB.T6G(SCH_1):PAGE150

U151 SN74AVC4T774PWR-SN74AVC4T774PWR,SMLF,IC,AL04T774K00
     1 PVDD18_S5_P0 @T6G_MB_LIB.T6G(SCH_1):PVDD18_S5_P0    I28 @T6G_MB_LIB.T6G(SCH_1):PAGE150
     2 PVDD18_S5_P0 @T6G_MB_LIB.T6G(SCH_1):PVDD18_S5_P0    I28 @T6G_MB_LIB.T6G(SCH_1):PAGE150
     3 JTAG_TCK @T6G_MB_LIB.T6G(SCH_1):JTAG_TCK    I28 @T6G_MB_LIB.T6G(SCH_1):PAGE150
     4 JTAG_TMS @T6G_MB_LIB.T6G(SCH_1):JTAG_TMS    I28 @T6G_MB_LIB.T6G(SCH_1):PAGE150
     5 JTAG_TRST_N @T6G_MB_LIB.T6G(SCH_1):JTAG_TRST_N    I28 @T6G_MB_LIB.T6G(SCH_1):PAGE150
     6 JTAG_DBREQ_N @T6G_MB_LIB.T6G(SCH_1):JTAG_DBREQ_N    I28 @T6G_MB_LIB.T6G(SCH_1):PAGE150
     7 PVDD18_S5_P0 @T6G_MB_LIB.T6G(SCH_1):PVDD18_S5_P0    I28 @T6G_MB_LIB.T6G(SCH_1):PAGE150
     8 PVDD18_S5_P0 @T6G_MB_LIB.T6G(SCH_1):PVDD18_S5_P0    I28 @T6G_MB_LIB.T6G(SCH_1):PAGE150
     9 CPU1_JTAG_BUF_OE @T6G_MB_LIB.T6G(SCH_1):CPU1_JTAG_BUF_OE    I28 @T6G_MB_LIB.T6G(SCH_1):PAGE150
    10    GND @T6G_MB_LIB.T6G(SCH_1):GND    I28 @T6G_MB_LIB.T6G(SCH_1):PAGE150
    11 JTAG_P1_R_DBREQ_N @T6G_MB_LIB.T6G(SCH_1):JTAG_P1_R_DBREQ_N    I28 @T6G_MB_LIB.T6G(SCH_1):PAGE150
    12 JTAG_P1_R_TRST_N @T6G_MB_LIB.T6G(SCH_1):JTAG_P1_R_TRST_N    I28 @T6G_MB_LIB.T6G(SCH_1):PAGE150
    13 JTAG_P1_R_TMS @T6G_MB_LIB.T6G(SCH_1):JTAG_P1_R_TMS    I28 @T6G_MB_LIB.T6G(SCH_1):PAGE150
    14 JTAG_P1_R_TCK @T6G_MB_LIB.T6G(SCH_1):JTAG_P1_R_TCK    I28 @T6G_MB_LIB.T6G(SCH_1):PAGE150
    15 PVDD18_S5_P1 @T6G_MB_LIB.T6G(SCH_1):PVDD18_S5_P1    I28 @T6G_MB_LIB.T6G(SCH_1):PAGE150
    16 PVDD18_S5_P0 @T6G_MB_LIB.T6G(SCH_1):PVDD18_S5_P0    I28 @T6G_MB_LIB.T6G(SCH_1):PAGE150

U152 SN74AVC2T245RSWR-SN74AVC2T245RSWR,SMLF,IC,AL02T245A
     1    GND @T6G_MB_LIB.T6G(SCH_1):GND    I60 @T6G_MB_LIB.T6G(SCH_1):PAGE150
     2 U152_OE_N @T6G_MB_LIB.T6G(SCH_1):U152_OE_N    I60 @T6G_MB_LIB.T6G(SCH_1):PAGE150
     3    GND @T6G_MB_LIB.T6G(SCH_1):GND    I60 @T6G_MB_LIB.T6G(SCH_1):PAGE150
     4 JTAG_CPUX_TDO @T6G_MB_LIB.T6G(SCH_1):JTAG_CPUX_TDO    I60 @T6G_MB_LIB.T6G(SCH_1):PAGE150
     5 JTAG_CPUX_TDI_R1 @T6G_MB_LIB.T6G(SCH_1):JTAG_CPUX_TDI_R1    I60 @T6G_MB_LIB.T6G(SCH_1):PAGE150
     6 PVDD18_S5_P0 @T6G_MB_LIB.T6G(SCH_1):PVDD18_S5_P0    I60 @T6G_MB_LIB.T6G(SCH_1):PAGE150
     7 PVDD18_S5_P0 @T6G_MB_LIB.T6G(SCH_1):PVDD18_S5_P0    I60 @T6G_MB_LIB.T6G(SCH_1):PAGE150
     8 JTAG_TDI @T6G_MB_LIB.T6G(SCH_1):JTAG_TDI    I60 @T6G_MB_LIB.T6G(SCH_1):PAGE150
     9 JTAG_TDO_R @T6G_MB_LIB.T6G(SCH_1):JTAG_TDO_R    I60 @T6G_MB_LIB.T6G(SCH_1):PAGE150
    10 PVDD18_S5_P0 @T6G_MB_LIB.T6G(SCH_1):PVDD18_S5_P0    I60 @T6G_MB_LIB.T6G(SCH_1):PAGE150

U153 SN74AUC2G66DCTR-SN74AUC2G66DCTR,SMLF,IC,AL2G0066C00
     1 JTAG_CPUX_TDI @T6G_MB_LIB.T6G(SCH_1):JTAG_CPUX_TDI     I1 @T6G_MB_LIB.T6G(SCH_1):PAGE151
     7 CPU0_HDT_BYPASS_SEL @T6G_MB_LIB.T6G(SCH_1):CPU0_HDT_BYPASS_SEL     I1 @T6G_MB_LIB.T6G(SCH_1):PAGE151
     5 JTAG_CPUX_TDI @T6G_MB_LIB.T6G(SCH_1):JTAG_CPUX_TDI     I1 @T6G_MB_LIB.T6G(SCH_1):PAGE151
     3 FM_PLD_CPU0_PRSNT_HDT_N @T6G_MB_LIB.T6G(SCH_1):FM_PLD_CPU0_PRSNT_HDT_N     I1 @T6G_MB_LIB.T6G(SCH_1):PAGE151
     8 PVDD18_S5_P0 @T6G_MB_LIB.T6G(SCH_1):PVDD18_S5_P0     I1 @T6G_MB_LIB.T6G(SCH_1):PAGE151
     4    GND @T6G_MB_LIB.T6G(SCH_1):GND     I1 @T6G_MB_LIB.T6G(SCH_1):PAGE151
     2 JTAG_CPU0_R_TDI @T6G_MB_LIB.T6G(SCH_1):JTAG_CPU0_R_TDI     I1 @T6G_MB_LIB.T6G(SCH_1):PAGE151
     6 JTAG_CPU0_BYPASS @T6G_MB_LIB.T6G(SCH_1):JTAG_CPU0_BYPASS     I1 @T6G_MB_LIB.T6G(SCH_1):PAGE151

U154 SN74AUC2G66DCTR-SN74AUC2G66DCTR,SMLF,IC,AL2G0066C00
     1 JTAG_CPU1_TDO @T6G_MB_LIB.T6G(SCH_1):JTAG_CPU1_TDO    I31 @T6G_MB_LIB.T6G(SCH_1):PAGE151
     7 CPU1_HDT_BYPASS_SEL @T6G_MB_LIB.T6G(SCH_1):CPU1_HDT_BYPASS_SEL    I31 @T6G_MB_LIB.T6G(SCH_1):PAGE151
     5 JTAG_CPU1_BYPASS @T6G_MB_LIB.T6G(SCH_1):JTAG_CPU1_BYPASS    I31 @T6G_MB_LIB.T6G(SCH_1):PAGE151
     3 FM_PLD_CPU1_PRSNT_HDT_N @T6G_MB_LIB.T6G(SCH_1):FM_PLD_CPU1_PRSNT_HDT_N    I31 @T6G_MB_LIB.T6G(SCH_1):PAGE151
     8 PVDD18_S5_P0 @T6G_MB_LIB.T6G(SCH_1):PVDD18_S5_P0    I31 @T6G_MB_LIB.T6G(SCH_1):PAGE151
     4    GND @T6G_MB_LIB.T6G(SCH_1):GND    I31 @T6G_MB_LIB.T6G(SCH_1):PAGE151
     2 JTAG_CPUX_TDO_R @T6G_MB_LIB.T6G(SCH_1):JTAG_CPUX_TDO_R    I31 @T6G_MB_LIB.T6G(SCH_1):PAGE151
     6 JTAG_CPUX_TDO_R @T6G_MB_LIB.T6G(SCH_1):JTAG_CPUX_TDO_R    I31 @T6G_MB_LIB.T6G(SCH_1):PAGE151

U157 74LVC1G07GV-74LVC1G07GV,SMLF,IC,AL1G0007001
     5 P3V3_AUX @T6G_MB_LIB.T6G(SCH_1):P3V3_AUX    I25 @T6G_MB_LIB.T6G(SCH_1):PAGE337
     2 OCP_SFF_WAKE_BUFF_R_N @T6G_MB_LIB.T6G(SCH_1):OCP_SFF_WAKE_BUFF_R_N    I25 @T6G_MB_LIB.T6G(SCH_1):PAGE337
     3    GND @T6G_MB_LIB.T6G(SCH_1):GND    I25 @T6G_MB_LIB.T6G(SCH_1):PAGE337
     4 IRQ_LVC3_WAKE_BUF_N @T6G_MB_LIB.T6G(SCH_1):IRQ_LVC3_WAKE_BUF_N    I25 @T6G_MB_LIB.T6G(SCH_1):PAGE337
     1 NC_U157_NC1 @T6G_MB_LIB.T6G(SCH_1):NC_U157_NC1    I25 @T6G_MB_LIB.T6G(SCH_1):PAGE337

U158 MOSFET_NCH_GDS_ESD_PROTECTED-2N7002K,SMLF,IC,BAM70A
     D FM_P12V_HSC_EN_N @T6G_MB_LIB.T6G(SCH_1):FM_P12V_HSC_EN_N     I6 @T6G_MB_LIB.T6G(SCH_1):PAGE365
     G FM_P12V_HSC_EN_R @T6G_MB_LIB.T6G(SCH_1):FM_P12V_HSC_EN_R     I6 @T6G_MB_LIB.T6G(SCH_1):PAGE365
     S    GND @T6G_MB_LIB.T6G(SCH_1):GND     I6 @T6G_MB_LIB.T6G(SCH_1):PAGE365

U160 74LV4052PW-74LV4052PW,SMLF,IC,ALLV4052K19
     1 TP_JTAG_SCM_SLOT3_R_TMS @T6G_MB_LIB.T6G(SCH_1):TP_JTAG_SCM_SLOT3_R_TMS   I266 @T6G_MB_LIB.T6G(SCH_1):PAGE148
     2 JTAG_SCM_PLD_R_TMS @T6G_MB_LIB.T6G(SCH_1):JTAG_SCM_PLD_R_TMS   I266 @T6G_MB_LIB.T6G(SCH_1):PAGE148
     3 JTAG_SCM_TMS @T6G_MB_LIB.T6G(SCH_1):JTAG_SCM_TMS   I266 @T6G_MB_LIB.T6G(SCH_1):PAGE148
     4 JTAG_SCM_PLD_R_TMS @T6G_MB_LIB.T6G(SCH_1):JTAG_SCM_PLD_R_TMS   I266 @T6G_MB_LIB.T6G(SCH_1):PAGE148
     5 JTAG_SCM_MUX_R_TMS @T6G_MB_LIB.T6G(SCH_1):JTAG_SCM_MUX_R_TMS   I266 @T6G_MB_LIB.T6G(SCH_1):PAGE148
     6 U160_EN_N @T6G_MB_LIB.T6G(SCH_1):U160_EN_N   I266 @T6G_MB_LIB.T6G(SCH_1):PAGE148
     7    GND @T6G_MB_LIB.T6G(SCH_1):GND   I266 @T6G_MB_LIB.T6G(SCH_1):PAGE148
     8    GND @T6G_MB_LIB.T6G(SCH_1):GND   I266 @T6G_MB_LIB.T6G(SCH_1):PAGE148
     9 SCM_JTAG_MUX_S1 @T6G_MB_LIB.T6G(SCH_1):SCM_JTAG_MUX_S1   I266 @T6G_MB_LIB.T6G(SCH_1):PAGE148
    10 SCM_JTAG_MUX_S0_R1 @T6G_MB_LIB.T6G(SCH_1):SCM_JTAG_MUX_S0_R1   I266 @T6G_MB_LIB.T6G(SCH_1):PAGE148
    11 JTAG_SCM_PLD_R_TCK @T6G_MB_LIB.T6G(SCH_1):JTAG_SCM_PLD_R_TCK   I266 @T6G_MB_LIB.T6G(SCH_1):PAGE148
    12 TP_JTAG_SCM_SLOT3_R_TCK @T6G_MB_LIB.T6G(SCH_1):TP_JTAG_SCM_SLOT3_R_TCK   I266 @T6G_MB_LIB.T6G(SCH_1):PAGE148
    13 JTAG_SCM_TCK @T6G_MB_LIB.T6G(SCH_1):JTAG_SCM_TCK   I266 @T6G_MB_LIB.T6G(SCH_1):PAGE148
    14 JTAG_SCM_MUX_R_TCK @T6G_MB_LIB.T6G(SCH_1):JTAG_SCM_MUX_R_TCK   I266 @T6G_MB_LIB.T6G(SCH_1):PAGE148
    15 JTAG_SCM_PLD_R_TCK @T6G_MB_LIB.T6G(SCH_1):JTAG_SCM_PLD_R_TCK   I266 @T6G_MB_LIB.T6G(SCH_1):PAGE148
    16 P3V3_AUX @T6G_MB_LIB.T6G(SCH_1):P3V3_AUX   I266 @T6G_MB_LIB.T6G(SCH_1):PAGE148

U166 SCHOTTKY_DUAL_12A_3C-BAT54CW,SMLF,IC,BCBAT54CZ13
     2 P3V_BAT_R @T6G_MB_LIB.T6G(SCH_1):P3V_BAT_R    I99 @T6G_MB_LIB.T6G(SCH_1):PAGE156
     1 P3V3_STBY_R @T6G_MB_LIB.T6G(SCH_1):P3V3_STBY_R    I99 @T6G_MB_LIB.T6G(SCH_1):PAGE156
     3 P3V3_RTC_AUX @T6G_MB_LIB.T6G(SCH_1):P3V3_RTC_AUX    I99 @T6G_MB_LIB.T6G(SCH_1):PAGE156

U167 NCP698SQ15T1G-NCP698SQ15T1G,SMLF,EMPTY,AL000698000
     1    GND @T6G_MB_LIB.T6G(SCH_1):GND   I130 @T6G_MB_LIB.T6G(SCH_1):PAGE156
     3 P1V5_BAT_OUT @T6G_MB_LIB.T6G(SCH_1):P1V5_BAT_OUT   I130 @T6G_MB_LIB.T6G(SCH_1):PAGE156
     2 P1V5_BAT_IN @T6G_MB_LIB.T6G(SCH_1):P1V5_BAT_IN   I130 @T6G_MB_LIB.T6G(SCH_1):PAGE156
     4 BAT_LDO_EN @T6G_MB_LIB.T6G(SCH_1):BAT_LDO_EN   I130 @T6G_MB_LIB.T6G(SCH_1):PAGE156

U175 LTC4307CMS8-LTC4307CMS8,SMLF,IC,AL004307000
     1 SMB_BMC_SWB_EN_R @T6G_MB_LIB.T6G(SCH_1):SMB_BMC_SWB_EN_R    I49 @T6G_MB_LIB.T6G(SCH_1):PAGE249
     3 SMB_BMC_SWB_R_SCL @T6G_MB_LIB.T6G(SCH_1):SMB_BMC_SWB_R_SCL    I49 @T6G_MB_LIB.T6G(SCH_1):PAGE249
     6 SMB_BMC_SWB_R_SDA @T6G_MB_LIB.T6G(SCH_1):SMB_BMC_SWB_R_SDA    I49 @T6G_MB_LIB.T6G(SCH_1):PAGE249
     2 SMB_BMC_SWB_BUF_R_SCL @T6G_MB_LIB.T6G(SCH_1):SMB_BMC_SWB_BUF_R_SCL    I49 @T6G_MB_LIB.T6G(SCH_1):PAGE249
     7 SMB_BMC_SWB_BUF_R_SDA @T6G_MB_LIB.T6G(SCH_1):SMB_BMC_SWB_BUF_R_SDA    I49 @T6G_MB_LIB.T6G(SCH_1):PAGE249
     5     NC     NC    I49 @T6G_MB_LIB.T6G(SCH_1):PAGE249
     4    GND @T6G_MB_LIB.T6G(SCH_1):GND    I49 @T6G_MB_LIB.T6G(SCH_1):PAGE249
     8 P3V3_AUX @T6G_MB_LIB.T6G(SCH_1):P3V3_AUX    I49 @T6G_MB_LIB.T6G(SCH_1):PAGE249

U176 LTC4307CMS8-LTC4307CMS8,SMLF,EMPTY,AL004307000
     1 SMB_BMC_SWB_EN_R2 @T6G_MB_LIB.T6G(SCH_1):SMB_BMC_SWB_EN_R2    I30 @T6G_MB_LIB.T6G(SCH_1):PAGE249
     3 I3C_BMC_SWB_R_SCL @T6G_MB_LIB.T6G(SCH_1):I3C_BMC_SWB_R_SCL    I30 @T6G_MB_LIB.T6G(SCH_1):PAGE249
     6 I3C_BMC_SWB_R_SDA @T6G_MB_LIB.T6G(SCH_1):I3C_BMC_SWB_R_SDA    I30 @T6G_MB_LIB.T6G(SCH_1):PAGE249
     2 I3C_BMC_SWB_BUF_R_SCL @T6G_MB_LIB.T6G(SCH_1):I3C_BMC_SWB_BUF_R_SCL    I30 @T6G_MB_LIB.T6G(SCH_1):PAGE249
     7 I3C_BMC_SWB_BUF_R_SDA @T6G_MB_LIB.T6G(SCH_1):I3C_BMC_SWB_BUF_R_SDA    I30 @T6G_MB_LIB.T6G(SCH_1):PAGE249
     5     NC     NC    I30 @T6G_MB_LIB.T6G(SCH_1):PAGE249
     4    GND @T6G_MB_LIB.T6G(SCH_1):GND    I30 @T6G_MB_LIB.T6G(SCH_1):PAGE249
     8 P3V3_AUX @T6G_MB_LIB.T6G(SCH_1):P3V3_AUX    I30 @T6G_MB_LIB.T6G(SCH_1):PAGE249

U181 PCA9539RPW-PCA9539RPW,SMLF,IC,AL009539K07
     1 PU_U181_INT @T6G_MB_LIB.T6G(SCH_1):PU_U181_INT    I83 @T6G_MB_LIB.T6G(SCH_1):PAGE246
     2 TCA9539_0_ADD1 @T6G_MB_LIB.T6G(SCH_1):TCA9539_0_ADD1    I83 @T6G_MB_LIB.T6G(SCH_1):PAGE246
     3 PU_RST_SMB_U181_N @T6G_MB_LIB.T6G(SCH_1):PU_RST_SMB_U181_N    I83 @T6G_MB_LIB.T6G(SCH_1):PAGE246
     4 RST_USB_HUB_N @T6G_MB_LIB.T6G(SCH_1):RST_USB_HUB_N    I83 @T6G_MB_LIB.T6G(SCH_1):PAGE246
     5 RST_SWB_BIC_N @T6G_MB_LIB.T6G(SCH_1):RST_SWB_BIC_N    I83 @T6G_MB_LIB.T6G(SCH_1):PAGE246
     6 TP_TCA9539_0_P0_2 @T6G_MB_LIB.T6G(SCH_1):TP_TCA9539_0_P0_2    I83 @T6G_MB_LIB.T6G(SCH_1):PAGE246
     7 TP_TCA9539_0_P0_3 @T6G_MB_LIB.T6G(SCH_1):TP_TCA9539_0_P0_3    I83 @T6G_MB_LIB.T6G(SCH_1):PAGE246
     8 PRSNT_SWB_ISO_R1_N @T6G_MB_LIB.T6G(SCH_1):PRSNT_SWB_ISO_R1_N    I83 @T6G_MB_LIB.T6G(SCH_1):PAGE246
     9 GPU_PRSNT_N_ISO_R1 @T6G_MB_LIB.T6G(SCH_1):GPU_PRSNT_N_ISO_R1    I83 @T6G_MB_LIB.T6G(SCH_1):PAGE246
    10 PRSNT_CABLE_GPU_B3_ISO_R1_N @T6G_MB_LIB.T6G(SCH_1):PRSNT_CABLE_GPU_B3_ISO_R1_N    I83 @T6G_MB_LIB.T6G(SCH_1):PAGE246
    11 PRSNT_CABLE_SWB_B2_ISO_R_N @T6G_MB_LIB.T6G(SCH_1):PRSNT_CABLE_SWB_B2_ISO_R_N    I83 @T6G_MB_LIB.T6G(SCH_1):PAGE246
    12    GND @T6G_MB_LIB.T6G(SCH_1):GND    I83 @T6G_MB_LIB.T6G(SCH_1):PAGE246
    13 PRSNT_CABLE_GPU_A2_ISO_R1_N @T6G_MB_LIB.T6G(SCH_1):PRSNT_CABLE_GPU_A2_ISO_R1_N    I83 @T6G_MB_LIB.T6G(SCH_1):PAGE246
    14 PRSNT_CABLE_SWB_B1_ISO_R_N @T6G_MB_LIB.T6G(SCH_1):PRSNT_CABLE_SWB_B1_ISO_R_N    I83 @T6G_MB_LIB.T6G(SCH_1):PAGE246
    15 GPU_BASE_ID0_R @T6G_MB_LIB.T6G(SCH_1):GPU_BASE_ID0_R    I83 @T6G_MB_LIB.T6G(SCH_1):PAGE246
    16 GPU_BASE_ID1_R @T6G_MB_LIB.T6G(SCH_1):GPU_BASE_ID1_R    I83 @T6G_MB_LIB.T6G(SCH_1):PAGE246
    17 GPU_PEX_STRAP0_R @T6G_MB_LIB.T6G(SCH_1):GPU_PEX_STRAP0_R    I83 @T6G_MB_LIB.T6G(SCH_1):PAGE246
    18 GPU_PEX_STRAP1_R @T6G_MB_LIB.T6G(SCH_1):GPU_PEX_STRAP1_R    I83 @T6G_MB_LIB.T6G(SCH_1):PAGE246
    19 PRSNT_CABLE_GPU_A1_ISO_R1_N @T6G_MB_LIB.T6G(SCH_1):PRSNT_CABLE_GPU_A1_ISO_R1_N    I83 @T6G_MB_LIB.T6G(SCH_1):PAGE246
    20 PRSNT_CABLE_GPU_A3_ISO_R_N @T6G_MB_LIB.T6G(SCH_1):PRSNT_CABLE_GPU_A3_ISO_R_N    I83 @T6G_MB_LIB.T6G(SCH_1):PAGE246
    21 TCA9539_0_ADD0 @T6G_MB_LIB.T6G(SCH_1):TCA9539_0_ADD0    I83 @T6G_MB_LIB.T6G(SCH_1):PAGE246
    22 SMB_IOEXP_3V3AUX_SCL_R1 @T6G_MB_LIB.T6G(SCH_1):SMB_IOEXP_3V3AUX_SCL_R1    I83 @T6G_MB_LIB.T6G(SCH_1):PAGE246
    23 SMB_IOEXP_3V3AUX_SDA_R1 @T6G_MB_LIB.T6G(SCH_1):SMB_IOEXP_3V3AUX_SDA_R1    I83 @T6G_MB_LIB.T6G(SCH_1):PAGE246
    24 P3V3_AUX @T6G_MB_LIB.T6G(SCH_1):P3V3_AUX    I83 @T6G_MB_LIB.T6G(SCH_1):PAGE246

U190 MOSFET_NCH_GDS_ESD_PROTECTED-2N7002K,SMLF,IC,BAM70A
     D FM_PDB_BUF_EN_R1 @T6G_MB_LIB.T6G(SCH_1):FM_PDB_BUF_EN_R1   I392 @T6G_MB_LIB.T6G(SCH_1):PAGE363
     G FM_PDB_BUF_EN_R1_N @T6G_MB_LIB.T6G(SCH_1):FM_PDB_BUF_EN_R1_N   I392 @T6G_MB_LIB.T6G(SCH_1):PAGE363
     S    GND @T6G_MB_LIB.T6G(SCH_1):GND   I392 @T6G_MB_LIB.T6G(SCH_1):PAGE363

U192 LTC4307CMS8-LTC4307CMS8,SMLF,IC,AL004307000
     1 MB_PDB_SMB9_R_EN @T6G_MB_LIB.T6G(SCH_1):MB_PDB_SMB9_R_EN   I398 @T6G_MB_LIB.T6G(SCH_1):PAGE363
     3 SMB_FAN_3V3AUX_R_SCL @T6G_MB_LIB.T6G(SCH_1):SMB_FAN_3V3AUX_R_SCL   I398 @T6G_MB_LIB.T6G(SCH_1):PAGE363
     6 SMB_FAN_3V3AUX_R_SDA @T6G_MB_LIB.T6G(SCH_1):SMB_FAN_3V3AUX_R_SDA   I398 @T6G_MB_LIB.T6G(SCH_1):PAGE363
     2 SMB_FAN_3V3AUX_BUF_SCL @T6G_MB_LIB.T6G(SCH_1):SMB_FAN_3V3AUX_BUF_SCL   I398 @T6G_MB_LIB.T6G(SCH_1):PAGE363
     7 SMB_FAN_3V3AUX_BUF_SDA @T6G_MB_LIB.T6G(SCH_1):SMB_FAN_3V3AUX_BUF_SDA   I398 @T6G_MB_LIB.T6G(SCH_1):PAGE363
     5     NC     NC   I398 @T6G_MB_LIB.T6G(SCH_1):PAGE363
     4    GND @T6G_MB_LIB.T6G(SCH_1):GND   I398 @T6G_MB_LIB.T6G(SCH_1):PAGE363
     8 P3V3_AUX @T6G_MB_LIB.T6G(SCH_1):P3V3_AUX   I398 @T6G_MB_LIB.T6G(SCH_1):PAGE363

U193 MAX11617EEET-MAX11617EEE+T,SMLF,EMPTY,AL011617W00
     1 MAX11617_VREF_R @T6G_MB_LIB.T6G(SCH_1):MAX11617_VREF_R   I169 @T6G_MB_LIB.T6G(SCH_1):PAGE369
     2    GND @T6G_MB_LIB.T6G(SCH_1):GND   I169 @T6G_MB_LIB.T6G(SCH_1):PAGE369
     3    GND @T6G_MB_LIB.T6G(SCH_1):GND   I169 @T6G_MB_LIB.T6G(SCH_1):PAGE369
     4    GND @T6G_MB_LIB.T6G(SCH_1):GND   I169 @T6G_MB_LIB.T6G(SCH_1):PAGE369
     5 P12V_AUX_ADC_MAM @T6G_MB_LIB.T6G(SCH_1):P12V_AUX_ADC_MAM   I169 @T6G_MB_LIB.T6G(SCH_1):PAGE369
     6 P12V_OCP_SFF_ISENSE_MAM @T6G_MB_LIB.T6G(SCH_1):P12V_OCP_SFF_ISENSE_MAM   I169 @T6G_MB_LIB.T6G(SCH_1):PAGE369
     7 P12V_OCP_V3_2_ISENSE_MAM @T6G_MB_LIB.T6G(SCH_1):P12V_OCP_V3_2_ISENSE_MAM   I169 @T6G_MB_LIB.T6G(SCH_1):PAGE369
     8 P5V_ADC_MAM @T6G_MB_LIB.T6G(SCH_1):P5V_ADC_MAM   I169 @T6G_MB_LIB.T6G(SCH_1):PAGE369
     9 P3V3_ADC_MAM @T6G_MB_LIB.T6G(SCH_1):P3V3_ADC_MAM   I169 @T6G_MB_LIB.T6G(SCH_1):PAGE369
    10 P3V3_AUX_ADC_MAM @T6G_MB_LIB.T6G(SCH_1):P3V3_AUX_ADC_MAM   I169 @T6G_MB_LIB.T6G(SCH_1):PAGE369
    11 P3V3_PDB_AUX_ADC_MAM @T6G_MB_LIB.T6G(SCH_1):P3V3_PDB_AUX_ADC_MAM   I169 @T6G_MB_LIB.T6G(SCH_1):PAGE369
    12 P12V_E1S_0_ISENSE_MAM @T6G_MB_LIB.T6G(SCH_1):P12V_E1S_0_ISENSE_MAM   I169 @T6G_MB_LIB.T6G(SCH_1):PAGE369
    13 SMB_SEN_MAM_3V3AUX_SCL @T6G_MB_LIB.T6G(SCH_1):SMB_SEN_MAM_3V3AUX_SCL   I169 @T6G_MB_LIB.T6G(SCH_1):PAGE369
    14 SMB_SEN_MAM_3V3AUX_SDA @T6G_MB_LIB.T6G(SCH_1):SMB_SEN_MAM_3V3AUX_SDA   I169 @T6G_MB_LIB.T6G(SCH_1):PAGE369
    15    GND @T6G_MB_LIB.T6G(SCH_1):GND   I169 @T6G_MB_LIB.T6G(SCH_1):PAGE369
    16 P3V3_MAX11617_VDD @T6G_MB_LIB.T6G(SCH_1):P3V3_MAX11617_VDD   I169 @T6G_MB_LIB.T6G(SCH_1):PAGE369

U194 LTC4307CMS8-LTC4307CMS8,SMLF,IC,AL004307000
     1 SMB_BMC_GPU_EN_R1 @T6G_MB_LIB.T6G(SCH_1):SMB_BMC_GPU_EN_R1    I42 @T6G_MB_LIB.T6G(SCH_1):PAGE249
     3 SMB_1_BMC_GPU_R_SCL @T6G_MB_LIB.T6G(SCH_1):SMB_1_BMC_GPU_R_SCL    I42 @T6G_MB_LIB.T6G(SCH_1):PAGE249
     6 SMB_1_BMC_GPU_R_SDA @T6G_MB_LIB.T6G(SCH_1):SMB_1_BMC_GPU_R_SDA    I42 @T6G_MB_LIB.T6G(SCH_1):PAGE249
     2 SMB_1_BMC_GPU_BUF_R_SCL @T6G_MB_LIB.T6G(SCH_1):SMB_1_BMC_GPU_BUF_R_SCL    I42 @T6G_MB_LIB.T6G(SCH_1):PAGE249
     7 SMB_1_BMC_GPU_BUF_R_SDA @T6G_MB_LIB.T6G(SCH_1):SMB_1_BMC_GPU_BUF_R_SDA    I42 @T6G_MB_LIB.T6G(SCH_1):PAGE249
     5     NC     NC    I42 @T6G_MB_LIB.T6G(SCH_1):PAGE249
     4    GND @T6G_MB_LIB.T6G(SCH_1):GND    I42 @T6G_MB_LIB.T6G(SCH_1):PAGE249
     8 P3V3_AUX @T6G_MB_LIB.T6G(SCH_1):P3V3_AUX    I42 @T6G_MB_LIB.T6G(SCH_1):PAGE249

U195 74LVC2G17GW-74LVC2G17GW,SMLF,IC,AL2G0017005
     5 P3V3_AUX @T6G_MB_LIB.T6G(SCH_1):P3V3_AUX    I65 @T6G_MB_LIB.T6G(SCH_1):PAGE256
     4 RST_SWB_BIC_BUF_R_N @T6G_MB_LIB.T6G(SCH_1):RST_SWB_BIC_BUF_R_N    I65 @T6G_MB_LIB.T6G(SCH_1):PAGE256
     2    GND @T6G_MB_LIB.T6G(SCH_1):GND    I65 @T6G_MB_LIB.T6G(SCH_1):PAGE256
     1 BMC_MONITER_R @T6G_MB_LIB.T6G(SCH_1):BMC_MONITER_R    I65 @T6G_MB_LIB.T6G(SCH_1):PAGE256
     3 RST_SWB_BIC_R_N @T6G_MB_LIB.T6G(SCH_1):RST_SWB_BIC_R_N    I65 @T6G_MB_LIB.T6G(SCH_1):PAGE256
     6 BMC_MONITER_BUF_R @T6G_MB_LIB.T6G(SCH_1):BMC_MONITER_BUF_R    I65 @T6G_MB_LIB.T6G(SCH_1):PAGE256

U196 74LVC2G17GW-74LVC2G17GW,SMLF,IC,AL2G0017005
     5 P3V3_AUX @T6G_MB_LIB.T6G(SCH_1):P3V3_AUX   I127 @T6G_MB_LIB.T6G(SCH_1):PAGE256
     4 GPU_FPGA_RST_R1_BUF_N @T6G_MB_LIB.T6G(SCH_1):GPU_FPGA_RST_R1_BUF_N   I127 @T6G_MB_LIB.T6G(SCH_1):PAGE256
     2    GND @T6G_MB_LIB.T6G(SCH_1):GND   I127 @T6G_MB_LIB.T6G(SCH_1):PAGE256
     1 FM_GPU_PWR_EN_R @T6G_MB_LIB.T6G(SCH_1):FM_GPU_PWR_EN_R   I127 @T6G_MB_LIB.T6G(SCH_1):PAGE256
     3 GPU_FPGA_RST_R_N @T6G_MB_LIB.T6G(SCH_1):GPU_FPGA_RST_R_N   I127 @T6G_MB_LIB.T6G(SCH_1):PAGE256
     6 FM_GPU_PWR_EN_R1 @T6G_MB_LIB.T6G(SCH_1):FM_GPU_PWR_EN_R1   I127 @T6G_MB_LIB.T6G(SCH_1):PAGE256

U200 LTC4307CMS8-LTC4307CMS8,SMLF,IC,AL004307000
     1 SMB_BMC_GPU_EN_R3 @T6G_MB_LIB.T6G(SCH_1):SMB_BMC_GPU_EN_R3    I15 @T6G_MB_LIB.T6G(SCH_1):PAGE249
     3 SMB_2_BMC_GPU_R_SCL @T6G_MB_LIB.T6G(SCH_1):SMB_2_BMC_GPU_R_SCL    I15 @T6G_MB_LIB.T6G(SCH_1):PAGE249
     6 SMB_2_BMC_GPU_R_SDA @T6G_MB_LIB.T6G(SCH_1):SMB_2_BMC_GPU_R_SDA    I15 @T6G_MB_LIB.T6G(SCH_1):PAGE249
     2 SMB_2_BMC_GPU_BUF_R_SCL @T6G_MB_LIB.T6G(SCH_1):SMB_2_BMC_GPU_BUF_R_SCL    I15 @T6G_MB_LIB.T6G(SCH_1):PAGE249
     7 SMB_2_BMC_GPU_BUF_R_SDA @T6G_MB_LIB.T6G(SCH_1):SMB_2_BMC_GPU_BUF_R_SDA    I15 @T6G_MB_LIB.T6G(SCH_1):PAGE249
     5     NC     NC    I15 @T6G_MB_LIB.T6G(SCH_1):PAGE249
     4    GND @T6G_MB_LIB.T6G(SCH_1):GND    I15 @T6G_MB_LIB.T6G(SCH_1):PAGE249
     8 P3V3_AUX @T6G_MB_LIB.T6G(SCH_1):P3V3_AUX    I15 @T6G_MB_LIB.T6G(SCH_1):PAGE249

U204 74LVC1G126SE7-74LVC1G126SE-7,SMLF,IC,AL1G0126009
     2 UART_BMC_BIC_R_RX @T6G_MB_LIB.T6G(SCH_1):UART_BMC_BIC_R_RX   I195 @T6G_MB_LIB.T6G(SCH_1):PAGE256
     4 UART_BMC_BIC_R_BUF_RX @T6G_MB_LIB.T6G(SCH_1):UART_BMC_BIC_R_BUF_RX   I195 @T6G_MB_LIB.T6G(SCH_1):PAGE256
     5 P3V3_AUX @T6G_MB_LIB.T6G(SCH_1):P3V3_AUX   I195 @T6G_MB_LIB.T6G(SCH_1):PAGE256
     3    GND @T6G_MB_LIB.T6G(SCH_1):GND   I195 @T6G_MB_LIB.T6G(SCH_1):PAGE256
     1 FM_UART_EN @T6G_MB_LIB.T6G(SCH_1):FM_UART_EN   I195 @T6G_MB_LIB.T6G(SCH_1):PAGE256

U206 LT6700CS61TRPBF-LT6700CS6-1#TRPBF,SMLF,EMPTY,AL006A
     5 U206_VS @T6G_MB_LIB.T6G(SCH_1):U206_VS    I49 @T6G_MB_LIB.T6G(SCH_1):PAGE372
     4 A_P12V_STBY_FP_TRIGGER @T6G_MB_LIB.T6G(SCH_1):A_P12V_STBY_FP_TRIGGER    I49 @T6G_MB_LIB.T6G(SCH_1):PAGE372
     2    GND @T6G_MB_LIB.T6G(SCH_1):GND    I49 @T6G_MB_LIB.T6G(SCH_1):PAGE372
     1 FM_UV_ADR_TRIGGER_N @T6G_MB_LIB.T6G(SCH_1):FM_UV_ADR_TRIGGER_N    I49 @T6G_MB_LIB.T6G(SCH_1):PAGE372
     3 A_P12V_STBY_ADR_TRIGGER @T6G_MB_LIB.T6G(SCH_1):A_P12V_STBY_ADR_TRIGGER    I49 @T6G_MB_LIB.T6G(SCH_1):PAGE372
     6 A_P12V_STBY_FPH_GATE @T6G_MB_LIB.T6G(SCH_1):A_P12V_STBY_FPH_GATE    I49 @T6G_MB_LIB.T6G(SCH_1):PAGE372

U207 74LVC1G17GW-74LVC1G17GW,SMLF,IC,AL1G0017K01
     5 P3V3_AUX @T6G_MB_LIB.T6G(SCH_1):P3V3_AUX    I58 @T6G_MB_LIB.T6G(SCH_1):PAGE342
     2 RST_PERST_OCP_V3_2_BUF_N @T6G_MB_LIB.T6G(SCH_1):RST_PERST_OCP_V3_2_BUF_N    I58 @T6G_MB_LIB.T6G(SCH_1):PAGE342
     3    GND @T6G_MB_LIB.T6G(SCH_1):GND    I58 @T6G_MB_LIB.T6G(SCH_1):PAGE342
     4 RST_PERST_OCP_V3_2_BUF2_N @T6G_MB_LIB.T6G(SCH_1):RST_PERST_OCP_V3_2_BUF2_N    I58 @T6G_MB_LIB.T6G(SCH_1):PAGE342
     1     NC     NC    I58 @T6G_MB_LIB.T6G(SCH_1):PAGE342

U211 74LVC2G07DW7-74LVC2G07DW-7,SMLF,IC,AL002G07003
     1 OCP_SFF_PRSNT0_R_N @T6G_MB_LIB.T6G(SCH_1):OCP_SFF_PRSNT0_R_N    I29 @T6G_MB_LIB.T6G(SCH_1):PAGE338
     3 OCP_SFF_PRSNT1_R_N @T6G_MB_LIB.T6G(SCH_1):OCP_SFF_PRSNT1_R_N    I29 @T6G_MB_LIB.T6G(SCH_1):PAGE338
     6 HP_LVC3_OCP_V3_1_PRSNT2_N_R @T6G_MB_LIB.T6G(SCH_1):HP_LVC3_OCP_V3_1_PRSNT2_N_R    I29 @T6G_MB_LIB.T6G(SCH_1):PAGE338
     4 HP_LVC3_OCP_V3_1_PRSNT2_N_R @T6G_MB_LIB.T6G(SCH_1):HP_LVC3_OCP_V3_1_PRSNT2_N_R    I29 @T6G_MB_LIB.T6G(SCH_1):PAGE338
     2    GND @T6G_MB_LIB.T6G(SCH_1):GND    I29 @T6G_MB_LIB.T6G(SCH_1):PAGE338
     5 P3V3_AUX @T6G_MB_LIB.T6G(SCH_1):P3V3_AUX    I29 @T6G_MB_LIB.T6G(SCH_1):PAGE338

U212 74LV4052PW-74LV4052PW,SMLF,IC,ALLV4052K19
     1 TP_JTAG_SCM_SLOT3_R_TDO @T6G_MB_LIB.T6G(SCH_1):TP_JTAG_SCM_SLOT3_R_TDO   I302 @T6G_MB_LIB.T6G(SCH_1):PAGE148
     2 JTAG_SCM_PLD_R_TDO @T6G_MB_LIB.T6G(SCH_1):JTAG_SCM_PLD_R_TDO   I302 @T6G_MB_LIB.T6G(SCH_1):PAGE148
     3 JTAG_SCM_TDO @T6G_MB_LIB.T6G(SCH_1):JTAG_SCM_TDO   I302 @T6G_MB_LIB.T6G(SCH_1):PAGE148
     4 JTAG_SCM_PLD_R_TDO @T6G_MB_LIB.T6G(SCH_1):JTAG_SCM_PLD_R_TDO   I302 @T6G_MB_LIB.T6G(SCH_1):PAGE148
     5 JTAG_SCM_MUX_R_TDO @T6G_MB_LIB.T6G(SCH_1):JTAG_SCM_MUX_R_TDO   I302 @T6G_MB_LIB.T6G(SCH_1):PAGE148
     6 U212_EN_N @T6G_MB_LIB.T6G(SCH_1):U212_EN_N   I302 @T6G_MB_LIB.T6G(SCH_1):PAGE148
     7    GND @T6G_MB_LIB.T6G(SCH_1):GND   I302 @T6G_MB_LIB.T6G(SCH_1):PAGE148
     8    GND @T6G_MB_LIB.T6G(SCH_1):GND   I302 @T6G_MB_LIB.T6G(SCH_1):PAGE148
     9 SCM_JTAG_MUX_S1 @T6G_MB_LIB.T6G(SCH_1):SCM_JTAG_MUX_S1   I302 @T6G_MB_LIB.T6G(SCH_1):PAGE148
    10 SCM_JTAG_MUX_S0_R2 @T6G_MB_LIB.T6G(SCH_1):SCM_JTAG_MUX_S0_R2   I302 @T6G_MB_LIB.T6G(SCH_1):PAGE148
    11 JTAG_SCM_PLD_R_TDI @T6G_MB_LIB.T6G(SCH_1):JTAG_SCM_PLD_R_TDI   I302 @T6G_MB_LIB.T6G(SCH_1):PAGE148
    12 TP_JTAG_SCM_SLOT3_R_TDI @T6G_MB_LIB.T6G(SCH_1):TP_JTAG_SCM_SLOT3_R_TDI   I302 @T6G_MB_LIB.T6G(SCH_1):PAGE148
    13 JTAG_SCM_TDI @T6G_MB_LIB.T6G(SCH_1):JTAG_SCM_TDI   I302 @T6G_MB_LIB.T6G(SCH_1):PAGE148
    14 JTAG_SCM_MUX_R_TDI @T6G_MB_LIB.T6G(SCH_1):JTAG_SCM_MUX_R_TDI   I302 @T6G_MB_LIB.T6G(SCH_1):PAGE148
    15 JTAG_SCM_PLD_R_TDI @T6G_MB_LIB.T6G(SCH_1):JTAG_SCM_PLD_R_TDI   I302 @T6G_MB_LIB.T6G(SCH_1):PAGE148
    16 P3V3_AUX @T6G_MB_LIB.T6G(SCH_1):P3V3_AUX   I302 @T6G_MB_LIB.T6G(SCH_1):PAGE148

U213 IML3112Y2B000NCG8-IML3112-Y2B000NCG8,SMLF,EMPTY,ALA
     2 SMB_CPU0_CPU1_APML_MUX1_SDA @T6G_MB_LIB.T6G(SCH_1):SMB_CPU0_CPU1_APML_MUX1_SDA   I111 @T6G_MB_LIB.T6G(SCH_1):PAGE138
     5 PVDD18_S5_P0 @T6G_MB_LIB.T6G(SCH_1):PVDD18_S5_P0   I111 @T6G_MB_LIB.T6G(SCH_1):PAGE138
     6 SMB_APML_CPU1_R_SCL @T6G_MB_LIB.T6G(SCH_1):SMB_APML_CPU1_R_SCL   I111 @T6G_MB_LIB.T6G(SCH_1):PAGE138
     7 I3C_MUX_CPU0_VIO @T6G_MB_LIB.T6G(SCH_1):I3C_MUX_CPU0_VIO   I111 @T6G_MB_LIB.T6G(SCH_1):PAGE138
     1 SMB_APML_CPU0_R_SDA @T6G_MB_LIB.T6G(SCH_1):SMB_APML_CPU0_R_SDA   I111 @T6G_MB_LIB.T6G(SCH_1):PAGE138
     4 SMB_APML_CPU0_R_SCL @T6G_MB_LIB.T6G(SCH_1):SMB_APML_CPU0_R_SCL   I111 @T6G_MB_LIB.T6G(SCH_1):PAGE138
     3 SMB_CPU0_CPU1_APML_MUX1_SCL @T6G_MB_LIB.T6G(SCH_1):SMB_CPU0_CPU1_APML_MUX1_SCL   I111 @T6G_MB_LIB.T6G(SCH_1):PAGE138
     8 SMB_APML_CPU1_R_SDA @T6G_MB_LIB.T6G(SCH_1):SMB_APML_CPU1_R_SDA   I111 @T6G_MB_LIB.T6G(SCH_1):PAGE138
     9    GND @T6G_MB_LIB.T6G(SCH_1):GND   I111 @T6G_MB_LIB.T6G(SCH_1):PAGE138

U217 74LVC1G126SE7-74LVC1G126SE-7,SMLF,IC,AL1G0126009
     2 IRQ_LVC3_OCP_V3_2_WAKE_N @T6G_MB_LIB.T6G(SCH_1):IRQ_LVC3_OCP_V3_2_WAKE_N    I14 @T6G_MB_LIB.T6G(SCH_1):PAGE342
     4 OCP_V3_2_WAKE_BUFF_N @T6G_MB_LIB.T6G(SCH_1):OCP_V3_2_WAKE_BUFF_N    I14 @T6G_MB_LIB.T6G(SCH_1):PAGE342
     5 P3V3_AUX @T6G_MB_LIB.T6G(SCH_1):P3V3_AUX    I14 @T6G_MB_LIB.T6G(SCH_1):PAGE342
     3    GND @T6G_MB_LIB.T6G(SCH_1):GND    I14 @T6G_MB_LIB.T6G(SCH_1):PAGE342
     1 PU_OCP_V3_2_WAKE_OE @T6G_MB_LIB.T6G(SCH_1):PU_OCP_V3_2_WAKE_OE    I14 @T6G_MB_LIB.T6G(SCH_1):PAGE342

U218 74LVC1G07GV-74LVC1G07GV,SMLF,IC,AL1G0007001
     5 P3V3_AUX @T6G_MB_LIB.T6G(SCH_1):P3V3_AUX    I22 @T6G_MB_LIB.T6G(SCH_1):PAGE342
     2 FM_SYS_THROTTLE_N @T6G_MB_LIB.T6G(SCH_1):FM_SYS_THROTTLE_N    I22 @T6G_MB_LIB.T6G(SCH_1):PAGE342
     3    GND @T6G_MB_LIB.T6G(SCH_1):GND    I22 @T6G_MB_LIB.T6G(SCH_1):PAGE342
     4 OCP_V3_2_PWRBRK_BUFF_N @T6G_MB_LIB.T6G(SCH_1):OCP_V3_2_PWRBRK_BUFF_N    I22 @T6G_MB_LIB.T6G(SCH_1):PAGE342
     1 NC_U218_NC1 @T6G_MB_LIB.T6G(SCH_1):NC_U218_NC1    I22 @T6G_MB_LIB.T6G(SCH_1):PAGE342

U219 74LVC1G07GV-74LVC1G07GV,SMLF,IC,AL1G0007001
     5 P3V3_AUX @T6G_MB_LIB.T6G(SCH_1):P3V3_AUX    I32 @T6G_MB_LIB.T6G(SCH_1):PAGE342
     2 OCP_V3_2_WAKE_BUFF_R_N @T6G_MB_LIB.T6G(SCH_1):OCP_V3_2_WAKE_BUFF_R_N    I32 @T6G_MB_LIB.T6G(SCH_1):PAGE342
     3    GND @T6G_MB_LIB.T6G(SCH_1):GND    I32 @T6G_MB_LIB.T6G(SCH_1):PAGE342
     4 IRQ_LVC3_V3_2_WAKE_BUF_N @T6G_MB_LIB.T6G(SCH_1):IRQ_LVC3_V3_2_WAKE_BUF_N    I32 @T6G_MB_LIB.T6G(SCH_1):PAGE342
     1 NC_U219_NC1 @T6G_MB_LIB.T6G(SCH_1):NC_U219_NC1    I32 @T6G_MB_LIB.T6G(SCH_1):PAGE342

U222 74CBTLV3126PW-74CBTLV3126PW,SMLF,IC,AL003126K08
     5 NCSI_BMC_RXD0_R1 @T6G_MB_LIB.T6G(SCH_1):NCSI_BMC_RXD0_R1    I32 @T6G_MB_LIB.T6G(SCH_1):PAGE307
     8 NCSI_OCP_V3_2_CRS_DV @T6G_MB_LIB.T6G(SCH_1):NCSI_OCP_V3_2_CRS_DV    I32 @T6G_MB_LIB.T6G(SCH_1):PAGE307
     1 FB_BMC_ISOLATE1 @T6G_MB_LIB.T6G(SCH_1):FB_BMC_ISOLATE1    I32 @T6G_MB_LIB.T6G(SCH_1):PAGE307
     4 FB_BMC_ISOLATE1 @T6G_MB_LIB.T6G(SCH_1):FB_BMC_ISOLATE1    I32 @T6G_MB_LIB.T6G(SCH_1):PAGE307
     3 NCSI_OCP_V3_2_RXD1 @T6G_MB_LIB.T6G(SCH_1):NCSI_OCP_V3_2_RXD1    I32 @T6G_MB_LIB.T6G(SCH_1):PAGE307
     6 NCSI_OCP_V3_2_RXD0 @T6G_MB_LIB.T6G(SCH_1):NCSI_OCP_V3_2_RXD0    I32 @T6G_MB_LIB.T6G(SCH_1):PAGE307
     2 NCSI_BMC_RXD1_R1 @T6G_MB_LIB.T6G(SCH_1):NCSI_BMC_RXD1_R1    I32 @T6G_MB_LIB.T6G(SCH_1):PAGE307
     7    GND @T6G_MB_LIB.T6G(SCH_1):GND    I32 @T6G_MB_LIB.T6G(SCH_1):PAGE307
     9 NCSI_BMC_CRS_DV_R1 @T6G_MB_LIB.T6G(SCH_1):NCSI_BMC_CRS_DV_R1    I32 @T6G_MB_LIB.T6G(SCH_1):PAGE307
    10 FB_BMC_ISOLATE1 @T6G_MB_LIB.T6G(SCH_1):FB_BMC_ISOLATE1    I32 @T6G_MB_LIB.T6G(SCH_1):PAGE307
    11 OCP_V3_2_ISO1_RBT_ARB_IN @T6G_MB_LIB.T6G(SCH_1):OCP_V3_2_ISO1_RBT_ARB_IN    I32 @T6G_MB_LIB.T6G(SCH_1):PAGE307
    12 OCP_V3_2_RBT_ARB_IN_R @T6G_MB_LIB.T6G(SCH_1):OCP_V3_2_RBT_ARB_IN_R    I32 @T6G_MB_LIB.T6G(SCH_1):PAGE307
    13 FB_BMC_ISOLATE1 @T6G_MB_LIB.T6G(SCH_1):FB_BMC_ISOLATE1    I32 @T6G_MB_LIB.T6G(SCH_1):PAGE307
    14 P3V3_AUX @T6G_MB_LIB.T6G(SCH_1):P3V3_AUX    I32 @T6G_MB_LIB.T6G(SCH_1):PAGE307

U223 74CBTLV3126PW-74CBTLV3126PW,SMLF,IC,AL003126K08
     5 NCSI_BMC_TXD0_R1 @T6G_MB_LIB.T6G(SCH_1):NCSI_BMC_TXD0_R1    I78 @T6G_MB_LIB.T6G(SCH_1):PAGE307
     8 NCSI_OCP_V3_2_TX_EN @T6G_MB_LIB.T6G(SCH_1):NCSI_OCP_V3_2_TX_EN    I78 @T6G_MB_LIB.T6G(SCH_1):PAGE307
     1 FB_BMC_ISOLATE1 @T6G_MB_LIB.T6G(SCH_1):FB_BMC_ISOLATE1    I78 @T6G_MB_LIB.T6G(SCH_1):PAGE307
     4 FB_BMC_ISOLATE1 @T6G_MB_LIB.T6G(SCH_1):FB_BMC_ISOLATE1    I78 @T6G_MB_LIB.T6G(SCH_1):PAGE307
     3 NCSI_OCP_V3_2_TXD1 @T6G_MB_LIB.T6G(SCH_1):NCSI_OCP_V3_2_TXD1    I78 @T6G_MB_LIB.T6G(SCH_1):PAGE307
     6 NCSI_OCP_V3_2_TXD0 @T6G_MB_LIB.T6G(SCH_1):NCSI_OCP_V3_2_TXD0    I78 @T6G_MB_LIB.T6G(SCH_1):PAGE307
     2 NCSI_BMC_TXD1_R1 @T6G_MB_LIB.T6G(SCH_1):NCSI_BMC_TXD1_R1    I78 @T6G_MB_LIB.T6G(SCH_1):PAGE307
     7    GND @T6G_MB_LIB.T6G(SCH_1):GND    I78 @T6G_MB_LIB.T6G(SCH_1):PAGE307
     9 NCSI_BMC_TX_EN_R1 @T6G_MB_LIB.T6G(SCH_1):NCSI_BMC_TX_EN_R1    I78 @T6G_MB_LIB.T6G(SCH_1):PAGE307
    10 FB_BMC_ISOLATE1 @T6G_MB_LIB.T6G(SCH_1):FB_BMC_ISOLATE1    I78 @T6G_MB_LIB.T6G(SCH_1):PAGE307
    11 OCP_V3_2_ISO2_RBT_ARB_OUT @T6G_MB_LIB.T6G(SCH_1):OCP_V3_2_ISO2_RBT_ARB_OUT    I78 @T6G_MB_LIB.T6G(SCH_1):PAGE307
    12 OCP_V3_2_RBT_ARB_OUT @T6G_MB_LIB.T6G(SCH_1):OCP_V3_2_RBT_ARB_OUT    I78 @T6G_MB_LIB.T6G(SCH_1):PAGE307
    13 FB_BMC_ISOLATE1 @T6G_MB_LIB.T6G(SCH_1):FB_BMC_ISOLATE1    I78 @T6G_MB_LIB.T6G(SCH_1):PAGE307
    14 P3V3_AUX @T6G_MB_LIB.T6G(SCH_1):P3V3_AUX    I78 @T6G_MB_LIB.T6G(SCH_1):PAGE307

U224 74LVC1G126SE7-74LVC1G126SE-7,SMLF,IC,AL1G0126009
     2 RST_SMB_SWITCH_N @T6G_MB_LIB.T6G(SCH_1):RST_SMB_SWITCH_N   I159 @T6G_MB_LIB.T6G(SCH_1):PAGE336
     4 RST_HP_OCP_SFF_R_N @T6G_MB_LIB.T6G(SCH_1):RST_HP_OCP_SFF_R_N   I159 @T6G_MB_LIB.T6G(SCH_1):PAGE336
     5 P3V3_AUX @T6G_MB_LIB.T6G(SCH_1):P3V3_AUX   I159 @T6G_MB_LIB.T6G(SCH_1):PAGE336
     3    GND @T6G_MB_LIB.T6G(SCH_1):GND   I159 @T6G_MB_LIB.T6G(SCH_1):PAGE336
     1 OCP_SFF_AUX_PWR_EN_R2 @T6G_MB_LIB.T6G(SCH_1):OCP_SFF_AUX_PWR_EN_R2   I159 @T6G_MB_LIB.T6G(SCH_1):PAGE336

U225 74LVC1G126SE7-74LVC1G126SE-7,SMLF,IC,AL1G0126009
     2 RST_SMB_SWITCH_N @T6G_MB_LIB.T6G(SCH_1):RST_SMB_SWITCH_N     I9 @T6G_MB_LIB.T6G(SCH_1):PAGE342
     4 RST_HP_OCP_V3_2_R_N @T6G_MB_LIB.T6G(SCH_1):RST_HP_OCP_V3_2_R_N     I9 @T6G_MB_LIB.T6G(SCH_1):PAGE342
     5 P3V3_AUX @T6G_MB_LIB.T6G(SCH_1):P3V3_AUX     I9 @T6G_MB_LIB.T6G(SCH_1):PAGE342
     3    GND @T6G_MB_LIB.T6G(SCH_1):GND     I9 @T6G_MB_LIB.T6G(SCH_1):PAGE342
     1 OCP_V3_2_AUX_PWR_EN_R3 @T6G_MB_LIB.T6G(SCH_1):OCP_V3_2_AUX_PWR_EN_R3     I9 @T6G_MB_LIB.T6G(SCH_1):PAGE342

U235 PCA9617ADP-PCA9617ADP,SMLF,IC,AL009617K02
     5 HP_LVC3_OCP_V3_2_R_EN @T6G_MB_LIB.T6G(SCH_1):HP_LVC3_OCP_V3_2_R_EN     I6 @T6G_MB_LIB.T6G(SCH_1):PAGE248
     1 P3V3_AUX @T6G_MB_LIB.T6G(SCH_1):P3V3_AUX     I6 @T6G_MB_LIB.T6G(SCH_1):PAGE248
     8 P3V3_OCP_V3_2 @T6G_MB_LIB.T6G(SCH_1):P3V3_OCP_V3_2     I6 @T6G_MB_LIB.T6G(SCH_1):PAGE248
     2 SMB_OCP_V3_2_3V3AUX_SCL @T6G_MB_LIB.T6G(SCH_1):SMB_OCP_V3_2_3V3AUX_SCL     I6 @T6G_MB_LIB.T6G(SCH_1):PAGE248
     3 SMB_OCP_V3_2_3V3AUX_SDA @T6G_MB_LIB.T6G(SCH_1):SMB_OCP_V3_2_3V3AUX_SDA     I6 @T6G_MB_LIB.T6G(SCH_1):PAGE248
     6 SMB_OCP_V3_2_3V3AUX_BUF_SDA @T6G_MB_LIB.T6G(SCH_1):SMB_OCP_V3_2_3V3AUX_BUF_SDA     I6 @T6G_MB_LIB.T6G(SCH_1):PAGE248
     7 SMB_OCP_V3_2_3V3AUX_BUF_SCL @T6G_MB_LIB.T6G(SCH_1):SMB_OCP_V3_2_3V3AUX_BUF_SCL     I6 @T6G_MB_LIB.T6G(SCH_1):PAGE248
     4    GND @T6G_MB_LIB.T6G(SCH_1):GND     I6 @T6G_MB_LIB.T6G(SCH_1):PAGE248

U236 PCA9617ADP-PCA9617ADP,SMLF,IC,AL009617K02
     5 HP_LVC3_OCP_V3_1_R_EN @T6G_MB_LIB.T6G(SCH_1):HP_LVC3_OCP_V3_1_R_EN    I14 @T6G_MB_LIB.T6G(SCH_1):PAGE248
     1 P3V3_AUX @T6G_MB_LIB.T6G(SCH_1):P3V3_AUX    I14 @T6G_MB_LIB.T6G(SCH_1):PAGE248
     8 P3V3_OCP_SFF @T6G_MB_LIB.T6G(SCH_1):P3V3_OCP_SFF    I14 @T6G_MB_LIB.T6G(SCH_1):PAGE248
     2 SMB_OCP_SFF_3V3AUX_SCL @T6G_MB_LIB.T6G(SCH_1):SMB_OCP_SFF_3V3AUX_SCL    I14 @T6G_MB_LIB.T6G(SCH_1):PAGE248
     3 SMB_OCP_SFF_3V3AUX_SDA @T6G_MB_LIB.T6G(SCH_1):SMB_OCP_SFF_3V3AUX_SDA    I14 @T6G_MB_LIB.T6G(SCH_1):PAGE248
     6 SMB_OCP_SFF_3V3AUX_BUF_SDA @T6G_MB_LIB.T6G(SCH_1):SMB_OCP_SFF_3V3AUX_BUF_SDA    I14 @T6G_MB_LIB.T6G(SCH_1):PAGE248
     7 SMB_OCP_SFF_3V3AUX_BUF_SCL @T6G_MB_LIB.T6G(SCH_1):SMB_OCP_SFF_3V3AUX_BUF_SCL    I14 @T6G_MB_LIB.T6G(SCH_1):PAGE248
     4    GND @T6G_MB_LIB.T6G(SCH_1):GND    I14 @T6G_MB_LIB.T6G(SCH_1):PAGE248

U237 PI3EQX12902AZLEX-PI3EQX12902AZLEX,SMLF,IC,AL012902A
     1 P3V3_AUX @T6G_MB_LIB.T6G(SCH_1):P3V3_AUX    I63 @T6G_MB_LIB.T6G(SCH_1):PAGE110
     2 P2E_MB_BMC_TX_C_R1_DP<0> @T6G_MB_LIB.T6G(SCH_1):P2E_MB_BMC_TX_C_R1_DP(0)    I63 @T6G_MB_LIB.T6G(SCH_1):PAGE110
     3 P2E_MB_BMC_TX_C_R1_DN<0> @T6G_MB_LIB.T6G(SCH_1):P2E_MB_BMC_TX_C_R1_DN(0)    I63 @T6G_MB_LIB.T6G(SCH_1):PAGE110
     4    GND @T6G_MB_LIB.T6G(SCH_1):GND    I63 @T6G_MB_LIB.T6G(SCH_1):PAGE110
     5 PU_TEST @T6G_MB_LIB.T6G(SCH_1):PU_TEST    I63 @T6G_MB_LIB.T6G(SCH_1):PAGE110
     6    GND @T6G_MB_LIB.T6G(SCH_1):GND    I63 @T6G_MB_LIB.T6G(SCH_1):PAGE110
     7    GND @T6G_MB_LIB.T6G(SCH_1):GND    I63 @T6G_MB_LIB.T6G(SCH_1):PAGE110
     8 P2E_MB_BMC_RX_BUF_C_DN<0> @T6G_MB_LIB.T6G(SCH_1):P2E_MB_BMC_RX_BUF_C_DN(0)    I63 @T6G_MB_LIB.T6G(SCH_1):PAGE110
     9 P2E_MB_BMC_RX_BUF_C_DP<0> @T6G_MB_LIB.T6G(SCH_1):P2E_MB_BMC_RX_BUF_C_DP(0)    I63 @T6G_MB_LIB.T6G(SCH_1):PAGE110
    10 P3V3_AUX @T6G_MB_LIB.T6G(SCH_1):P3V3_AUX    I63 @T6G_MB_LIB.T6G(SCH_1):PAGE110
    11 FM_P2E_EN_N @T6G_MB_LIB.T6G(SCH_1):FM_P2E_EN_N    I63 @T6G_MB_LIB.T6G(SCH_1):PAGE110
    12 FM_P2E_SWB @T6G_MB_LIB.T6G(SCH_1):FM_P2E_SWB    I63 @T6G_MB_LIB.T6G(SCH_1):PAGE110
    13    GND @T6G_MB_LIB.T6G(SCH_1):GND    I63 @T6G_MB_LIB.T6G(SCH_1):PAGE110
    14 FM_P2E_FGB @T6G_MB_LIB.T6G(SCH_1):FM_P2E_FGB    I63 @T6G_MB_LIB.T6G(SCH_1):PAGE110
    15 FM_P2E_EQB1 @T6G_MB_LIB.T6G(SCH_1):FM_P2E_EQB1    I63 @T6G_MB_LIB.T6G(SCH_1):PAGE110
    16 P3V3_AUX @T6G_MB_LIB.T6G(SCH_1):P3V3_AUX    I63 @T6G_MB_LIB.T6G(SCH_1):PAGE110
    17 P2E_MB_BMC_RX_R1_DP<0> @T6G_MB_LIB.T6G(SCH_1):P2E_MB_BMC_RX_R1_DP(0)    I63 @T6G_MB_LIB.T6G(SCH_1):PAGE110
    18 P2E_MB_BMC_RX_R1_DN<0> @T6G_MB_LIB.T6G(SCH_1):P2E_MB_BMC_RX_R1_DN(0)    I63 @T6G_MB_LIB.T6G(SCH_1):PAGE110
    19    GND @T6G_MB_LIB.T6G(SCH_1):GND    I63 @T6G_MB_LIB.T6G(SCH_1):PAGE110
    20 FM_P2E_EQB0 @T6G_MB_LIB.T6G(SCH_1):FM_P2E_EQB0    I63 @T6G_MB_LIB.T6G(SCH_1):PAGE110
    21 FM_P2E_EQA0 @T6G_MB_LIB.T6G(SCH_1):FM_P2E_EQA0    I63 @T6G_MB_LIB.T6G(SCH_1):PAGE110
    22    GND @T6G_MB_LIB.T6G(SCH_1):GND    I63 @T6G_MB_LIB.T6G(SCH_1):PAGE110
    23 P2E_MB_BMC_TX_BUF_DN<0> @T6G_MB_LIB.T6G(SCH_1):P2E_MB_BMC_TX_BUF_DN(0)    I63 @T6G_MB_LIB.T6G(SCH_1):PAGE110
    24 P2E_MB_BMC_TX_BUF_DP<0> @T6G_MB_LIB.T6G(SCH_1):P2E_MB_BMC_TX_BUF_DP(0)    I63 @T6G_MB_LIB.T6G(SCH_1):PAGE110
    25 P3V3_AUX @T6G_MB_LIB.T6G(SCH_1):P3V3_AUX    I63 @T6G_MB_LIB.T6G(SCH_1):PAGE110
    26 FM_P2E_EQA1 @T6G_MB_LIB.T6G(SCH_1):FM_P2E_EQA1    I63 @T6G_MB_LIB.T6G(SCH_1):PAGE110
    27 FM_P2E_FGA @T6G_MB_LIB.T6G(SCH_1):FM_P2E_FGA    I63 @T6G_MB_LIB.T6G(SCH_1):PAGE110
    28    GND @T6G_MB_LIB.T6G(SCH_1):GND    I63 @T6G_MB_LIB.T6G(SCH_1):PAGE110
    29 FM_P2E_SWA @T6G_MB_LIB.T6G(SCH_1):FM_P2E_SWA    I63 @T6G_MB_LIB.T6G(SCH_1):PAGE110
    30 FM_P2E_MODE @T6G_MB_LIB.T6G(SCH_1):FM_P2E_MODE    I63 @T6G_MB_LIB.T6G(SCH_1):PAGE110
    TH    GND @T6G_MB_LIB.T6G(SCH_1):GND    I63 @T6G_MB_LIB.T6G(SCH_1):PAGE110

U239 74LVC1G126SE7-74LVC1G126SE-7,SMLF,IC,AL1G0126009
     2 LED_HDD_ACTIVITY_N @T6G_MB_LIB.T6G(SCH_1):LED_HDD_ACTIVITY_N    I53 @T6G_MB_LIB.T6G(SCH_1):PAGE345
     4 LED_HDD_ACTIVITY_B_N @T6G_MB_LIB.T6G(SCH_1):LED_HDD_ACTIVITY_B_N    I53 @T6G_MB_LIB.T6G(SCH_1):PAGE345
     5 P3V3_AUX @T6G_MB_LIB.T6G(SCH_1):P3V3_AUX    I53 @T6G_MB_LIB.T6G(SCH_1):PAGE345
     3    GND @T6G_MB_LIB.T6G(SCH_1):GND    I53 @T6G_MB_LIB.T6G(SCH_1):PAGE345
     1 PU_BUFFER_HDD_ACTIVITY @T6G_MB_LIB.T6G(SCH_1):PU_BUFFER_HDD_ACTIVITY    I53 @T6G_MB_LIB.T6G(SCH_1):PAGE345

U240 74LVC2G08DP-74LVC2G08DP,SMLF,EMPTY,ALVC2G08K01
     8 P3V3_AUX @T6G_MB_LIB.T6G(SCH_1):P3V3_AUX    I11 @T6G_MB_LIB.T6G(SCH_1):PAGE258
     4    GND @T6G_MB_LIB.T6G(SCH_1):GND    I11 @T6G_MB_LIB.T6G(SCH_1):PAGE258
     1 OCP_SFF_PRSNT0_R_N @T6G_MB_LIB.T6G(SCH_1):OCP_SFF_PRSNT0_R_N    I11 @T6G_MB_LIB.T6G(SCH_1):PAGE258
     2 OCP_SFF_PRSNT1_R_N @T6G_MB_LIB.T6G(SCH_1):OCP_SFF_PRSNT1_R_N    I11 @T6G_MB_LIB.T6G(SCH_1):PAGE258
     7 OCP_SFF_PRSNT01_R_N @T6G_MB_LIB.T6G(SCH_1):OCP_SFF_PRSNT01_R_N    I11 @T6G_MB_LIB.T6G(SCH_1):PAGE258
     5 OCP_SFF_PRSNT2_R_N @T6G_MB_LIB.T6G(SCH_1):OCP_SFF_PRSNT2_R_N    I12 @T6G_MB_LIB.T6G(SCH_1):PAGE258
     6 OCP_SFF_PRSNT3_R_N @T6G_MB_LIB.T6G(SCH_1):OCP_SFF_PRSNT3_R_N    I12 @T6G_MB_LIB.T6G(SCH_1):PAGE258
     3 OCP_SFF_PRSNT23_R_N @T6G_MB_LIB.T6G(SCH_1):OCP_SFF_PRSNT23_R_N    I12 @T6G_MB_LIB.T6G(SCH_1):PAGE258

U241 74LVC2G08DP-74LVC2G08DP,SMLF,EMPTY,ALVC2G08K01
     8 P3V3_AUX @T6G_MB_LIB.T6G(SCH_1):P3V3_AUX     I1 @T6G_MB_LIB.T6G(SCH_1):PAGE258
     4    GND @T6G_MB_LIB.T6G(SCH_1):GND     I1 @T6G_MB_LIB.T6G(SCH_1):PAGE258
     1 OCP_V3_2_PRSNT0_R_N @T6G_MB_LIB.T6G(SCH_1):OCP_V3_2_PRSNT0_R_N     I1 @T6G_MB_LIB.T6G(SCH_1):PAGE258
     2 OCP_V3_2_PRSNT1_R_N @T6G_MB_LIB.T6G(SCH_1):OCP_V3_2_PRSNT1_R_N     I1 @T6G_MB_LIB.T6G(SCH_1):PAGE258
     7 OCP_V3_2_PRSNT01_R_N @T6G_MB_LIB.T6G(SCH_1):OCP_V3_2_PRSNT01_R_N     I1 @T6G_MB_LIB.T6G(SCH_1):PAGE258
     5 OCP_V3_2_PRSNT2_R_N @T6G_MB_LIB.T6G(SCH_1):OCP_V3_2_PRSNT2_R_N     I2 @T6G_MB_LIB.T6G(SCH_1):PAGE258
     6 OCP_V3_2_PRSNT3_R_N @T6G_MB_LIB.T6G(SCH_1):OCP_V3_2_PRSNT3_R_N     I2 @T6G_MB_LIB.T6G(SCH_1):PAGE258
     3 OCP_V3_2_PRSNT23_R_N @T6G_MB_LIB.T6G(SCH_1):OCP_V3_2_PRSNT23_R_N     I2 @T6G_MB_LIB.T6G(SCH_1):PAGE258

U242 74LVC2G08DP-74LVC2G08DP,SMLF,EMPTY,ALVC2G08K01
     8 P3V3_AUX @T6G_MB_LIB.T6G(SCH_1):P3V3_AUX    I13 @T6G_MB_LIB.T6G(SCH_1):PAGE258
     4    GND @T6G_MB_LIB.T6G(SCH_1):GND    I13 @T6G_MB_LIB.T6G(SCH_1):PAGE258
     1 OCP_SFF_PRSNT01_R1_N @T6G_MB_LIB.T6G(SCH_1):OCP_SFF_PRSNT01_R1_N    I13 @T6G_MB_LIB.T6G(SCH_1):PAGE258
     2 OCP_SFF_PRSNT23_R1_N @T6G_MB_LIB.T6G(SCH_1):OCP_SFF_PRSNT23_R1_N    I13 @T6G_MB_LIB.T6G(SCH_1):PAGE258
     7 OCP_SFF_PRSNT_ALL_R_N @T6G_MB_LIB.T6G(SCH_1):OCP_SFF_PRSNT_ALL_R_N    I13 @T6G_MB_LIB.T6G(SCH_1):PAGE258
     5 OCP_V3_2_PRSNT01_R1_N @T6G_MB_LIB.T6G(SCH_1):OCP_V3_2_PRSNT01_R1_N    I14 @T6G_MB_LIB.T6G(SCH_1):PAGE258
     6 OCP_V3_2_PRSNT23_R1_N @T6G_MB_LIB.T6G(SCH_1):OCP_V3_2_PRSNT23_R1_N    I14 @T6G_MB_LIB.T6G(SCH_1):PAGE258
     3 OCP_V3_2_PRSNT_ALL_R_N @T6G_MB_LIB.T6G(SCH_1):OCP_V3_2_PRSNT_ALL_R_N    I14 @T6G_MB_LIB.T6G(SCH_1):PAGE258

U243 NC7SB3157_SMLF-NC7SB3157P6X,NC7SB3157P6X,EMPTY,ALSA
     1 OCP_SFF_NOT_PRSNT_RBT_ARB_IN @T6G_MB_LIB.T6G(SCH_1):OCP_SFF_NOT_PRSNT_RBT_ARB_IN    I15 @T6G_MB_LIB.T6G(SCH_1):PAGE258
     2    GND @T6G_MB_LIB.T6G(SCH_1):GND    I15 @T6G_MB_LIB.T6G(SCH_1):PAGE258
     3 OCP_SFF_RBT_ARB_OUT @T6G_MB_LIB.T6G(SCH_1):OCP_SFF_RBT_ARB_OUT    I15 @T6G_MB_LIB.T6G(SCH_1):PAGE258
     6 OCP_SFF_PRSNT_ALL_R1_N @T6G_MB_LIB.T6G(SCH_1):OCP_SFF_PRSNT_ALL_R1_N    I15 @T6G_MB_LIB.T6G(SCH_1):PAGE258
     5 P3V3_AUX @T6G_MB_LIB.T6G(SCH_1):P3V3_AUX    I15 @T6G_MB_LIB.T6G(SCH_1):PAGE258
     4 OCP_SFF_RBT_ARB_IN_MUX2 @T6G_MB_LIB.T6G(SCH_1):OCP_SFF_RBT_ARB_IN_MUX2    I15 @T6G_MB_LIB.T6G(SCH_1):PAGE258

U244 NC7SB3157_SMLF-NC7SB3157P6X,NC7SB3157P6X,EMPTY,ALSA
     1 OCP_SFF_NOT_PRSNT_RBT_ARB_IN @T6G_MB_LIB.T6G(SCH_1):OCP_SFF_NOT_PRSNT_RBT_ARB_IN    I16 @T6G_MB_LIB.T6G(SCH_1):PAGE258
     2    GND @T6G_MB_LIB.T6G(SCH_1):GND    I16 @T6G_MB_LIB.T6G(SCH_1):PAGE258
     3 OCP_SFF_RBT_ARB_IN @T6G_MB_LIB.T6G(SCH_1):OCP_SFF_RBT_ARB_IN    I16 @T6G_MB_LIB.T6G(SCH_1):PAGE258
     6 OCP_SFF_PRSNT_ALL_R3_N @T6G_MB_LIB.T6G(SCH_1):OCP_SFF_PRSNT_ALL_R3_N    I16 @T6G_MB_LIB.T6G(SCH_1):PAGE258
     5 P3V3_AUX @T6G_MB_LIB.T6G(SCH_1):P3V3_AUX    I16 @T6G_MB_LIB.T6G(SCH_1):PAGE258
     4 OCP_SFF_RBT_ARB_IN_MUX1_R @T6G_MB_LIB.T6G(SCH_1):OCP_SFF_RBT_ARB_IN_MUX1_R    I16 @T6G_MB_LIB.T6G(SCH_1):PAGE258

U245 NC7SB3157_SMLF-NC7SB3157P6X,NC7SB3157P6X,EMPTY,ALSA
     1 OCP_V3_2_NOT_PRSNT_RBT_ARB_IN @T6G_MB_LIB.T6G(SCH_1):OCP_V3_2_NOT_PRSNT_RBT_ARB_IN    I18 @T6G_MB_LIB.T6G(SCH_1):PAGE258
     2    GND @T6G_MB_LIB.T6G(SCH_1):GND    I18 @T6G_MB_LIB.T6G(SCH_1):PAGE258
     3 OCP_V3_2_RBT_ARB_IN @T6G_MB_LIB.T6G(SCH_1):OCP_V3_2_RBT_ARB_IN    I18 @T6G_MB_LIB.T6G(SCH_1):PAGE258
     6 OCP_V3_2_PRSNT_ALL_R3_N @T6G_MB_LIB.T6G(SCH_1):OCP_V3_2_PRSNT_ALL_R3_N    I18 @T6G_MB_LIB.T6G(SCH_1):PAGE258
     5 P3V3_AUX @T6G_MB_LIB.T6G(SCH_1):P3V3_AUX    I18 @T6G_MB_LIB.T6G(SCH_1):PAGE258
     4 OCP_SFF_RBT_ARB_IN_MUX2_R @T6G_MB_LIB.T6G(SCH_1):OCP_SFF_RBT_ARB_IN_MUX2_R    I18 @T6G_MB_LIB.T6G(SCH_1):PAGE258

U246 NC7SB3157_SMLF-NC7SB3157P6X,NC7SB3157P6X,EMPTY,ALSA
     1 OCP_V3_2_NOT_PRSNT_RBT_ARB_IN @T6G_MB_LIB.T6G(SCH_1):OCP_V3_2_NOT_PRSNT_RBT_ARB_IN    I17 @T6G_MB_LIB.T6G(SCH_1):PAGE258
     2    GND @T6G_MB_LIB.T6G(SCH_1):GND    I17 @T6G_MB_LIB.T6G(SCH_1):PAGE258
     3 OCP_V3_2_RBT_ARB_OUT @T6G_MB_LIB.T6G(SCH_1):OCP_V3_2_RBT_ARB_OUT    I17 @T6G_MB_LIB.T6G(SCH_1):PAGE258
     6 OCP_V3_2_PRSNT_ALL_R1_N @T6G_MB_LIB.T6G(SCH_1):OCP_V3_2_PRSNT_ALL_R1_N    I17 @T6G_MB_LIB.T6G(SCH_1):PAGE258
     5 P3V3_AUX @T6G_MB_LIB.T6G(SCH_1):P3V3_AUX    I17 @T6G_MB_LIB.T6G(SCH_1):PAGE258
     4 OCP_SFF_RBT_ARB_IN_MUX1 @T6G_MB_LIB.T6G(SCH_1):OCP_SFF_RBT_ARB_IN_MUX1    I17 @T6G_MB_LIB.T6G(SCH_1):PAGE258

U247 9FGL0251DKILFT-9FGL0251DKILFT,SMLF,IC,AL000251002
     1 CLK_GEN2_XTAL_IN @T6G_MB_LIB.T6G(SCH_1):CLK_GEN2_XTAL_IN    I77 @T6G_MB_LIB.T6G(SCH_1):PAGE232
     2 CLK_GEN2_XTAL_OUT @T6G_MB_LIB.T6G(SCH_1):CLK_GEN2_XTAL_OUT    I77 @T6G_MB_LIB.T6G(SCH_1):PAGE232
     3 VFG3P3_CLK_GEN @T6G_MB_LIB.T6G(SCH_1):VFG3P3_CLK_GEN    I77 @T6G_MB_LIB.T6G(SCH_1):PAGE232
     4 CLK_GEN2_SMB_SADR @T6G_MB_LIB.T6G(SCH_1):CLK_GEN2_SMB_SADR    I77 @T6G_MB_LIB.T6G(SCH_1):PAGE232
     5    GND @T6G_MB_LIB.T6G(SCH_1):GND    I77 @T6G_MB_LIB.T6G(SCH_1):PAGE232
     6    GND @T6G_MB_LIB.T6G(SCH_1):GND    I77 @T6G_MB_LIB.T6G(SCH_1):PAGE232
     7 VFG3P3_CLK_GEN @T6G_MB_LIB.T6G(SCH_1):VFG3P3_CLK_GEN    I77 @T6G_MB_LIB.T6G(SCH_1):PAGE232
     8 SMB_HOST_CLK_GEN2_3V3AUX_SCL @T6G_MB_LIB.T6G(SCH_1):SMB_HOST_CLK_GEN2_3V3AUX_SCL    I77 @T6G_MB_LIB.T6G(SCH_1):PAGE232
     9 SMB_HOST_CLK_GEN2_3V3AUX_SDA @T6G_MB_LIB.T6G(SCH_1):SMB_HOST_CLK_GEN2_3V3AUX_SDA    I77 @T6G_MB_LIB.T6G(SCH_1):PAGE232
    10    GND @T6G_MB_LIB.T6G(SCH_1):GND    I77 @T6G_MB_LIB.T6G(SCH_1):PAGE232
    11 VFG3P3_CLK_GEN @T6G_MB_LIB.T6G(SCH_1):VFG3P3_CLK_GEN    I77 @T6G_MB_LIB.T6G(SCH_1):PAGE232
    12 CLK_GEN2_BMC_RC_OE_R3_N @T6G_MB_LIB.T6G(SCH_1):CLK_GEN2_BMC_RC_OE_R3_N    I77 @T6G_MB_LIB.T6G(SCH_1):PAGE232
    13 CLK_100M_BMC_RC_DP_R @T6G_MB_LIB.T6G(SCH_1):CLK_100M_BMC_RC_DP_R    I77 @T6G_MB_LIB.T6G(SCH_1):PAGE232
    14 CLK_100M_BMC_RC_DN_R @T6G_MB_LIB.T6G(SCH_1):CLK_100M_BMC_RC_DN_R    I77 @T6G_MB_LIB.T6G(SCH_1):PAGE232
    15    GND @T6G_MB_LIB.T6G(SCH_1):GND    I77 @T6G_MB_LIB.T6G(SCH_1):PAGE232
    16 VFG_3P3A_CLK_GEN @T6G_MB_LIB.T6G(SCH_1):VFG_3P3A_CLK_GEN    I77 @T6G_MB_LIB.T6G(SCH_1):PAGE232
    17 CLK_100M_GPU_FPGA_DP_R @T6G_MB_LIB.T6G(SCH_1):CLK_100M_GPU_FPGA_DP_R    I77 @T6G_MB_LIB.T6G(SCH_1):PAGE232
    18 CLK_100M_GPU_FPGA_DN_R @T6G_MB_LIB.T6G(SCH_1):CLK_100M_GPU_FPGA_DN_R    I77 @T6G_MB_LIB.T6G(SCH_1):PAGE232
    19 CLK_GEN2_GPU_OE_N @T6G_MB_LIB.T6G(SCH_1):CLK_GEN2_GPU_OE_N    I77 @T6G_MB_LIB.T6G(SCH_1):PAGE232
    20 VFG3P3_CLK_GEN @T6G_MB_LIB.T6G(SCH_1):VFG3P3_CLK_GEN    I77 @T6G_MB_LIB.T6G(SCH_1):PAGE232
    21    GND @T6G_MB_LIB.T6G(SCH_1):GND    I77 @T6G_MB_LIB.T6G(SCH_1):PAGE232
    22 P3V3_PWRGD_CLKGEN @T6G_MB_LIB.T6G(SCH_1):P3V3_PWRGD_CLKGEN    I77 @T6G_MB_LIB.T6G(SCH_1):PAGE232
    23 FG_SS_EN @T6G_MB_LIB.T6G(SCH_1):FG_SS_EN    I77 @T6G_MB_LIB.T6G(SCH_1):PAGE232
    24    GND @T6G_MB_LIB.T6G(SCH_1):GND    I77 @T6G_MB_LIB.T6G(SCH_1):PAGE232
    25    GND @T6G_MB_LIB.T6G(SCH_1):GND    I77 @T6G_MB_LIB.T6G(SCH_1):PAGE232

U248 74LVC1G32GW_SMLF-74LVC1G32GW,IC,ALVC1G32007
     1 GPU_FPGA_READY_R_N @T6G_MB_LIB.T6G(SCH_1):GPU_FPGA_READY_R_N    I26 @T6G_MB_LIB.T6G(SCH_1):PAGE232
     2 CLK_GEN2_GPU_FPGA_OE_R2_N @T6G_MB_LIB.T6G(SCH_1):CLK_GEN2_GPU_FPGA_OE_R2_N    I26 @T6G_MB_LIB.T6G(SCH_1):PAGE232
     4 CLK_GEN2_GPU_FPGA_OE_OR_N @T6G_MB_LIB.T6G(SCH_1):CLK_GEN2_GPU_FPGA_OE_OR_N    I26 @T6G_MB_LIB.T6G(SCH_1):PAGE232
     5 P3V3_AUX @T6G_MB_LIB.T6G(SCH_1):P3V3_AUX    I26 @T6G_MB_LIB.T6G(SCH_1):PAGE232
     3    GND @T6G_MB_LIB.T6G(SCH_1):GND    I26 @T6G_MB_LIB.T6G(SCH_1):PAGE232

U252 74LVC2G17GW-74LVC2G17GW,SMLF,IC,AL2G0017005
     5 P3V3_AUX @T6G_MB_LIB.T6G(SCH_1):P3V3_AUX   I153 @T6G_MB_LIB.T6G(SCH_1):PAGE334
     4 RST_PERST_2_SWB_BUF_R_N @T6G_MB_LIB.T6G(SCH_1):RST_PERST_2_SWB_BUF_R_N   I153 @T6G_MB_LIB.T6G(SCH_1):PAGE334
     2    GND @T6G_MB_LIB.T6G(SCH_1):GND   I153 @T6G_MB_LIB.T6G(SCH_1):PAGE334
     1 RST_PERST_CPU1_SWB_R_N @T6G_MB_LIB.T6G(SCH_1):RST_PERST_CPU1_SWB_R_N   I153 @T6G_MB_LIB.T6G(SCH_1):PAGE334
     3 RST_PERST_CPU1_SWB_1_R_N @T6G_MB_LIB.T6G(SCH_1):RST_PERST_CPU1_SWB_1_R_N   I153 @T6G_MB_LIB.T6G(SCH_1):PAGE334
     6 RST_PERST_0_SWB_BUF_R_N @T6G_MB_LIB.T6G(SCH_1):RST_PERST_0_SWB_BUF_R_N   I153 @T6G_MB_LIB.T6G(SCH_1):PAGE334

U253 74LVC2G17GW-74LVC2G17GW,SMLF,IC,AL2G0017005
     5 P3V3_AUX @T6G_MB_LIB.T6G(SCH_1):P3V3_AUX    I26 @T6G_MB_LIB.T6G(SCH_1):PAGE334
     4 GPU_BASE_STBY_EN_BUF_R @T6G_MB_LIB.T6G(SCH_1):GPU_BASE_STBY_EN_BUF_R    I26 @T6G_MB_LIB.T6G(SCH_1):PAGE334
     2    GND @T6G_MB_LIB.T6G(SCH_1):GND    I26 @T6G_MB_LIB.T6G(SCH_1):PAGE334
     1 GPU_FPGA_BOOT_EN @T6G_MB_LIB.T6G(SCH_1):GPU_FPGA_BOOT_EN    I26 @T6G_MB_LIB.T6G(SCH_1):PAGE334
     3 GPU_BASE_STBY_EN @T6G_MB_LIB.T6G(SCH_1):GPU_BASE_STBY_EN    I26 @T6G_MB_LIB.T6G(SCH_1):PAGE334
     6 GPU_FPGA_BOOT_EN_BUF_R @T6G_MB_LIB.T6G(SCH_1):GPU_FPGA_BOOT_EN_BUF_R    I26 @T6G_MB_LIB.T6G(SCH_1):PAGE334

U255 74LVC2G07DW7-74LVC2G07DW-7,SMLF,IC,AL002G07003
     1 GPU_NVS_PWR_BRAKE_N @T6G_MB_LIB.T6G(SCH_1):GPU_NVS_PWR_BRAKE_N    I16 @T6G_MB_LIB.T6G(SCH_1):PAGE255
     3 GPU_FPGA_EROT_RST_N @T6G_MB_LIB.T6G(SCH_1):GPU_FPGA_EROT_RST_N    I16 @T6G_MB_LIB.T6G(SCH_1):PAGE255
     6 GPU_NVS_PWR_BRAKE_N_R @T6G_MB_LIB.T6G(SCH_1):GPU_NVS_PWR_BRAKE_N_R    I16 @T6G_MB_LIB.T6G(SCH_1):PAGE255
     4 GPU_FPGA_EROT_RST_BUF_R_N @T6G_MB_LIB.T6G(SCH_1):GPU_FPGA_EROT_RST_BUF_R_N    I16 @T6G_MB_LIB.T6G(SCH_1):PAGE255
     2    GND @T6G_MB_LIB.T6G(SCH_1):GND    I16 @T6G_MB_LIB.T6G(SCH_1):PAGE255
     5 P3V3_AUX @T6G_MB_LIB.T6G(SCH_1):P3V3_AUX    I16 @T6G_MB_LIB.T6G(SCH_1):PAGE255

U256 74LVC2G17GW-74LVC2G17GW,SMLF,IC,AL2G0017005
     5 P3V3_AUX @T6G_MB_LIB.T6G(SCH_1):P3V3_AUX   I173 @T6G_MB_LIB.T6G(SCH_1):PAGE334
     4 FM_SWB_PWR_EN_R1_BUF @T6G_MB_LIB.T6G(SCH_1):FM_SWB_PWR_EN_R1_BUF   I173 @T6G_MB_LIB.T6G(SCH_1):PAGE334
     2    GND @T6G_MB_LIB.T6G(SCH_1):GND   I173 @T6G_MB_LIB.T6G(SCH_1):PAGE334
     1 RST_PERST_CPU0_SWB_R_N @T6G_MB_LIB.T6G(SCH_1):RST_PERST_CPU0_SWB_R_N   I173 @T6G_MB_LIB.T6G(SCH_1):PAGE334
     3 FM_SWB_PWR_EN_R @T6G_MB_LIB.T6G(SCH_1):FM_SWB_PWR_EN_R   I173 @T6G_MB_LIB.T6G(SCH_1):PAGE334
     6 RST_PERST_1_SWB_BUF_R_N @T6G_MB_LIB.T6G(SCH_1):RST_PERST_1_SWB_BUF_R_N   I173 @T6G_MB_LIB.T6G(SCH_1):PAGE334

U257 74LVC2G07DW7-74LVC2G07DW-7,SMLF,IC,AL002G07003
     1 GPU_FPGA_EROT_RECOV_N @T6G_MB_LIB.T6G(SCH_1):GPU_FPGA_EROT_RECOV_N    I50 @T6G_MB_LIB.T6G(SCH_1):PAGE255
     3    GND @T6G_MB_LIB.T6G(SCH_1):GND    I50 @T6G_MB_LIB.T6G(SCH_1):PAGE255
     6 GPU_FPGA_EROT_RECOV_BUF_R_N @T6G_MB_LIB.T6G(SCH_1):GPU_FPGA_EROT_RECOV_BUF_R_N    I50 @T6G_MB_LIB.T6G(SCH_1):PAGE255
     4 NC_U257_2Y @T6G_MB_LIB.T6G(SCH_1):NC_U257_2Y    I50 @T6G_MB_LIB.T6G(SCH_1):PAGE255
     2    GND @T6G_MB_LIB.T6G(SCH_1):GND    I50 @T6G_MB_LIB.T6G(SCH_1):PAGE255
     5 P3V3_AUX @T6G_MB_LIB.T6G(SCH_1):P3V3_AUX    I50 @T6G_MB_LIB.T6G(SCH_1):PAGE255

U259 SN74LVC2G07DCKR_SMLF-SN74LVC2G07DCKR,IC,AL002G07006
     1 M2_SSD0_CLKREQ_EN_N @T6G_MB_LIB.T6G(SCH_1):M2_SSD0_CLKREQ_EN_N     I5 @T6G_MB_LIB.T6G(SCH_1):PAGE345
     3 RST_PERST_M2_0_N @T6G_MB_LIB.T6G(SCH_1):RST_PERST_M2_0_N     I5 @T6G_MB_LIB.T6G(SCH_1):PAGE345
     6 HDD_ACTIVITY_BUF @T6G_MB_LIB.T6G(SCH_1):HDD_ACTIVITY_BUF     I5 @T6G_MB_LIB.T6G(SCH_1):PAGE345
     4 RST_PERST_BUF_M2_0_N @T6G_MB_LIB.T6G(SCH_1):RST_PERST_BUF_M2_0_N     I5 @T6G_MB_LIB.T6G(SCH_1):PAGE345
     2    GND @T6G_MB_LIB.T6G(SCH_1):GND     I5 @T6G_MB_LIB.T6G(SCH_1):PAGE345
     5 P3V3_AUX @T6G_MB_LIB.T6G(SCH_1):P3V3_AUX     I5 @T6G_MB_LIB.T6G(SCH_1):PAGE345

U263 ISL28022FRZT-ISL28022FRZ-T,SMLF,IC,AL028022003
     9 P3V3_AUX @T6G_MB_LIB.T6G(SCH_1):P3V3_AUX    I94 @T6G_MB_LIB.T6G(SCH_1):PAGE360
     1 INA230_3_A1 @T6G_MB_LIB.T6G(SCH_1):INA230_3_A1    I94 @T6G_MB_LIB.T6G(SCH_1):PAGE360
     2 INA230_3_A0 @T6G_MB_LIB.T6G(SCH_1):INA230_3_A0    I94 @T6G_MB_LIB.T6G(SCH_1):PAGE360
     5 SMB_INA230_3_3V3AUX_SCL_R1 @T6G_MB_LIB.T6G(SCH_1):SMB_INA230_3_3V3AUX_SCL_R1    I94 @T6G_MB_LIB.T6G(SCH_1):PAGE360
     4 SMB_INA230_3_3V3AUX_SDA_R1 @T6G_MB_LIB.T6G(SCH_1):SMB_INA230_3_3V3AUX_SDA_R1    I94 @T6G_MB_LIB.T6G(SCH_1):PAGE360
    11 P3V3_OCP_V3_2_R @T6G_MB_LIB.T6G(SCH_1):P3V3_OCP_V3_2_R    I94 @T6G_MB_LIB.T6G(SCH_1):PAGE360
    13 VSENSE_P12V_INA230_3_INP @T6G_MB_LIB.T6G(SCH_1):VSENSE_P12V_INA230_3_INP    I94 @T6G_MB_LIB.T6G(SCH_1):PAGE360
    12 VSENSE_P12V_INA230_3_INN @T6G_MB_LIB.T6G(SCH_1):VSENSE_P12V_INA230_3_INN    I94 @T6G_MB_LIB.T6G(SCH_1):PAGE360
     3 OCP_V3_2_P3V3_ADC_ALERT_R @T6G_MB_LIB.T6G(SCH_1):OCP_V3_2_P3V3_ADC_ALERT_R    I94 @T6G_MB_LIB.T6G(SCH_1):PAGE360
     6 NC_INA230_3_NC0 @T6G_MB_LIB.T6G(SCH_1):NC_INA230_3_NC0    I94 @T6G_MB_LIB.T6G(SCH_1):PAGE360
     7 NC_INA230_3_NC1 @T6G_MB_LIB.T6G(SCH_1):NC_INA230_3_NC1    I94 @T6G_MB_LIB.T6G(SCH_1):PAGE360
     8 NC_INA230_3_NC2 @T6G_MB_LIB.T6G(SCH_1):NC_INA230_3_NC2    I94 @T6G_MB_LIB.T6G(SCH_1):PAGE360
    14 NC_INA230_3_NC3 @T6G_MB_LIB.T6G(SCH_1):NC_INA230_3_NC3    I94 @T6G_MB_LIB.T6G(SCH_1):PAGE360
    15 NC_INA230_3_NC4 @T6G_MB_LIB.T6G(SCH_1):NC_INA230_3_NC4    I94 @T6G_MB_LIB.T6G(SCH_1):PAGE360
    16 NC_INA230_3_NC5 @T6G_MB_LIB.T6G(SCH_1):NC_INA230_3_NC5    I94 @T6G_MB_LIB.T6G(SCH_1):PAGE360
    10    GND @T6G_MB_LIB.T6G(SCH_1):GND    I94 @T6G_MB_LIB.T6G(SCH_1):PAGE360
    TH    GND @T6G_MB_LIB.T6G(SCH_1):GND    I94 @T6G_MB_LIB.T6G(SCH_1):PAGE360

U264 ISL28022FRZT-ISL28022FRZ-T,SMLF,IC,AL028022003
     9 P3V3_AUX @T6G_MB_LIB.T6G(SCH_1):P3V3_AUX    I46 @T6G_MB_LIB.T6G(SCH_1):PAGE360
     1 INA230_4_A1 @T6G_MB_LIB.T6G(SCH_1):INA230_4_A1    I46 @T6G_MB_LIB.T6G(SCH_1):PAGE360
     2 INA230_4_A0 @T6G_MB_LIB.T6G(SCH_1):INA230_4_A0    I46 @T6G_MB_LIB.T6G(SCH_1):PAGE360
     5 SMB_INA230_4_3V3AUX_SCL_R1 @T6G_MB_LIB.T6G(SCH_1):SMB_INA230_4_3V3AUX_SCL_R1    I46 @T6G_MB_LIB.T6G(SCH_1):PAGE360
     4 SMB_INA230_4_3V3AUX_SDA_R1 @T6G_MB_LIB.T6G(SCH_1):SMB_INA230_4_3V3AUX_SDA_R1    I46 @T6G_MB_LIB.T6G(SCH_1):PAGE360
    11   P3V3 @T6G_MB_LIB.T6G(SCH_1):P3V3    I46 @T6G_MB_LIB.T6G(SCH_1):PAGE360
    13 VSENSE_P12V_INA230_4_INP @T6G_MB_LIB.T6G(SCH_1):VSENSE_P12V_INA230_4_INP    I46 @T6G_MB_LIB.T6G(SCH_1):PAGE360
    12 VSENSE_P12V_INA230_4_INN @T6G_MB_LIB.T6G(SCH_1):VSENSE_P12V_INA230_4_INN    I46 @T6G_MB_LIB.T6G(SCH_1):PAGE360
     3 M2_0_P3V3_ADC_ALERT_R @T6G_MB_LIB.T6G(SCH_1):M2_0_P3V3_ADC_ALERT_R    I46 @T6G_MB_LIB.T6G(SCH_1):PAGE360
     6 NC_INA230_4_NC0 @T6G_MB_LIB.T6G(SCH_1):NC_INA230_4_NC0    I46 @T6G_MB_LIB.T6G(SCH_1):PAGE360
     7 NC_INA230_4_NC1 @T6G_MB_LIB.T6G(SCH_1):NC_INA230_4_NC1    I46 @T6G_MB_LIB.T6G(SCH_1):PAGE360
     8 NC_INA230_4_NC2 @T6G_MB_LIB.T6G(SCH_1):NC_INA230_4_NC2    I46 @T6G_MB_LIB.T6G(SCH_1):PAGE360
    14 NC_INA230_4_NC3 @T6G_MB_LIB.T6G(SCH_1):NC_INA230_4_NC3    I46 @T6G_MB_LIB.T6G(SCH_1):PAGE360
    15 NC_INA230_4_NC4 @T6G_MB_LIB.T6G(SCH_1):NC_INA230_4_NC4    I46 @T6G_MB_LIB.T6G(SCH_1):PAGE360
    16 NC_INA230_4_NC5 @T6G_MB_LIB.T6G(SCH_1):NC_INA230_4_NC5    I46 @T6G_MB_LIB.T6G(SCH_1):PAGE360
    10    GND @T6G_MB_LIB.T6G(SCH_1):GND    I46 @T6G_MB_LIB.T6G(SCH_1):PAGE360
    TH    GND @T6G_MB_LIB.T6G(SCH_1):GND    I46 @T6G_MB_LIB.T6G(SCH_1):PAGE360

U265 ISL28022FRZT-ISL28022FRZ-T,SMLF,IC,AL028022003
     9 P3V3_AUX @T6G_MB_LIB.T6G(SCH_1):P3V3_AUX    I69 @T6G_MB_LIB.T6G(SCH_1):PAGE360
     1 INA230_5_A1 @T6G_MB_LIB.T6G(SCH_1):INA230_5_A1    I69 @T6G_MB_LIB.T6G(SCH_1):PAGE360
     2 INA230_5_A0 @T6G_MB_LIB.T6G(SCH_1):INA230_5_A0    I69 @T6G_MB_LIB.T6G(SCH_1):PAGE360
     5 SMB_INA230_5_3V3AUX_SCL_R1 @T6G_MB_LIB.T6G(SCH_1):SMB_INA230_5_3V3AUX_SCL_R1    I69 @T6G_MB_LIB.T6G(SCH_1):PAGE360
     4 SMB_INA230_5_3V3AUX_SDA_R1 @T6G_MB_LIB.T6G(SCH_1):SMB_INA230_5_3V3AUX_SDA_R1    I69 @T6G_MB_LIB.T6G(SCH_1):PAGE360
    11 P12V_SCM_R @T6G_MB_LIB.T6G(SCH_1):P12V_SCM_R    I69 @T6G_MB_LIB.T6G(SCH_1):PAGE360
    13 VSENSE_P12V_INA230_5_INP @T6G_MB_LIB.T6G(SCH_1):VSENSE_P12V_INA230_5_INP    I69 @T6G_MB_LIB.T6G(SCH_1):PAGE360
    12 VSENSE_P12V_INA230_5_INN @T6G_MB_LIB.T6G(SCH_1):VSENSE_P12V_INA230_5_INN    I69 @T6G_MB_LIB.T6G(SCH_1):PAGE360
     3 P12V_SCM_ADC_ALERT_R @T6G_MB_LIB.T6G(SCH_1):P12V_SCM_ADC_ALERT_R    I69 @T6G_MB_LIB.T6G(SCH_1):PAGE360
     6 NC_INA230_5_NC0 @T6G_MB_LIB.T6G(SCH_1):NC_INA230_5_NC0    I69 @T6G_MB_LIB.T6G(SCH_1):PAGE360
     7 NC_INA230_5_NC1 @T6G_MB_LIB.T6G(SCH_1):NC_INA230_5_NC1    I69 @T6G_MB_LIB.T6G(SCH_1):PAGE360
     8 NC_INA230_5_NC2 @T6G_MB_LIB.T6G(SCH_1):NC_INA230_5_NC2    I69 @T6G_MB_LIB.T6G(SCH_1):PAGE360
    14 NC_INA230_5_NC3 @T6G_MB_LIB.T6G(SCH_1):NC_INA230_5_NC3    I69 @T6G_MB_LIB.T6G(SCH_1):PAGE360
    15 NC_INA230_5_NC4 @T6G_MB_LIB.T6G(SCH_1):NC_INA230_5_NC4    I69 @T6G_MB_LIB.T6G(SCH_1):PAGE360
    16 NC_INA230_5_NC5 @T6G_MB_LIB.T6G(SCH_1):NC_INA230_5_NC5    I69 @T6G_MB_LIB.T6G(SCH_1):PAGE360
    10    GND @T6G_MB_LIB.T6G(SCH_1):GND    I69 @T6G_MB_LIB.T6G(SCH_1):PAGE360
    TH    GND @T6G_MB_LIB.T6G(SCH_1):GND    I69 @T6G_MB_LIB.T6G(SCH_1):PAGE360

U266 ISL28022FRZT-ISL28022FRZ-T,SMLF,IC,AL028022003
     9 P3V3_AUX @T6G_MB_LIB.T6G(SCH_1):P3V3_AUX    I30 @T6G_MB_LIB.T6G(SCH_1):PAGE295
     1 INA230_1_A1 @T6G_MB_LIB.T6G(SCH_1):INA230_1_A1    I30 @T6G_MB_LIB.T6G(SCH_1):PAGE295
     2 INA230_1_A0 @T6G_MB_LIB.T6G(SCH_1):INA230_1_A0    I30 @T6G_MB_LIB.T6G(SCH_1):PAGE295
     5 SMB_INA230_1_3V3AUX_SCL_R1 @T6G_MB_LIB.T6G(SCH_1):SMB_INA230_1_3V3AUX_SCL_R1    I30 @T6G_MB_LIB.T6G(SCH_1):PAGE295
     4 SMB_INA230_1_3V3AUX_SDA_R1 @T6G_MB_LIB.T6G(SCH_1):SMB_INA230_1_3V3AUX_SDA_R1    I30 @T6G_MB_LIB.T6G(SCH_1):PAGE295
    11 P3V3_OCP_SFF_R @T6G_MB_LIB.T6G(SCH_1):P3V3_OCP_SFF_R    I30 @T6G_MB_LIB.T6G(SCH_1):PAGE295
    13 VSENSE_P3V3_INA230_1_INP @T6G_MB_LIB.T6G(SCH_1):VSENSE_P3V3_INA230_1_INP    I30 @T6G_MB_LIB.T6G(SCH_1):PAGE295
    12 VSENSE_P3V3_INA230_1_INN @T6G_MB_LIB.T6G(SCH_1):VSENSE_P3V3_INA230_1_INN    I30 @T6G_MB_LIB.T6G(SCH_1):PAGE295
     3 OCP_SFF_P3V3_ADC_ALERT_R @T6G_MB_LIB.T6G(SCH_1):OCP_SFF_P3V3_ADC_ALERT_R    I30 @T6G_MB_LIB.T6G(SCH_1):PAGE295
     6 NC_INA230_1_NC0 @T6G_MB_LIB.T6G(SCH_1):NC_INA230_1_NC0    I30 @T6G_MB_LIB.T6G(SCH_1):PAGE295
     7 NC_INA230_1_NC1 @T6G_MB_LIB.T6G(SCH_1):NC_INA230_1_NC1    I30 @T6G_MB_LIB.T6G(SCH_1):PAGE295
     8 NC_INA230_1_NC2 @T6G_MB_LIB.T6G(SCH_1):NC_INA230_1_NC2    I30 @T6G_MB_LIB.T6G(SCH_1):PAGE295
    14 NC_INA230_1_NC3 @T6G_MB_LIB.T6G(SCH_1):NC_INA230_1_NC3    I30 @T6G_MB_LIB.T6G(SCH_1):PAGE295
    15 NC_INA230_1_NC4 @T6G_MB_LIB.T6G(SCH_1):NC_INA230_1_NC4    I30 @T6G_MB_LIB.T6G(SCH_1):PAGE295
    16 NC_INA230_1_NC5 @T6G_MB_LIB.T6G(SCH_1):NC_INA230_1_NC5    I30 @T6G_MB_LIB.T6G(SCH_1):PAGE295
    10    GND @T6G_MB_LIB.T6G(SCH_1):GND    I30 @T6G_MB_LIB.T6G(SCH_1):PAGE295
    TH    GND @T6G_MB_LIB.T6G(SCH_1):GND    I30 @T6G_MB_LIB.T6G(SCH_1):PAGE295

U268 GL852GOHY60-GL852G-OHY60,SMLF,IC,AL000852001
    10 USB_HUB_XTAL_IN @T6G_MB_LIB.T6G(SCH_1):USB_HUB_XTAL_IN   I100 @T6G_MB_LIB.T6G(SCH_1):PAGE358
    11 USB_HUB_XTAL_OUT @T6G_MB_LIB.T6G(SCH_1):USB_HUB_XTAL_OUT   I100 @T6G_MB_LIB.T6G(SCH_1):PAGE358
    18 USB_HUB_TEST @T6G_MB_LIB.T6G(SCH_1):USB_HUB_TEST   I100 @T6G_MB_LIB.T6G(SCH_1):PAGE358
    26 NC_USB_HUB_SDA @T6G_MB_LIB.T6G(SCH_1):NC_USB_HUB_SDA   I100 @T6G_MB_LIB.T6G(SCH_1):PAGE358
    27 P3V3_AUX_USB_HUB @T6G_MB_LIB.T6G(SCH_1):P3V3_AUX_USB_HUB   I100 @T6G_MB_LIB.T6G(SCH_1):PAGE358
    28 P3V3_AUX_USB_HUB @T6G_MB_LIB.T6G(SCH_1):P3V3_AUX_USB_HUB   I100 @T6G_MB_LIB.T6G(SCH_1):PAGE358
     5 P3V3_AUX_USB_HUB @T6G_MB_LIB.T6G(SCH_1):P3V3_AUX_USB_HUB   I100 @T6G_MB_LIB.T6G(SCH_1):PAGE358
     9 P3V3_AUX_USB_HUB @T6G_MB_LIB.T6G(SCH_1):P3V3_AUX_USB_HUB   I100 @T6G_MB_LIB.T6G(SCH_1):PAGE358
    14 P3V3_AUX_USB_HUB @T6G_MB_LIB.T6G(SCH_1):P3V3_AUX_USB_HUB   I100 @T6G_MB_LIB.T6G(SCH_1):PAGE358
    21 USB_HUB_DVDD @T6G_MB_LIB.T6G(SCH_1):USB_HUB_DVDD   I100 @T6G_MB_LIB.T6G(SCH_1):PAGE358
    TH    GND @T6G_MB_LIB.T6G(SCH_1):GND   I100 @T6G_MB_LIB.T6G(SCH_1):PAGE358
    25 USB_HUB_OVCUR1 @T6G_MB_LIB.T6G(SCH_1):USB_HUB_OVCUR1   I100 @T6G_MB_LIB.T6G(SCH_1):PAGE358
    24 USB_HUB_OVCUR2 @T6G_MB_LIB.T6G(SCH_1):USB_HUB_OVCUR2   I100 @T6G_MB_LIB.T6G(SCH_1):PAGE358
    20 USB_HUB_OVCUR3 @T6G_MB_LIB.T6G(SCH_1):USB_HUB_OVCUR3   I100 @T6G_MB_LIB.T6G(SCH_1):PAGE358
    19 USB_HUB_OVCUR4 @T6G_MB_LIB.T6G(SCH_1):USB_HUB_OVCUR4   I100 @T6G_MB_LIB.T6G(SCH_1):PAGE358
    17 RST_USB_HUB_R_N @T6G_MB_LIB.T6G(SCH_1):RST_USB_HUB_R_N   I100 @T6G_MB_LIB.T6G(SCH_1):PAGE358
    23 USB_HUB_PGANG @T6G_MB_LIB.T6G(SCH_1):USB_HUB_PGANG   I100 @T6G_MB_LIB.T6G(SCH_1):PAGE358
    22 USB_HUB_PSELF @T6G_MB_LIB.T6G(SCH_1):USB_HUB_PSELF   I100 @T6G_MB_LIB.T6G(SCH_1):PAGE358
     8 USB_HUB_RREF @T6G_MB_LIB.T6G(SCH_1):USB_HUB_RREF   I100 @T6G_MB_LIB.T6G(SCH_1):PAGE358
     2 USB2_P0_R_DP @T6G_MB_LIB.T6G(SCH_1):USB2_P0_R_DP   I100 @T6G_MB_LIB.T6G(SCH_1):PAGE358
     1 USB2_P0_R_DN @T6G_MB_LIB.T6G(SCH_1):USB2_P0_R_DN   I100 @T6G_MB_LIB.T6G(SCH_1):PAGE358
     4 USB2_HUB_SWB_DP @T6G_MB_LIB.T6G(SCH_1):USB2_HUB_SWB_DP   I100 @T6G_MB_LIB.T6G(SCH_1):PAGE358
     3 USB2_HUB_SWB_DN @T6G_MB_LIB.T6G(SCH_1):USB2_HUB_SWB_DN   I100 @T6G_MB_LIB.T6G(SCH_1):PAGE358
     7 NC_USB_HUB_DP2 @T6G_MB_LIB.T6G(SCH_1):NC_USB_HUB_DP2   I100 @T6G_MB_LIB.T6G(SCH_1):PAGE358
     6 NC_USB_HUB_DM2 @T6G_MB_LIB.T6G(SCH_1):NC_USB_HUB_DM2   I100 @T6G_MB_LIB.T6G(SCH_1):PAGE358
    13 NC_USB_HUB_DP3 @T6G_MB_LIB.T6G(SCH_1):NC_USB_HUB_DP3   I100 @T6G_MB_LIB.T6G(SCH_1):PAGE358
    12 NC_USB_HUB_DM3 @T6G_MB_LIB.T6G(SCH_1):NC_USB_HUB_DM3   I100 @T6G_MB_LIB.T6G(SCH_1):PAGE358
    16 NC_USB_HUB_DP4 @T6G_MB_LIB.T6G(SCH_1):NC_USB_HUB_DP4   I100 @T6G_MB_LIB.T6G(SCH_1):PAGE358
    15 NC_USB_HUB_DM4 @T6G_MB_LIB.T6G(SCH_1):NC_USB_HUB_DM4   I100 @T6G_MB_LIB.T6G(SCH_1):PAGE358

U269 ADC128D818CIMTXNOPB-ADC128D818CIMTX/NOPB,SMLF,IC,AA
     1 ADC128_VREF @T6G_MB_LIB.T6G(SCH_1):ADC128_VREF   I142 @T6G_MB_LIB.T6G(SCH_1):PAGE369
     5 P3V3_ADC128_VCC @T6G_MB_LIB.T6G(SCH_1):P3V3_ADC128_VCC   I142 @T6G_MB_LIB.T6G(SCH_1):PAGE369
     7 ADC128_A0 @T6G_MB_LIB.T6G(SCH_1):ADC128_A0   I142 @T6G_MB_LIB.T6G(SCH_1):PAGE369
     8 ADC128_A1 @T6G_MB_LIB.T6G(SCH_1):ADC128_A1   I142 @T6G_MB_LIB.T6G(SCH_1):PAGE369
     9 P12V_E1S_0_ISENSE_TIC @T6G_MB_LIB.T6G(SCH_1):P12V_E1S_0_ISENSE_TIC   I142 @T6G_MB_LIB.T6G(SCH_1):PAGE369
    10 P3V3_PDB_AUX_ADC_TIC @T6G_MB_LIB.T6G(SCH_1):P3V3_PDB_AUX_ADC_TIC   I142 @T6G_MB_LIB.T6G(SCH_1):PAGE369
    11 P3V3_AUX_ADC_TIC @T6G_MB_LIB.T6G(SCH_1):P3V3_AUX_ADC_TIC   I142 @T6G_MB_LIB.T6G(SCH_1):PAGE369
    12 P3V3_ADC_TIC @T6G_MB_LIB.T6G(SCH_1):P3V3_ADC_TIC   I142 @T6G_MB_LIB.T6G(SCH_1):PAGE369
    13 P5V_ADC_TIC @T6G_MB_LIB.T6G(SCH_1):P5V_ADC_TIC   I142 @T6G_MB_LIB.T6G(SCH_1):PAGE369
    14 P12V_OCP_V3_2_ISENSE_TIC @T6G_MB_LIB.T6G(SCH_1):P12V_OCP_V3_2_ISENSE_TIC   I142 @T6G_MB_LIB.T6G(SCH_1):PAGE369
    15 P12V_OCP_SFF_ISENSE_TIC @T6G_MB_LIB.T6G(SCH_1):P12V_OCP_SFF_ISENSE_TIC   I142 @T6G_MB_LIB.T6G(SCH_1):PAGE369
    16 P12V_AUX_ADC_TIC @T6G_MB_LIB.T6G(SCH_1):P12V_AUX_ADC_TIC   I142 @T6G_MB_LIB.T6G(SCH_1):PAGE369
     2 SMB_SEN_TIC_3V3AUX_SDA @T6G_MB_LIB.T6G(SCH_1):SMB_SEN_TIC_3V3AUX_SDA   I142 @T6G_MB_LIB.T6G(SCH_1):PAGE369
     3 SMB_SEN_TIC_3V3AUX_SCL @T6G_MB_LIB.T6G(SCH_1):SMB_SEN_TIC_3V3AUX_SCL   I142 @T6G_MB_LIB.T6G(SCH_1):PAGE369
     4    GND @T6G_MB_LIB.T6G(SCH_1):GND   I142 @T6G_MB_LIB.T6G(SCH_1):PAGE369
     6 TP_ADC128_INT @T6G_MB_LIB.T6G(SCH_1):TP_ADC128_INT   I142 @T6G_MB_LIB.T6G(SCH_1):PAGE369

U270 LM75BD-LM75BD,SMLF,IC,AL0075BD000
     1 SMB_LM75_0_3V3AUX_SDA_R1 @T6G_MB_LIB.T6G(SCH_1):SMB_LM75_0_3V3AUX_SDA_R1   I164 @T6G_MB_LIB.T6G(SCH_1):PAGE359
     2 SMB_LM75_0_3V3AUX_SCL_R1 @T6G_MB_LIB.T6G(SCH_1):SMB_LM75_0_3V3AUX_SCL_R1   I164 @T6G_MB_LIB.T6G(SCH_1):PAGE359
     3 FM_G751_0_ALERT_N @T6G_MB_LIB.T6G(SCH_1):FM_G751_0_ALERT_N   I164 @T6G_MB_LIB.T6G(SCH_1):PAGE359
     4    GND @T6G_MB_LIB.T6G(SCH_1):GND   I164 @T6G_MB_LIB.T6G(SCH_1):PAGE359
     5 U270_0_ADD2 @T6G_MB_LIB.T6G(SCH_1):U270_0_ADD2   I164 @T6G_MB_LIB.T6G(SCH_1):PAGE359
     6 U270_0_ADD1 @T6G_MB_LIB.T6G(SCH_1):U270_0_ADD1   I164 @T6G_MB_LIB.T6G(SCH_1):PAGE359
     7 U270_0_ADD0 @T6G_MB_LIB.T6G(SCH_1):U270_0_ADD0   I164 @T6G_MB_LIB.T6G(SCH_1):PAGE359
     8 P3V3_AUX @T6G_MB_LIB.T6G(SCH_1):P3V3_AUX   I164 @T6G_MB_LIB.T6G(SCH_1):PAGE359

U271 LM75BD-LM75BD,SMLF,IC,AL0075BD000
     1 SMB_LM75_1_3V3AUX_SDA_R1 @T6G_MB_LIB.T6G(SCH_1):SMB_LM75_1_3V3AUX_SDA_R1   I165 @T6G_MB_LIB.T6G(SCH_1):PAGE359
     2 SMB_LM75_1_3V3AUX_SCL_R1 @T6G_MB_LIB.T6G(SCH_1):SMB_LM75_1_3V3AUX_SCL_R1   I165 @T6G_MB_LIB.T6G(SCH_1):PAGE359
     3 FM_G751_1_ALERT_N @T6G_MB_LIB.T6G(SCH_1):FM_G751_1_ALERT_N   I165 @T6G_MB_LIB.T6G(SCH_1):PAGE359
     4    GND @T6G_MB_LIB.T6G(SCH_1):GND   I165 @T6G_MB_LIB.T6G(SCH_1):PAGE359
     5 U271_1_ADD2 @T6G_MB_LIB.T6G(SCH_1):U271_1_ADD2   I165 @T6G_MB_LIB.T6G(SCH_1):PAGE359
     6 U271_1_ADD1 @T6G_MB_LIB.T6G(SCH_1):U271_1_ADD1   I165 @T6G_MB_LIB.T6G(SCH_1):PAGE359
     7 U271_1_ADD0 @T6G_MB_LIB.T6G(SCH_1):U271_1_ADD0   I165 @T6G_MB_LIB.T6G(SCH_1):PAGE359
     8 P3V3_AUX @T6G_MB_LIB.T6G(SCH_1):P3V3_AUX   I165 @T6G_MB_LIB.T6G(SCH_1):PAGE359

U272 LM75BD-LM75BD,SMLF,IC,AL0075BD000
     1 SMB_LM75_2_3V3AUX_SDA_R1 @T6G_MB_LIB.T6G(SCH_1):SMB_LM75_2_3V3AUX_SDA_R1   I166 @T6G_MB_LIB.T6G(SCH_1):PAGE359
     2 SMB_LM75_2_3V3AUX_SCL_R1 @T6G_MB_LIB.T6G(SCH_1):SMB_LM75_2_3V3AUX_SCL_R1   I166 @T6G_MB_LIB.T6G(SCH_1):PAGE359
     3 FM_LM75_2_ALERT_N @T6G_MB_LIB.T6G(SCH_1):FM_LM75_2_ALERT_N   I166 @T6G_MB_LIB.T6G(SCH_1):PAGE359
     4    GND @T6G_MB_LIB.T6G(SCH_1):GND   I166 @T6G_MB_LIB.T6G(SCH_1):PAGE359
     5 U272_2_ADD2 @T6G_MB_LIB.T6G(SCH_1):U272_2_ADD2   I166 @T6G_MB_LIB.T6G(SCH_1):PAGE359
     6 U272_2_ADD1 @T6G_MB_LIB.T6G(SCH_1):U272_2_ADD1   I166 @T6G_MB_LIB.T6G(SCH_1):PAGE359
     7 U272_2_ADD0 @T6G_MB_LIB.T6G(SCH_1):U272_2_ADD0   I166 @T6G_MB_LIB.T6G(SCH_1):PAGE359
     8 P3V3_AUX @T6G_MB_LIB.T6G(SCH_1):P3V3_AUX   I166 @T6G_MB_LIB.T6G(SCH_1):PAGE359

U273 LM75BD-LM75BD,SMLF,IC,AL0075BD000
     1 SMB_LM75_3_3V3AUX_SDA_R1 @T6G_MB_LIB.T6G(SCH_1):SMB_LM75_3_3V3AUX_SDA_R1   I167 @T6G_MB_LIB.T6G(SCH_1):PAGE359
     2 SMB_LM75_3_3V3AUX_SCL_R1 @T6G_MB_LIB.T6G(SCH_1):SMB_LM75_3_3V3AUX_SCL_R1   I167 @T6G_MB_LIB.T6G(SCH_1):PAGE359
     3 FM_LM75_3_ALERT_N @T6G_MB_LIB.T6G(SCH_1):FM_LM75_3_ALERT_N   I167 @T6G_MB_LIB.T6G(SCH_1):PAGE359
     4    GND @T6G_MB_LIB.T6G(SCH_1):GND   I167 @T6G_MB_LIB.T6G(SCH_1):PAGE359
     5 U273_3_ADD2 @T6G_MB_LIB.T6G(SCH_1):U273_3_ADD2   I167 @T6G_MB_LIB.T6G(SCH_1):PAGE359
     6 U273_3_ADD1 @T6G_MB_LIB.T6G(SCH_1):U273_3_ADD1   I167 @T6G_MB_LIB.T6G(SCH_1):PAGE359
     7 U273_3_ADD0 @T6G_MB_LIB.T6G(SCH_1):U273_3_ADD0   I167 @T6G_MB_LIB.T6G(SCH_1):PAGE359
     8 P3V3_AUX @T6G_MB_LIB.T6G(SCH_1):P3V3_AUX   I167 @T6G_MB_LIB.T6G(SCH_1):PAGE359

U276 ISL28022FRZT-ISL28022FRZ-T,SMLF,IC,AL028022003
     9 P3V3_AUX @T6G_MB_LIB.T6G(SCH_1):P3V3_AUX   I129 @T6G_MB_LIB.T6G(SCH_1):PAGE295
     1 INA230_2_A1 @T6G_MB_LIB.T6G(SCH_1):INA230_2_A1   I129 @T6G_MB_LIB.T6G(SCH_1):PAGE295
     2 INA230_2_A0 @T6G_MB_LIB.T6G(SCH_1):INA230_2_A0   I129 @T6G_MB_LIB.T6G(SCH_1):PAGE295
     5 SMB_INA230_2_3V3AUX_SCL_R1 @T6G_MB_LIB.T6G(SCH_1):SMB_INA230_2_3V3AUX_SCL_R1   I129 @T6G_MB_LIB.T6G(SCH_1):PAGE295
     4 SMB_INA230_2_3V3AUX_SDA_R1 @T6G_MB_LIB.T6G(SCH_1):SMB_INA230_2_3V3AUX_SDA_R1   I129 @T6G_MB_LIB.T6G(SCH_1):PAGE295
    11 P3V3_E1S_0_R @T6G_MB_LIB.T6G(SCH_1):P3V3_E1S_0_R   I129 @T6G_MB_LIB.T6G(SCH_1):PAGE295
    13 VSENSE_P3V3_INA230_2_INP @T6G_MB_LIB.T6G(SCH_1):VSENSE_P3V3_INA230_2_INP   I129 @T6G_MB_LIB.T6G(SCH_1):PAGE295
    12 VSENSE_P3V3_INA230_2_INN @T6G_MB_LIB.T6G(SCH_1):VSENSE_P3V3_INA230_2_INN   I129 @T6G_MB_LIB.T6G(SCH_1):PAGE295
     3 E1S_0_P3V3_ADC_ALERT_R @T6G_MB_LIB.T6G(SCH_1):E1S_0_P3V3_ADC_ALERT_R   I129 @T6G_MB_LIB.T6G(SCH_1):PAGE295
     6 NC_INA230_2_NC0 @T6G_MB_LIB.T6G(SCH_1):NC_INA230_2_NC0   I129 @T6G_MB_LIB.T6G(SCH_1):PAGE295
     7 NC_INA230_2_NC1 @T6G_MB_LIB.T6G(SCH_1):NC_INA230_2_NC1   I129 @T6G_MB_LIB.T6G(SCH_1):PAGE295
     8 NC_INA230_2_NC2 @T6G_MB_LIB.T6G(SCH_1):NC_INA230_2_NC2   I129 @T6G_MB_LIB.T6G(SCH_1):PAGE295
    14 NC_INA230_2_NC3 @T6G_MB_LIB.T6G(SCH_1):NC_INA230_2_NC3   I129 @T6G_MB_LIB.T6G(SCH_1):PAGE295
    15 NC_INA230_2_NC4 @T6G_MB_LIB.T6G(SCH_1):NC_INA230_2_NC4   I129 @T6G_MB_LIB.T6G(SCH_1):PAGE295
    16 NC_INA230_2_NC5 @T6G_MB_LIB.T6G(SCH_1):NC_INA230_2_NC5   I129 @T6G_MB_LIB.T6G(SCH_1):PAGE295
    10    GND @T6G_MB_LIB.T6G(SCH_1):GND   I129 @T6G_MB_LIB.T6G(SCH_1):PAGE295
    TH    GND @T6G_MB_LIB.T6G(SCH_1):GND   I129 @T6G_MB_LIB.T6G(SCH_1):PAGE295

U278 74LVC1G08W57-74LVC1G08W5-7,SMLF,IC,AL1G0008020
     1 FM_GPU_HSC_EN @T6G_MB_LIB.T6G(SCH_1):FM_GPU_HSC_EN    I31 @T6G_MB_LIB.T6G(SCH_1):PAGE364
     2 GPU_PRSNT_R @T6G_MB_LIB.T6G(SCH_1):GPU_PRSNT_R    I31 @T6G_MB_LIB.T6G(SCH_1):PAGE364
     3    GND @T6G_MB_LIB.T6G(SCH_1):GND    I31 @T6G_MB_LIB.T6G(SCH_1):PAGE364
     4 FM_GPU_HSC_EN_BUF_R @T6G_MB_LIB.T6G(SCH_1):FM_GPU_HSC_EN_BUF_R    I31 @T6G_MB_LIB.T6G(SCH_1):PAGE364
     5 P3V3_AUX @T6G_MB_LIB.T6G(SCH_1):P3V3_AUX    I31 @T6G_MB_LIB.T6G(SCH_1):PAGE364

U279 PCA9617ADP-PCA9617ADP,SMLF,IC,AL009617K02
     5 SMB_PCIE_E1S_ISO_EN_R @T6G_MB_LIB.T6G(SCH_1):SMB_PCIE_E1S_ISO_EN_R    I93 @T6G_MB_LIB.T6G(SCH_1):PAGE346
     1 P3V3_E1S_0 @T6G_MB_LIB.T6G(SCH_1):P3V3_E1S_0    I93 @T6G_MB_LIB.T6G(SCH_1):PAGE346
     8 P3V3_AUX @T6G_MB_LIB.T6G(SCH_1):P3V3_AUX    I93 @T6G_MB_LIB.T6G(SCH_1):PAGE346
     2 SMB_E1S_3V3AUX_ISO_SCL_R @T6G_MB_LIB.T6G(SCH_1):SMB_E1S_3V3AUX_ISO_SCL_R    I93 @T6G_MB_LIB.T6G(SCH_1):PAGE346
     3 SMB_E1S_3V3AUX_ISO_SDA_R @T6G_MB_LIB.T6G(SCH_1):SMB_E1S_3V3AUX_ISO_SDA_R    I93 @T6G_MB_LIB.T6G(SCH_1):PAGE346
     6 SMB_SENSOR_E1S_3V3AUX_SDA @T6G_MB_LIB.T6G(SCH_1):SMB_SENSOR_E1S_3V3AUX_SDA    I93 @T6G_MB_LIB.T6G(SCH_1):PAGE346
     7 SMB_SENSOR_E1S_3V3AUX_SCL @T6G_MB_LIB.T6G(SCH_1):SMB_SENSOR_E1S_3V3AUX_SCL    I93 @T6G_MB_LIB.T6G(SCH_1):PAGE346
     4    GND @T6G_MB_LIB.T6G(SCH_1):GND    I93 @T6G_MB_LIB.T6G(SCH_1):PAGE346

U286 74LVC1G126SE7-74LVC1G126SE-7,SMLF,IC,AL1G0126009
     2 FM_OCP_V3_2_PWR_GOOD @T6G_MB_LIB.T6G(SCH_1):FM_OCP_V3_2_PWR_GOOD    I80 @T6G_MB_LIB.T6G(SCH_1):PAGE307
     4 FB_BMC_ISOLATE_R2 @T6G_MB_LIB.T6G(SCH_1):FB_BMC_ISOLATE_R2    I80 @T6G_MB_LIB.T6G(SCH_1):PAGE307
     5 P3V3_AUX @T6G_MB_LIB.T6G(SCH_1):P3V3_AUX    I80 @T6G_MB_LIB.T6G(SCH_1):PAGE307
     3    GND @T6G_MB_LIB.T6G(SCH_1):GND    I80 @T6G_MB_LIB.T6G(SCH_1):PAGE307
     1 OCP_V3_2_AUX_PWR_EN_R1 @T6G_MB_LIB.T6G(SCH_1):OCP_V3_2_AUX_PWR_EN_R1    I80 @T6G_MB_LIB.T6G(SCH_1):PAGE307

U290 MOSFET_NCH_GDS_ESD_PROTECTED-2N7002K,SMLF,IC,BAM70A
     D HSC_EN @T6G_MB_LIB.T6G(SCH_1):HSC_EN    I11 @T6G_MB_LIB.T6G(SCH_1):PAGE372
     G PDB_PRSNT_R_N @T6G_MB_LIB.T6G(SCH_1):PDB_PRSNT_R_N    I11 @T6G_MB_LIB.T6G(SCH_1):PAGE372
     S    GND @T6G_MB_LIB.T6G(SCH_1):GND    I11 @T6G_MB_LIB.T6G(SCH_1):PAGE372

U308 74LVC2G07DW7-74LVC2G07DW-7,SMLF,IC,AL002G07003
     1 PWRGD_P3V3_AUX_PDB_R @T6G_MB_LIB.T6G(SCH_1):PWRGD_P3V3_AUX_PDB_R    I37 @T6G_MB_LIB.T6G(SCH_1):PAGE364
     3     NC     NC    I37 @T6G_MB_LIB.T6G(SCH_1):PAGE364
     6 PWRGD_P3V3_AUX_PDB_BUF_R @T6G_MB_LIB.T6G(SCH_1):PWRGD_P3V3_AUX_PDB_BUF_R    I37 @T6G_MB_LIB.T6G(SCH_1):PAGE364
     4     NC     NC    I37 @T6G_MB_LIB.T6G(SCH_1):PAGE364
     2    GND @T6G_MB_LIB.T6G(SCH_1):GND    I37 @T6G_MB_LIB.T6G(SCH_1):PAGE364
     5 P3V3_AUX @T6G_MB_LIB.T6G(SCH_1):P3V3_AUX    I37 @T6G_MB_LIB.T6G(SCH_1):PAGE364

U314 9ZXL0451EKILFT-9ZXL0451EKILFT,SMLF,IC,AL000451003
     3 CLK_100M_CPU0_CLK13_DP @T6G_MB_LIB.T6G(SCH_1):CLK_100M_CPU0_CLK13_DP    I63 @T6G_MB_LIB.T6G(SCH_1):PAGE160
     4 CLK_100M_CPU0_CLK13_DN @T6G_MB_LIB.T6G(SCH_1):CLK_100M_CPU0_CLK13_DN    I63 @T6G_MB_LIB.T6G(SCH_1):PAGE160
     2 P3V3_9ZXL045_P0_VDDR @T6G_MB_LIB.T6G(SCH_1):P3V3_9ZXL045_P0_VDDR    I63 @T6G_MB_LIB.T6G(SCH_1):PAGE160
    25 P3V3_9ZXL045_P0_VDD @T6G_MB_LIB.T6G(SCH_1):P3V3_9ZXL045_P0_VDD    I63 @T6G_MB_LIB.T6G(SCH_1):PAGE160
    29 P3V3_9ZXL045_P0_VDD @T6G_MB_LIB.T6G(SCH_1):P3V3_9ZXL045_P0_VDD    I63 @T6G_MB_LIB.T6G(SCH_1):PAGE160
     9 NC_U314_FBOUT @T6G_MB_LIB.T6G(SCH_1):NC_U314_FBOUT    I63 @T6G_MB_LIB.T6G(SCH_1):PAGE160
    15 FM_9ZXL045_P0_0_OE_N @T6G_MB_LIB.T6G(SCH_1):FM_9ZXL045_P0_0_OE_N    I63 @T6G_MB_LIB.T6G(SCH_1):PAGE160
    26 FM_9ZXL045_P0_3_OE_N @T6G_MB_LIB.T6G(SCH_1):FM_9ZXL045_P0_3_OE_N    I63 @T6G_MB_LIB.T6G(SCH_1):PAGE160
     6 SMB_9ZXL045_P0_SDA @T6G_MB_LIB.T6G(SCH_1):SMB_9ZXL045_P0_SDA    I63 @T6G_MB_LIB.T6G(SCH_1):PAGE160
    11 NC_U314_NC1 @T6G_MB_LIB.T6G(SCH_1):NC_U314_NC1    I63 @T6G_MB_LIB.T6G(SCH_1):PAGE160
     8 NC_U314_FBOUT_N @T6G_MB_LIB.T6G(SCH_1):NC_U314_FBOUT_N    I63 @T6G_MB_LIB.T6G(SCH_1):PAGE160
     7 SMB_9ZXL045_P0_SCL @T6G_MB_LIB.T6G(SCH_1):SMB_9ZXL045_P0_SCL    I63 @T6G_MB_LIB.T6G(SCH_1):PAGE160
    21 P3V3_9ZXL045_P0_VDD @T6G_MB_LIB.T6G(SCH_1):P3V3_9ZXL045_P0_VDD    I63 @T6G_MB_LIB.T6G(SCH_1):PAGE160
     1 FM_9ZXL045_P0_DEV_EN @T6G_MB_LIB.T6G(SCH_1):FM_9ZXL045_P0_DEV_EN    I63 @T6G_MB_LIB.T6G(SCH_1):PAGE160
    14 CLK_100M_RETIMER_CPU0_P0_R_DN @T6G_MB_LIB.T6G(SCH_1):CLK_100M_RETIMER_CPU0_P0_R_DN    I63 @T6G_MB_LIB.T6G(SCH_1):PAGE160
    13 CLK_100M_RETIMER_CPU0_P0_R_DP @T6G_MB_LIB.T6G(SCH_1):CLK_100M_RETIMER_CPU0_P0_R_DP    I63 @T6G_MB_LIB.T6G(SCH_1):PAGE160
    18 FM_9ZXL045_P0_1_OE_N @T6G_MB_LIB.T6G(SCH_1):FM_9ZXL045_P0_1_OE_N    I63 @T6G_MB_LIB.T6G(SCH_1):PAGE160
    20 CLK_100M_RETIMER_CPU0_P1_R_DN @T6G_MB_LIB.T6G(SCH_1):CLK_100M_RETIMER_CPU0_P1_R_DN    I63 @T6G_MB_LIB.T6G(SCH_1):PAGE160
    22 CLK_100M_RETIMER_CPU0_P2_R_DP @T6G_MB_LIB.T6G(SCH_1):CLK_100M_RETIMER_CPU0_P2_R_DP    I63 @T6G_MB_LIB.T6G(SCH_1):PAGE160
    24 FM_9ZXL045_P0_2_OE_N @T6G_MB_LIB.T6G(SCH_1):FM_9ZXL045_P0_2_OE_N    I63 @T6G_MB_LIB.T6G(SCH_1):PAGE160
    23 CLK_100M_RETIMER_CPU0_P2_R_DN @T6G_MB_LIB.T6G(SCH_1):CLK_100M_RETIMER_CPU0_P2_R_DN    I63 @T6G_MB_LIB.T6G(SCH_1):PAGE160
    28 CLK_100M_RETIMER_CPU0_P3_R_DN @T6G_MB_LIB.T6G(SCH_1):CLK_100M_RETIMER_CPU0_P3_R_DN    I63 @T6G_MB_LIB.T6G(SCH_1):PAGE160
    10 NC_U314_NC0 @T6G_MB_LIB.T6G(SCH_1):NC_U314_NC0    I63 @T6G_MB_LIB.T6G(SCH_1):PAGE160
    31 P3V3_9ZXL045_P0_VDDA @T6G_MB_LIB.T6G(SCH_1):P3V3_9ZXL045_P0_VDDA    I63 @T6G_MB_LIB.T6G(SCH_1):PAGE160
    16 P3V3_9ZXL045_P0_VDD @T6G_MB_LIB.T6G(SCH_1):P3V3_9ZXL045_P0_VDD    I63 @T6G_MB_LIB.T6G(SCH_1):PAGE160
    32 CLK_9ZXL045_P0_HIBW @T6G_MB_LIB.T6G(SCH_1):CLK_9ZXL045_P0_HIBW    I63 @T6G_MB_LIB.T6G(SCH_1):PAGE160
    33    GND @T6G_MB_LIB.T6G(SCH_1):GND    I63 @T6G_MB_LIB.T6G(SCH_1):PAGE160
    19 CLK_100M_RETIMER_CPU0_P1_R_DP @T6G_MB_LIB.T6G(SCH_1):CLK_100M_RETIMER_CPU0_P1_R_DP    I63 @T6G_MB_LIB.T6G(SCH_1):PAGE160
    27 CLK_100M_RETIMER_CPU0_P3_R_DP @T6G_MB_LIB.T6G(SCH_1):CLK_100M_RETIMER_CPU0_P3_R_DP    I63 @T6G_MB_LIB.T6G(SCH_1):PAGE160
    12 P3V3_9ZXL045_P0_VDD @T6G_MB_LIB.T6G(SCH_1):P3V3_9ZXL045_P0_VDD    I63 @T6G_MB_LIB.T6G(SCH_1):PAGE160
    30 NC_U314_NC3 @T6G_MB_LIB.T6G(SCH_1):NC_U314_NC3    I63 @T6G_MB_LIB.T6G(SCH_1):PAGE160
    17 NC_U314_NC2 @T6G_MB_LIB.T6G(SCH_1):NC_U314_NC2    I63 @T6G_MB_LIB.T6G(SCH_1):PAGE160
     5 CLK_9ZXL045_P0_SADR0 @T6G_MB_LIB.T6G(SCH_1):CLK_9ZXL045_P0_SADR0    I63 @T6G_MB_LIB.T6G(SCH_1):PAGE160

U316 74LVC2G17GW-74LVC2G17GW,SMLF,IC,AL2G0017005
     5 P3V3_AUX @T6G_MB_LIB.T6G(SCH_1):P3V3_AUX    I86 @T6G_MB_LIB.T6G(SCH_1):PAGE331
     4 NC_U316_2Y @T6G_MB_LIB.T6G(SCH_1):NC_U316_2Y    I86 @T6G_MB_LIB.T6G(SCH_1):PAGE331
     2    GND @T6G_MB_LIB.T6G(SCH_1):GND    I86 @T6G_MB_LIB.T6G(SCH_1):PAGE331
     1 SWB_HSC_EN @T6G_MB_LIB.T6G(SCH_1):SWB_HSC_EN    I86 @T6G_MB_LIB.T6G(SCH_1):PAGE331
     3    GND @T6G_MB_LIB.T6G(SCH_1):GND    I86 @T6G_MB_LIB.T6G(SCH_1):PAGE331
     6 SWB_HSC_EN_BUF_R @T6G_MB_LIB.T6G(SCH_1):SWB_HSC_EN_BUF_R    I86 @T6G_MB_LIB.T6G(SCH_1):PAGE331

U320 74LVC1G66GV-74LVC1G66GV,SMLF,IC,AL001G66000
     1 CLK_50M_NCSI_OCP_SFF @T6G_MB_LIB.T6G(SCH_1):CLK_50M_NCSI_OCP_SFF    I82 @T6G_MB_LIB.T6G(SCH_1):PAGE337
     2 CLK_50M_NCSI_OCP_SFF_ISO_R @T6G_MB_LIB.T6G(SCH_1):CLK_50M_NCSI_OCP_SFF_ISO_R    I82 @T6G_MB_LIB.T6G(SCH_1):PAGE337
     3    GND @T6G_MB_LIB.T6G(SCH_1):GND    I82 @T6G_MB_LIB.T6G(SCH_1):PAGE337
     4 FB_BMC_ISOLATE @T6G_MB_LIB.T6G(SCH_1):FB_BMC_ISOLATE    I82 @T6G_MB_LIB.T6G(SCH_1):PAGE337
     5 P3V3_AUX @T6G_MB_LIB.T6G(SCH_1):P3V3_AUX    I82 @T6G_MB_LIB.T6G(SCH_1):PAGE337

U321 74LVC1G66GV-74LVC1G66GV,SMLF,IC,AL001G66000
     1 CLK_50M_NCSI_OCP_V3_2 @T6G_MB_LIB.T6G(SCH_1):CLK_50M_NCSI_OCP_V3_2    I76 @T6G_MB_LIB.T6G(SCH_1):PAGE342
     2 CLK_50M_NCSI_OCP_V3_2_ISO_R @T6G_MB_LIB.T6G(SCH_1):CLK_50M_NCSI_OCP_V3_2_ISO_R    I76 @T6G_MB_LIB.T6G(SCH_1):PAGE342
     3    GND @T6G_MB_LIB.T6G(SCH_1):GND    I76 @T6G_MB_LIB.T6G(SCH_1):PAGE342
     4 FB_BMC_ISOLATE1 @T6G_MB_LIB.T6G(SCH_1):FB_BMC_ISOLATE1    I76 @T6G_MB_LIB.T6G(SCH_1):PAGE342
     5 P3V3_AUX @T6G_MB_LIB.T6G(SCH_1):P3V3_AUX    I76 @T6G_MB_LIB.T6G(SCH_1):PAGE342

U324 MOSFET_NCH_GDS_ESD_PROTECTED-2N7002K,SMLF,IC,BAM70A
     D VR_P5V_EN_D @T6G_MB_LIB.T6G(SCH_1):VR_P5V_EN_D    I62 @T6G_MB_LIB.T6G(SCH_1):PAGE273
     G VR_P5V_EN_N @T6G_MB_LIB.T6G(SCH_1):VR_P5V_EN_N    I62 @T6G_MB_LIB.T6G(SCH_1):PAGE273
     S    GND @T6G_MB_LIB.T6G(SCH_1):GND    I62 @T6G_MB_LIB.T6G(SCH_1):PAGE273

U325 MOSFET_N_SMLF-BSS138K,BSS138K,EMPTY,BAM138K0000
     G A_P12V_STBY_FPH_GATE @T6G_MB_LIB.T6G(SCH_1):A_P12V_STBY_FPH_GATE    I42 @T6G_MB_LIB.T6G(SCH_1):PAGE372
     D IRQ_UV_DETECT_N @T6G_MB_LIB.T6G(SCH_1):IRQ_UV_DETECT_N    I42 @T6G_MB_LIB.T6G(SCH_1):PAGE372
     S    GND @T6G_MB_LIB.T6G(SCH_1):GND    I42 @T6G_MB_LIB.T6G(SCH_1):PAGE372

U326 MPQ8633AGLEC807Z-MPQ8633AGLE-C807-Z,SMLF,IC,AL0086A
    10 SW_P5V_AUX_FLT @T6G_MB_LIB.T6G(SCH_1):SW_P5V_AUX_FLT    I38 @T6G_MB_LIB.T6G(SCH_1):PAGE244
     9 PWRGD_P5V_AUX_R @T6G_MB_LIB.T6G(SCH_1):PWRGD_P5V_AUX_R    I38 @T6G_MB_LIB.T6G(SCH_1):PAGE244
 11_18    GND @T6G_MB_LIB.T6G(SCH_1):GND    I38 @T6G_MB_LIB.T6G(SCH_1):PAGE244
     8 P5V_AUX_EN @T6G_MB_LIB.T6G(SCH_1):P5V_AUX_EN    I38 @T6G_MB_LIB.T6G(SCH_1):PAGE244
     1 SW_P5V_AUX_BST @T6G_MB_LIB.T6G(SCH_1):SW_P5V_AUX_BST    I38 @T6G_MB_LIB.T6G(SCH_1):PAGE244
     7 P5V_AUX_FB @T6G_MB_LIB.T6G(SCH_1):P5V_AUX_FB    I38 @T6G_MB_LIB.T6G(SCH_1):PAGE244
     2    GND @T6G_MB_LIB.T6G(SCH_1):GND    I38 @T6G_MB_LIB.T6G(SCH_1):PAGE244
    19 P5V_AUX_VCC @T6G_MB_LIB.T6G(SCH_1):P5V_AUX_VCC    I38 @T6G_MB_LIB.T6G(SCH_1):PAGE244
     6    GND @T6G_MB_LIB.T6G(SCH_1):GND    I38 @T6G_MB_LIB.T6G(SCH_1):PAGE244
    20 SW_P5V_AUX_SW @T6G_MB_LIB.T6G(SCH_1):SW_P5V_AUX_SW    I38 @T6G_MB_LIB.T6G(SCH_1):PAGE244
     5 P5V_AUX_REF @T6G_MB_LIB.T6G(SCH_1):P5V_AUX_REF    I38 @T6G_MB_LIB.T6G(SCH_1):PAGE244
     4 P5V_AUX_MODE @T6G_MB_LIB.T6G(SCH_1):P5V_AUX_MODE    I38 @T6G_MB_LIB.T6G(SCH_1):PAGE244
     3 P5V_AUX_CS @T6G_MB_LIB.T6G(SCH_1):P5V_AUX_CS    I38 @T6G_MB_LIB.T6G(SCH_1):PAGE244
    21 SW_P5V_AUX_FLT @T6G_MB_LIB.T6G(SCH_1):SW_P5V_AUX_FLT    I38 @T6G_MB_LIB.T6G(SCH_1):PAGE244

U5201 TUSB211IRWBR-TUSB211IRWBR,SMLF,EMPTY,AL000211007
     5 PD_U5201_RSTN @T6G_MB_LIB.T6G(SCH_1):PD_U5201_RSTN    I84 @T6G_MB_LIB.T6G(SCH_1):PAGE358
     8 USB2_HUB_BUF_SWB_R_DN @T6G_MB_LIB.T6G(SCH_1):USB2_HUB_BUF_SWB_R_DN    I84 @T6G_MB_LIB.T6G(SCH_1):PAGE358
    11 PD_U5201_VREG @T6G_MB_LIB.T6G(SCH_1):PD_U5201_VREG    I84 @T6G_MB_LIB.T6G(SCH_1):PAGE358
     3 TP_USB2_TEST @T6G_MB_LIB.T6G(SCH_1):TP_USB2_TEST    I84 @T6G_MB_LIB.T6G(SCH_1):PAGE358
    12 P3V3_AUX @T6G_MB_LIB.T6G(SCH_1):P3V3_AUX    I84 @T6G_MB_LIB.T6G(SCH_1):PAGE358
     9 TP_USB2_ENA_HS @T6G_MB_LIB.T6G(SCH_1):TP_USB2_ENA_HS    I84 @T6G_MB_LIB.T6G(SCH_1):PAGE358
     4 TP_USB2_CD @T6G_MB_LIB.T6G(SCH_1):TP_USB2_CD    I84 @T6G_MB_LIB.T6G(SCH_1):PAGE358
     1 USB2_HUB_BUF_SWB_R_DN @T6G_MB_LIB.T6G(SCH_1):USB2_HUB_BUF_SWB_R_DN    I84 @T6G_MB_LIB.T6G(SCH_1):PAGE358
     2 USB2_HUB_BUF_SWB_R_DP @T6G_MB_LIB.T6G(SCH_1):USB2_HUB_BUF_SWB_R_DP    I84 @T6G_MB_LIB.T6G(SCH_1):PAGE358
     7 USB2_HUB_BUF_SWB_R_DP @T6G_MB_LIB.T6G(SCH_1):USB2_HUB_BUF_SWB_R_DP    I84 @T6G_MB_LIB.T6G(SCH_1):PAGE358
     6 PD_U5201_EQ @T6G_MB_LIB.T6G(SCH_1):PD_U5201_EQ    I84 @T6G_MB_LIB.T6G(SCH_1):PAGE358
    10    GND @T6G_MB_LIB.T6G(SCH_1):GND    I84 @T6G_MB_LIB.T6G(SCH_1):PAGE358

U6000 DS125BR111RTWR-DS125BR111RTWR,SMLF,IC,AL000125003
     1 FM_P2E_BUF2_EQB0 @T6G_MB_LIB.T6G(SCH_1):FM_P2E_BUF2_EQB0     I1 @T6G_MB_LIB.T6G(SCH_1):PAGE111
     2 FM_P2E_BUF2_EQB1 @T6G_MB_LIB.T6G(SCH_1):FM_P2E_BUF2_EQB1     I1 @T6G_MB_LIB.T6G(SCH_1):PAGE111
     3 PD_P2E_BUF2_ENSMB @T6G_MB_LIB.T6G(SCH_1):PD_P2E_BUF2_ENSMB     I1 @T6G_MB_LIB.T6G(SCH_1):PAGE111
     4 FM_P2E_BUF2_VODA_DB @T6G_MB_LIB.T6G(SCH_1):FM_P2E_BUF2_VODA_DB     I1 @T6G_MB_LIB.T6G(SCH_1):PAGE111
     5 FM_P2E_BUF2_VODB_DB @T6G_MB_LIB.T6G(SCH_1):FM_P2E_BUF2_VODB_DB     I1 @T6G_MB_LIB.T6G(SCH_1):PAGE111
     6 FM_P2E_EN2_N @T6G_MB_LIB.T6G(SCH_1):FM_P2E_EN2_N     I1 @T6G_MB_LIB.T6G(SCH_1):PAGE111
     7 P2E_MB_BMC_TX_BUF2_DP<0> @T6G_MB_LIB.T6G(SCH_1):P2E_MB_BMC_TX_BUF2_DP(0)     I1 @T6G_MB_LIB.T6G(SCH_1):PAGE111
     8 P2E_MB_BMC_TX_BUF2_DN<0> @T6G_MB_LIB.T6G(SCH_1):P2E_MB_BMC_TX_BUF2_DN(0)     I1 @T6G_MB_LIB.T6G(SCH_1):PAGE111
     9 FM_P2E_BUF2_EQA1 @T6G_MB_LIB.T6G(SCH_1):FM_P2E_BUF2_EQA1     I1 @T6G_MB_LIB.T6G(SCH_1):PAGE111
    10 FM_P2E_BUF2_EQA0 @T6G_MB_LIB.T6G(SCH_1):FM_P2E_BUF2_EQA0     I1 @T6G_MB_LIB.T6G(SCH_1):PAGE111
    11 P2E_MB_BMC_RX_R2_DP<0> @T6G_MB_LIB.T6G(SCH_1):P2E_MB_BMC_RX_R2_DP(0)     I1 @T6G_MB_LIB.T6G(SCH_1):PAGE111
    12 P2E_MB_BMC_RX_R2_DN<0> @T6G_MB_LIB.T6G(SCH_1):P2E_MB_BMC_RX_R2_DN(0)     I1 @T6G_MB_LIB.T6G(SCH_1):PAGE111
    13 NC_RES @T6G_MB_LIB.T6G(SCH_1):NC_RES     I1 @T6G_MB_LIB.T6G(SCH_1):PAGE111
    14 FM_P2E_BUF2_SD_TH @T6G_MB_LIB.T6G(SCH_1):FM_P2E_BUF2_SD_TH     I1 @T6G_MB_LIB.T6G(SCH_1):PAGE111
    15 P3V3_AUX @T6G_MB_LIB.T6G(SCH_1):P3V3_AUX     I1 @T6G_MB_LIB.T6G(SCH_1):PAGE111
    16    GND @T6G_MB_LIB.T6G(SCH_1):GND     I1 @T6G_MB_LIB.T6G(SCH_1):PAGE111
    17 FM_P2E_BUF2_VOD_SEL @T6G_MB_LIB.T6G(SCH_1):FM_P2E_BUF2_VOD_SEL     I1 @T6G_MB_LIB.T6G(SCH_1):PAGE111
    18 FM_P2E_BUF2_RXDET @T6G_MB_LIB.T6G(SCH_1):FM_P2E_BUF2_RXDET     I1 @T6G_MB_LIB.T6G(SCH_1):PAGE111
    19 P2E_MB_BMC_RX_BUF2_C_DN<0> @T6G_MB_LIB.T6G(SCH_1):P2E_MB_BMC_RX_BUF2_C_DN(0)     I1 @T6G_MB_LIB.T6G(SCH_1):PAGE111
    20 P2E_MB_BMC_RX_BUF2_C_DP<0> @T6G_MB_LIB.T6G(SCH_1):P2E_MB_BMC_RX_BUF2_C_DP(0)     I1 @T6G_MB_LIB.T6G(SCH_1):PAGE111
    21 BUF2_VDD @T6G_MB_LIB.T6G(SCH_1):BUF2_VDD     I1 @T6G_MB_LIB.T6G(SCH_1):PAGE111
    22 BUF2_VDD @T6G_MB_LIB.T6G(SCH_1):BUF2_VDD     I1 @T6G_MB_LIB.T6G(SCH_1):PAGE111
    23 P2E_MB_BMC_TX_C_R2_DN<0> @T6G_MB_LIB.T6G(SCH_1):P2E_MB_BMC_TX_C_R2_DN(0)     I1 @T6G_MB_LIB.T6G(SCH_1):PAGE111
    24 P2E_MB_BMC_TX_C_R2_DP<0> @T6G_MB_LIB.T6G(SCH_1):P2E_MB_BMC_TX_C_R2_DP(0)     I1 @T6G_MB_LIB.T6G(SCH_1):PAGE111
    25    GND @T6G_MB_LIB.T6G(SCH_1):GND     I1 @T6G_MB_LIB.T6G(SCH_1):PAGE111

U6001 CYUSB330468LTXI-CYUSB3304-68LTXI,SMLF,IC,AJ0330400A
    60 USB2_CPU0_P0_HUB1_R_DP @T6G_MB_LIB.T6G(SCH_1):USB2_CPU0_P0_HUB1_R_DP     I1 @T6G_MB_LIB.T6G(SCH_1):PAGE153
    59 USB2_CPU0_P0_HUB1_R_DN @T6G_MB_LIB.T6G(SCH_1):USB2_CPU0_P0_HUB1_R_DN     I1 @T6G_MB_LIB.T6G(SCH_1):PAGE153
    51 USB3_CPU0_BMC_RX_C1_DP @T6G_MB_LIB.T6G(SCH_1):USB3_CPU0_BMC_RX_C1_DP     I1 @T6G_MB_LIB.T6G(SCH_1):PAGE153
    50 USB3_CPU0_BMC_RX_C1_DN @T6G_MB_LIB.T6G(SCH_1):USB3_CPU0_BMC_RX_C1_DN     I1 @T6G_MB_LIB.T6G(SCH_1):PAGE153
    47 USB3_CPU0_BMC_HUB1_TX_DP @T6G_MB_LIB.T6G(SCH_1):USB3_CPU0_BMC_HUB1_TX_DP     I1 @T6G_MB_LIB.T6G(SCH_1):PAGE153
    48 USB3_CPU0_BMC_HUB1_TX_DN @T6G_MB_LIB.T6G(SCH_1):USB3_CPU0_BMC_HUB1_TX_DN     I1 @T6G_MB_LIB.T6G(SCH_1):PAGE153
    62     NC     NC     I1 @T6G_MB_LIB.T6G(SCH_1):PAGE153
    63     NC     NC     I1 @T6G_MB_LIB.T6G(SCH_1):PAGE153
    45     NC     NC     I1 @T6G_MB_LIB.T6G(SCH_1):PAGE153
    44     NC     NC     I1 @T6G_MB_LIB.T6G(SCH_1):PAGE153
    41     NC     NC     I1 @T6G_MB_LIB.T6G(SCH_1):PAGE153
    42     NC     NC     I1 @T6G_MB_LIB.T6G(SCH_1):PAGE153
    65     NC     NC     I1 @T6G_MB_LIB.T6G(SCH_1):PAGE153
    64     NC     NC     I1 @T6G_MB_LIB.T6G(SCH_1):PAGE153
    35     NC     NC     I1 @T6G_MB_LIB.T6G(SCH_1):PAGE153
    36     NC     NC     I1 @T6G_MB_LIB.T6G(SCH_1):PAGE153
    38     NC     NC     I1 @T6G_MB_LIB.T6G(SCH_1):PAGE153
    39     NC     NC     I1 @T6G_MB_LIB.T6G(SCH_1):PAGE153
    67     NC     NC     I1 @T6G_MB_LIB.T6G(SCH_1):PAGE153
    68     NC     NC     I1 @T6G_MB_LIB.T6G(SCH_1):PAGE153
    15     NC     NC     I1 @T6G_MB_LIB.T6G(SCH_1):PAGE153
    14     NC     NC     I1 @T6G_MB_LIB.T6G(SCH_1):PAGE153
    11     NC     NC     I1 @T6G_MB_LIB.T6G(SCH_1):PAGE153
    12     NC     NC     I1 @T6G_MB_LIB.T6G(SCH_1):PAGE153
    18 USB_CPU0_HUB1_VBUS_DS @T6G_MB_LIB.T6G(SCH_1):USB_CPU0_HUB1_VBUS_DS     I1 @T6G_MB_LIB.T6G(SCH_1):PAGE153
    32 SMB_USB_CPU0_HUB1_SCL @T6G_MB_LIB.T6G(SCH_1):SMB_USB_CPU0_HUB1_SCL     I1 @T6G_MB_LIB.T6G(SCH_1):PAGE153
    33 SMB_USB_CPU0_HUB1_SDA @T6G_MB_LIB.T6G(SCH_1):SMB_USB_CPU0_HUB1_SDA     I1 @T6G_MB_LIB.T6G(SCH_1):PAGE153
    20 TP_CPU0_USB_HUB1_SUSPEND @T6G_MB_LIB.T6G(SCH_1):TP_CPU0_USB_HUB1_SUSPEND     I1 @T6G_MB_LIB.T6G(SCH_1):PAGE153
    55 XTAL_USB_CPU0_HUB1_XIN @T6G_MB_LIB.T6G(SCH_1):XTAL_USB_CPU0_HUB1_XIN     I1 @T6G_MB_LIB.T6G(SCH_1):PAGE153
    54 XTAL_USB_CPU0_HUB1_XOUT @T6G_MB_LIB.T6G(SCH_1):XTAL_USB_CPU0_HUB1_XOUT     I1 @T6G_MB_LIB.T6G(SCH_1):PAGE153
    23 USB_CPU0_HUB1_MODE_SEL0 @T6G_MB_LIB.T6G(SCH_1):USB_CPU0_HUB1_MODE_SEL0     I1 @T6G_MB_LIB.T6G(SCH_1):PAGE153
    24 USB_CPU0_HUB1_MODE_SEL1 @T6G_MB_LIB.T6G(SCH_1):USB_CPU0_HUB1_MODE_SEL1     I1 @T6G_MB_LIB.T6G(SCH_1):PAGE153
    40    GND @T6G_MB_LIB.T6G(SCH_1):GND     I1 @T6G_MB_LIB.T6G(SCH_1):PAGE153
    17 USB_CPU0_HUB1_VBUS_US @T6G_MB_LIB.T6G(SCH_1):USB_CPU0_HUB1_VBUS_US     I1 @T6G_MB_LIB.T6G(SCH_1):PAGE153
    57 USB2_CPU0_P0_R1_DP @T6G_MB_LIB.T6G(SCH_1):USB2_CPU0_P0_R1_DP     I1 @T6G_MB_LIB.T6G(SCH_1):PAGE153
    58 USB2_CPU0_P0_R1_DN @T6G_MB_LIB.T6G(SCH_1):USB2_CPU0_P0_R1_DN     I1 @T6G_MB_LIB.T6G(SCH_1):PAGE153
     9 USB3_CPU0_BMC_TX_C1_DP @T6G_MB_LIB.T6G(SCH_1):USB3_CPU0_BMC_TX_C1_DP     I1 @T6G_MB_LIB.T6G(SCH_1):PAGE153
     8 USB3_CPU0_BMC_TX_C1_DN @T6G_MB_LIB.T6G(SCH_1):USB3_CPU0_BMC_TX_C1_DN     I1 @T6G_MB_LIB.T6G(SCH_1):PAGE153
     6 USB3_CPU0_BMC_RX_HUB1_DP @T6G_MB_LIB.T6G(SCH_1):USB3_CPU0_BMC_RX_HUB1_DP     I1 @T6G_MB_LIB.T6G(SCH_1):PAGE153
     5 USB3_CPU0_BMC_RX_HUB1_DN @T6G_MB_LIB.T6G(SCH_1):USB3_CPU0_BMC_RX_HUB1_DN     I1 @T6G_MB_LIB.T6G(SCH_1):PAGE153
    26 USB_CPU0_HUB1_RREF_SS @T6G_MB_LIB.T6G(SCH_1):USB_CPU0_HUB1_RREF_SS     I1 @T6G_MB_LIB.T6G(SCH_1):PAGE153
     2 USB_CPU0_HUB1_RREF_USB2 @T6G_MB_LIB.T6G(SCH_1):USB_CPU0_HUB1_RREF_USB2     I1 @T6G_MB_LIB.T6G(SCH_1):PAGE153
    25     NC     NC     I1 @T6G_MB_LIB.T6G(SCH_1):PAGE153
    29 PU_CPU0_USB_HUB_PWR_EN @T6G_MB_LIB.T6G(SCH_1):PU_CPU0_USB_HUB_PWR_EN     I1 @T6G_MB_LIB.T6G(SCH_1):PAGE153
    30 PU_CPU0_USB_HUB_OVRCURR @T6G_MB_LIB.T6G(SCH_1):PU_CPU0_USB_HUB_OVRCURR     I1 @T6G_MB_LIB.T6G(SCH_1):PAGE153
    31 RST_USB_CPU0_HUB1_R_N @T6G_MB_LIB.T6G(SCH_1):RST_USB_CPU0_HUB1_R_N     I1 @T6G_MB_LIB.T6G(SCH_1):PAGE153
    22 PU_CPU0_USB_HUB_RESERVED2 @T6G_MB_LIB.T6G(SCH_1):PU_CPU0_USB_HUB_RESERVED2     I1 @T6G_MB_LIB.T6G(SCH_1):PAGE153
    21 PU_CPU0_USB_HUB_RESERVED1 @T6G_MB_LIB.T6G(SCH_1):PU_CPU0_USB_HUB_RESERVED1     I1 @T6G_MB_LIB.T6G(SCH_1):PAGE153
    TH    GND @T6G_MB_LIB.T6G(SCH_1):GND     I1 @T6G_MB_LIB.T6G(SCH_1):PAGE153
     1 P1V2_CPU0_USB_DVDD12 @T6G_MB_LIB.T6G(SCH_1):P1V2_CPU0_USB_DVDD12     I1 @T6G_MB_LIB.T6G(SCH_1):PAGE154
     3 P1V2_CPU0_USB_DVDD12 @T6G_MB_LIB.T6G(SCH_1):P1V2_CPU0_USB_DVDD12     I1 @T6G_MB_LIB.T6G(SCH_1):PAGE154
    19 P1V2_CPU0_USB_DVDD12 @T6G_MB_LIB.T6G(SCH_1):P1V2_CPU0_USB_DVDD12     I1 @T6G_MB_LIB.T6G(SCH_1):PAGE154
    27 P1V2_CPU0_USB_DVDD12 @T6G_MB_LIB.T6G(SCH_1):P1V2_CPU0_USB_DVDD12     I1 @T6G_MB_LIB.T6G(SCH_1):PAGE154
    43 P1V2_AUX @T6G_MB_LIB.T6G(SCH_1):P1V2_AUX     I1 @T6G_MB_LIB.T6G(SCH_1):PAGE154
    49 P1V2_AUX @T6G_MB_LIB.T6G(SCH_1):P1V2_AUX     I1 @T6G_MB_LIB.T6G(SCH_1):PAGE154
    53 P1V2_AUX @T6G_MB_LIB.T6G(SCH_1):P1V2_AUX     I1 @T6G_MB_LIB.T6G(SCH_1):PAGE154
     7 P1V2_AUX @T6G_MB_LIB.T6G(SCH_1):P1V2_AUX     I1 @T6G_MB_LIB.T6G(SCH_1):PAGE154
    13 P1V2_AUX @T6G_MB_LIB.T6G(SCH_1):P1V2_AUX     I1 @T6G_MB_LIB.T6G(SCH_1):PAGE154
    37 P1V2_AUX @T6G_MB_LIB.T6G(SCH_1):P1V2_AUX     I1 @T6G_MB_LIB.T6G(SCH_1):PAGE154
     4 P3V3_AUX_CPU0_USB_AVDD33 @T6G_MB_LIB.T6G(SCH_1):P3V3_AUX_CPU0_USB_AVDD33     I1 @T6G_MB_LIB.T6G(SCH_1):PAGE154
    56 P3V3_AUX @T6G_MB_LIB.T6G(SCH_1):P3V3_AUX     I1 @T6G_MB_LIB.T6G(SCH_1):PAGE154
    61 P3V3_AUX @T6G_MB_LIB.T6G(SCH_1):P3V3_AUX     I1 @T6G_MB_LIB.T6G(SCH_1):PAGE154
    66 P3V3_AUX @T6G_MB_LIB.T6G(SCH_1):P3V3_AUX     I1 @T6G_MB_LIB.T6G(SCH_1):PAGE154
    28 P3V3_AUX @T6G_MB_LIB.T6G(SCH_1):P3V3_AUX     I1 @T6G_MB_LIB.T6G(SCH_1):PAGE154
    10 P1V2_AUX @T6G_MB_LIB.T6G(SCH_1):P1V2_AUX     I1 @T6G_MB_LIB.T6G(SCH_1):PAGE154
    16 P1V2_AUX @T6G_MB_LIB.T6G(SCH_1):P1V2_AUX     I1 @T6G_MB_LIB.T6G(SCH_1):PAGE154
    34 P1V2_AUX @T6G_MB_LIB.T6G(SCH_1):P1V2_AUX     I1 @T6G_MB_LIB.T6G(SCH_1):PAGE154
    46 P1V2_AUX @T6G_MB_LIB.T6G(SCH_1):P1V2_AUX     I1 @T6G_MB_LIB.T6G(SCH_1):PAGE154
    52 P1V2_AUX @T6G_MB_LIB.T6G(SCH_1):P1V2_AUX     I1 @T6G_MB_LIB.T6G(SCH_1):PAGE154

U6002 TUSB8042AIRGCR-TUSB8042AIRGCR,SMLF,IC,AL008042000
    59 USB3_CPU0_BMC_TX_C2_DN @T6G_MB_LIB.T6G(SCH_1):USB3_CPU0_BMC_TX_C2_DN   I101 @T6G_MB_LIB.T6G(SCH_1):PAGE155
    15 USB3_CPU0_BMC_RX_C2_DN @T6G_MB_LIB.T6G(SCH_1):USB3_CPU0_BMC_RX_C2_DN   I101 @T6G_MB_LIB.T6G(SCH_1):PAGE155
    14 USB3_CPU0_BMC_RX_C2_DP @T6G_MB_LIB.T6G(SCH_1):USB3_CPU0_BMC_RX_C2_DP   I101 @T6G_MB_LIB.T6G(SCH_1):PAGE155
    11 USB3_CPU0_BMC_HUB2_TX_DP @T6G_MB_LIB.T6G(SCH_1):USB3_CPU0_BMC_HUB2_TX_DP   I101 @T6G_MB_LIB.T6G(SCH_1):PAGE155
    12 USB3_CPU0_BMC_HUB2_TX_DN @T6G_MB_LIB.T6G(SCH_1):USB3_CPU0_BMC_HUB2_TX_DN   I101 @T6G_MB_LIB.T6G(SCH_1):PAGE155
    18 USB_HUB2_TI_USB_DM_DN3_MRP_VDD33 @T6G_MB_LIB.T6G(SCH_1):USB_HUB2_TI_USB_DM_DN3_MRP_VDD33   I101 @T6G_MB_LIB.T6G(SCH_1):PAGE155
    20     NC     NC   I101 @T6G_MB_LIB.T6G(SCH_1):PAGE155
    55 USB3_CPU0_BMC_RX_HUB2_DP @T6G_MB_LIB.T6G(SCH_1):USB3_CPU0_BMC_RX_HUB2_DP   I101 @T6G_MB_LIB.T6G(SCH_1):PAGE155
    54 USB2_CPU0_P0_R2_DN @T6G_MB_LIB.T6G(SCH_1):USB2_CPU0_P0_R2_DN   I101 @T6G_MB_LIB.T6G(SCH_1):PAGE155
    23 USB_HUB2_TI_USB_SSRXM_DN3_MRP_VDD12 @T6G_MB_LIB.T6G(SCH_1):USB_HUB2_TI_USB_SSRXM_DN3_MRP_VDD12   I101 @T6G_MB_LIB.T6G(SCH_1):PAGE155
    24     NC     NC   I101 @T6G_MB_LIB.T6G(SCH_1):PAGE155
    17 USB_HUB2_TI_USB_DP_DN3_MRP_VDD12 @T6G_MB_LIB.T6G(SCH_1):USB_HUB2_TI_USB_DP_DN3_MRP_VDD12   I101 @T6G_MB_LIB.T6G(SCH_1):PAGE155
    58 USB3_CPU0_BMC_TX_C2_DP @T6G_MB_LIB.T6G(SCH_1):USB3_CPU0_BMC_TX_C2_DP   I101 @T6G_MB_LIB.T6G(SCH_1):PAGE155
     9 USB2_CPU0_P0_HUB2_R_DP @T6G_MB_LIB.T6G(SCH_1):USB2_CPU0_P0_HUB2_R_DP   I101 @T6G_MB_LIB.T6G(SCH_1):PAGE155
     6 USB_HUB2_TI_USB_SSRXP_DN1_MRP_VDD12 @T6G_MB_LIB.T6G(SCH_1):USB_HUB2_TI_USB_SSRXP_DN1_MRP_VDD12   I101 @T6G_MB_LIB.T6G(SCH_1):PAGE155
    26     NC     NC   I101 @T6G_MB_LIB.T6G(SCH_1):PAGE155
     2     NC     NC   I101 @T6G_MB_LIB.T6G(SCH_1):PAGE155
    25     NC     NC   I101 @T6G_MB_LIB.T6G(SCH_1):PAGE155
    29     NC     NC   I101 @T6G_MB_LIB.T6G(SCH_1):PAGE155
    30 USB_HUB2_TI_USB_SSRXM_DN4_MRP_VDD12 @T6G_MB_LIB.T6G(SCH_1):USB_HUB2_TI_USB_SSRXM_DN4_MRP_VDD12   I101 @T6G_MB_LIB.T6G(SCH_1):PAGE155
    22     NC     NC   I101 @T6G_MB_LIB.T6G(SCH_1):PAGE155
    TH    GND @T6G_MB_LIB.T6G(SCH_1):GND   I101 @T6G_MB_LIB.T6G(SCH_1):PAGE155
    53 USB2_CPU0_P0_R2_DP @T6G_MB_LIB.T6G(SCH_1):USB2_CPU0_P0_R2_DP   I101 @T6G_MB_LIB.T6G(SCH_1):PAGE155
    56 USB3_CPU0_BMC_RX_HUB2_DN @T6G_MB_LIB.T6G(SCH_1):USB3_CPU0_BMC_RX_HUB2_DN   I101 @T6G_MB_LIB.T6G(SCH_1):PAGE155
     1 USB_HUB2_TI_USB_DP_DN1_MRP_CFG_STRAP @T6G_MB_LIB.T6G(SCH_1):USB_HUB2_TI_USB_DP_DN1_MRP_CFG_STRAP   I101 @T6G_MB_LIB.T6G(SCH_1):PAGE155
     7     NC     NC   I101 @T6G_MB_LIB.T6G(SCH_1):PAGE155
     3     NC     NC   I101 @T6G_MB_LIB.T6G(SCH_1):PAGE155
     4     NC     NC   I101 @T6G_MB_LIB.T6G(SCH_1):PAGE155
    10 USB2_CPU0_P0_HUB2_R_DN @T6G_MB_LIB.T6G(SCH_1):USB2_CPU0_P0_HUB2_R_DN   I101 @T6G_MB_LIB.T6G(SCH_1):PAGE155
    19     NC     NC   I101 @T6G_MB_LIB.T6G(SCH_1):PAGE155
    27     NC     NC   I101 @T6G_MB_LIB.T6G(SCH_1):PAGE155
    48 USB_HUB2_TI_USB_VBUS_MRP_RESET_N @T6G_MB_LIB.T6G(SCH_1):USB_HUB2_TI_USB_VBUS_MRP_RESET_N   I101 @T6G_MB_LIB.T6G(SCH_1):PAGE155
    36     NC     NC   I101 @T6G_MB_LIB.T6G(SCH_1):PAGE155
    35 USB_HUB2_TI_PWRCTL2_MRP_VDD12 @T6G_MB_LIB.T6G(SCH_1):USB_HUB2_TI_PWRCTL2_MRP_VDD12   I101 @T6G_MB_LIB.T6G(SCH_1):PAGE155
    33 USB_HUB2_TI_PWRCTL3_MRP_VDD33 @T6G_MB_LIB.T6G(SCH_1):USB_HUB2_TI_PWRCTL3_MRP_VDD33   I101 @T6G_MB_LIB.T6G(SCH_1):PAGE155
    32     NC     NC   I101 @T6G_MB_LIB.T6G(SCH_1):PAGE155
    41 USB_HUB2_TI_PWRCTL_POL_MRP_VBUS_DET @T6G_MB_LIB.T6G(SCH_1):USB_HUB2_TI_PWRCTL_POL_MRP_VBUS_DET   I101 @T6G_MB_LIB.T6G(SCH_1):PAGE155
    50 USB_HUB2_TI_GRSTZ_MRP_PROG_FUNC1 @T6G_MB_LIB.T6G(SCH_1):USB_HUB2_TI_GRSTZ_MRP_PROG_FUNC1   I101 @T6G_MB_LIB.T6G(SCH_1):PAGE155
    46 USB_HUB2_TI_OVERCUR1_MRP_PROG_FUNC4 @T6G_MB_LIB.T6G(SCH_1):USB_HUB2_TI_OVERCUR1_MRP_PROG_FUNC4   I101 @T6G_MB_LIB.T6G(SCH_1):PAGE155
    47 USB_HUB2_TI_OVERCUR2_MRP_PROG_FUNC5 @T6G_MB_LIB.T6G(SCH_1):USB_HUB2_TI_OVERCUR2_MRP_PROG_FUNC5   I101 @T6G_MB_LIB.T6G(SCH_1):PAGE155
    44 USB_HUB2_TI_OVERCUR3_MRP_CFG_BC_EN @T6G_MB_LIB.T6G(SCH_1):USB_HUB2_TI_OVERCUR3_MRP_CFG_BC_EN   I101 @T6G_MB_LIB.T6G(SCH_1):PAGE155
    43 USB_HUB2_TI_OVERCUR4_MRP_I2C_SLV_CFG1 @T6G_MB_LIB.T6G(SCH_1):USB_HUB2_TI_OVERCUR4_MRP_I2C_SLV_CFG1   I101 @T6G_MB_LIB.T6G(SCH_1):PAGE155
    49 USB_HUB2_TI_TEST_MRP_PROG_FUNC6 @T6G_MB_LIB.T6G(SCH_1):USB_HUB2_TI_TEST_MRP_PROG_FUNC6   I101 @T6G_MB_LIB.T6G(SCH_1):PAGE155
    64 USB_HUB2_TI_USB_R1_MRP_RBIAS @T6G_MB_LIB.T6G(SCH_1):USB_HUB2_TI_USB_R1_MRP_RBIAS   I101 @T6G_MB_LIB.T6G(SCH_1):PAGE155
    60 USB_HUB2_TI_NC_MRP_ATEST @T6G_MB_LIB.T6G(SCH_1):USB_HUB2_TI_NC_MRP_ATEST   I101 @T6G_MB_LIB.T6G(SCH_1):PAGE155
    13 P1V2_CPU0_USB2_DVDD12 @T6G_MB_LIB.T6G(SCH_1):P1V2_CPU0_USB2_DVDD12   I119 @T6G_MB_LIB.T6G(SCH_1):PAGE157
    37 SMB_USB_HUB2_TI_SDA_MRP_PRT_CTL2 @T6G_MB_LIB.T6G(SCH_1):SMB_USB_HUB2_TI_SDA_MRP_PRT_CTL2   I119 @T6G_MB_LIB.T6G(SCH_1):PAGE157
    28 USB_HUB2_TI_VDD_MRP_USB3DN_TXDP4 @T6G_MB_LIB.T6G(SCH_1):USB_HUB2_TI_VDD_MRP_USB3DN_TXDP4   I119 @T6G_MB_LIB.T6G(SCH_1):PAGE157
    16 USB_HUB2_TI_VDD33_MRP_PROG_FUNC7 @T6G_MB_LIB.T6G(SCH_1):USB_HUB2_TI_VDD33_MRP_PROG_FUNC7   I119 @T6G_MB_LIB.T6G(SCH_1):PAGE157
    34 USB_HUB2_TI_VDD33_MRP_PRT_CTL4_GANGPWR @T6G_MB_LIB.T6G(SCH_1):USB_HUB2_TI_VDD33_MRP_PRT_CTL4_GANGPWR   I119 @T6G_MB_LIB.T6G(SCH_1):PAGE157
    52 P3V3_AUX_CPU0_USB2_AVDD33 @T6G_MB_LIB.T6G(SCH_1):P3V3_AUX_CPU0_USB2_AVDD33   I119 @T6G_MB_LIB.T6G(SCH_1):PAGE157
    40 USB_HUB2_TI_FULLPWRMGMTZ_MRP_PROG_FUNC3 @T6G_MB_LIB.T6G(SCH_1):USB_HUB2_TI_FULLPWRMGMTZ_MRP_PROG_FUNC3   I119 @T6G_MB_LIB.T6G(SCH_1):PAGE157
    42 USB_HUB2_TI_GANGED_MRP_I2C_SLV_CFG0 @T6G_MB_LIB.T6G(SCH_1):USB_HUB2_TI_GANGED_MRP_I2C_SLV_CFG0   I119 @T6G_MB_LIB.T6G(SCH_1):PAGE157
    38 SMB_USB_HUB2_TI_SCL_MRP_PRT_CTL1 @T6G_MB_LIB.T6G(SCH_1):SMB_USB_HUB2_TI_SCL_MRP_PRT_CTL1   I119 @T6G_MB_LIB.T6G(SCH_1):PAGE157
    39 USB_HUB2_TI_SMBUSZ_MRP_PROG_FUNC2 @T6G_MB_LIB.T6G(SCH_1):USB_HUB2_TI_SMBUSZ_MRP_PROG_FUNC2   I119 @T6G_MB_LIB.T6G(SCH_1):PAGE157
    63 P3V3_AUX_CPU0_USB2_AVDD33 @T6G_MB_LIB.T6G(SCH_1):P3V3_AUX_CPU0_USB2_AVDD33   I119 @T6G_MB_LIB.T6G(SCH_1):PAGE157
    51 P1V2_CPU0_USB2_DVDD12 @T6G_MB_LIB.T6G(SCH_1):P1V2_CPU0_USB2_DVDD12   I119 @T6G_MB_LIB.T6G(SCH_1):PAGE157
    45 USB_HUB2_TI_HS_SUSPEND_MRP_CFG_NON_REM @T6G_MB_LIB.T6G(SCH_1):USB_HUB2_TI_HS_SUSPEND_MRP_CFG_NON_REM   I119 @T6G_MB_LIB.T6G(SCH_1):PAGE157
     8 USB_HUB2_TI_VDD_MRP_USB3DN_RXDM1 @T6G_MB_LIB.T6G(SCH_1):USB_HUB2_TI_VDD_MRP_USB3DN_RXDM1   I119 @T6G_MB_LIB.T6G(SCH_1):PAGE157
     5 USB_HUB2_TI_VDD_MRP_USB3DN_TXDM1 @T6G_MB_LIB.T6G(SCH_1):USB_HUB2_TI_VDD_MRP_USB3DN_TXDM1   I119 @T6G_MB_LIB.T6G(SCH_1):PAGE157
    57 P1V2_CPU0_USB2_DVDD12 @T6G_MB_LIB.T6G(SCH_1):P1V2_CPU0_USB2_DVDD12   I119 @T6G_MB_LIB.T6G(SCH_1):PAGE157
    21 USB_HUB2_TI_VDD_MRP_USB3DN_TXDP3 @T6G_MB_LIB.T6G(SCH_1):USB_HUB2_TI_VDD_MRP_USB3DN_TXDP3   I119 @T6G_MB_LIB.T6G(SCH_1):PAGE157
    31 USB_HUB2_TI_VDD_MRP_USB3DN_RXDP4 @T6G_MB_LIB.T6G(SCH_1):USB_HUB2_TI_VDD_MRP_USB3DN_RXDP4   I119 @T6G_MB_LIB.T6G(SCH_1):PAGE157
    61 XTAL_USB_CPU0_HUB2_XOUT @T6G_MB_LIB.T6G(SCH_1):XTAL_USB_CPU0_HUB2_XOUT   I119 @T6G_MB_LIB.T6G(SCH_1):PAGE157
    62 XTAL_USB_CPU0_HUB2_XIN @T6G_MB_LIB.T6G(SCH_1):XTAL_USB_CPU0_HUB2_XIN   I119 @T6G_MB_LIB.T6G(SCH_1):PAGE157

U6003 M24128BWMN6TP-M24128-BWMN6TP,SMLF,IC,AKE30Z00613
     8 P3V3_AUX @T6G_MB_LIB.T6G(SCH_1):P3V3_AUX    I64 @T6G_MB_LIB.T6G(SCH_1):PAGE153
     7 PD_USB_CPU0_WP @T6G_MB_LIB.T6G(SCH_1):PD_USB_CPU0_WP    I64 @T6G_MB_LIB.T6G(SCH_1):PAGE153
     6 SMB_USB_CPU0_HUB1_SCL_R2 @T6G_MB_LIB.T6G(SCH_1):SMB_USB_CPU0_HUB1_SCL_R2    I64 @T6G_MB_LIB.T6G(SCH_1):PAGE153
     5 SMB_USB_CPU0_HUB1_SDA_R2 @T6G_MB_LIB.T6G(SCH_1):SMB_USB_CPU0_HUB1_SDA_R2    I64 @T6G_MB_LIB.T6G(SCH_1):PAGE153
     4    GND @T6G_MB_LIB.T6G(SCH_1):GND    I64 @T6G_MB_LIB.T6G(SCH_1):PAGE153
     3 USB_CPU0_ADD_A2 @T6G_MB_LIB.T6G(SCH_1):USB_CPU0_ADD_A2    I64 @T6G_MB_LIB.T6G(SCH_1):PAGE153
     2 USB_CPU0_ADD_A1 @T6G_MB_LIB.T6G(SCH_1):USB_CPU0_ADD_A1    I64 @T6G_MB_LIB.T6G(SCH_1):PAGE153
     1 USB_CPU0_ADD_A0 @T6G_MB_LIB.T6G(SCH_1):USB_CPU0_ADD_A0    I64 @T6G_MB_LIB.T6G(SCH_1):PAGE153

U6004 MOSFET_NCH_GDS_ESD_PROTECTED-2N7002K,SMLF,EMPTY,BAA
     D A_HSC_LOW_DRAIN @T6G_MB_LIB.T6G(SCH_1):A_HSC_LOW_DRAIN    I68 @T6G_MB_LIB.T6G(SCH_1):PAGE371
     G A_HSC_LOW_GATE @T6G_MB_LIB.T6G(SCH_1):A_HSC_LOW_GATE    I68 @T6G_MB_LIB.T6G(SCH_1):PAGE371
     S    GND @T6G_MB_LIB.T6G(SCH_1):GND    I68 @T6G_MB_LIB.T6G(SCH_1):PAGE371

U6005 ISL28022FRZT-ISL28022FRZ-T,SMLF,IC,AL028022003
     9 P3V3_AUX @T6G_MB_LIB.T6G(SCH_1):P3V3_AUX    I28 @T6G_MB_LIB.T6G(SCH_1):PAGE271
     1 HSC_TYPE_ADC_A1 @T6G_MB_LIB.T6G(SCH_1):HSC_TYPE_ADC_A1    I28 @T6G_MB_LIB.T6G(SCH_1):PAGE271
     2 HSC_TYPE_ADC_A0 @T6G_MB_LIB.T6G(SCH_1):HSC_TYPE_ADC_A0    I28 @T6G_MB_LIB.T6G(SCH_1):PAGE271
     5 SMB_HSC_TYPE_ADC_SCL @T6G_MB_LIB.T6G(SCH_1):SMB_HSC_TYPE_ADC_SCL    I28 @T6G_MB_LIB.T6G(SCH_1):PAGE271
     4 SMB_HSC_TYPE_ADC_SDA @T6G_MB_LIB.T6G(SCH_1):SMB_HSC_TYPE_ADC_SDA    I28 @T6G_MB_LIB.T6G(SCH_1):PAGE271
    11 HSC_TYPE_ADC @T6G_MB_LIB.T6G(SCH_1):HSC_TYPE_ADC    I28 @T6G_MB_LIB.T6G(SCH_1):PAGE271
    13 NC_HSC_TYPE_VINP @T6G_MB_LIB.T6G(SCH_1):NC_HSC_TYPE_VINP    I28 @T6G_MB_LIB.T6G(SCH_1):PAGE271
    12 NC_HSC_TYPE_VINM @T6G_MB_LIB.T6G(SCH_1):NC_HSC_TYPE_VINM    I28 @T6G_MB_LIB.T6G(SCH_1):PAGE271
     3 HSC_TYPE_ADC_ALERT @T6G_MB_LIB.T6G(SCH_1):HSC_TYPE_ADC_ALERT    I28 @T6G_MB_LIB.T6G(SCH_1):PAGE271
     6 NC_HSC_TYPE_NC0 @T6G_MB_LIB.T6G(SCH_1):NC_HSC_TYPE_NC0    I28 @T6G_MB_LIB.T6G(SCH_1):PAGE271
     7 NC_HSC_TYPE_NC1 @T6G_MB_LIB.T6G(SCH_1):NC_HSC_TYPE_NC1    I28 @T6G_MB_LIB.T6G(SCH_1):PAGE271
     8 NC_HSC_TYPE_NC2 @T6G_MB_LIB.T6G(SCH_1):NC_HSC_TYPE_NC2    I28 @T6G_MB_LIB.T6G(SCH_1):PAGE271
    14 NC_HSC_TYPE_NC3 @T6G_MB_LIB.T6G(SCH_1):NC_HSC_TYPE_NC3    I28 @T6G_MB_LIB.T6G(SCH_1):PAGE271
    15 NC_HSC_TYPE_NC4 @T6G_MB_LIB.T6G(SCH_1):NC_HSC_TYPE_NC4    I28 @T6G_MB_LIB.T6G(SCH_1):PAGE271
    16 NC_HSC_TYPE_NC5 @T6G_MB_LIB.T6G(SCH_1):NC_HSC_TYPE_NC5    I28 @T6G_MB_LIB.T6G(SCH_1):PAGE271
    10    GND @T6G_MB_LIB.T6G(SCH_1):GND    I28 @T6G_MB_LIB.T6G(SCH_1):PAGE271
    TH    GND @T6G_MB_LIB.T6G(SCH_1):GND    I28 @T6G_MB_LIB.T6G(SCH_1):PAGE271

U6006 APX80929SAG7-APX809-29SAG-7,SMLF,IC,AL080929000
     3   P3V3 @T6G_MB_LIB.T6G(SCH_1):P3V3   I131 @T6G_MB_LIB.T6G(SCH_1):PAGE273
     2 PWRGD_P3V3_EN_R @T6G_MB_LIB.T6G(SCH_1):PWRGD_P3V3_EN_R   I131 @T6G_MB_LIB.T6G(SCH_1):PAGE273
     1    GND @T6G_MB_LIB.T6G(SCH_1):GND   I131 @T6G_MB_LIB.T6G(SCH_1):PAGE273

U6010 PT5161LRS-PT5161LRS,SMLF,IC,AJ051610U03
    R1 P5E_CPU0_P0_RX_BUF_DP<15> @T6G_MB_LIB.T6G(SCH_1):P5E_CPU0_P0_RX_BUF_DP(15)     I4 @T6G_MB_LIB.T6G(SCH_1):PAGE383
    N2 P5E_CPU0_P0_RX_BUF_DN<15> @T6G_MB_LIB.T6G(SCH_1):P5E_CPU0_P0_RX_BUF_DN(15)     I4 @T6G_MB_LIB.T6G(SCH_1):PAGE383
   AB1 P5E_CPU0_P0_RX_BUF_DP<14> @T6G_MB_LIB.T6G(SCH_1):P5E_CPU0_P0_RX_BUF_DP(14)     I4 @T6G_MB_LIB.T6G(SCH_1):PAGE383
    Y2 P5E_CPU0_P0_RX_BUF_DN<14> @T6G_MB_LIB.T6G(SCH_1):P5E_CPU0_P0_RX_BUF_DN(14)     I4 @T6G_MB_LIB.T6G(SCH_1):PAGE383
   AJ1 P5E_CPU0_P0_RX_BUF_DP<13> @T6G_MB_LIB.T6G(SCH_1):P5E_CPU0_P0_RX_BUF_DP(13)     I4 @T6G_MB_LIB.T6G(SCH_1):PAGE383
   AG2 P5E_CPU0_P0_RX_BUF_DN<13> @T6G_MB_LIB.T6G(SCH_1):P5E_CPU0_P0_RX_BUF_DN(13)     I4 @T6G_MB_LIB.T6G(SCH_1):PAGE383
   AT1 P5E_CPU0_P0_RX_BUF_DP<12> @T6G_MB_LIB.T6G(SCH_1):P5E_CPU0_P0_RX_BUF_DP(12)     I4 @T6G_MB_LIB.T6G(SCH_1):PAGE383
   AP2 P5E_CPU0_P0_RX_BUF_DN<12> @T6G_MB_LIB.T6G(SCH_1):P5E_CPU0_P0_RX_BUF_DN(12)     I4 @T6G_MB_LIB.T6G(SCH_1):PAGE383
   BC1 P5E_CPU0_P0_RX_BUF_DP<11> @T6G_MB_LIB.T6G(SCH_1):P5E_CPU0_P0_RX_BUF_DP(11)     I4 @T6G_MB_LIB.T6G(SCH_1):PAGE383
   BA2 P5E_CPU0_P0_RX_BUF_DN<11> @T6G_MB_LIB.T6G(SCH_1):P5E_CPU0_P0_RX_BUF_DN(11)     I4 @T6G_MB_LIB.T6G(SCH_1):PAGE383
   BK1 P5E_CPU0_P0_RX_BUF_DP<10> @T6G_MB_LIB.T6G(SCH_1):P5E_CPU0_P0_RX_BUF_DP(10)     I4 @T6G_MB_LIB.T6G(SCH_1):PAGE383
   BH2 P5E_CPU0_P0_RX_BUF_DN<10> @T6G_MB_LIB.T6G(SCH_1):P5E_CPU0_P0_RX_BUF_DN(10)     I4 @T6G_MB_LIB.T6G(SCH_1):PAGE383
   BU1 P5E_CPU0_P0_RX_BUF_DP<9> @T6G_MB_LIB.T6G(SCH_1):P5E_CPU0_P0_RX_BUF_DP(9)     I4 @T6G_MB_LIB.T6G(SCH_1):PAGE383
   BR2 P5E_CPU0_P0_RX_BUF_DN<9> @T6G_MB_LIB.T6G(SCH_1):P5E_CPU0_P0_RX_BUF_DN(9)     I4 @T6G_MB_LIB.T6G(SCH_1):PAGE383
   CD1 P5E_CPU0_P0_RX_BUF_DP<8> @T6G_MB_LIB.T6G(SCH_1):P5E_CPU0_P0_RX_BUF_DP(8)     I4 @T6G_MB_LIB.T6G(SCH_1):PAGE383
   CB2 P5E_CPU0_P0_RX_BUF_DN<8> @T6G_MB_LIB.T6G(SCH_1):P5E_CPU0_P0_RX_BUF_DN(8)     I4 @T6G_MB_LIB.T6G(SCH_1):PAGE383
   CL1 P5E_CPU0_P0_RX_BUF_DP<7> @T6G_MB_LIB.T6G(SCH_1):P5E_CPU0_P0_RX_BUF_DP(7)     I3 @T6G_MB_LIB.T6G(SCH_1):PAGE383
   CJ2 P5E_CPU0_P0_RX_BUF_DN<7> @T6G_MB_LIB.T6G(SCH_1):P5E_CPU0_P0_RX_BUF_DN(7)     I3 @T6G_MB_LIB.T6G(SCH_1):PAGE383
   CV1 P5E_CPU0_P0_RX_BUF_DP<6> @T6G_MB_LIB.T6G(SCH_1):P5E_CPU0_P0_RX_BUF_DP(6)     I3 @T6G_MB_LIB.T6G(SCH_1):PAGE383
   CT2 P5E_CPU0_P0_RX_BUF_DN<6> @T6G_MB_LIB.T6G(SCH_1):P5E_CPU0_P0_RX_BUF_DN(6)     I3 @T6G_MB_LIB.T6G(SCH_1):PAGE383
   DE1 P5E_CPU0_P0_RX_BUF_DP<5> @T6G_MB_LIB.T6G(SCH_1):P5E_CPU0_P0_RX_BUF_DP(5)     I3 @T6G_MB_LIB.T6G(SCH_1):PAGE383
   DC2 P5E_CPU0_P0_RX_BUF_DN<5> @T6G_MB_LIB.T6G(SCH_1):P5E_CPU0_P0_RX_BUF_DN(5)     I3 @T6G_MB_LIB.T6G(SCH_1):PAGE383
   DM1 P5E_CPU0_P0_RX_BUF_DP<4> @T6G_MB_LIB.T6G(SCH_1):P5E_CPU0_P0_RX_BUF_DP(4)     I3 @T6G_MB_LIB.T6G(SCH_1):PAGE383
   DK2 P5E_CPU0_P0_RX_BUF_DN<4> @T6G_MB_LIB.T6G(SCH_1):P5E_CPU0_P0_RX_BUF_DN(4)     I3 @T6G_MB_LIB.T6G(SCH_1):PAGE383
   DW1 P5E_CPU0_P0_RX_BUF_DP<3> @T6G_MB_LIB.T6G(SCH_1):P5E_CPU0_P0_RX_BUF_DP(3)     I3 @T6G_MB_LIB.T6G(SCH_1):PAGE383
   DU2 P5E_CPU0_P0_RX_BUF_DN<3> @T6G_MB_LIB.T6G(SCH_1):P5E_CPU0_P0_RX_BUF_DN(3)     I3 @T6G_MB_LIB.T6G(SCH_1):PAGE383
   EF1 P5E_CPU0_P0_RX_BUF_DP<2> @T6G_MB_LIB.T6G(SCH_1):P5E_CPU0_P0_RX_BUF_DP(2)     I3 @T6G_MB_LIB.T6G(SCH_1):PAGE383
   ED2 P5E_CPU0_P0_RX_BUF_DN<2> @T6G_MB_LIB.T6G(SCH_1):P5E_CPU0_P0_RX_BUF_DN(2)     I3 @T6G_MB_LIB.T6G(SCH_1):PAGE383
   EN1 P5E_CPU0_P0_RX_BUF_DP<1> @T6G_MB_LIB.T6G(SCH_1):P5E_CPU0_P0_RX_BUF_DP(1)     I3 @T6G_MB_LIB.T6G(SCH_1):PAGE383
   EL2 P5E_CPU0_P0_RX_BUF_DN<1> @T6G_MB_LIB.T6G(SCH_1):P5E_CPU0_P0_RX_BUF_DN(1)     I3 @T6G_MB_LIB.T6G(SCH_1):PAGE383
   EY1 P5E_CPU0_P0_RX_BUF_DP<0> @T6G_MB_LIB.T6G(SCH_1):P5E_CPU0_P0_RX_BUF_DP(0)     I3 @T6G_MB_LIB.T6G(SCH_1):PAGE383
   EV2 P5E_CPU0_P0_RX_BUF_DN<0> @T6G_MB_LIB.T6G(SCH_1):P5E_CPU0_P0_RX_BUF_DN(0)     I3 @T6G_MB_LIB.T6G(SCH_1):PAGE383
   FJ6     NC     NC    I53 @T6G_MB_LIB.T6G(SCH_1):PAGE385
  FJ23     NC     NC    I53 @T6G_MB_LIB.T6G(SCH_1):PAGE385
  FJ25 GPIO2_RT_CPU0_P0 @T6G_MB_LIB.T6G(SCH_1):GPIO2_RT_CPU0_P0    I53 @T6G_MB_LIB.T6G(SCH_1):PAGE385
  FJ28 GPIO3_RT_CPU0_P0 @T6G_MB_LIB.T6G(SCH_1):GPIO3_RT_CPU0_P0    I53 @T6G_MB_LIB.T6G(SCH_1):PAGE385
  FJ31     NC     NC    I53 @T6G_MB_LIB.T6G(SCH_1):PAGE385
    B3 JTAG_TCK_RT_CPU0_P0 @T6G_MB_LIB.T6G(SCH_1):JTAG_TCK_RT_CPU0_P0    I53 @T6G_MB_LIB.T6G(SCH_1):PAGE385
    B6 JTAG_TDI_RT_CPU0_P0 @T6G_MB_LIB.T6G(SCH_1):JTAG_TDI_RT_CPU0_P0    I53 @T6G_MB_LIB.T6G(SCH_1):PAGE385
    B9 JTAG_TDO_RT_CPU0_P0 @T6G_MB_LIB.T6G(SCH_1):JTAG_TDO_RT_CPU0_P0    I53 @T6G_MB_LIB.T6G(SCH_1):PAGE385
   FF8 JTAG_TEST_MODE_RT_CPU0_P0 @T6G_MB_LIB.T6G(SCH_1):JTAG_TEST_MODE_RT_CPU0_P0    I53 @T6G_MB_LIB.T6G(SCH_1):PAGE385
   B12 JTAG_TMS_RT_CPU0_P0 @T6G_MB_LIB.T6G(SCH_1):JTAG_TMS_RT_CPU0_P0    I53 @T6G_MB_LIB.T6G(SCH_1):PAGE385
    E8 JTAG_TRST_RT_CPU0_P0_N @T6G_MB_LIB.T6G(SCH_1):JTAG_TRST_RT_CPU0_P0_N    I53 @T6G_MB_LIB.T6G(SCH_1):PAGE385
   FJ9 MODE_RT_CPU0_P0 @T6G_MB_LIB.T6G(SCH_1):MODE_RT_CPU0_P0    I53 @T6G_MB_LIB.T6G(SCH_1):PAGE385
    F2 RST_RT_CPU0_P0_PERST_N @T6G_MB_LIB.T6G(SCH_1):RST_RT_CPU0_P0_PERST_N    I53 @T6G_MB_LIB.T6G(SCH_1):PAGE385
   E18     NC     NC    I53 @T6G_MB_LIB.T6G(SCH_1):PAGE385
   B16     NC     NC    I53 @T6G_MB_LIB.T6G(SCH_1):PAGE385
  FF18 CLK_100M_RETIMER_CPU0_P0_DN @T6G_MB_LIB.T6G(SCH_1):CLK_100M_RETIMER_CPU0_P0_DN    I53 @T6G_MB_LIB.T6G(SCH_1):PAGE385
  FJ16 CLK_100M_RETIMER_CPU0_P0_DP @T6G_MB_LIB.T6G(SCH_1):CLK_100M_RETIMER_CPU0_P0_DP    I53 @T6G_MB_LIB.T6G(SCH_1):PAGE385
  FF11 RST_RT_CPU0_P0_RESET_N @T6G_MB_LIB.T6G(SCH_1):RST_RT_CPU0_P0_RESET_N    I53 @T6G_MB_LIB.T6G(SCH_1):PAGE385
   E11 RXDET_BYP_RT_CPU0_P0 @T6G_MB_LIB.T6G(SCH_1):RXDET_BYP_RT_CPU0_P0    I53 @T6G_MB_LIB.T6G(SCH_1):PAGE385
  FF33 RT_CPU0_P0_SCAN_MODE @T6G_MB_LIB.T6G(SCH_1):RT_CPU0_P0_SCAN_MODE    I53 @T6G_MB_LIB.T6G(SCH_1):PAGE385
   F34 RT_CPU0_P0_ADDR1 @T6G_MB_LIB.T6G(SCH_1):RT_CPU0_P0_ADDR1    I53 @T6G_MB_LIB.T6G(SCH_1):PAGE385
   B23 RT_CPU0_P0_ADDR2 @T6G_MB_LIB.T6G(SCH_1):RT_CPU0_P0_ADDR2    I53 @T6G_MB_LIB.T6G(SCH_1):PAGE385
   B25 RT_CPU0_P0_ADDR3 @T6G_MB_LIB.T6G(SCH_1):RT_CPU0_P0_ADDR3    I53 @T6G_MB_LIB.T6G(SCH_1):PAGE385
   B31 SMB_RT_CPU0_P0_R2_SCL @T6G_MB_LIB.T6G(SCH_1):SMB_RT_CPU0_P0_R2_SCL    I53 @T6G_MB_LIB.T6G(SCH_1):PAGE385
   B28 SMB_RT_CPU0_P0_R2_SDA @T6G_MB_LIB.T6G(SCH_1):SMB_RT_CPU0_P0_R2_SDA    I53 @T6G_MB_LIB.T6G(SCH_1):PAGE385
   E30    GND @T6G_MB_LIB.T6G(SCH_1):GND    I53 @T6G_MB_LIB.T6G(SCH_1):PAGE385
  FF24 TEST0_RT_CPU0_P0 @T6G_MB_LIB.T6G(SCH_1):TEST0_RT_CPU0_P0    I53 @T6G_MB_LIB.T6G(SCH_1):PAGE385
  FF27 TEST1_RT_CPU0_P0 @T6G_MB_LIB.T6G(SCH_1):TEST1_RT_CPU0_P0    I53 @T6G_MB_LIB.T6G(SCH_1):PAGE385
  FF30 TEST2_RT_CPU0_P0 @T6G_MB_LIB.T6G(SCH_1):TEST2_RT_CPU0_P0    I53 @T6G_MB_LIB.T6G(SCH_1):PAGE385
   G35 CLKREQ_RT_CPU0_P0_N @T6G_MB_LIB.T6G(SCH_1):CLKREQ_RT_CPU0_P0_N    I53 @T6G_MB_LIB.T6G(SCH_1):PAGE385
   FF5 SMB_RT_CPU0_P0_ROM_MUX_1D_R_SCL @T6G_MB_LIB.T6G(SCH_1):SMB_RT_CPU0_P0_ROM_MUX_1D_R_SCL    I53 @T6G_MB_LIB.T6G(SCH_1):PAGE385
   FJ3 SMB_RT_CPU0_P0_ROM_MUX_1D_R_SDA @T6G_MB_LIB.T6G(SCH_1):SMB_RT_CPU0_P0_ROM_MUX_1D_R_SDA    I53 @T6G_MB_LIB.T6G(SCH_1):PAGE385
    G1 RT_CPU0_P0_VQPS @T6G_MB_LIB.T6G(SCH_1):RT_CPU0_P0_VQPS     I3 @T6G_MB_LIB.T6G(SCH_1):PAGE386
  BV20 P1V8_CPU0_RT0_1A @T6G_MB_LIB.T6G(SCH_1):P1V8_CPU0_RT0_1A     I3 @T6G_MB_LIB.T6G(SCH_1):PAGE386
  CE17 P1V8_CPU0_RT0_1A @T6G_MB_LIB.T6G(SCH_1):P1V8_CPU0_RT0_1A     I3 @T6G_MB_LIB.T6G(SCH_1):PAGE386
  CE20 P1V8_CPU0_RT0_1A @T6G_MB_LIB.T6G(SCH_1):P1V8_CPU0_RT0_1A     I3 @T6G_MB_LIB.T6G(SCH_1):PAGE386
  CM17 P1V8_CPU0_RT0_1A @T6G_MB_LIB.T6G(SCH_1):P1V8_CPU0_RT0_1A     I3 @T6G_MB_LIB.T6G(SCH_1):PAGE386
  CM20 P1V8_CPU0_RT0_1A @T6G_MB_LIB.T6G(SCH_1):P1V8_CPU0_RT0_1A     I3 @T6G_MB_LIB.T6G(SCH_1):PAGE386
  BL17 P0V9_CPU0_RT_2D @T6G_MB_LIB.T6G(SCH_1):P0V9_CPU0_RT_2D     I3 @T6G_MB_LIB.T6G(SCH_1):PAGE386
  BL20 P0V9_CPU0_RT_2D @T6G_MB_LIB.T6G(SCH_1):P0V9_CPU0_RT_2D     I3 @T6G_MB_LIB.T6G(SCH_1):PAGE386
  CW17 P0V9_CPU0_RT_2D @T6G_MB_LIB.T6G(SCH_1):P0V9_CPU0_RT_2D     I3 @T6G_MB_LIB.T6G(SCH_1):PAGE386
  CW20 P0V9_CPU0_RT_2D @T6G_MB_LIB.T6G(SCH_1):P0V9_CPU0_RT_2D     I3 @T6G_MB_LIB.T6G(SCH_1):PAGE386
  BV17 P1V8_CPU0_RT0_1A_1D @T6G_MB_LIB.T6G(SCH_1):P1V8_CPU0_RT0_1A_1D     I3 @T6G_MB_LIB.T6G(SCH_1):PAGE386
  AC17 P0V9_CPU0_RT0_2A @T6G_MB_LIB.T6G(SCH_1):P0V9_CPU0_RT0_2A     I3 @T6G_MB_LIB.T6G(SCH_1):PAGE386
  AC20 P0V9_CPU0_RT0_2A @T6G_MB_LIB.T6G(SCH_1):P0V9_CPU0_RT0_2A     I3 @T6G_MB_LIB.T6G(SCH_1):PAGE386
  AK17 P0V9_CPU0_RT0_2A @T6G_MB_LIB.T6G(SCH_1):P0V9_CPU0_RT0_2A     I3 @T6G_MB_LIB.T6G(SCH_1):PAGE386
  AK20 P0V9_CPU0_RT0_2A @T6G_MB_LIB.T6G(SCH_1):P0V9_CPU0_RT0_2A     I3 @T6G_MB_LIB.T6G(SCH_1):PAGE386
  AU17 P0V9_CPU0_RT0_2A @T6G_MB_LIB.T6G(SCH_1):P0V9_CPU0_RT0_2A     I3 @T6G_MB_LIB.T6G(SCH_1):PAGE386
  AU20 P0V9_CPU0_RT0_2A @T6G_MB_LIB.T6G(SCH_1):P0V9_CPU0_RT0_2A     I3 @T6G_MB_LIB.T6G(SCH_1):PAGE386
  BD17 P0V9_CPU0_RT0_2A_2D @T6G_MB_LIB.T6G(SCH_1):P0V9_CPU0_RT0_2A_2D     I3 @T6G_MB_LIB.T6G(SCH_1):PAGE386
  BD20 P0V9_CPU0_RT0_2A_2D @T6G_MB_LIB.T6G(SCH_1):P0V9_CPU0_RT0_2A_2D     I3 @T6G_MB_LIB.T6G(SCH_1):PAGE386
  DF17 P0V9_CPU0_RT0_2A_2D @T6G_MB_LIB.T6G(SCH_1):P0V9_CPU0_RT0_2A_2D     I3 @T6G_MB_LIB.T6G(SCH_1):PAGE386
  DF20 P0V9_CPU0_RT0_2A_2D @T6G_MB_LIB.T6G(SCH_1):P0V9_CPU0_RT0_2A_2D     I3 @T6G_MB_LIB.T6G(SCH_1):PAGE386
  DN17 P0V9_CPU0_RT0_2A @T6G_MB_LIB.T6G(SCH_1):P0V9_CPU0_RT0_2A     I3 @T6G_MB_LIB.T6G(SCH_1):PAGE386
  DN20 P0V9_CPU0_RT0_2A @T6G_MB_LIB.T6G(SCH_1):P0V9_CPU0_RT0_2A     I3 @T6G_MB_LIB.T6G(SCH_1):PAGE386
  DY17 P0V9_CPU0_RT0_2A @T6G_MB_LIB.T6G(SCH_1):P0V9_CPU0_RT0_2A     I3 @T6G_MB_LIB.T6G(SCH_1):PAGE386
  DY20 P0V9_CPU0_RT0_2A @T6G_MB_LIB.T6G(SCH_1):P0V9_CPU0_RT0_2A     I3 @T6G_MB_LIB.T6G(SCH_1):PAGE386
  EG17 P0V9_CPU0_RT0_2A @T6G_MB_LIB.T6G(SCH_1):P0V9_CPU0_RT0_2A     I3 @T6G_MB_LIB.T6G(SCH_1):PAGE386
  EG20 P0V9_CPU0_RT0_2A @T6G_MB_LIB.T6G(SCH_1):P0V9_CPU0_RT0_2A     I3 @T6G_MB_LIB.T6G(SCH_1):PAGE386
  EP17 P0V9_CPU0_RT0_2A @T6G_MB_LIB.T6G(SCH_1):P0V9_CPU0_RT0_2A     I3 @T6G_MB_LIB.T6G(SCH_1):PAGE386
  EP20 P0V9_CPU0_RT0_2A @T6G_MB_LIB.T6G(SCH_1):P0V9_CPU0_RT0_2A     I3 @T6G_MB_LIB.T6G(SCH_1):PAGE386
   T17 P0V9_CPU0_RT0_2A @T6G_MB_LIB.T6G(SCH_1):P0V9_CPU0_RT0_2A     I3 @T6G_MB_LIB.T6G(SCH_1):PAGE386
   T20 P0V9_CPU0_RT0_2A @T6G_MB_LIB.T6G(SCH_1):P0V9_CPU0_RT0_2A     I3 @T6G_MB_LIB.T6G(SCH_1):PAGE386
  AC13    GND @T6G_MB_LIB.T6G(SCH_1):GND    I17 @T6G_MB_LIB.T6G(SCH_1):PAGE386
  AC22    GND @T6G_MB_LIB.T6G(SCH_1):GND    I17 @T6G_MB_LIB.T6G(SCH_1):PAGE386
  AC32    GND @T6G_MB_LIB.T6G(SCH_1):GND    I17 @T6G_MB_LIB.T6G(SCH_1):PAGE386
   AC4    GND @T6G_MB_LIB.T6G(SCH_1):GND    I17 @T6G_MB_LIB.T6G(SCH_1):PAGE386
   AD2    GND @T6G_MB_LIB.T6G(SCH_1):GND    I17 @T6G_MB_LIB.T6G(SCH_1):PAGE386
  AD34    GND @T6G_MB_LIB.T6G(SCH_1):GND    I17 @T6G_MB_LIB.T6G(SCH_1):PAGE386
   AE1    GND @T6G_MB_LIB.T6G(SCH_1):GND    I17 @T6G_MB_LIB.T6G(SCH_1):PAGE386
  AE35    GND @T6G_MB_LIB.T6G(SCH_1):GND    I17 @T6G_MB_LIB.T6G(SCH_1):PAGE386
  AK13    GND @T6G_MB_LIB.T6G(SCH_1):GND    I17 @T6G_MB_LIB.T6G(SCH_1):PAGE386
  AK22    GND @T6G_MB_LIB.T6G(SCH_1):GND    I17 @T6G_MB_LIB.T6G(SCH_1):PAGE386
  AK32    GND @T6G_MB_LIB.T6G(SCH_1):GND    I17 @T6G_MB_LIB.T6G(SCH_1):PAGE386
   AK4    GND @T6G_MB_LIB.T6G(SCH_1):GND    I17 @T6G_MB_LIB.T6G(SCH_1):PAGE386
   AL2    GND @T6G_MB_LIB.T6G(SCH_1):GND    I17 @T6G_MB_LIB.T6G(SCH_1):PAGE386
  AL34    GND @T6G_MB_LIB.T6G(SCH_1):GND    I17 @T6G_MB_LIB.T6G(SCH_1):PAGE386
   AM1    GND @T6G_MB_LIB.T6G(SCH_1):GND    I17 @T6G_MB_LIB.T6G(SCH_1):PAGE386
  AM35    GND @T6G_MB_LIB.T6G(SCH_1):GND    I17 @T6G_MB_LIB.T6G(SCH_1):PAGE386
  AU13    GND @T6G_MB_LIB.T6G(SCH_1):GND    I17 @T6G_MB_LIB.T6G(SCH_1):PAGE386
  AU22    GND @T6G_MB_LIB.T6G(SCH_1):GND    I17 @T6G_MB_LIB.T6G(SCH_1):PAGE386
  AU32    GND @T6G_MB_LIB.T6G(SCH_1):GND    I17 @T6G_MB_LIB.T6G(SCH_1):PAGE386
   AU4    GND @T6G_MB_LIB.T6G(SCH_1):GND    I17 @T6G_MB_LIB.T6G(SCH_1):PAGE386
   AV2    GND @T6G_MB_LIB.T6G(SCH_1):GND    I17 @T6G_MB_LIB.T6G(SCH_1):PAGE386
  AV34    GND @T6G_MB_LIB.T6G(SCH_1):GND    I17 @T6G_MB_LIB.T6G(SCH_1):PAGE386
   AW1    GND @T6G_MB_LIB.T6G(SCH_1):GND    I17 @T6G_MB_LIB.T6G(SCH_1):PAGE386
  AW35    GND @T6G_MB_LIB.T6G(SCH_1):GND    I17 @T6G_MB_LIB.T6G(SCH_1):PAGE386
   B19    GND @T6G_MB_LIB.T6G(SCH_1):GND    I17 @T6G_MB_LIB.T6G(SCH_1):PAGE386
  BD13    GND @T6G_MB_LIB.T6G(SCH_1):GND    I17 @T6G_MB_LIB.T6G(SCH_1):PAGE386
  BD22    GND @T6G_MB_LIB.T6G(SCH_1):GND    I17 @T6G_MB_LIB.T6G(SCH_1):PAGE386
  BD32    GND @T6G_MB_LIB.T6G(SCH_1):GND    I17 @T6G_MB_LIB.T6G(SCH_1):PAGE386
   BD4    GND @T6G_MB_LIB.T6G(SCH_1):GND    I17 @T6G_MB_LIB.T6G(SCH_1):PAGE386
   BE2    GND @T6G_MB_LIB.T6G(SCH_1):GND    I17 @T6G_MB_LIB.T6G(SCH_1):PAGE386
  BE34    GND @T6G_MB_LIB.T6G(SCH_1):GND    I17 @T6G_MB_LIB.T6G(SCH_1):PAGE386
   BF1    GND @T6G_MB_LIB.T6G(SCH_1):GND    I17 @T6G_MB_LIB.T6G(SCH_1):PAGE386
  BF35    GND @T6G_MB_LIB.T6G(SCH_1):GND    I17 @T6G_MB_LIB.T6G(SCH_1):PAGE386
  BL13    GND @T6G_MB_LIB.T6G(SCH_1):GND    I17 @T6G_MB_LIB.T6G(SCH_1):PAGE386
  BL22    GND @T6G_MB_LIB.T6G(SCH_1):GND    I17 @T6G_MB_LIB.T6G(SCH_1):PAGE386
  BL32    GND @T6G_MB_LIB.T6G(SCH_1):GND    I17 @T6G_MB_LIB.T6G(SCH_1):PAGE386
   BL4    GND @T6G_MB_LIB.T6G(SCH_1):GND    I17 @T6G_MB_LIB.T6G(SCH_1):PAGE386
   BM2    GND @T6G_MB_LIB.T6G(SCH_1):GND    I17 @T6G_MB_LIB.T6G(SCH_1):PAGE386
  BM34    GND @T6G_MB_LIB.T6G(SCH_1):GND    I17 @T6G_MB_LIB.T6G(SCH_1):PAGE386
   BN1    GND @T6G_MB_LIB.T6G(SCH_1):GND    I17 @T6G_MB_LIB.T6G(SCH_1):PAGE386
  BN35    GND @T6G_MB_LIB.T6G(SCH_1):GND    I17 @T6G_MB_LIB.T6G(SCH_1):PAGE386
  BV13    GND @T6G_MB_LIB.T6G(SCH_1):GND    I17 @T6G_MB_LIB.T6G(SCH_1):PAGE386
  BV22    GND @T6G_MB_LIB.T6G(SCH_1):GND    I17 @T6G_MB_LIB.T6G(SCH_1):PAGE386
  BV32    GND @T6G_MB_LIB.T6G(SCH_1):GND    I17 @T6G_MB_LIB.T6G(SCH_1):PAGE386
   BV4    GND @T6G_MB_LIB.T6G(SCH_1):GND    I17 @T6G_MB_LIB.T6G(SCH_1):PAGE386
   BW2    GND @T6G_MB_LIB.T6G(SCH_1):GND    I17 @T6G_MB_LIB.T6G(SCH_1):PAGE386
  BW34    GND @T6G_MB_LIB.T6G(SCH_1):GND    I17 @T6G_MB_LIB.T6G(SCH_1):PAGE386
   BY1    GND @T6G_MB_LIB.T6G(SCH_1):GND    I17 @T6G_MB_LIB.T6G(SCH_1):PAGE386
  BY35    GND @T6G_MB_LIB.T6G(SCH_1):GND    I17 @T6G_MB_LIB.T6G(SCH_1):PAGE386
  CE13    GND @T6G_MB_LIB.T6G(SCH_1):GND    I17 @T6G_MB_LIB.T6G(SCH_1):PAGE386
  CE22    GND @T6G_MB_LIB.T6G(SCH_1):GND    I17 @T6G_MB_LIB.T6G(SCH_1):PAGE386
  CE32    GND @T6G_MB_LIB.T6G(SCH_1):GND    I17 @T6G_MB_LIB.T6G(SCH_1):PAGE386
   CE4    GND @T6G_MB_LIB.T6G(SCH_1):GND    I17 @T6G_MB_LIB.T6G(SCH_1):PAGE386
   CF2    GND @T6G_MB_LIB.T6G(SCH_1):GND    I17 @T6G_MB_LIB.T6G(SCH_1):PAGE386
  CF34    GND @T6G_MB_LIB.T6G(SCH_1):GND    I17 @T6G_MB_LIB.T6G(SCH_1):PAGE386
   CG1    GND @T6G_MB_LIB.T6G(SCH_1):GND    I17 @T6G_MB_LIB.T6G(SCH_1):PAGE386
  CG35    GND @T6G_MB_LIB.T6G(SCH_1):GND    I17 @T6G_MB_LIB.T6G(SCH_1):PAGE386
  CM13    GND @T6G_MB_LIB.T6G(SCH_1):GND    I17 @T6G_MB_LIB.T6G(SCH_1):PAGE386
  CM22    GND @T6G_MB_LIB.T6G(SCH_1):GND    I17 @T6G_MB_LIB.T6G(SCH_1):PAGE386
  CM32    GND @T6G_MB_LIB.T6G(SCH_1):GND    I17 @T6G_MB_LIB.T6G(SCH_1):PAGE386
   CM4    GND @T6G_MB_LIB.T6G(SCH_1):GND    I17 @T6G_MB_LIB.T6G(SCH_1):PAGE386
   CN2    GND @T6G_MB_LIB.T6G(SCH_1):GND    I17 @T6G_MB_LIB.T6G(SCH_1):PAGE386
  CN34    GND @T6G_MB_LIB.T6G(SCH_1):GND    I17 @T6G_MB_LIB.T6G(SCH_1):PAGE386
   CP1    GND @T6G_MB_LIB.T6G(SCH_1):GND    I17 @T6G_MB_LIB.T6G(SCH_1):PAGE386
  CP35    GND @T6G_MB_LIB.T6G(SCH_1):GND    I17 @T6G_MB_LIB.T6G(SCH_1):PAGE386
  CW13    GND @T6G_MB_LIB.T6G(SCH_1):GND    I17 @T6G_MB_LIB.T6G(SCH_1):PAGE386
  CW22    GND @T6G_MB_LIB.T6G(SCH_1):GND    I17 @T6G_MB_LIB.T6G(SCH_1):PAGE386
  CW32    GND @T6G_MB_LIB.T6G(SCH_1):GND    I17 @T6G_MB_LIB.T6G(SCH_1):PAGE386
   CW4    GND @T6G_MB_LIB.T6G(SCH_1):GND    I17 @T6G_MB_LIB.T6G(SCH_1):PAGE386
   CY2    GND @T6G_MB_LIB.T6G(SCH_1):GND    I17 @T6G_MB_LIB.T6G(SCH_1):PAGE386
  CY34    GND @T6G_MB_LIB.T6G(SCH_1):GND    I17 @T6G_MB_LIB.T6G(SCH_1):PAGE386
   DA1    GND @T6G_MB_LIB.T6G(SCH_1):GND    I17 @T6G_MB_LIB.T6G(SCH_1):PAGE386
  DA35    GND @T6G_MB_LIB.T6G(SCH_1):GND    I17 @T6G_MB_LIB.T6G(SCH_1):PAGE386
  DF13    GND @T6G_MB_LIB.T6G(SCH_1):GND    I17 @T6G_MB_LIB.T6G(SCH_1):PAGE386
  DF22    GND @T6G_MB_LIB.T6G(SCH_1):GND    I17 @T6G_MB_LIB.T6G(SCH_1):PAGE386
  DF32    GND @T6G_MB_LIB.T6G(SCH_1):GND    I17 @T6G_MB_LIB.T6G(SCH_1):PAGE386
   DF4    GND @T6G_MB_LIB.T6G(SCH_1):GND    I17 @T6G_MB_LIB.T6G(SCH_1):PAGE386
   DG2    GND @T6G_MB_LIB.T6G(SCH_1):GND    I17 @T6G_MB_LIB.T6G(SCH_1):PAGE386
  DG34    GND @T6G_MB_LIB.T6G(SCH_1):GND    I17 @T6G_MB_LIB.T6G(SCH_1):PAGE386
   DH1    GND @T6G_MB_LIB.T6G(SCH_1):GND    I17 @T6G_MB_LIB.T6G(SCH_1):PAGE386
  DH35    GND @T6G_MB_LIB.T6G(SCH_1):GND    I17 @T6G_MB_LIB.T6G(SCH_1):PAGE386
  DN13    GND @T6G_MB_LIB.T6G(SCH_1):GND    I17 @T6G_MB_LIB.T6G(SCH_1):PAGE386
    A1 NCF_A1_CPU0_P0_GND @T6G_MB_LIB.T6G(SCH_1):NCF_A1_CPU0_P0_GND    I17 @T6G_MB_LIB.T6G(SCH_1):PAGE386
   A35 NCF_CPU0_P0_GND @T6G_MB_LIB.T6G(SCH_1):NCF_CPU0_P0_GND    I17 @T6G_MB_LIB.T6G(SCH_1):PAGE386
    C2 NCF_CPU0_P0_GND @T6G_MB_LIB.T6G(SCH_1):NCF_CPU0_P0_GND    I17 @T6G_MB_LIB.T6G(SCH_1):PAGE386
   C34 NCF_CPU0_P0_GND @T6G_MB_LIB.T6G(SCH_1):NCF_CPU0_P0_GND    I17 @T6G_MB_LIB.T6G(SCH_1):PAGE386
    D1 NCF_CPU0_P0_GND @T6G_MB_LIB.T6G(SCH_1):NCF_CPU0_P0_GND    I17 @T6G_MB_LIB.T6G(SCH_1):PAGE386
   D35 NCF_CPU0_P0_GND @T6G_MB_LIB.T6G(SCH_1):NCF_CPU0_P0_GND    I17 @T6G_MB_LIB.T6G(SCH_1):PAGE386
   FE2 NCF_CPU0_P0_GND @T6G_MB_LIB.T6G(SCH_1):NCF_CPU0_P0_GND    I17 @T6G_MB_LIB.T6G(SCH_1):PAGE386
  FE34 NCF_CPU0_P0_GND @T6G_MB_LIB.T6G(SCH_1):NCF_CPU0_P0_GND    I17 @T6G_MB_LIB.T6G(SCH_1):PAGE386
   FG1 NCF_CPU0_P0_GND @T6G_MB_LIB.T6G(SCH_1):NCF_CPU0_P0_GND    I17 @T6G_MB_LIB.T6G(SCH_1):PAGE386
  FG35 NCF_CPU0_P0_GND @T6G_MB_LIB.T6G(SCH_1):NCF_CPU0_P0_GND    I17 @T6G_MB_LIB.T6G(SCH_1):PAGE386
   FH2 NCF_CPU0_P0_GND @T6G_MB_LIB.T6G(SCH_1):NCF_CPU0_P0_GND    I17 @T6G_MB_LIB.T6G(SCH_1):PAGE386
  FH34 NCF_CPU0_P0_GND @T6G_MB_LIB.T6G(SCH_1):NCF_CPU0_P0_GND    I17 @T6G_MB_LIB.T6G(SCH_1):PAGE386
  DN22    GND @T6G_MB_LIB.T6G(SCH_1):GND    I17 @T6G_MB_LIB.T6G(SCH_1):PAGE386
  DN32    GND @T6G_MB_LIB.T6G(SCH_1):GND    I17 @T6G_MB_LIB.T6G(SCH_1):PAGE386
   DN4    GND @T6G_MB_LIB.T6G(SCH_1):GND    I17 @T6G_MB_LIB.T6G(SCH_1):PAGE386
   DP2    GND @T6G_MB_LIB.T6G(SCH_1):GND    I17 @T6G_MB_LIB.T6G(SCH_1):PAGE386
  DP34    GND @T6G_MB_LIB.T6G(SCH_1):GND    I17 @T6G_MB_LIB.T6G(SCH_1):PAGE386
   DR1    GND @T6G_MB_LIB.T6G(SCH_1):GND    I17 @T6G_MB_LIB.T6G(SCH_1):PAGE386
  DR35    GND @T6G_MB_LIB.T6G(SCH_1):GND    I17 @T6G_MB_LIB.T6G(SCH_1):PAGE386
  DY13    GND @T6G_MB_LIB.T6G(SCH_1):GND    I17 @T6G_MB_LIB.T6G(SCH_1):PAGE386
  DY22    GND @T6G_MB_LIB.T6G(SCH_1):GND    I17 @T6G_MB_LIB.T6G(SCH_1):PAGE386
  DY32    GND @T6G_MB_LIB.T6G(SCH_1):GND    I17 @T6G_MB_LIB.T6G(SCH_1):PAGE386
   DY4    GND @T6G_MB_LIB.T6G(SCH_1):GND    I17 @T6G_MB_LIB.T6G(SCH_1):PAGE386
   E14    GND @T6G_MB_LIB.T6G(SCH_1):GND    I17 @T6G_MB_LIB.T6G(SCH_1):PAGE386
   E27    GND @T6G_MB_LIB.T6G(SCH_1):GND    I17 @T6G_MB_LIB.T6G(SCH_1):PAGE386
   E33    GND @T6G_MB_LIB.T6G(SCH_1):GND    I17 @T6G_MB_LIB.T6G(SCH_1):PAGE386
   EA2    GND @T6G_MB_LIB.T6G(SCH_1):GND    I17 @T6G_MB_LIB.T6G(SCH_1):PAGE386
  EA34    GND @T6G_MB_LIB.T6G(SCH_1):GND    I17 @T6G_MB_LIB.T6G(SCH_1):PAGE386
   EB1    GND @T6G_MB_LIB.T6G(SCH_1):GND    I17 @T6G_MB_LIB.T6G(SCH_1):PAGE386
  EB35    GND @T6G_MB_LIB.T6G(SCH_1):GND    I17 @T6G_MB_LIB.T6G(SCH_1):PAGE386
  EG13    GND @T6G_MB_LIB.T6G(SCH_1):GND    I17 @T6G_MB_LIB.T6G(SCH_1):PAGE386
  EG22    GND @T6G_MB_LIB.T6G(SCH_1):GND    I17 @T6G_MB_LIB.T6G(SCH_1):PAGE386
  EG32    GND @T6G_MB_LIB.T6G(SCH_1):GND    I17 @T6G_MB_LIB.T6G(SCH_1):PAGE386
   EG4    GND @T6G_MB_LIB.T6G(SCH_1):GND    I17 @T6G_MB_LIB.T6G(SCH_1):PAGE386
   EH2    GND @T6G_MB_LIB.T6G(SCH_1):GND    I17 @T6G_MB_LIB.T6G(SCH_1):PAGE386
  EH34    GND @T6G_MB_LIB.T6G(SCH_1):GND    I17 @T6G_MB_LIB.T6G(SCH_1):PAGE386
   EJ1    GND @T6G_MB_LIB.T6G(SCH_1):GND    I17 @T6G_MB_LIB.T6G(SCH_1):PAGE386
  EJ35    GND @T6G_MB_LIB.T6G(SCH_1):GND    I17 @T6G_MB_LIB.T6G(SCH_1):PAGE386
  EP13    GND @T6G_MB_LIB.T6G(SCH_1):GND    I17 @T6G_MB_LIB.T6G(SCH_1):PAGE386
  EP22    GND @T6G_MB_LIB.T6G(SCH_1):GND    I17 @T6G_MB_LIB.T6G(SCH_1):PAGE386
  EP32    GND @T6G_MB_LIB.T6G(SCH_1):GND    I17 @T6G_MB_LIB.T6G(SCH_1):PAGE386
   EP4    GND @T6G_MB_LIB.T6G(SCH_1):GND    I17 @T6G_MB_LIB.T6G(SCH_1):PAGE386
   ER2    GND @T6G_MB_LIB.T6G(SCH_1):GND    I17 @T6G_MB_LIB.T6G(SCH_1):PAGE386
  ER34    GND @T6G_MB_LIB.T6G(SCH_1):GND    I17 @T6G_MB_LIB.T6G(SCH_1):PAGE386
   ET1    GND @T6G_MB_LIB.T6G(SCH_1):GND    I17 @T6G_MB_LIB.T6G(SCH_1):PAGE386
  ET35    GND @T6G_MB_LIB.T6G(SCH_1):GND    I17 @T6G_MB_LIB.T6G(SCH_1):PAGE386
  FA15    GND @T6G_MB_LIB.T6G(SCH_1):GND    I17 @T6G_MB_LIB.T6G(SCH_1):PAGE386
  FA32    GND @T6G_MB_LIB.T6G(SCH_1):GND    I17 @T6G_MB_LIB.T6G(SCH_1):PAGE386
   FB2    GND @T6G_MB_LIB.T6G(SCH_1):GND    I17 @T6G_MB_LIB.T6G(SCH_1):PAGE386
  FB34    GND @T6G_MB_LIB.T6G(SCH_1):GND    I17 @T6G_MB_LIB.T6G(SCH_1):PAGE386
  FC19    GND @T6G_MB_LIB.T6G(SCH_1):GND    I17 @T6G_MB_LIB.T6G(SCH_1):PAGE386
  FC23    GND @T6G_MB_LIB.T6G(SCH_1):GND    I17 @T6G_MB_LIB.T6G(SCH_1):PAGE386
  FC25    GND @T6G_MB_LIB.T6G(SCH_1):GND    I17 @T6G_MB_LIB.T6G(SCH_1):PAGE386
  FC28    GND @T6G_MB_LIB.T6G(SCH_1):GND    I17 @T6G_MB_LIB.T6G(SCH_1):PAGE386
   FC3    GND @T6G_MB_LIB.T6G(SCH_1):GND    I17 @T6G_MB_LIB.T6G(SCH_1):PAGE386
   FC6    GND @T6G_MB_LIB.T6G(SCH_1):GND    I17 @T6G_MB_LIB.T6G(SCH_1):PAGE386
   FC9    GND @T6G_MB_LIB.T6G(SCH_1):GND    I17 @T6G_MB_LIB.T6G(SCH_1):PAGE386
   FD1    GND @T6G_MB_LIB.T6G(SCH_1):GND    I17 @T6G_MB_LIB.T6G(SCH_1):PAGE386
  FD35    GND @T6G_MB_LIB.T6G(SCH_1):GND    I17 @T6G_MB_LIB.T6G(SCH_1):PAGE386
  FF14    GND @T6G_MB_LIB.T6G(SCH_1):GND    I17 @T6G_MB_LIB.T6G(SCH_1):PAGE386
  FF21    GND @T6G_MB_LIB.T6G(SCH_1):GND    I17 @T6G_MB_LIB.T6G(SCH_1):PAGE386
  FJ12    GND @T6G_MB_LIB.T6G(SCH_1):GND    I17 @T6G_MB_LIB.T6G(SCH_1):PAGE386
  FJ19    GND @T6G_MB_LIB.T6G(SCH_1):GND    I17 @T6G_MB_LIB.T6G(SCH_1):PAGE386
   H12    GND @T6G_MB_LIB.T6G(SCH_1):GND    I17 @T6G_MB_LIB.T6G(SCH_1):PAGE386
   H16    GND @T6G_MB_LIB.T6G(SCH_1):GND    I17 @T6G_MB_LIB.T6G(SCH_1):PAGE386
   H19    GND @T6G_MB_LIB.T6G(SCH_1):GND    I17 @T6G_MB_LIB.T6G(SCH_1):PAGE386
   H31    GND @T6G_MB_LIB.T6G(SCH_1):GND    I17 @T6G_MB_LIB.T6G(SCH_1):PAGE386
   J22    GND @T6G_MB_LIB.T6G(SCH_1):GND    I17 @T6G_MB_LIB.T6G(SCH_1):PAGE386
    J4    GND @T6G_MB_LIB.T6G(SCH_1):GND    I17 @T6G_MB_LIB.T6G(SCH_1):PAGE386
    K2    GND @T6G_MB_LIB.T6G(SCH_1):GND    I17 @T6G_MB_LIB.T6G(SCH_1):PAGE386
   K34    GND @T6G_MB_LIB.T6G(SCH_1):GND    I17 @T6G_MB_LIB.T6G(SCH_1):PAGE386
    L1    GND @T6G_MB_LIB.T6G(SCH_1):GND    I17 @T6G_MB_LIB.T6G(SCH_1):PAGE386
   L35    GND @T6G_MB_LIB.T6G(SCH_1):GND    I17 @T6G_MB_LIB.T6G(SCH_1):PAGE386
   T13    GND @T6G_MB_LIB.T6G(SCH_1):GND    I17 @T6G_MB_LIB.T6G(SCH_1):PAGE386
   T22    GND @T6G_MB_LIB.T6G(SCH_1):GND    I17 @T6G_MB_LIB.T6G(SCH_1):PAGE386
   T32    GND @T6G_MB_LIB.T6G(SCH_1):GND    I17 @T6G_MB_LIB.T6G(SCH_1):PAGE386
    T4    GND @T6G_MB_LIB.T6G(SCH_1):GND    I17 @T6G_MB_LIB.T6G(SCH_1):PAGE386
    U2    GND @T6G_MB_LIB.T6G(SCH_1):GND    I17 @T6G_MB_LIB.T6G(SCH_1):PAGE386
   U34    GND @T6G_MB_LIB.T6G(SCH_1):GND    I17 @T6G_MB_LIB.T6G(SCH_1):PAGE386
    V1    GND @T6G_MB_LIB.T6G(SCH_1):GND    I17 @T6G_MB_LIB.T6G(SCH_1):PAGE386
   V35    GND @T6G_MB_LIB.T6G(SCH_1):GND    I17 @T6G_MB_LIB.T6G(SCH_1):PAGE386
   M26 P5E_CPU0_P0_RX_DP<15> @T6G_MB_LIB.T6G(SCH_1):P5E_CPU0_P0_RX_DP(15)     I2 @T6G_MB_LIB.T6G(SCH_1):PAGE382
   P29 P5E_CPU0_P0_RX_DN<15> @T6G_MB_LIB.T6G(SCH_1):P5E_CPU0_P0_RX_DN(15)     I2 @T6G_MB_LIB.T6G(SCH_1):PAGE382
   W26 P5E_CPU0_P0_RX_DP<14> @T6G_MB_LIB.T6G(SCH_1):P5E_CPU0_P0_RX_DP(14)     I2 @T6G_MB_LIB.T6G(SCH_1):PAGE382
  AA29 P5E_CPU0_P0_RX_DN<14> @T6G_MB_LIB.T6G(SCH_1):P5E_CPU0_P0_RX_DN(14)     I2 @T6G_MB_LIB.T6G(SCH_1):PAGE382
  AF26 P5E_CPU0_P0_RX_DP<13> @T6G_MB_LIB.T6G(SCH_1):P5E_CPU0_P0_RX_DP(13)     I2 @T6G_MB_LIB.T6G(SCH_1):PAGE382
  AH29 P5E_CPU0_P0_RX_DN<13> @T6G_MB_LIB.T6G(SCH_1):P5E_CPU0_P0_RX_DN(13)     I2 @T6G_MB_LIB.T6G(SCH_1):PAGE382
  AN26 P5E_CPU0_P0_RX_DP<12> @T6G_MB_LIB.T6G(SCH_1):P5E_CPU0_P0_RX_DP(12)     I2 @T6G_MB_LIB.T6G(SCH_1):PAGE382
  AR29 P5E_CPU0_P0_RX_DN<12> @T6G_MB_LIB.T6G(SCH_1):P5E_CPU0_P0_RX_DN(12)     I2 @T6G_MB_LIB.T6G(SCH_1):PAGE382
  AY26 P5E_CPU0_P0_RX_DP<11> @T6G_MB_LIB.T6G(SCH_1):P5E_CPU0_P0_RX_DP(11)     I2 @T6G_MB_LIB.T6G(SCH_1):PAGE382
  BB29 P5E_CPU0_P0_RX_DN<11> @T6G_MB_LIB.T6G(SCH_1):P5E_CPU0_P0_RX_DN(11)     I2 @T6G_MB_LIB.T6G(SCH_1):PAGE382
  BG26 P5E_CPU0_P0_RX_DP<10> @T6G_MB_LIB.T6G(SCH_1):P5E_CPU0_P0_RX_DP(10)     I2 @T6G_MB_LIB.T6G(SCH_1):PAGE382
  BJ29 P5E_CPU0_P0_RX_DN<10> @T6G_MB_LIB.T6G(SCH_1):P5E_CPU0_P0_RX_DN(10)     I2 @T6G_MB_LIB.T6G(SCH_1):PAGE382
  BP26 P5E_CPU0_P0_RX_DP<9> @T6G_MB_LIB.T6G(SCH_1):P5E_CPU0_P0_RX_DP(9)     I2 @T6G_MB_LIB.T6G(SCH_1):PAGE382
  BT29 P5E_CPU0_P0_RX_DN<9> @T6G_MB_LIB.T6G(SCH_1):P5E_CPU0_P0_RX_DN(9)     I2 @T6G_MB_LIB.T6G(SCH_1):PAGE382
  CA26 P5E_CPU0_P0_RX_DP<8> @T6G_MB_LIB.T6G(SCH_1):P5E_CPU0_P0_RX_DP(8)     I2 @T6G_MB_LIB.T6G(SCH_1):PAGE382
  CC29 P5E_CPU0_P0_RX_DN<8> @T6G_MB_LIB.T6G(SCH_1):P5E_CPU0_P0_RX_DN(8)     I2 @T6G_MB_LIB.T6G(SCH_1):PAGE382
  CH26 P5E_CPU0_P0_RX_DP<7> @T6G_MB_LIB.T6G(SCH_1):P5E_CPU0_P0_RX_DP(7)     I3 @T6G_MB_LIB.T6G(SCH_1):PAGE382
  CK29 P5E_CPU0_P0_RX_DN<7> @T6G_MB_LIB.T6G(SCH_1):P5E_CPU0_P0_RX_DN(7)     I3 @T6G_MB_LIB.T6G(SCH_1):PAGE382
  CR26 P5E_CPU0_P0_RX_DP<6> @T6G_MB_LIB.T6G(SCH_1):P5E_CPU0_P0_RX_DP(6)     I3 @T6G_MB_LIB.T6G(SCH_1):PAGE382
  CU29 P5E_CPU0_P0_RX_DN<6> @T6G_MB_LIB.T6G(SCH_1):P5E_CPU0_P0_RX_DN(6)     I3 @T6G_MB_LIB.T6G(SCH_1):PAGE382
  DB26 P5E_CPU0_P0_RX_DP<5> @T6G_MB_LIB.T6G(SCH_1):P5E_CPU0_P0_RX_DP(5)     I3 @T6G_MB_LIB.T6G(SCH_1):PAGE382
  DD29 P5E_CPU0_P0_RX_DN<5> @T6G_MB_LIB.T6G(SCH_1):P5E_CPU0_P0_RX_DN(5)     I3 @T6G_MB_LIB.T6G(SCH_1):PAGE382
  DJ26 P5E_CPU0_P0_RX_DP<4> @T6G_MB_LIB.T6G(SCH_1):P5E_CPU0_P0_RX_DP(4)     I3 @T6G_MB_LIB.T6G(SCH_1):PAGE382
  DL29 P5E_CPU0_P0_RX_DN<4> @T6G_MB_LIB.T6G(SCH_1):P5E_CPU0_P0_RX_DN(4)     I3 @T6G_MB_LIB.T6G(SCH_1):PAGE382
  DT26 P5E_CPU0_P0_RX_DP<3> @T6G_MB_LIB.T6G(SCH_1):P5E_CPU0_P0_RX_DP(3)     I3 @T6G_MB_LIB.T6G(SCH_1):PAGE382
  DV29 P5E_CPU0_P0_RX_DN<3> @T6G_MB_LIB.T6G(SCH_1):P5E_CPU0_P0_RX_DN(3)     I3 @T6G_MB_LIB.T6G(SCH_1):PAGE382
  EC26 P5E_CPU0_P0_RX_DP<2> @T6G_MB_LIB.T6G(SCH_1):P5E_CPU0_P0_RX_DP(2)     I3 @T6G_MB_LIB.T6G(SCH_1):PAGE382
  EE29 P5E_CPU0_P0_RX_DN<2> @T6G_MB_LIB.T6G(SCH_1):P5E_CPU0_P0_RX_DN(2)     I3 @T6G_MB_LIB.T6G(SCH_1):PAGE382
  EK26 P5E_CPU0_P0_RX_DP<1> @T6G_MB_LIB.T6G(SCH_1):P5E_CPU0_P0_RX_DP(1)     I3 @T6G_MB_LIB.T6G(SCH_1):PAGE382
  EM29 P5E_CPU0_P0_RX_DN<1> @T6G_MB_LIB.T6G(SCH_1):P5E_CPU0_P0_RX_DN(1)     I3 @T6G_MB_LIB.T6G(SCH_1):PAGE382
  EU26 P5E_CPU0_P0_RX_DP<0> @T6G_MB_LIB.T6G(SCH_1):P5E_CPU0_P0_RX_DP(0)     I3 @T6G_MB_LIB.T6G(SCH_1):PAGE382
  EW29 P5E_CPU0_P0_RX_DN<0> @T6G_MB_LIB.T6G(SCH_1):P5E_CPU0_P0_RX_DN(0)     I3 @T6G_MB_LIB.T6G(SCH_1):PAGE382
   N34 P5E_CPU0_P0_TX_C_DN<15> @T6G_MB_LIB.T6G(SCH_1):P5E_CPU0_P0_TX_C_DN(15)     I3 @T6G_MB_LIB.T6G(SCH_1):PAGE381
   R35 P5E_CPU0_P0_TX_C_DP<15> @T6G_MB_LIB.T6G(SCH_1):P5E_CPU0_P0_TX_C_DP(15)     I3 @T6G_MB_LIB.T6G(SCH_1):PAGE381
   Y34 P5E_CPU0_P0_TX_C_DN<14> @T6G_MB_LIB.T6G(SCH_1):P5E_CPU0_P0_TX_C_DN(14)     I3 @T6G_MB_LIB.T6G(SCH_1):PAGE381
  AB35 P5E_CPU0_P0_TX_C_DP<14> @T6G_MB_LIB.T6G(SCH_1):P5E_CPU0_P0_TX_C_DP(14)     I3 @T6G_MB_LIB.T6G(SCH_1):PAGE381
  AG34 P5E_CPU0_P0_TX_C_DP<13> @T6G_MB_LIB.T6G(SCH_1):P5E_CPU0_P0_TX_C_DP(13)     I3 @T6G_MB_LIB.T6G(SCH_1):PAGE381
  AJ35 P5E_CPU0_P0_TX_C_DN<13> @T6G_MB_LIB.T6G(SCH_1):P5E_CPU0_P0_TX_C_DN(13)     I3 @T6G_MB_LIB.T6G(SCH_1):PAGE381
  AP34 P5E_CPU0_P0_TX_C_DN<12> @T6G_MB_LIB.T6G(SCH_1):P5E_CPU0_P0_TX_C_DN(12)     I3 @T6G_MB_LIB.T6G(SCH_1):PAGE381
  AT35 P5E_CPU0_P0_TX_C_DP<12> @T6G_MB_LIB.T6G(SCH_1):P5E_CPU0_P0_TX_C_DP(12)     I3 @T6G_MB_LIB.T6G(SCH_1):PAGE381
  BA34 P5E_CPU0_P0_TX_C_DN<11> @T6G_MB_LIB.T6G(SCH_1):P5E_CPU0_P0_TX_C_DN(11)     I3 @T6G_MB_LIB.T6G(SCH_1):PAGE381
  BC35 P5E_CPU0_P0_TX_C_DP<11> @T6G_MB_LIB.T6G(SCH_1):P5E_CPU0_P0_TX_C_DP(11)     I3 @T6G_MB_LIB.T6G(SCH_1):PAGE381
  BH34 P5E_CPU0_P0_TX_C_DN<10> @T6G_MB_LIB.T6G(SCH_1):P5E_CPU0_P0_TX_C_DN(10)     I3 @T6G_MB_LIB.T6G(SCH_1):PAGE381
  BK35 P5E_CPU0_P0_TX_C_DP<10> @T6G_MB_LIB.T6G(SCH_1):P5E_CPU0_P0_TX_C_DP(10)     I3 @T6G_MB_LIB.T6G(SCH_1):PAGE381
  BR34 P5E_CPU0_P0_TX_C_DN<9> @T6G_MB_LIB.T6G(SCH_1):P5E_CPU0_P0_TX_C_DN(9)     I3 @T6G_MB_LIB.T6G(SCH_1):PAGE381
  BU35 P5E_CPU0_P0_TX_C_DP<9> @T6G_MB_LIB.T6G(SCH_1):P5E_CPU0_P0_TX_C_DP(9)     I3 @T6G_MB_LIB.T6G(SCH_1):PAGE381
  CB34 P5E_CPU0_P0_TX_C_DN<8> @T6G_MB_LIB.T6G(SCH_1):P5E_CPU0_P0_TX_C_DN(8)     I3 @T6G_MB_LIB.T6G(SCH_1):PAGE381
  CD35 P5E_CPU0_P0_TX_C_DP<8> @T6G_MB_LIB.T6G(SCH_1):P5E_CPU0_P0_TX_C_DP(8)     I3 @T6G_MB_LIB.T6G(SCH_1):PAGE381
  CJ34 P5E_CPU0_P0_TX_C_DN<7> @T6G_MB_LIB.T6G(SCH_1):P5E_CPU0_P0_TX_C_DN(7)     I4 @T6G_MB_LIB.T6G(SCH_1):PAGE381
  CL35 P5E_CPU0_P0_TX_C_DP<7> @T6G_MB_LIB.T6G(SCH_1):P5E_CPU0_P0_TX_C_DP(7)     I4 @T6G_MB_LIB.T6G(SCH_1):PAGE381
  CT34 P5E_CPU0_P0_TX_C_DN<6> @T6G_MB_LIB.T6G(SCH_1):P5E_CPU0_P0_TX_C_DN(6)     I4 @T6G_MB_LIB.T6G(SCH_1):PAGE381
  CV35 P5E_CPU0_P0_TX_C_DP<6> @T6G_MB_LIB.T6G(SCH_1):P5E_CPU0_P0_TX_C_DP(6)     I4 @T6G_MB_LIB.T6G(SCH_1):PAGE381
  DC34 P5E_CPU0_P0_TX_C_DN<5> @T6G_MB_LIB.T6G(SCH_1):P5E_CPU0_P0_TX_C_DN(5)     I4 @T6G_MB_LIB.T6G(SCH_1):PAGE381
  DE35 P5E_CPU0_P0_TX_C_DP<5> @T6G_MB_LIB.T6G(SCH_1):P5E_CPU0_P0_TX_C_DP(5)     I4 @T6G_MB_LIB.T6G(SCH_1):PAGE381
  DK34 P5E_CPU0_P0_TX_C_DN<4> @T6G_MB_LIB.T6G(SCH_1):P5E_CPU0_P0_TX_C_DN(4)     I4 @T6G_MB_LIB.T6G(SCH_1):PAGE381
  DM35 P5E_CPU0_P0_TX_C_DP<4> @T6G_MB_LIB.T6G(SCH_1):P5E_CPU0_P0_TX_C_DP(4)     I4 @T6G_MB_LIB.T6G(SCH_1):PAGE381
  DU34 P5E_CPU0_P0_TX_C_DN<3> @T6G_MB_LIB.T6G(SCH_1):P5E_CPU0_P0_TX_C_DN(3)     I4 @T6G_MB_LIB.T6G(SCH_1):PAGE381
  DW35 P5E_CPU0_P0_TX_C_DP<3> @T6G_MB_LIB.T6G(SCH_1):P5E_CPU0_P0_TX_C_DP(3)     I4 @T6G_MB_LIB.T6G(SCH_1):PAGE381
  ED34 P5E_CPU0_P0_TX_C_DN<2> @T6G_MB_LIB.T6G(SCH_1):P5E_CPU0_P0_TX_C_DN(2)     I4 @T6G_MB_LIB.T6G(SCH_1):PAGE381
  EF35 P5E_CPU0_P0_TX_C_DP<2> @T6G_MB_LIB.T6G(SCH_1):P5E_CPU0_P0_TX_C_DP(2)     I4 @T6G_MB_LIB.T6G(SCH_1):PAGE381
  EL34 P5E_CPU0_P0_TX_C_DP<1> @T6G_MB_LIB.T6G(SCH_1):P5E_CPU0_P0_TX_C_DP(1)     I4 @T6G_MB_LIB.T6G(SCH_1):PAGE381
  EN35 P5E_CPU0_P0_TX_C_DN<1> @T6G_MB_LIB.T6G(SCH_1):P5E_CPU0_P0_TX_C_DN(1)     I4 @T6G_MB_LIB.T6G(SCH_1):PAGE381
  EV34 P5E_CPU0_P0_TX_C_DN<0> @T6G_MB_LIB.T6G(SCH_1):P5E_CPU0_P0_TX_C_DN(0)     I4 @T6G_MB_LIB.T6G(SCH_1):PAGE381
  EY35 P5E_CPU0_P0_TX_C_DP<0> @T6G_MB_LIB.T6G(SCH_1):P5E_CPU0_P0_TX_C_DP(0)     I4 @T6G_MB_LIB.T6G(SCH_1):PAGE381
    M7 P5E_CPU0_P0_TX_BUF_DP<15> @T6G_MB_LIB.T6G(SCH_1):P5E_CPU0_P0_TX_BUF_DP(15)     I1 @T6G_MB_LIB.T6G(SCH_1):PAGE384
   P10 P5E_CPU0_P0_TX_BUF_DN<15> @T6G_MB_LIB.T6G(SCH_1):P5E_CPU0_P0_TX_BUF_DN(15)     I1 @T6G_MB_LIB.T6G(SCH_1):PAGE384
    W7 P5E_CPU0_P0_TX_BUF_DP<14> @T6G_MB_LIB.T6G(SCH_1):P5E_CPU0_P0_TX_BUF_DP(14)     I1 @T6G_MB_LIB.T6G(SCH_1):PAGE384
  AA10 P5E_CPU0_P0_TX_BUF_DN<14> @T6G_MB_LIB.T6G(SCH_1):P5E_CPU0_P0_TX_BUF_DN(14)     I1 @T6G_MB_LIB.T6G(SCH_1):PAGE384
   AF7 P5E_CPU0_P0_TX_BUF_DP<13> @T6G_MB_LIB.T6G(SCH_1):P5E_CPU0_P0_TX_BUF_DP(13)     I1 @T6G_MB_LIB.T6G(SCH_1):PAGE384
  AH10 P5E_CPU0_P0_TX_BUF_DN<13> @T6G_MB_LIB.T6G(SCH_1):P5E_CPU0_P0_TX_BUF_DN(13)     I1 @T6G_MB_LIB.T6G(SCH_1):PAGE384
   AN7 P5E_CPU0_P0_TX_BUF_DP<12> @T6G_MB_LIB.T6G(SCH_1):P5E_CPU0_P0_TX_BUF_DP(12)     I1 @T6G_MB_LIB.T6G(SCH_1):PAGE384
  AR10 P5E_CPU0_P0_TX_BUF_DN<12> @T6G_MB_LIB.T6G(SCH_1):P5E_CPU0_P0_TX_BUF_DN(12)     I1 @T6G_MB_LIB.T6G(SCH_1):PAGE384
   AY7 P5E_CPU0_P0_TX_BUF_DP<11> @T6G_MB_LIB.T6G(SCH_1):P5E_CPU0_P0_TX_BUF_DP(11)     I1 @T6G_MB_LIB.T6G(SCH_1):PAGE384
  BB10 P5E_CPU0_P0_TX_BUF_DN<11> @T6G_MB_LIB.T6G(SCH_1):P5E_CPU0_P0_TX_BUF_DN(11)     I1 @T6G_MB_LIB.T6G(SCH_1):PAGE384
   BG7 P5E_CPU0_P0_TX_BUF_DP<10> @T6G_MB_LIB.T6G(SCH_1):P5E_CPU0_P0_TX_BUF_DP(10)     I1 @T6G_MB_LIB.T6G(SCH_1):PAGE384
  BJ10 P5E_CPU0_P0_TX_BUF_DN<10> @T6G_MB_LIB.T6G(SCH_1):P5E_CPU0_P0_TX_BUF_DN(10)     I1 @T6G_MB_LIB.T6G(SCH_1):PAGE384
   BP7 P5E_CPU0_P0_TX_BUF_DP<9> @T6G_MB_LIB.T6G(SCH_1):P5E_CPU0_P0_TX_BUF_DP(9)     I1 @T6G_MB_LIB.T6G(SCH_1):PAGE384
  BT10 P5E_CPU0_P0_TX_BUF_DN<9> @T6G_MB_LIB.T6G(SCH_1):P5E_CPU0_P0_TX_BUF_DN(9)     I1 @T6G_MB_LIB.T6G(SCH_1):PAGE384
   CA7 P5E_CPU0_P0_TX_BUF_DP<8> @T6G_MB_LIB.T6G(SCH_1):P5E_CPU0_P0_TX_BUF_DP(8)     I1 @T6G_MB_LIB.T6G(SCH_1):PAGE384
  CC10 P5E_CPU0_P0_TX_BUF_DN<8> @T6G_MB_LIB.T6G(SCH_1):P5E_CPU0_P0_TX_BUF_DN(8)     I1 @T6G_MB_LIB.T6G(SCH_1):PAGE384
   CH7 P5E_CPU0_P0_TX_BUF_DP<7> @T6G_MB_LIB.T6G(SCH_1):P5E_CPU0_P0_TX_BUF_DP(7)     I2 @T6G_MB_LIB.T6G(SCH_1):PAGE384
  CK10 P5E_CPU0_P0_TX_BUF_DN<7> @T6G_MB_LIB.T6G(SCH_1):P5E_CPU0_P0_TX_BUF_DN(7)     I2 @T6G_MB_LIB.T6G(SCH_1):PAGE384
   CR7 P5E_CPU0_P0_TX_BUF_DP<6> @T6G_MB_LIB.T6G(SCH_1):P5E_CPU0_P0_TX_BUF_DP(6)     I2 @T6G_MB_LIB.T6G(SCH_1):PAGE384
  CU10 P5E_CPU0_P0_TX_BUF_DN<6> @T6G_MB_LIB.T6G(SCH_1):P5E_CPU0_P0_TX_BUF_DN(6)     I2 @T6G_MB_LIB.T6G(SCH_1):PAGE384
   DB7 P5E_CPU0_P0_TX_BUF_DP<5> @T6G_MB_LIB.T6G(SCH_1):P5E_CPU0_P0_TX_BUF_DP(5)     I2 @T6G_MB_LIB.T6G(SCH_1):PAGE384
  DD10 P5E_CPU0_P0_TX_BUF_DN<5> @T6G_MB_LIB.T6G(SCH_1):P5E_CPU0_P0_TX_BUF_DN(5)     I2 @T6G_MB_LIB.T6G(SCH_1):PAGE384
   DJ7 P5E_CPU0_P0_TX_BUF_DP<4> @T6G_MB_LIB.T6G(SCH_1):P5E_CPU0_P0_TX_BUF_DP(4)     I2 @T6G_MB_LIB.T6G(SCH_1):PAGE384
  DL10 P5E_CPU0_P0_TX_BUF_DN<4> @T6G_MB_LIB.T6G(SCH_1):P5E_CPU0_P0_TX_BUF_DN(4)     I2 @T6G_MB_LIB.T6G(SCH_1):PAGE384
   DT7 P5E_CPU0_P0_TX_BUF_DP<3> @T6G_MB_LIB.T6G(SCH_1):P5E_CPU0_P0_TX_BUF_DP(3)     I2 @T6G_MB_LIB.T6G(SCH_1):PAGE384
  DV10 P5E_CPU0_P0_TX_BUF_DN<3> @T6G_MB_LIB.T6G(SCH_1):P5E_CPU0_P0_TX_BUF_DN(3)     I2 @T6G_MB_LIB.T6G(SCH_1):PAGE384
   EC7 P5E_CPU0_P0_TX_BUF_DP<2> @T6G_MB_LIB.T6G(SCH_1):P5E_CPU0_P0_TX_BUF_DP(2)     I2 @T6G_MB_LIB.T6G(SCH_1):PAGE384
  EE10 P5E_CPU0_P0_TX_BUF_DN<2> @T6G_MB_LIB.T6G(SCH_1):P5E_CPU0_P0_TX_BUF_DN(2)     I2 @T6G_MB_LIB.T6G(SCH_1):PAGE384
   EK7 P5E_CPU0_P0_TX_BUF_DP<1> @T6G_MB_LIB.T6G(SCH_1):P5E_CPU0_P0_TX_BUF_DP(1)     I2 @T6G_MB_LIB.T6G(SCH_1):PAGE384
  EM10 P5E_CPU0_P0_TX_BUF_DN<1> @T6G_MB_LIB.T6G(SCH_1):P5E_CPU0_P0_TX_BUF_DN(1)     I2 @T6G_MB_LIB.T6G(SCH_1):PAGE384
   EU7 P5E_CPU0_P0_TX_BUF_DP<0> @T6G_MB_LIB.T6G(SCH_1):P5E_CPU0_P0_TX_BUF_DP(0)     I2 @T6G_MB_LIB.T6G(SCH_1):PAGE384
  EW10 P5E_CPU0_P0_TX_BUF_DN<0> @T6G_MB_LIB.T6G(SCH_1):P5E_CPU0_P0_TX_BUF_DN(0)     I2 @T6G_MB_LIB.T6G(SCH_1):PAGE384

U6011 PT5161LRS-PT5161LRS,SMLF,IC,AJ051610U03
    R1 P5E_CPU0_P1_RX_BUF_DP<15> @T6G_MB_LIB.T6G(SCH_1):P5E_CPU0_P1_RX_BUF_DP(15)     I1 @T6G_MB_LIB.T6G(SCH_1):PAGE406
    N2 P5E_CPU0_P1_RX_BUF_DN<15> @T6G_MB_LIB.T6G(SCH_1):P5E_CPU0_P1_RX_BUF_DN(15)     I1 @T6G_MB_LIB.T6G(SCH_1):PAGE406
   AB1 P5E_CPU0_P1_RX_BUF_DP<14> @T6G_MB_LIB.T6G(SCH_1):P5E_CPU0_P1_RX_BUF_DP(14)     I1 @T6G_MB_LIB.T6G(SCH_1):PAGE406
    Y2 P5E_CPU0_P1_RX_BUF_DN<14> @T6G_MB_LIB.T6G(SCH_1):P5E_CPU0_P1_RX_BUF_DN(14)     I1 @T6G_MB_LIB.T6G(SCH_1):PAGE406
   AJ1 P5E_CPU0_P1_RX_BUF_DP<13> @T6G_MB_LIB.T6G(SCH_1):P5E_CPU0_P1_RX_BUF_DP(13)     I1 @T6G_MB_LIB.T6G(SCH_1):PAGE406
   AG2 P5E_CPU0_P1_RX_BUF_DN<13> @T6G_MB_LIB.T6G(SCH_1):P5E_CPU0_P1_RX_BUF_DN(13)     I1 @T6G_MB_LIB.T6G(SCH_1):PAGE406
   AT1 P5E_CPU0_P1_RX_BUF_DP<12> @T6G_MB_LIB.T6G(SCH_1):P5E_CPU0_P1_RX_BUF_DP(12)     I1 @T6G_MB_LIB.T6G(SCH_1):PAGE406
   AP2 P5E_CPU0_P1_RX_BUF_DN<12> @T6G_MB_LIB.T6G(SCH_1):P5E_CPU0_P1_RX_BUF_DN(12)     I1 @T6G_MB_LIB.T6G(SCH_1):PAGE406
   BC1 P5E_CPU0_P1_RX_BUF_DP<11> @T6G_MB_LIB.T6G(SCH_1):P5E_CPU0_P1_RX_BUF_DP(11)     I1 @T6G_MB_LIB.T6G(SCH_1):PAGE406
   BA2 P5E_CPU0_P1_RX_BUF_DN<11> @T6G_MB_LIB.T6G(SCH_1):P5E_CPU0_P1_RX_BUF_DN(11)     I1 @T6G_MB_LIB.T6G(SCH_1):PAGE406
   BK1 P5E_CPU0_P1_RX_BUF_DP<10> @T6G_MB_LIB.T6G(SCH_1):P5E_CPU0_P1_RX_BUF_DP(10)     I1 @T6G_MB_LIB.T6G(SCH_1):PAGE406
   BH2 P5E_CPU0_P1_RX_BUF_DN<10> @T6G_MB_LIB.T6G(SCH_1):P5E_CPU0_P1_RX_BUF_DN(10)     I1 @T6G_MB_LIB.T6G(SCH_1):PAGE406
   BU1 P5E_CPU0_P1_RX_BUF_DP<9> @T6G_MB_LIB.T6G(SCH_1):P5E_CPU0_P1_RX_BUF_DP(9)     I1 @T6G_MB_LIB.T6G(SCH_1):PAGE406
   BR2 P5E_CPU0_P1_RX_BUF_DN<9> @T6G_MB_LIB.T6G(SCH_1):P5E_CPU0_P1_RX_BUF_DN(9)     I1 @T6G_MB_LIB.T6G(SCH_1):PAGE406
   CD1 P5E_CPU0_P1_RX_BUF_DP<8> @T6G_MB_LIB.T6G(SCH_1):P5E_CPU0_P1_RX_BUF_DP(8)     I1 @T6G_MB_LIB.T6G(SCH_1):PAGE406
   CB2 P5E_CPU0_P1_RX_BUF_DN<8> @T6G_MB_LIB.T6G(SCH_1):P5E_CPU0_P1_RX_BUF_DN(8)     I1 @T6G_MB_LIB.T6G(SCH_1):PAGE406
   CL1 P5E_CPU0_P1_RX_BUF_DP<7> @T6G_MB_LIB.T6G(SCH_1):P5E_CPU0_P1_RX_BUF_DP(7)    I38 @T6G_MB_LIB.T6G(SCH_1):PAGE406
   CJ2 P5E_CPU0_P1_RX_BUF_DN<7> @T6G_MB_LIB.T6G(SCH_1):P5E_CPU0_P1_RX_BUF_DN(7)    I38 @T6G_MB_LIB.T6G(SCH_1):PAGE406
   CV1 P5E_CPU0_P1_RX_BUF_DP<6> @T6G_MB_LIB.T6G(SCH_1):P5E_CPU0_P1_RX_BUF_DP(6)    I38 @T6G_MB_LIB.T6G(SCH_1):PAGE406
   CT2 P5E_CPU0_P1_RX_BUF_DN<6> @T6G_MB_LIB.T6G(SCH_1):P5E_CPU0_P1_RX_BUF_DN(6)    I38 @T6G_MB_LIB.T6G(SCH_1):PAGE406
   DE1 P5E_CPU0_P1_RX_BUF_DP<5> @T6G_MB_LIB.T6G(SCH_1):P5E_CPU0_P1_RX_BUF_DP(5)    I38 @T6G_MB_LIB.T6G(SCH_1):PAGE406
   DC2 P5E_CPU0_P1_RX_BUF_DN<5> @T6G_MB_LIB.T6G(SCH_1):P5E_CPU0_P1_RX_BUF_DN(5)    I38 @T6G_MB_LIB.T6G(SCH_1):PAGE406
   DM1 P5E_CPU0_P1_RX_BUF_DP<4> @T6G_MB_LIB.T6G(SCH_1):P5E_CPU0_P1_RX_BUF_DP(4)    I38 @T6G_MB_LIB.T6G(SCH_1):PAGE406
   DK2 P5E_CPU0_P1_RX_BUF_DN<4> @T6G_MB_LIB.T6G(SCH_1):P5E_CPU0_P1_RX_BUF_DN(4)    I38 @T6G_MB_LIB.T6G(SCH_1):PAGE406
   DW1 P5E_CPU0_P1_RX_BUF_DP<3> @T6G_MB_LIB.T6G(SCH_1):P5E_CPU0_P1_RX_BUF_DP(3)    I38 @T6G_MB_LIB.T6G(SCH_1):PAGE406
   DU2 P5E_CPU0_P1_RX_BUF_DN<3> @T6G_MB_LIB.T6G(SCH_1):P5E_CPU0_P1_RX_BUF_DN(3)    I38 @T6G_MB_LIB.T6G(SCH_1):PAGE406
   EF1 P5E_CPU0_P1_RX_BUF_DP<2> @T6G_MB_LIB.T6G(SCH_1):P5E_CPU0_P1_RX_BUF_DP(2)    I38 @T6G_MB_LIB.T6G(SCH_1):PAGE406
   ED2 P5E_CPU0_P1_RX_BUF_DN<2> @T6G_MB_LIB.T6G(SCH_1):P5E_CPU0_P1_RX_BUF_DN(2)    I38 @T6G_MB_LIB.T6G(SCH_1):PAGE406
   EN1 P5E_CPU0_P1_RX_BUF_DP<1> @T6G_MB_LIB.T6G(SCH_1):P5E_CPU0_P1_RX_BUF_DP(1)    I38 @T6G_MB_LIB.T6G(SCH_1):PAGE406
   EL2 P5E_CPU0_P1_RX_BUF_DN<1> @T6G_MB_LIB.T6G(SCH_1):P5E_CPU0_P1_RX_BUF_DN(1)    I38 @T6G_MB_LIB.T6G(SCH_1):PAGE406
   EY1 P5E_CPU0_P1_RX_BUF_DP<0> @T6G_MB_LIB.T6G(SCH_1):P5E_CPU0_P1_RX_BUF_DP(0)    I38 @T6G_MB_LIB.T6G(SCH_1):PAGE406
   EV2 P5E_CPU0_P1_RX_BUF_DN<0> @T6G_MB_LIB.T6G(SCH_1):P5E_CPU0_P1_RX_BUF_DN(0)    I38 @T6G_MB_LIB.T6G(SCH_1):PAGE406
   FJ6     NC     NC    I83 @T6G_MB_LIB.T6G(SCH_1):PAGE408
  FJ23     NC     NC    I83 @T6G_MB_LIB.T6G(SCH_1):PAGE408
  FJ25 GPIO2_RT_CPU0_P1 @T6G_MB_LIB.T6G(SCH_1):GPIO2_RT_CPU0_P1    I83 @T6G_MB_LIB.T6G(SCH_1):PAGE408
  FJ28 GPIO3_RT_CPU0_P1 @T6G_MB_LIB.T6G(SCH_1):GPIO3_RT_CPU0_P1    I83 @T6G_MB_LIB.T6G(SCH_1):PAGE408
  FJ31     NC     NC    I83 @T6G_MB_LIB.T6G(SCH_1):PAGE408
    B3 JTAG_TCK_RT_CPU0_P1 @T6G_MB_LIB.T6G(SCH_1):JTAG_TCK_RT_CPU0_P1    I83 @T6G_MB_LIB.T6G(SCH_1):PAGE408
    B6 JTAG_TDI_RT_CPU0_P1 @T6G_MB_LIB.T6G(SCH_1):JTAG_TDI_RT_CPU0_P1    I83 @T6G_MB_LIB.T6G(SCH_1):PAGE408
    B9 JTAG_TDO_RT_CPU0_P1 @T6G_MB_LIB.T6G(SCH_1):JTAG_TDO_RT_CPU0_P1    I83 @T6G_MB_LIB.T6G(SCH_1):PAGE408
   FF8 JTAG_TEST_MODE_RT_CPU0_P1 @T6G_MB_LIB.T6G(SCH_1):JTAG_TEST_MODE_RT_CPU0_P1    I83 @T6G_MB_LIB.T6G(SCH_1):PAGE408
   B12 JTAG_TMS_RT_CPU0_P1 @T6G_MB_LIB.T6G(SCH_1):JTAG_TMS_RT_CPU0_P1    I83 @T6G_MB_LIB.T6G(SCH_1):PAGE408
    E8 JTAG_TRST_RT_CPU0_P1_N @T6G_MB_LIB.T6G(SCH_1):JTAG_TRST_RT_CPU0_P1_N    I83 @T6G_MB_LIB.T6G(SCH_1):PAGE408
   FJ9 MODE_RT_CPU0_P1 @T6G_MB_LIB.T6G(SCH_1):MODE_RT_CPU0_P1    I83 @T6G_MB_LIB.T6G(SCH_1):PAGE408
    F2 RST_RT_CPU0_P1_PERST_N @T6G_MB_LIB.T6G(SCH_1):RST_RT_CPU0_P1_PERST_N    I83 @T6G_MB_LIB.T6G(SCH_1):PAGE408
   E18     NC     NC    I83 @T6G_MB_LIB.T6G(SCH_1):PAGE408
   B16     NC     NC    I83 @T6G_MB_LIB.T6G(SCH_1):PAGE408
  FF18 CLK_100M_RETIMER_CPU0_P1_DN @T6G_MB_LIB.T6G(SCH_1):CLK_100M_RETIMER_CPU0_P1_DN    I83 @T6G_MB_LIB.T6G(SCH_1):PAGE408
  FJ16 CLK_100M_RETIMER_CPU0_P1_DP @T6G_MB_LIB.T6G(SCH_1):CLK_100M_RETIMER_CPU0_P1_DP    I83 @T6G_MB_LIB.T6G(SCH_1):PAGE408
  FF11 RST_RT_CPU0_P1_RESET_N @T6G_MB_LIB.T6G(SCH_1):RST_RT_CPU0_P1_RESET_N    I83 @T6G_MB_LIB.T6G(SCH_1):PAGE408
   E11 RXDET_BYP_RT_CPU0_P1 @T6G_MB_LIB.T6G(SCH_1):RXDET_BYP_RT_CPU0_P1    I83 @T6G_MB_LIB.T6G(SCH_1):PAGE408
  FF33 RT_CPU0_P1_SCAN_MODE @T6G_MB_LIB.T6G(SCH_1):RT_CPU0_P1_SCAN_MODE    I83 @T6G_MB_LIB.T6G(SCH_1):PAGE408
   F34 RT_CPU0_P1_ADDR1 @T6G_MB_LIB.T6G(SCH_1):RT_CPU0_P1_ADDR1    I83 @T6G_MB_LIB.T6G(SCH_1):PAGE408
   B23 RT_CPU0_P1_ADDR2 @T6G_MB_LIB.T6G(SCH_1):RT_CPU0_P1_ADDR2    I83 @T6G_MB_LIB.T6G(SCH_1):PAGE408
   B25 RT_CPU0_P1_ADDR3 @T6G_MB_LIB.T6G(SCH_1):RT_CPU0_P1_ADDR3    I83 @T6G_MB_LIB.T6G(SCH_1):PAGE408
   B31 SMB_RT_CPU0_P1_R2_SCL @T6G_MB_LIB.T6G(SCH_1):SMB_RT_CPU0_P1_R2_SCL    I83 @T6G_MB_LIB.T6G(SCH_1):PAGE408
   B28 SMB_RT_CPU0_P1_R2_SDA @T6G_MB_LIB.T6G(SCH_1):SMB_RT_CPU0_P1_R2_SDA    I83 @T6G_MB_LIB.T6G(SCH_1):PAGE408
   E30    GND @T6G_MB_LIB.T6G(SCH_1):GND    I83 @T6G_MB_LIB.T6G(SCH_1):PAGE408
  FF24 TEST0_RT_CPU0_P1 @T6G_MB_LIB.T6G(SCH_1):TEST0_RT_CPU0_P1    I83 @T6G_MB_LIB.T6G(SCH_1):PAGE408
  FF27 TEST1_RT_CPU0_P1 @T6G_MB_LIB.T6G(SCH_1):TEST1_RT_CPU0_P1    I83 @T6G_MB_LIB.T6G(SCH_1):PAGE408
  FF30 TEST2_RT_CPU0_P1 @T6G_MB_LIB.T6G(SCH_1):TEST2_RT_CPU0_P1    I83 @T6G_MB_LIB.T6G(SCH_1):PAGE408
   G35 CLKREQ_RT_CPU0_P1_N @T6G_MB_LIB.T6G(SCH_1):CLKREQ_RT_CPU0_P1_N    I83 @T6G_MB_LIB.T6G(SCH_1):PAGE408
   FF5 SMB_RT_CPU0_P1_ROM_MUX_1D_R_SCL @T6G_MB_LIB.T6G(SCH_1):SMB_RT_CPU0_P1_ROM_MUX_1D_R_SCL    I83 @T6G_MB_LIB.T6G(SCH_1):PAGE408
   FJ3 SMB_RT_CPU0_P1_ROM_MUX_1D_R_SDA @T6G_MB_LIB.T6G(SCH_1):SMB_RT_CPU0_P1_ROM_MUX_1D_R_SDA    I83 @T6G_MB_LIB.T6G(SCH_1):PAGE408
    G1 RT_CPU0_P1_VQPS @T6G_MB_LIB.T6G(SCH_1):RT_CPU0_P1_VQPS     I5 @T6G_MB_LIB.T6G(SCH_1):PAGE409
  BV20 P1V8_CPU0_RT1_1A @T6G_MB_LIB.T6G(SCH_1):P1V8_CPU0_RT1_1A     I5 @T6G_MB_LIB.T6G(SCH_1):PAGE409
  CE17 P1V8_CPU0_RT1_1A @T6G_MB_LIB.T6G(SCH_1):P1V8_CPU0_RT1_1A     I5 @T6G_MB_LIB.T6G(SCH_1):PAGE409
  CE20 P1V8_CPU0_RT1_1A @T6G_MB_LIB.T6G(SCH_1):P1V8_CPU0_RT1_1A     I5 @T6G_MB_LIB.T6G(SCH_1):PAGE409
  CM17 P1V8_CPU0_RT1_1A @T6G_MB_LIB.T6G(SCH_1):P1V8_CPU0_RT1_1A     I5 @T6G_MB_LIB.T6G(SCH_1):PAGE409
  CM20 P1V8_CPU0_RT1_1A @T6G_MB_LIB.T6G(SCH_1):P1V8_CPU0_RT1_1A     I5 @T6G_MB_LIB.T6G(SCH_1):PAGE409
  BL17 P0V9_CPU0_RT_2D @T6G_MB_LIB.T6G(SCH_1):P0V9_CPU0_RT_2D     I5 @T6G_MB_LIB.T6G(SCH_1):PAGE409
  BL20 P0V9_CPU0_RT_2D @T6G_MB_LIB.T6G(SCH_1):P0V9_CPU0_RT_2D     I5 @T6G_MB_LIB.T6G(SCH_1):PAGE409
  CW17 P0V9_CPU0_RT_2D @T6G_MB_LIB.T6G(SCH_1):P0V9_CPU0_RT_2D     I5 @T6G_MB_LIB.T6G(SCH_1):PAGE409
  CW20 P0V9_CPU0_RT_2D @T6G_MB_LIB.T6G(SCH_1):P0V9_CPU0_RT_2D     I5 @T6G_MB_LIB.T6G(SCH_1):PAGE409
  BV17 P1V8_CPU0_RT1_1A_1D @T6G_MB_LIB.T6G(SCH_1):P1V8_CPU0_RT1_1A_1D     I5 @T6G_MB_LIB.T6G(SCH_1):PAGE409
  AC17 P0V9_CPU0_RT1_2A @T6G_MB_LIB.T6G(SCH_1):P0V9_CPU0_RT1_2A     I5 @T6G_MB_LIB.T6G(SCH_1):PAGE409
  AC20 P0V9_CPU0_RT1_2A @T6G_MB_LIB.T6G(SCH_1):P0V9_CPU0_RT1_2A     I5 @T6G_MB_LIB.T6G(SCH_1):PAGE409
  AK17 P0V9_CPU0_RT1_2A @T6G_MB_LIB.T6G(SCH_1):P0V9_CPU0_RT1_2A     I5 @T6G_MB_LIB.T6G(SCH_1):PAGE409
  AK20 P0V9_CPU0_RT1_2A @T6G_MB_LIB.T6G(SCH_1):P0V9_CPU0_RT1_2A     I5 @T6G_MB_LIB.T6G(SCH_1):PAGE409
  AU17 P0V9_CPU0_RT1_2A @T6G_MB_LIB.T6G(SCH_1):P0V9_CPU0_RT1_2A     I5 @T6G_MB_LIB.T6G(SCH_1):PAGE409
  AU20 P0V9_CPU0_RT1_2A @T6G_MB_LIB.T6G(SCH_1):P0V9_CPU0_RT1_2A     I5 @T6G_MB_LIB.T6G(SCH_1):PAGE409
  BD17 P0V9_CPU0_RT1_2A_2D @T6G_MB_LIB.T6G(SCH_1):P0V9_CPU0_RT1_2A_2D     I5 @T6G_MB_LIB.T6G(SCH_1):PAGE409
  BD20 P0V9_CPU0_RT1_2A_2D @T6G_MB_LIB.T6G(SCH_1):P0V9_CPU0_RT1_2A_2D     I5 @T6G_MB_LIB.T6G(SCH_1):PAGE409
  DF17 P0V9_CPU0_RT1_2A_2D @T6G_MB_LIB.T6G(SCH_1):P0V9_CPU0_RT1_2A_2D     I5 @T6G_MB_LIB.T6G(SCH_1):PAGE409
  DF20 P0V9_CPU0_RT1_2A_2D @T6G_MB_LIB.T6G(SCH_1):P0V9_CPU0_RT1_2A_2D     I5 @T6G_MB_LIB.T6G(SCH_1):PAGE409
  DN17 P0V9_CPU0_RT1_2A @T6G_MB_LIB.T6G(SCH_1):P0V9_CPU0_RT1_2A     I5 @T6G_MB_LIB.T6G(SCH_1):PAGE409
  DN20 P0V9_CPU0_RT1_2A @T6G_MB_LIB.T6G(SCH_1):P0V9_CPU0_RT1_2A     I5 @T6G_MB_LIB.T6G(SCH_1):PAGE409
  DY17 P0V9_CPU0_RT1_2A @T6G_MB_LIB.T6G(SCH_1):P0V9_CPU0_RT1_2A     I5 @T6G_MB_LIB.T6G(SCH_1):PAGE409
  DY20 P0V9_CPU0_RT1_2A @T6G_MB_LIB.T6G(SCH_1):P0V9_CPU0_RT1_2A     I5 @T6G_MB_LIB.T6G(SCH_1):PAGE409
  EG17 P0V9_CPU0_RT1_2A @T6G_MB_LIB.T6G(SCH_1):P0V9_CPU0_RT1_2A     I5 @T6G_MB_LIB.T6G(SCH_1):PAGE409
  EG20 P0V9_CPU0_RT1_2A @T6G_MB_LIB.T6G(SCH_1):P0V9_CPU0_RT1_2A     I5 @T6G_MB_LIB.T6G(SCH_1):PAGE409
  EP17 P0V9_CPU0_RT1_2A @T6G_MB_LIB.T6G(SCH_1):P0V9_CPU0_RT1_2A     I5 @T6G_MB_LIB.T6G(SCH_1):PAGE409
  EP20 P0V9_CPU0_RT1_2A @T6G_MB_LIB.T6G(SCH_1):P0V9_CPU0_RT1_2A     I5 @T6G_MB_LIB.T6G(SCH_1):PAGE409
   T17 P0V9_CPU0_RT1_2A @T6G_MB_LIB.T6G(SCH_1):P0V9_CPU0_RT1_2A     I5 @T6G_MB_LIB.T6G(SCH_1):PAGE409
   T20 P0V9_CPU0_RT1_2A @T6G_MB_LIB.T6G(SCH_1):P0V9_CPU0_RT1_2A     I5 @T6G_MB_LIB.T6G(SCH_1):PAGE409
  AC13    GND @T6G_MB_LIB.T6G(SCH_1):GND    I17 @T6G_MB_LIB.T6G(SCH_1):PAGE409
  AC22    GND @T6G_MB_LIB.T6G(SCH_1):GND    I17 @T6G_MB_LIB.T6G(SCH_1):PAGE409
  AC32    GND @T6G_MB_LIB.T6G(SCH_1):GND    I17 @T6G_MB_LIB.T6G(SCH_1):PAGE409
   AC4    GND @T6G_MB_LIB.T6G(SCH_1):GND    I17 @T6G_MB_LIB.T6G(SCH_1):PAGE409
   AD2    GND @T6G_MB_LIB.T6G(SCH_1):GND    I17 @T6G_MB_LIB.T6G(SCH_1):PAGE409
  AD34    GND @T6G_MB_LIB.T6G(SCH_1):GND    I17 @T6G_MB_LIB.T6G(SCH_1):PAGE409
   AE1    GND @T6G_MB_LIB.T6G(SCH_1):GND    I17 @T6G_MB_LIB.T6G(SCH_1):PAGE409
  AE35    GND @T6G_MB_LIB.T6G(SCH_1):GND    I17 @T6G_MB_LIB.T6G(SCH_1):PAGE409
  AK13    GND @T6G_MB_LIB.T6G(SCH_1):GND    I17 @T6G_MB_LIB.T6G(SCH_1):PAGE409
  AK22    GND @T6G_MB_LIB.T6G(SCH_1):GND    I17 @T6G_MB_LIB.T6G(SCH_1):PAGE409
  AK32    GND @T6G_MB_LIB.T6G(SCH_1):GND    I17 @T6G_MB_LIB.T6G(SCH_1):PAGE409
   AK4    GND @T6G_MB_LIB.T6G(SCH_1):GND    I17 @T6G_MB_LIB.T6G(SCH_1):PAGE409
   AL2    GND @T6G_MB_LIB.T6G(SCH_1):GND    I17 @T6G_MB_LIB.T6G(SCH_1):PAGE409
  AL34    GND @T6G_MB_LIB.T6G(SCH_1):GND    I17 @T6G_MB_LIB.T6G(SCH_1):PAGE409
   AM1    GND @T6G_MB_LIB.T6G(SCH_1):GND    I17 @T6G_MB_LIB.T6G(SCH_1):PAGE409
  AM35    GND @T6G_MB_LIB.T6G(SCH_1):GND    I17 @T6G_MB_LIB.T6G(SCH_1):PAGE409
  AU13    GND @T6G_MB_LIB.T6G(SCH_1):GND    I17 @T6G_MB_LIB.T6G(SCH_1):PAGE409
  AU22    GND @T6G_MB_LIB.T6G(SCH_1):GND    I17 @T6G_MB_LIB.T6G(SCH_1):PAGE409
  AU32    GND @T6G_MB_LIB.T6G(SCH_1):GND    I17 @T6G_MB_LIB.T6G(SCH_1):PAGE409
   AU4    GND @T6G_MB_LIB.T6G(SCH_1):GND    I17 @T6G_MB_LIB.T6G(SCH_1):PAGE409
   AV2    GND @T6G_MB_LIB.T6G(SCH_1):GND    I17 @T6G_MB_LIB.T6G(SCH_1):PAGE409
  AV34    GND @T6G_MB_LIB.T6G(SCH_1):GND    I17 @T6G_MB_LIB.T6G(SCH_1):PAGE409
   AW1    GND @T6G_MB_LIB.T6G(SCH_1):GND    I17 @T6G_MB_LIB.T6G(SCH_1):PAGE409
  AW35    GND @T6G_MB_LIB.T6G(SCH_1):GND    I17 @T6G_MB_LIB.T6G(SCH_1):PAGE409
   B19    GND @T6G_MB_LIB.T6G(SCH_1):GND    I17 @T6G_MB_LIB.T6G(SCH_1):PAGE409
  BD13    GND @T6G_MB_LIB.T6G(SCH_1):GND    I17 @T6G_MB_LIB.T6G(SCH_1):PAGE409
  BD22    GND @T6G_MB_LIB.T6G(SCH_1):GND    I17 @T6G_MB_LIB.T6G(SCH_1):PAGE409
  BD32    GND @T6G_MB_LIB.T6G(SCH_1):GND    I17 @T6G_MB_LIB.T6G(SCH_1):PAGE409
   BD4    GND @T6G_MB_LIB.T6G(SCH_1):GND    I17 @T6G_MB_LIB.T6G(SCH_1):PAGE409
   BE2    GND @T6G_MB_LIB.T6G(SCH_1):GND    I17 @T6G_MB_LIB.T6G(SCH_1):PAGE409
  BE34    GND @T6G_MB_LIB.T6G(SCH_1):GND    I17 @T6G_MB_LIB.T6G(SCH_1):PAGE409
   BF1    GND @T6G_MB_LIB.T6G(SCH_1):GND    I17 @T6G_MB_LIB.T6G(SCH_1):PAGE409
  BF35    GND @T6G_MB_LIB.T6G(SCH_1):GND    I17 @T6G_MB_LIB.T6G(SCH_1):PAGE409
  BL13    GND @T6G_MB_LIB.T6G(SCH_1):GND    I17 @T6G_MB_LIB.T6G(SCH_1):PAGE409
  BL22    GND @T6G_MB_LIB.T6G(SCH_1):GND    I17 @T6G_MB_LIB.T6G(SCH_1):PAGE409
  BL32    GND @T6G_MB_LIB.T6G(SCH_1):GND    I17 @T6G_MB_LIB.T6G(SCH_1):PAGE409
   BL4    GND @T6G_MB_LIB.T6G(SCH_1):GND    I17 @T6G_MB_LIB.T6G(SCH_1):PAGE409
   BM2    GND @T6G_MB_LIB.T6G(SCH_1):GND    I17 @T6G_MB_LIB.T6G(SCH_1):PAGE409
  BM34    GND @T6G_MB_LIB.T6G(SCH_1):GND    I17 @T6G_MB_LIB.T6G(SCH_1):PAGE409
   BN1    GND @T6G_MB_LIB.T6G(SCH_1):GND    I17 @T6G_MB_LIB.T6G(SCH_1):PAGE409
  BN35    GND @T6G_MB_LIB.T6G(SCH_1):GND    I17 @T6G_MB_LIB.T6G(SCH_1):PAGE409
  BV13    GND @T6G_MB_LIB.T6G(SCH_1):GND    I17 @T6G_MB_LIB.T6G(SCH_1):PAGE409
  BV22    GND @T6G_MB_LIB.T6G(SCH_1):GND    I17 @T6G_MB_LIB.T6G(SCH_1):PAGE409
  BV32    GND @T6G_MB_LIB.T6G(SCH_1):GND    I17 @T6G_MB_LIB.T6G(SCH_1):PAGE409
   BV4    GND @T6G_MB_LIB.T6G(SCH_1):GND    I17 @T6G_MB_LIB.T6G(SCH_1):PAGE409
   BW2    GND @T6G_MB_LIB.T6G(SCH_1):GND    I17 @T6G_MB_LIB.T6G(SCH_1):PAGE409
  BW34    GND @T6G_MB_LIB.T6G(SCH_1):GND    I17 @T6G_MB_LIB.T6G(SCH_1):PAGE409
   BY1    GND @T6G_MB_LIB.T6G(SCH_1):GND    I17 @T6G_MB_LIB.T6G(SCH_1):PAGE409
  BY35    GND @T6G_MB_LIB.T6G(SCH_1):GND    I17 @T6G_MB_LIB.T6G(SCH_1):PAGE409
  CE13    GND @T6G_MB_LIB.T6G(SCH_1):GND    I17 @T6G_MB_LIB.T6G(SCH_1):PAGE409
  CE22    GND @T6G_MB_LIB.T6G(SCH_1):GND    I17 @T6G_MB_LIB.T6G(SCH_1):PAGE409
  CE32    GND @T6G_MB_LIB.T6G(SCH_1):GND    I17 @T6G_MB_LIB.T6G(SCH_1):PAGE409
   CE4    GND @T6G_MB_LIB.T6G(SCH_1):GND    I17 @T6G_MB_LIB.T6G(SCH_1):PAGE409
   CF2    GND @T6G_MB_LIB.T6G(SCH_1):GND    I17 @T6G_MB_LIB.T6G(SCH_1):PAGE409
  CF34    GND @T6G_MB_LIB.T6G(SCH_1):GND    I17 @T6G_MB_LIB.T6G(SCH_1):PAGE409
   CG1    GND @T6G_MB_LIB.T6G(SCH_1):GND    I17 @T6G_MB_LIB.T6G(SCH_1):PAGE409
  CG35    GND @T6G_MB_LIB.T6G(SCH_1):GND    I17 @T6G_MB_LIB.T6G(SCH_1):PAGE409
  CM13    GND @T6G_MB_LIB.T6G(SCH_1):GND    I17 @T6G_MB_LIB.T6G(SCH_1):PAGE409
  CM22    GND @T6G_MB_LIB.T6G(SCH_1):GND    I17 @T6G_MB_LIB.T6G(SCH_1):PAGE409
  CM32    GND @T6G_MB_LIB.T6G(SCH_1):GND    I17 @T6G_MB_LIB.T6G(SCH_1):PAGE409
   CM4    GND @T6G_MB_LIB.T6G(SCH_1):GND    I17 @T6G_MB_LIB.T6G(SCH_1):PAGE409
   CN2    GND @T6G_MB_LIB.T6G(SCH_1):GND    I17 @T6G_MB_LIB.T6G(SCH_1):PAGE409
  CN34    GND @T6G_MB_LIB.T6G(SCH_1):GND    I17 @T6G_MB_LIB.T6G(SCH_1):PAGE409
   CP1    GND @T6G_MB_LIB.T6G(SCH_1):GND    I17 @T6G_MB_LIB.T6G(SCH_1):PAGE409
  CP35    GND @T6G_MB_LIB.T6G(SCH_1):GND    I17 @T6G_MB_LIB.T6G(SCH_1):PAGE409
  CW13    GND @T6G_MB_LIB.T6G(SCH_1):GND    I17 @T6G_MB_LIB.T6G(SCH_1):PAGE409
  CW22    GND @T6G_MB_LIB.T6G(SCH_1):GND    I17 @T6G_MB_LIB.T6G(SCH_1):PAGE409
  CW32    GND @T6G_MB_LIB.T6G(SCH_1):GND    I17 @T6G_MB_LIB.T6G(SCH_1):PAGE409
   CW4    GND @T6G_MB_LIB.T6G(SCH_1):GND    I17 @T6G_MB_LIB.T6G(SCH_1):PAGE409
   CY2    GND @T6G_MB_LIB.T6G(SCH_1):GND    I17 @T6G_MB_LIB.T6G(SCH_1):PAGE409
  CY34    GND @T6G_MB_LIB.T6G(SCH_1):GND    I17 @T6G_MB_LIB.T6G(SCH_1):PAGE409
   DA1    GND @T6G_MB_LIB.T6G(SCH_1):GND    I17 @T6G_MB_LIB.T6G(SCH_1):PAGE409
  DA35    GND @T6G_MB_LIB.T6G(SCH_1):GND    I17 @T6G_MB_LIB.T6G(SCH_1):PAGE409
  DF13    GND @T6G_MB_LIB.T6G(SCH_1):GND    I17 @T6G_MB_LIB.T6G(SCH_1):PAGE409
  DF22    GND @T6G_MB_LIB.T6G(SCH_1):GND    I17 @T6G_MB_LIB.T6G(SCH_1):PAGE409
  DF32    GND @T6G_MB_LIB.T6G(SCH_1):GND    I17 @T6G_MB_LIB.T6G(SCH_1):PAGE409
   DF4    GND @T6G_MB_LIB.T6G(SCH_1):GND    I17 @T6G_MB_LIB.T6G(SCH_1):PAGE409
   DG2    GND @T6G_MB_LIB.T6G(SCH_1):GND    I17 @T6G_MB_LIB.T6G(SCH_1):PAGE409
  DG34    GND @T6G_MB_LIB.T6G(SCH_1):GND    I17 @T6G_MB_LIB.T6G(SCH_1):PAGE409
   DH1    GND @T6G_MB_LIB.T6G(SCH_1):GND    I17 @T6G_MB_LIB.T6G(SCH_1):PAGE409
  DH35    GND @T6G_MB_LIB.T6G(SCH_1):GND    I17 @T6G_MB_LIB.T6G(SCH_1):PAGE409
  DN13    GND @T6G_MB_LIB.T6G(SCH_1):GND    I17 @T6G_MB_LIB.T6G(SCH_1):PAGE409
    A1 NCF_A1_CPU0_P1_GND @T6G_MB_LIB.T6G(SCH_1):NCF_A1_CPU0_P1_GND    I17 @T6G_MB_LIB.T6G(SCH_1):PAGE409
   A35 NCF_CPU0_P1_GND @T6G_MB_LIB.T6G(SCH_1):NCF_CPU0_P1_GND    I17 @T6G_MB_LIB.T6G(SCH_1):PAGE409
    C2 NCF_CPU0_P1_GND @T6G_MB_LIB.T6G(SCH_1):NCF_CPU0_P1_GND    I17 @T6G_MB_LIB.T6G(SCH_1):PAGE409
   C34 NCF_CPU0_P1_GND @T6G_MB_LIB.T6G(SCH_1):NCF_CPU0_P1_GND    I17 @T6G_MB_LIB.T6G(SCH_1):PAGE409
    D1 NCF_CPU0_P1_GND @T6G_MB_LIB.T6G(SCH_1):NCF_CPU0_P1_GND    I17 @T6G_MB_LIB.T6G(SCH_1):PAGE409
   D35 NCF_CPU0_P1_GND @T6G_MB_LIB.T6G(SCH_1):NCF_CPU0_P1_GND    I17 @T6G_MB_LIB.T6G(SCH_1):PAGE409
   FE2 NCF_CPU0_P1_GND @T6G_MB_LIB.T6G(SCH_1):NCF_CPU0_P1_GND    I17 @T6G_MB_LIB.T6G(SCH_1):PAGE409
  FE34 NCF_CPU0_P1_GND @T6G_MB_LIB.T6G(SCH_1):NCF_CPU0_P1_GND    I17 @T6G_MB_LIB.T6G(SCH_1):PAGE409
   FG1 NCF_CPU0_P1_GND @T6G_MB_LIB.T6G(SCH_1):NCF_CPU0_P1_GND    I17 @T6G_MB_LIB.T6G(SCH_1):PAGE409
  FG35 NCF_CPU0_P1_GND @T6G_MB_LIB.T6G(SCH_1):NCF_CPU0_P1_GND    I17 @T6G_MB_LIB.T6G(SCH_1):PAGE409
   FH2 NCF_CPU0_P1_GND @T6G_MB_LIB.T6G(SCH_1):NCF_CPU0_P1_GND    I17 @T6G_MB_LIB.T6G(SCH_1):PAGE409
  FH34 NCF_CPU0_P1_GND @T6G_MB_LIB.T6G(SCH_1):NCF_CPU0_P1_GND    I17 @T6G_MB_LIB.T6G(SCH_1):PAGE409
  DN22    GND @T6G_MB_LIB.T6G(SCH_1):GND    I17 @T6G_MB_LIB.T6G(SCH_1):PAGE409
  DN32    GND @T6G_MB_LIB.T6G(SCH_1):GND    I17 @T6G_MB_LIB.T6G(SCH_1):PAGE409
   DN4    GND @T6G_MB_LIB.T6G(SCH_1):GND    I17 @T6G_MB_LIB.T6G(SCH_1):PAGE409
   DP2    GND @T6G_MB_LIB.T6G(SCH_1):GND    I17 @T6G_MB_LIB.T6G(SCH_1):PAGE409
  DP34    GND @T6G_MB_LIB.T6G(SCH_1):GND    I17 @T6G_MB_LIB.T6G(SCH_1):PAGE409
   DR1    GND @T6G_MB_LIB.T6G(SCH_1):GND    I17 @T6G_MB_LIB.T6G(SCH_1):PAGE409
  DR35    GND @T6G_MB_LIB.T6G(SCH_1):GND    I17 @T6G_MB_LIB.T6G(SCH_1):PAGE409
  DY13    GND @T6G_MB_LIB.T6G(SCH_1):GND    I17 @T6G_MB_LIB.T6G(SCH_1):PAGE409
  DY22    GND @T6G_MB_LIB.T6G(SCH_1):GND    I17 @T6G_MB_LIB.T6G(SCH_1):PAGE409
  DY32    GND @T6G_MB_LIB.T6G(SCH_1):GND    I17 @T6G_MB_LIB.T6G(SCH_1):PAGE409
   DY4    GND @T6G_MB_LIB.T6G(SCH_1):GND    I17 @T6G_MB_LIB.T6G(SCH_1):PAGE409
   E14    GND @T6G_MB_LIB.T6G(SCH_1):GND    I17 @T6G_MB_LIB.T6G(SCH_1):PAGE409
   E27    GND @T6G_MB_LIB.T6G(SCH_1):GND    I17 @T6G_MB_LIB.T6G(SCH_1):PAGE409
   E33    GND @T6G_MB_LIB.T6G(SCH_1):GND    I17 @T6G_MB_LIB.T6G(SCH_1):PAGE409
   EA2    GND @T6G_MB_LIB.T6G(SCH_1):GND    I17 @T6G_MB_LIB.T6G(SCH_1):PAGE409
  EA34    GND @T6G_MB_LIB.T6G(SCH_1):GND    I17 @T6G_MB_LIB.T6G(SCH_1):PAGE409
   EB1    GND @T6G_MB_LIB.T6G(SCH_1):GND    I17 @T6G_MB_LIB.T6G(SCH_1):PAGE409
  EB35    GND @T6G_MB_LIB.T6G(SCH_1):GND    I17 @T6G_MB_LIB.T6G(SCH_1):PAGE409
  EG13    GND @T6G_MB_LIB.T6G(SCH_1):GND    I17 @T6G_MB_LIB.T6G(SCH_1):PAGE409
  EG22    GND @T6G_MB_LIB.T6G(SCH_1):GND    I17 @T6G_MB_LIB.T6G(SCH_1):PAGE409
  EG32    GND @T6G_MB_LIB.T6G(SCH_1):GND    I17 @T6G_MB_LIB.T6G(SCH_1):PAGE409
   EG4    GND @T6G_MB_LIB.T6G(SCH_1):GND    I17 @T6G_MB_LIB.T6G(SCH_1):PAGE409
   EH2    GND @T6G_MB_LIB.T6G(SCH_1):GND    I17 @T6G_MB_LIB.T6G(SCH_1):PAGE409
  EH34    GND @T6G_MB_LIB.T6G(SCH_1):GND    I17 @T6G_MB_LIB.T6G(SCH_1):PAGE409
   EJ1    GND @T6G_MB_LIB.T6G(SCH_1):GND    I17 @T6G_MB_LIB.T6G(SCH_1):PAGE409
  EJ35    GND @T6G_MB_LIB.T6G(SCH_1):GND    I17 @T6G_MB_LIB.T6G(SCH_1):PAGE409
  EP13    GND @T6G_MB_LIB.T6G(SCH_1):GND    I17 @T6G_MB_LIB.T6G(SCH_1):PAGE409
  EP22    GND @T6G_MB_LIB.T6G(SCH_1):GND    I17 @T6G_MB_LIB.T6G(SCH_1):PAGE409
  EP32    GND @T6G_MB_LIB.T6G(SCH_1):GND    I17 @T6G_MB_LIB.T6G(SCH_1):PAGE409
   EP4    GND @T6G_MB_LIB.T6G(SCH_1):GND    I17 @T6G_MB_LIB.T6G(SCH_1):PAGE409
   ER2    GND @T6G_MB_LIB.T6G(SCH_1):GND    I17 @T6G_MB_LIB.T6G(SCH_1):PAGE409
  ER34    GND @T6G_MB_LIB.T6G(SCH_1):GND    I17 @T6G_MB_LIB.T6G(SCH_1):PAGE409
   ET1    GND @T6G_MB_LIB.T6G(SCH_1):GND    I17 @T6G_MB_LIB.T6G(SCH_1):PAGE409
  ET35    GND @T6G_MB_LIB.T6G(SCH_1):GND    I17 @T6G_MB_LIB.T6G(SCH_1):PAGE409
  FA15    GND @T6G_MB_LIB.T6G(SCH_1):GND    I17 @T6G_MB_LIB.T6G(SCH_1):PAGE409
  FA32    GND @T6G_MB_LIB.T6G(SCH_1):GND    I17 @T6G_MB_LIB.T6G(SCH_1):PAGE409
   FB2    GND @T6G_MB_LIB.T6G(SCH_1):GND    I17 @T6G_MB_LIB.T6G(SCH_1):PAGE409
  FB34    GND @T6G_MB_LIB.T6G(SCH_1):GND    I17 @T6G_MB_LIB.T6G(SCH_1):PAGE409
  FC19    GND @T6G_MB_LIB.T6G(SCH_1):GND    I17 @T6G_MB_LIB.T6G(SCH_1):PAGE409
  FC23    GND @T6G_MB_LIB.T6G(SCH_1):GND    I17 @T6G_MB_LIB.T6G(SCH_1):PAGE409
  FC25    GND @T6G_MB_LIB.T6G(SCH_1):GND    I17 @T6G_MB_LIB.T6G(SCH_1):PAGE409
  FC28    GND @T6G_MB_LIB.T6G(SCH_1):GND    I17 @T6G_MB_LIB.T6G(SCH_1):PAGE409
   FC3    GND @T6G_MB_LIB.T6G(SCH_1):GND    I17 @T6G_MB_LIB.T6G(SCH_1):PAGE409
   FC6    GND @T6G_MB_LIB.T6G(SCH_1):GND    I17 @T6G_MB_LIB.T6G(SCH_1):PAGE409
   FC9    GND @T6G_MB_LIB.T6G(SCH_1):GND    I17 @T6G_MB_LIB.T6G(SCH_1):PAGE409
   FD1    GND @T6G_MB_LIB.T6G(SCH_1):GND    I17 @T6G_MB_LIB.T6G(SCH_1):PAGE409
  FD35    GND @T6G_MB_LIB.T6G(SCH_1):GND    I17 @T6G_MB_LIB.T6G(SCH_1):PAGE409
  FF14    GND @T6G_MB_LIB.T6G(SCH_1):GND    I17 @T6G_MB_LIB.T6G(SCH_1):PAGE409
  FF21    GND @T6G_MB_LIB.T6G(SCH_1):GND    I17 @T6G_MB_LIB.T6G(SCH_1):PAGE409
  FJ12    GND @T6G_MB_LIB.T6G(SCH_1):GND    I17 @T6G_MB_LIB.T6G(SCH_1):PAGE409
  FJ19    GND @T6G_MB_LIB.T6G(SCH_1):GND    I17 @T6G_MB_LIB.T6G(SCH_1):PAGE409
   H12    GND @T6G_MB_LIB.T6G(SCH_1):GND    I17 @T6G_MB_LIB.T6G(SCH_1):PAGE409
   H16    GND @T6G_MB_LIB.T6G(SCH_1):GND    I17 @T6G_MB_LIB.T6G(SCH_1):PAGE409
   H19    GND @T6G_MB_LIB.T6G(SCH_1):GND    I17 @T6G_MB_LIB.T6G(SCH_1):PAGE409
   H31    GND @T6G_MB_LIB.T6G(SCH_1):GND    I17 @T6G_MB_LIB.T6G(SCH_1):PAGE409
   J22    GND @T6G_MB_LIB.T6G(SCH_1):GND    I17 @T6G_MB_LIB.T6G(SCH_1):PAGE409
    J4    GND @T6G_MB_LIB.T6G(SCH_1):GND    I17 @T6G_MB_LIB.T6G(SCH_1):PAGE409
    K2    GND @T6G_MB_LIB.T6G(SCH_1):GND    I17 @T6G_MB_LIB.T6G(SCH_1):PAGE409
   K34    GND @T6G_MB_LIB.T6G(SCH_1):GND    I17 @T6G_MB_LIB.T6G(SCH_1):PAGE409
    L1    GND @T6G_MB_LIB.T6G(SCH_1):GND    I17 @T6G_MB_LIB.T6G(SCH_1):PAGE409
   L35    GND @T6G_MB_LIB.T6G(SCH_1):GND    I17 @T6G_MB_LIB.T6G(SCH_1):PAGE409
   T13    GND @T6G_MB_LIB.T6G(SCH_1):GND    I17 @T6G_MB_LIB.T6G(SCH_1):PAGE409
   T22    GND @T6G_MB_LIB.T6G(SCH_1):GND    I17 @T6G_MB_LIB.T6G(SCH_1):PAGE409
   T32    GND @T6G_MB_LIB.T6G(SCH_1):GND    I17 @T6G_MB_LIB.T6G(SCH_1):PAGE409
    T4    GND @T6G_MB_LIB.T6G(SCH_1):GND    I17 @T6G_MB_LIB.T6G(SCH_1):PAGE409
    U2    GND @T6G_MB_LIB.T6G(SCH_1):GND    I17 @T6G_MB_LIB.T6G(SCH_1):PAGE409
   U34    GND @T6G_MB_LIB.T6G(SCH_1):GND    I17 @T6G_MB_LIB.T6G(SCH_1):PAGE409
    V1    GND @T6G_MB_LIB.T6G(SCH_1):GND    I17 @T6G_MB_LIB.T6G(SCH_1):PAGE409
   V35    GND @T6G_MB_LIB.T6G(SCH_1):GND    I17 @T6G_MB_LIB.T6G(SCH_1):PAGE409
   M26 P5E_CPU0_P1_RX_DP<15> @T6G_MB_LIB.T6G(SCH_1):P5E_CPU0_P1_RX_DP(15)     I1 @T6G_MB_LIB.T6G(SCH_1):PAGE405
   P29 P5E_CPU0_P1_RX_DN<15> @T6G_MB_LIB.T6G(SCH_1):P5E_CPU0_P1_RX_DN(15)     I1 @T6G_MB_LIB.T6G(SCH_1):PAGE405
   W26 P5E_CPU0_P1_RX_DP<14> @T6G_MB_LIB.T6G(SCH_1):P5E_CPU0_P1_RX_DP(14)     I1 @T6G_MB_LIB.T6G(SCH_1):PAGE405
  AA29 P5E_CPU0_P1_RX_DN<14> @T6G_MB_LIB.T6G(SCH_1):P5E_CPU0_P1_RX_DN(14)     I1 @T6G_MB_LIB.T6G(SCH_1):PAGE405
  AF26 P5E_CPU0_P1_RX_DP<13> @T6G_MB_LIB.T6G(SCH_1):P5E_CPU0_P1_RX_DP(13)     I1 @T6G_MB_LIB.T6G(SCH_1):PAGE405
  AH29 P5E_CPU0_P1_RX_DN<13> @T6G_MB_LIB.T6G(SCH_1):P5E_CPU0_P1_RX_DN(13)     I1 @T6G_MB_LIB.T6G(SCH_1):PAGE405
  AN26 P5E_CPU0_P1_RX_DP<12> @T6G_MB_LIB.T6G(SCH_1):P5E_CPU0_P1_RX_DP(12)     I1 @T6G_MB_LIB.T6G(SCH_1):PAGE405
  AR29 P5E_CPU0_P1_RX_DN<12> @T6G_MB_LIB.T6G(SCH_1):P5E_CPU0_P1_RX_DN(12)     I1 @T6G_MB_LIB.T6G(SCH_1):PAGE405
  AY26 P5E_CPU0_P1_RX_DP<11> @T6G_MB_LIB.T6G(SCH_1):P5E_CPU0_P1_RX_DP(11)     I1 @T6G_MB_LIB.T6G(SCH_1):PAGE405
  BB29 P5E_CPU0_P1_RX_DN<11> @T6G_MB_LIB.T6G(SCH_1):P5E_CPU0_P1_RX_DN(11)     I1 @T6G_MB_LIB.T6G(SCH_1):PAGE405
  BG26 P5E_CPU0_P1_RX_DP<10> @T6G_MB_LIB.T6G(SCH_1):P5E_CPU0_P1_RX_DP(10)     I1 @T6G_MB_LIB.T6G(SCH_1):PAGE405
  BJ29 P5E_CPU0_P1_RX_DN<10> @T6G_MB_LIB.T6G(SCH_1):P5E_CPU0_P1_RX_DN(10)     I1 @T6G_MB_LIB.T6G(SCH_1):PAGE405
  BP26 P5E_CPU0_P1_RX_DP<9> @T6G_MB_LIB.T6G(SCH_1):P5E_CPU0_P1_RX_DP(9)     I1 @T6G_MB_LIB.T6G(SCH_1):PAGE405
  BT29 P5E_CPU0_P1_RX_DN<9> @T6G_MB_LIB.T6G(SCH_1):P5E_CPU0_P1_RX_DN(9)     I1 @T6G_MB_LIB.T6G(SCH_1):PAGE405
  CA26 P5E_CPU0_P1_RX_DP<8> @T6G_MB_LIB.T6G(SCH_1):P5E_CPU0_P1_RX_DP(8)     I1 @T6G_MB_LIB.T6G(SCH_1):PAGE405
  CC29 P5E_CPU0_P1_RX_DN<8> @T6G_MB_LIB.T6G(SCH_1):P5E_CPU0_P1_RX_DN(8)     I1 @T6G_MB_LIB.T6G(SCH_1):PAGE405
  CH26 P5E_CPU0_P1_RX_DP<7> @T6G_MB_LIB.T6G(SCH_1):P5E_CPU0_P1_RX_DP(7)    I38 @T6G_MB_LIB.T6G(SCH_1):PAGE405
  CK29 P5E_CPU0_P1_RX_DN<7> @T6G_MB_LIB.T6G(SCH_1):P5E_CPU0_P1_RX_DN(7)    I38 @T6G_MB_LIB.T6G(SCH_1):PAGE405
  CR26 P5E_CPU0_P1_RX_DP<6> @T6G_MB_LIB.T6G(SCH_1):P5E_CPU0_P1_RX_DP(6)    I38 @T6G_MB_LIB.T6G(SCH_1):PAGE405
  CU29 P5E_CPU0_P1_RX_DN<6> @T6G_MB_LIB.T6G(SCH_1):P5E_CPU0_P1_RX_DN(6)    I38 @T6G_MB_LIB.T6G(SCH_1):PAGE405
  DB26 P5E_CPU0_P1_RX_DP<5> @T6G_MB_LIB.T6G(SCH_1):P5E_CPU0_P1_RX_DP(5)    I38 @T6G_MB_LIB.T6G(SCH_1):PAGE405
  DD29 P5E_CPU0_P1_RX_DN<5> @T6G_MB_LIB.T6G(SCH_1):P5E_CPU0_P1_RX_DN(5)    I38 @T6G_MB_LIB.T6G(SCH_1):PAGE405
  DJ26 P5E_CPU0_P1_RX_DP<4> @T6G_MB_LIB.T6G(SCH_1):P5E_CPU0_P1_RX_DP(4)    I38 @T6G_MB_LIB.T6G(SCH_1):PAGE405
  DL29 P5E_CPU0_P1_RX_DN<4> @T6G_MB_LIB.T6G(SCH_1):P5E_CPU0_P1_RX_DN(4)    I38 @T6G_MB_LIB.T6G(SCH_1):PAGE405
  DT26 P5E_CPU0_P1_RX_DP<3> @T6G_MB_LIB.T6G(SCH_1):P5E_CPU0_P1_RX_DP(3)    I38 @T6G_MB_LIB.T6G(SCH_1):PAGE405
  DV29 P5E_CPU0_P1_RX_DN<3> @T6G_MB_LIB.T6G(SCH_1):P5E_CPU0_P1_RX_DN(3)    I38 @T6G_MB_LIB.T6G(SCH_1):PAGE405
  EC26 P5E_CPU0_P1_RX_DP<2> @T6G_MB_LIB.T6G(SCH_1):P5E_CPU0_P1_RX_DP(2)    I38 @T6G_MB_LIB.T6G(SCH_1):PAGE405
  EE29 P5E_CPU0_P1_RX_DN<2> @T6G_MB_LIB.T6G(SCH_1):P5E_CPU0_P1_RX_DN(2)    I38 @T6G_MB_LIB.T6G(SCH_1):PAGE405
  EK26 P5E_CPU0_P1_RX_DP<1> @T6G_MB_LIB.T6G(SCH_1):P5E_CPU0_P1_RX_DP(1)    I38 @T6G_MB_LIB.T6G(SCH_1):PAGE405
  EM29 P5E_CPU0_P1_RX_DN<1> @T6G_MB_LIB.T6G(SCH_1):P5E_CPU0_P1_RX_DN(1)    I38 @T6G_MB_LIB.T6G(SCH_1):PAGE405
  EU26 P5E_CPU0_P1_RX_DP<0> @T6G_MB_LIB.T6G(SCH_1):P5E_CPU0_P1_RX_DP(0)    I38 @T6G_MB_LIB.T6G(SCH_1):PAGE405
  EW29 P5E_CPU0_P1_RX_DN<0> @T6G_MB_LIB.T6G(SCH_1):P5E_CPU0_P1_RX_DN(0)    I38 @T6G_MB_LIB.T6G(SCH_1):PAGE405
   N34 P5E_CPU0_P1_TX_C_DN<15> @T6G_MB_LIB.T6G(SCH_1):P5E_CPU0_P1_TX_C_DN(15)     I1 @T6G_MB_LIB.T6G(SCH_1):PAGE404
   R35 P5E_CPU0_P1_TX_C_DP<15> @T6G_MB_LIB.T6G(SCH_1):P5E_CPU0_P1_TX_C_DP(15)     I1 @T6G_MB_LIB.T6G(SCH_1):PAGE404
   Y34 P5E_CPU0_P1_TX_C_DP<14> @T6G_MB_LIB.T6G(SCH_1):P5E_CPU0_P1_TX_C_DP(14)     I1 @T6G_MB_LIB.T6G(SCH_1):PAGE404
  AB35 P5E_CPU0_P1_TX_C_DN<14> @T6G_MB_LIB.T6G(SCH_1):P5E_CPU0_P1_TX_C_DN(14)     I1 @T6G_MB_LIB.T6G(SCH_1):PAGE404
  AG34 P5E_CPU0_P1_TX_C_DN<13> @T6G_MB_LIB.T6G(SCH_1):P5E_CPU0_P1_TX_C_DN(13)     I1 @T6G_MB_LIB.T6G(SCH_1):PAGE404
  AJ35 P5E_CPU0_P1_TX_C_DP<13> @T6G_MB_LIB.T6G(SCH_1):P5E_CPU0_P1_TX_C_DP(13)     I1 @T6G_MB_LIB.T6G(SCH_1):PAGE404
  AP34 P5E_CPU0_P1_TX_C_DN<12> @T6G_MB_LIB.T6G(SCH_1):P5E_CPU0_P1_TX_C_DN(12)     I1 @T6G_MB_LIB.T6G(SCH_1):PAGE404
  AT35 P5E_CPU0_P1_TX_C_DP<12> @T6G_MB_LIB.T6G(SCH_1):P5E_CPU0_P1_TX_C_DP(12)     I1 @T6G_MB_LIB.T6G(SCH_1):PAGE404
  BA34 P5E_CPU0_P1_TX_C_DN<11> @T6G_MB_LIB.T6G(SCH_1):P5E_CPU0_P1_TX_C_DN(11)     I1 @T6G_MB_LIB.T6G(SCH_1):PAGE404
  BC35 P5E_CPU0_P1_TX_C_DP<11> @T6G_MB_LIB.T6G(SCH_1):P5E_CPU0_P1_TX_C_DP(11)     I1 @T6G_MB_LIB.T6G(SCH_1):PAGE404
  BH34 P5E_CPU0_P1_TX_C_DN<10> @T6G_MB_LIB.T6G(SCH_1):P5E_CPU0_P1_TX_C_DN(10)     I1 @T6G_MB_LIB.T6G(SCH_1):PAGE404
  BK35 P5E_CPU0_P1_TX_C_DP<10> @T6G_MB_LIB.T6G(SCH_1):P5E_CPU0_P1_TX_C_DP(10)     I1 @T6G_MB_LIB.T6G(SCH_1):PAGE404
  BR34 P5E_CPU0_P1_TX_C_DN<9> @T6G_MB_LIB.T6G(SCH_1):P5E_CPU0_P1_TX_C_DN(9)     I1 @T6G_MB_LIB.T6G(SCH_1):PAGE404
  BU35 P5E_CPU0_P1_TX_C_DP<9> @T6G_MB_LIB.T6G(SCH_1):P5E_CPU0_P1_TX_C_DP(9)     I1 @T6G_MB_LIB.T6G(SCH_1):PAGE404
  CB34 P5E_CPU0_P1_TX_C_DN<8> @T6G_MB_LIB.T6G(SCH_1):P5E_CPU0_P1_TX_C_DN(8)     I1 @T6G_MB_LIB.T6G(SCH_1):PAGE404
  CD35 P5E_CPU0_P1_TX_C_DP<8> @T6G_MB_LIB.T6G(SCH_1):P5E_CPU0_P1_TX_C_DP(8)     I1 @T6G_MB_LIB.T6G(SCH_1):PAGE404
  CJ34 P5E_CPU0_P1_TX_C_DN<7> @T6G_MB_LIB.T6G(SCH_1):P5E_CPU0_P1_TX_C_DN(7)    I38 @T6G_MB_LIB.T6G(SCH_1):PAGE404
  CL35 P5E_CPU0_P1_TX_C_DP<7> @T6G_MB_LIB.T6G(SCH_1):P5E_CPU0_P1_TX_C_DP(7)    I38 @T6G_MB_LIB.T6G(SCH_1):PAGE404
  CT34 P5E_CPU0_P1_TX_C_DN<6> @T6G_MB_LIB.T6G(SCH_1):P5E_CPU0_P1_TX_C_DN(6)    I38 @T6G_MB_LIB.T6G(SCH_1):PAGE404
  CV35 P5E_CPU0_P1_TX_C_DP<6> @T6G_MB_LIB.T6G(SCH_1):P5E_CPU0_P1_TX_C_DP(6)    I38 @T6G_MB_LIB.T6G(SCH_1):PAGE404
  DC34 P5E_CPU0_P1_TX_C_DN<5> @T6G_MB_LIB.T6G(SCH_1):P5E_CPU0_P1_TX_C_DN(5)    I38 @T6G_MB_LIB.T6G(SCH_1):PAGE404
  DE35 P5E_CPU0_P1_TX_C_DP<5> @T6G_MB_LIB.T6G(SCH_1):P5E_CPU0_P1_TX_C_DP(5)    I38 @T6G_MB_LIB.T6G(SCH_1):PAGE404
  DK34 P5E_CPU0_P1_TX_C_DN<4> @T6G_MB_LIB.T6G(SCH_1):P5E_CPU0_P1_TX_C_DN(4)    I38 @T6G_MB_LIB.T6G(SCH_1):PAGE404
  DM35 P5E_CPU0_P1_TX_C_DP<4> @T6G_MB_LIB.T6G(SCH_1):P5E_CPU0_P1_TX_C_DP(4)    I38 @T6G_MB_LIB.T6G(SCH_1):PAGE404
  DU34 P5E_CPU0_P1_TX_C_DN<3> @T6G_MB_LIB.T6G(SCH_1):P5E_CPU0_P1_TX_C_DN(3)    I38 @T6G_MB_LIB.T6G(SCH_1):PAGE404
  DW35 P5E_CPU0_P1_TX_C_DP<3> @T6G_MB_LIB.T6G(SCH_1):P5E_CPU0_P1_TX_C_DP(3)    I38 @T6G_MB_LIB.T6G(SCH_1):PAGE404
  ED34 P5E_CPU0_P1_TX_C_DN<2> @T6G_MB_LIB.T6G(SCH_1):P5E_CPU0_P1_TX_C_DN(2)    I38 @T6G_MB_LIB.T6G(SCH_1):PAGE404
  EF35 P5E_CPU0_P1_TX_C_DP<2> @T6G_MB_LIB.T6G(SCH_1):P5E_CPU0_P1_TX_C_DP(2)    I38 @T6G_MB_LIB.T6G(SCH_1):PAGE404
  EL34 P5E_CPU0_P1_TX_C_DP<1> @T6G_MB_LIB.T6G(SCH_1):P5E_CPU0_P1_TX_C_DP(1)    I38 @T6G_MB_LIB.T6G(SCH_1):PAGE404
  EN35 P5E_CPU0_P1_TX_C_DN<1> @T6G_MB_LIB.T6G(SCH_1):P5E_CPU0_P1_TX_C_DN(1)    I38 @T6G_MB_LIB.T6G(SCH_1):PAGE404
  EV34 P5E_CPU0_P1_TX_C_DN<0> @T6G_MB_LIB.T6G(SCH_1):P5E_CPU0_P1_TX_C_DN(0)    I38 @T6G_MB_LIB.T6G(SCH_1):PAGE404
  EY35 P5E_CPU0_P1_TX_C_DP<0> @T6G_MB_LIB.T6G(SCH_1):P5E_CPU0_P1_TX_C_DP(0)    I38 @T6G_MB_LIB.T6G(SCH_1):PAGE404
    M7 P5E_CPU0_P1_TX_BUF_DP<15> @T6G_MB_LIB.T6G(SCH_1):P5E_CPU0_P1_TX_BUF_DP(15)    I43 @T6G_MB_LIB.T6G(SCH_1):PAGE407
   P10 P5E_CPU0_P1_TX_BUF_DN<15> @T6G_MB_LIB.T6G(SCH_1):P5E_CPU0_P1_TX_BUF_DN(15)    I43 @T6G_MB_LIB.T6G(SCH_1):PAGE407
    W7 P5E_CPU0_P1_TX_BUF_DP<14> @T6G_MB_LIB.T6G(SCH_1):P5E_CPU0_P1_TX_BUF_DP(14)    I43 @T6G_MB_LIB.T6G(SCH_1):PAGE407
  AA10 P5E_CPU0_P1_TX_BUF_DN<14> @T6G_MB_LIB.T6G(SCH_1):P5E_CPU0_P1_TX_BUF_DN(14)    I43 @T6G_MB_LIB.T6G(SCH_1):PAGE407
   AF7 P5E_CPU0_P1_TX_BUF_DP<13> @T6G_MB_LIB.T6G(SCH_1):P5E_CPU0_P1_TX_BUF_DP(13)    I43 @T6G_MB_LIB.T6G(SCH_1):PAGE407
  AH10 P5E_CPU0_P1_TX_BUF_DN<13> @T6G_MB_LIB.T6G(SCH_1):P5E_CPU0_P1_TX_BUF_DN(13)    I43 @T6G_MB_LIB.T6G(SCH_1):PAGE407
   AN7 P5E_CPU0_P1_TX_BUF_DP<12> @T6G_MB_LIB.T6G(SCH_1):P5E_CPU0_P1_TX_BUF_DP(12)    I43 @T6G_MB_LIB.T6G(SCH_1):PAGE407
  AR10 P5E_CPU0_P1_TX_BUF_DN<12> @T6G_MB_LIB.T6G(SCH_1):P5E_CPU0_P1_TX_BUF_DN(12)    I43 @T6G_MB_LIB.T6G(SCH_1):PAGE407
   AY7 P5E_CPU0_P1_TX_BUF_DP<11> @T6G_MB_LIB.T6G(SCH_1):P5E_CPU0_P1_TX_BUF_DP(11)    I43 @T6G_MB_LIB.T6G(SCH_1):PAGE407
  BB10 P5E_CPU0_P1_TX_BUF_DN<11> @T6G_MB_LIB.T6G(SCH_1):P5E_CPU0_P1_TX_BUF_DN(11)    I43 @T6G_MB_LIB.T6G(SCH_1):PAGE407
   BG7 P5E_CPU0_P1_TX_BUF_DP<10> @T6G_MB_LIB.T6G(SCH_1):P5E_CPU0_P1_TX_BUF_DP(10)    I43 @T6G_MB_LIB.T6G(SCH_1):PAGE407
  BJ10 P5E_CPU0_P1_TX_BUF_DN<10> @T6G_MB_LIB.T6G(SCH_1):P5E_CPU0_P1_TX_BUF_DN(10)    I43 @T6G_MB_LIB.T6G(SCH_1):PAGE407
   BP7 P5E_CPU0_P1_TX_BUF_DP<9> @T6G_MB_LIB.T6G(SCH_1):P5E_CPU0_P1_TX_BUF_DP(9)    I43 @T6G_MB_LIB.T6G(SCH_1):PAGE407
  BT10 P5E_CPU0_P1_TX_BUF_DN<9> @T6G_MB_LIB.T6G(SCH_1):P5E_CPU0_P1_TX_BUF_DN(9)    I43 @T6G_MB_LIB.T6G(SCH_1):PAGE407
   CA7 P5E_CPU0_P1_TX_BUF_DP<8> @T6G_MB_LIB.T6G(SCH_1):P5E_CPU0_P1_TX_BUF_DP(8)    I43 @T6G_MB_LIB.T6G(SCH_1):PAGE407
  CC10 P5E_CPU0_P1_TX_BUF_DN<8> @T6G_MB_LIB.T6G(SCH_1):P5E_CPU0_P1_TX_BUF_DN(8)    I43 @T6G_MB_LIB.T6G(SCH_1):PAGE407
   CH7 P5E_CPU0_P1_TX_BUF_DP<7> @T6G_MB_LIB.T6G(SCH_1):P5E_CPU0_P1_TX_BUF_DP(7)   I142 @T6G_MB_LIB.T6G(SCH_1):PAGE407
  CK10 P5E_CPU0_P1_TX_BUF_DN<7> @T6G_MB_LIB.T6G(SCH_1):P5E_CPU0_P1_TX_BUF_DN(7)   I142 @T6G_MB_LIB.T6G(SCH_1):PAGE407
   CR7 P5E_CPU0_P1_TX_BUF_DP<6> @T6G_MB_LIB.T6G(SCH_1):P5E_CPU0_P1_TX_BUF_DP(6)   I142 @T6G_MB_LIB.T6G(SCH_1):PAGE407
  CU10 P5E_CPU0_P1_TX_BUF_DN<6> @T6G_MB_LIB.T6G(SCH_1):P5E_CPU0_P1_TX_BUF_DN(6)   I142 @T6G_MB_LIB.T6G(SCH_1):PAGE407
   DB7 P5E_CPU0_P1_TX_BUF_DP<5> @T6G_MB_LIB.T6G(SCH_1):P5E_CPU0_P1_TX_BUF_DP(5)   I142 @T6G_MB_LIB.T6G(SCH_1):PAGE407
  DD10 P5E_CPU0_P1_TX_BUF_DN<5> @T6G_MB_LIB.T6G(SCH_1):P5E_CPU0_P1_TX_BUF_DN(5)   I142 @T6G_MB_LIB.T6G(SCH_1):PAGE407
   DJ7 P5E_CPU0_P1_TX_BUF_DP<4> @T6G_MB_LIB.T6G(SCH_1):P5E_CPU0_P1_TX_BUF_DP(4)   I142 @T6G_MB_LIB.T6G(SCH_1):PAGE407
  DL10 P5E_CPU0_P1_TX_BUF_DN<4> @T6G_MB_LIB.T6G(SCH_1):P5E_CPU0_P1_TX_BUF_DN(4)   I142 @T6G_MB_LIB.T6G(SCH_1):PAGE407
   DT7 P5E_CPU0_P1_TX_BUF_DP<3> @T6G_MB_LIB.T6G(SCH_1):P5E_CPU0_P1_TX_BUF_DP(3)   I142 @T6G_MB_LIB.T6G(SCH_1):PAGE407
  DV10 P5E_CPU0_P1_TX_BUF_DN<3> @T6G_MB_LIB.T6G(SCH_1):P5E_CPU0_P1_TX_BUF_DN(3)   I142 @T6G_MB_LIB.T6G(SCH_1):PAGE407
   EC7 P5E_CPU0_P1_TX_BUF_DP<2> @T6G_MB_LIB.T6G(SCH_1):P5E_CPU0_P1_TX_BUF_DP(2)   I142 @T6G_MB_LIB.T6G(SCH_1):PAGE407
  EE10 P5E_CPU0_P1_TX_BUF_DN<2> @T6G_MB_LIB.T6G(SCH_1):P5E_CPU0_P1_TX_BUF_DN(2)   I142 @T6G_MB_LIB.T6G(SCH_1):PAGE407
   EK7 P5E_CPU0_P1_TX_BUF_DP<1> @T6G_MB_LIB.T6G(SCH_1):P5E_CPU0_P1_TX_BUF_DP(1)   I142 @T6G_MB_LIB.T6G(SCH_1):PAGE407
  EM10 P5E_CPU0_P1_TX_BUF_DN<1> @T6G_MB_LIB.T6G(SCH_1):P5E_CPU0_P1_TX_BUF_DN(1)   I142 @T6G_MB_LIB.T6G(SCH_1):PAGE407
   EU7 P5E_CPU0_P1_TX_BUF_DP<0> @T6G_MB_LIB.T6G(SCH_1):P5E_CPU0_P1_TX_BUF_DP(0)   I142 @T6G_MB_LIB.T6G(SCH_1):PAGE407
  EW10 P5E_CPU0_P1_TX_BUF_DN<0> @T6G_MB_LIB.T6G(SCH_1):P5E_CPU0_P1_TX_BUF_DN(0)   I142 @T6G_MB_LIB.T6G(SCH_1):PAGE407

U6012 PT5161LRS-PT5161LRS,SMLF,IC,AJ051610U03
    R1 P5E_CPU0_P2_RX_BUF_DP<15> @T6G_MB_LIB.T6G(SCH_1):P5E_CPU0_P2_RX_BUF_DP(15)     I1 @T6G_MB_LIB.T6G(SCH_1):PAGE417
    N2 P5E_CPU0_P2_RX_BUF_DN<15> @T6G_MB_LIB.T6G(SCH_1):P5E_CPU0_P2_RX_BUF_DN(15)     I1 @T6G_MB_LIB.T6G(SCH_1):PAGE417
   AB1 P5E_CPU0_P2_RX_BUF_DP<14> @T6G_MB_LIB.T6G(SCH_1):P5E_CPU0_P2_RX_BUF_DP(14)     I1 @T6G_MB_LIB.T6G(SCH_1):PAGE417
    Y2 P5E_CPU0_P2_RX_BUF_DN<14> @T6G_MB_LIB.T6G(SCH_1):P5E_CPU0_P2_RX_BUF_DN(14)     I1 @T6G_MB_LIB.T6G(SCH_1):PAGE417
   AJ1 P5E_CPU0_P2_RX_BUF_DP<13> @T6G_MB_LIB.T6G(SCH_1):P5E_CPU0_P2_RX_BUF_DP(13)     I1 @T6G_MB_LIB.T6G(SCH_1):PAGE417
   AG2 P5E_CPU0_P2_RX_BUF_DN<13> @T6G_MB_LIB.T6G(SCH_1):P5E_CPU0_P2_RX_BUF_DN(13)     I1 @T6G_MB_LIB.T6G(SCH_1):PAGE417
   AT1 P5E_CPU0_P2_RX_BUF_DP<12> @T6G_MB_LIB.T6G(SCH_1):P5E_CPU0_P2_RX_BUF_DP(12)     I1 @T6G_MB_LIB.T6G(SCH_1):PAGE417
   AP2 P5E_CPU0_P2_RX_BUF_DN<12> @T6G_MB_LIB.T6G(SCH_1):P5E_CPU0_P2_RX_BUF_DN(12)     I1 @T6G_MB_LIB.T6G(SCH_1):PAGE417
   BC1 P5E_CPU0_P2_RX_BUF_DP<11> @T6G_MB_LIB.T6G(SCH_1):P5E_CPU0_P2_RX_BUF_DP(11)     I1 @T6G_MB_LIB.T6G(SCH_1):PAGE417
   BA2 P5E_CPU0_P2_RX_BUF_DN<11> @T6G_MB_LIB.T6G(SCH_1):P5E_CPU0_P2_RX_BUF_DN(11)     I1 @T6G_MB_LIB.T6G(SCH_1):PAGE417
   BK1 P5E_CPU0_P2_RX_BUF_DP<10> @T6G_MB_LIB.T6G(SCH_1):P5E_CPU0_P2_RX_BUF_DP(10)     I1 @T6G_MB_LIB.T6G(SCH_1):PAGE417
   BH2 P5E_CPU0_P2_RX_BUF_DN<10> @T6G_MB_LIB.T6G(SCH_1):P5E_CPU0_P2_RX_BUF_DN(10)     I1 @T6G_MB_LIB.T6G(SCH_1):PAGE417
   BU1 P5E_CPU0_P2_RX_BUF_DP<9> @T6G_MB_LIB.T6G(SCH_1):P5E_CPU0_P2_RX_BUF_DP(9)     I1 @T6G_MB_LIB.T6G(SCH_1):PAGE417
   BR2 P5E_CPU0_P2_RX_BUF_DN<9> @T6G_MB_LIB.T6G(SCH_1):P5E_CPU0_P2_RX_BUF_DN(9)     I1 @T6G_MB_LIB.T6G(SCH_1):PAGE417
   CD1 P5E_CPU0_P2_RX_BUF_DP<8> @T6G_MB_LIB.T6G(SCH_1):P5E_CPU0_P2_RX_BUF_DP(8)     I1 @T6G_MB_LIB.T6G(SCH_1):PAGE417
   CB2 P5E_CPU0_P2_RX_BUF_DN<8> @T6G_MB_LIB.T6G(SCH_1):P5E_CPU0_P2_RX_BUF_DN(8)     I1 @T6G_MB_LIB.T6G(SCH_1):PAGE417
   CL1 P5E_CPU0_P2_RX_BUF_DP<7> @T6G_MB_LIB.T6G(SCH_1):P5E_CPU0_P2_RX_BUF_DP(7)    I38 @T6G_MB_LIB.T6G(SCH_1):PAGE417
   CJ2 P5E_CPU0_P2_RX_BUF_DN<7> @T6G_MB_LIB.T6G(SCH_1):P5E_CPU0_P2_RX_BUF_DN(7)    I38 @T6G_MB_LIB.T6G(SCH_1):PAGE417
   CV1 P5E_CPU0_P2_RX_BUF_DP<6> @T6G_MB_LIB.T6G(SCH_1):P5E_CPU0_P2_RX_BUF_DP(6)    I38 @T6G_MB_LIB.T6G(SCH_1):PAGE417
   CT2 P5E_CPU0_P2_RX_BUF_DN<6> @T6G_MB_LIB.T6G(SCH_1):P5E_CPU0_P2_RX_BUF_DN(6)    I38 @T6G_MB_LIB.T6G(SCH_1):PAGE417
   DE1 P5E_CPU0_P2_RX_BUF_DP<5> @T6G_MB_LIB.T6G(SCH_1):P5E_CPU0_P2_RX_BUF_DP(5)    I38 @T6G_MB_LIB.T6G(SCH_1):PAGE417
   DC2 P5E_CPU0_P2_RX_BUF_DN<5> @T6G_MB_LIB.T6G(SCH_1):P5E_CPU0_P2_RX_BUF_DN(5)    I38 @T6G_MB_LIB.T6G(SCH_1):PAGE417
   DM1 P5E_CPU0_P2_RX_BUF_DP<4> @T6G_MB_LIB.T6G(SCH_1):P5E_CPU0_P2_RX_BUF_DP(4)    I38 @T6G_MB_LIB.T6G(SCH_1):PAGE417
   DK2 P5E_CPU0_P2_RX_BUF_DN<4> @T6G_MB_LIB.T6G(SCH_1):P5E_CPU0_P2_RX_BUF_DN(4)    I38 @T6G_MB_LIB.T6G(SCH_1):PAGE417
   DW1 P5E_CPU0_P2_RX_BUF_DP<3> @T6G_MB_LIB.T6G(SCH_1):P5E_CPU0_P2_RX_BUF_DP(3)    I38 @T6G_MB_LIB.T6G(SCH_1):PAGE417
   DU2 P5E_CPU0_P2_RX_BUF_DN<3> @T6G_MB_LIB.T6G(SCH_1):P5E_CPU0_P2_RX_BUF_DN(3)    I38 @T6G_MB_LIB.T6G(SCH_1):PAGE417
   EF1 P5E_CPU0_P2_RX_BUF_DP<2> @T6G_MB_LIB.T6G(SCH_1):P5E_CPU0_P2_RX_BUF_DP(2)    I38 @T6G_MB_LIB.T6G(SCH_1):PAGE417
   ED2 P5E_CPU0_P2_RX_BUF_DN<2> @T6G_MB_LIB.T6G(SCH_1):P5E_CPU0_P2_RX_BUF_DN(2)    I38 @T6G_MB_LIB.T6G(SCH_1):PAGE417
   EN1 P5E_CPU0_P2_RX_BUF_DP<1> @T6G_MB_LIB.T6G(SCH_1):P5E_CPU0_P2_RX_BUF_DP(1)    I38 @T6G_MB_LIB.T6G(SCH_1):PAGE417
   EL2 P5E_CPU0_P2_RX_BUF_DN<1> @T6G_MB_LIB.T6G(SCH_1):P5E_CPU0_P2_RX_BUF_DN(1)    I38 @T6G_MB_LIB.T6G(SCH_1):PAGE417
   EY1 P5E_CPU0_P2_RX_BUF_DP<0> @T6G_MB_LIB.T6G(SCH_1):P5E_CPU0_P2_RX_BUF_DP(0)    I38 @T6G_MB_LIB.T6G(SCH_1):PAGE417
   EV2 P5E_CPU0_P2_RX_BUF_DN<0> @T6G_MB_LIB.T6G(SCH_1):P5E_CPU0_P2_RX_BUF_DN(0)    I38 @T6G_MB_LIB.T6G(SCH_1):PAGE417
   FJ6     NC     NC    I83 @T6G_MB_LIB.T6G(SCH_1):PAGE419
  FJ23     NC     NC    I83 @T6G_MB_LIB.T6G(SCH_1):PAGE419
  FJ25 GPIO2_RT_CPU0_P2 @T6G_MB_LIB.T6G(SCH_1):GPIO2_RT_CPU0_P2    I83 @T6G_MB_LIB.T6G(SCH_1):PAGE419
  FJ28 GPIO3_RT_CPU0_P2 @T6G_MB_LIB.T6G(SCH_1):GPIO3_RT_CPU0_P2    I83 @T6G_MB_LIB.T6G(SCH_1):PAGE419
  FJ31     NC     NC    I83 @T6G_MB_LIB.T6G(SCH_1):PAGE419
    B3 JTAG_TCK_RT_CPU0_P2 @T6G_MB_LIB.T6G(SCH_1):JTAG_TCK_RT_CPU0_P2    I83 @T6G_MB_LIB.T6G(SCH_1):PAGE419
    B6 JTAG_TDI_RT_CPU0_P2 @T6G_MB_LIB.T6G(SCH_1):JTAG_TDI_RT_CPU0_P2    I83 @T6G_MB_LIB.T6G(SCH_1):PAGE419
    B9 JTAG_TDO_RT_CPU0_P2 @T6G_MB_LIB.T6G(SCH_1):JTAG_TDO_RT_CPU0_P2    I83 @T6G_MB_LIB.T6G(SCH_1):PAGE419
   FF8 JTAG_TEST_MODE_RT_CPU0_P2 @T6G_MB_LIB.T6G(SCH_1):JTAG_TEST_MODE_RT_CPU0_P2    I83 @T6G_MB_LIB.T6G(SCH_1):PAGE419
   B12 JTAG_TMS_RT_CPU0_P2 @T6G_MB_LIB.T6G(SCH_1):JTAG_TMS_RT_CPU0_P2    I83 @T6G_MB_LIB.T6G(SCH_1):PAGE419
    E8 JTAG_TRST_RT_CPU0_P2_N @T6G_MB_LIB.T6G(SCH_1):JTAG_TRST_RT_CPU0_P2_N    I83 @T6G_MB_LIB.T6G(SCH_1):PAGE419
   FJ9 MODE_RT_CPU0_P2 @T6G_MB_LIB.T6G(SCH_1):MODE_RT_CPU0_P2    I83 @T6G_MB_LIB.T6G(SCH_1):PAGE419
    F2 RST_RT_CPU0_P2_PERST_N @T6G_MB_LIB.T6G(SCH_1):RST_RT_CPU0_P2_PERST_N    I83 @T6G_MB_LIB.T6G(SCH_1):PAGE419
   E18     NC     NC    I83 @T6G_MB_LIB.T6G(SCH_1):PAGE419
   B16     NC     NC    I83 @T6G_MB_LIB.T6G(SCH_1):PAGE419
  FF18 CLK_100M_RETIMER_CPU0_P2_DN @T6G_MB_LIB.T6G(SCH_1):CLK_100M_RETIMER_CPU0_P2_DN    I83 @T6G_MB_LIB.T6G(SCH_1):PAGE419
  FJ16 CLK_100M_RETIMER_CPU0_P2_DP @T6G_MB_LIB.T6G(SCH_1):CLK_100M_RETIMER_CPU0_P2_DP    I83 @T6G_MB_LIB.T6G(SCH_1):PAGE419
  FF11 RST_RT_CPU0_P2_RESET_N @T6G_MB_LIB.T6G(SCH_1):RST_RT_CPU0_P2_RESET_N    I83 @T6G_MB_LIB.T6G(SCH_1):PAGE419
   E11 RXDET_BYP_RT_CPU0_P2 @T6G_MB_LIB.T6G(SCH_1):RXDET_BYP_RT_CPU0_P2    I83 @T6G_MB_LIB.T6G(SCH_1):PAGE419
  FF33 RT_CPU0_P2_SCAN_MODE @T6G_MB_LIB.T6G(SCH_1):RT_CPU0_P2_SCAN_MODE    I83 @T6G_MB_LIB.T6G(SCH_1):PAGE419
   F34 RT_CPU0_P2_ADDR1 @T6G_MB_LIB.T6G(SCH_1):RT_CPU0_P2_ADDR1    I83 @T6G_MB_LIB.T6G(SCH_1):PAGE419
   B23 RT_CPU0_P2_ADDR2 @T6G_MB_LIB.T6G(SCH_1):RT_CPU0_P2_ADDR2    I83 @T6G_MB_LIB.T6G(SCH_1):PAGE419
   B25 RT_CPU0_P2_ADDR3 @T6G_MB_LIB.T6G(SCH_1):RT_CPU0_P2_ADDR3    I83 @T6G_MB_LIB.T6G(SCH_1):PAGE419
   B31 SMB_RT_CPU0_P2_R2_SCL @T6G_MB_LIB.T6G(SCH_1):SMB_RT_CPU0_P2_R2_SCL    I83 @T6G_MB_LIB.T6G(SCH_1):PAGE419
   B28 SMB_RT_CPU0_P2_R2_SDA @T6G_MB_LIB.T6G(SCH_1):SMB_RT_CPU0_P2_R2_SDA    I83 @T6G_MB_LIB.T6G(SCH_1):PAGE419
   E30    GND @T6G_MB_LIB.T6G(SCH_1):GND    I83 @T6G_MB_LIB.T6G(SCH_1):PAGE419
  FF24 TEST0_RT_CPU0_P2 @T6G_MB_LIB.T6G(SCH_1):TEST0_RT_CPU0_P2    I83 @T6G_MB_LIB.T6G(SCH_1):PAGE419
  FF27 TEST1_RT_CPU0_P2 @T6G_MB_LIB.T6G(SCH_1):TEST1_RT_CPU0_P2    I83 @T6G_MB_LIB.T6G(SCH_1):PAGE419
  FF30 TEST2_RT_CPU0_P2 @T6G_MB_LIB.T6G(SCH_1):TEST2_RT_CPU0_P2    I83 @T6G_MB_LIB.T6G(SCH_1):PAGE419
   G35 CLKREQ_RT_CPU0_P2_N @T6G_MB_LIB.T6G(SCH_1):CLKREQ_RT_CPU0_P2_N    I83 @T6G_MB_LIB.T6G(SCH_1):PAGE419
   FF5 SMB_RT_CPU0_P2_ROM_MUX_1D_R_SCL @T6G_MB_LIB.T6G(SCH_1):SMB_RT_CPU0_P2_ROM_MUX_1D_R_SCL    I83 @T6G_MB_LIB.T6G(SCH_1):PAGE419
   FJ3 SMB_RT_CPU0_P2_ROM_MUX_1D_R_SDA @T6G_MB_LIB.T6G(SCH_1):SMB_RT_CPU0_P2_ROM_MUX_1D_R_SDA    I83 @T6G_MB_LIB.T6G(SCH_1):PAGE419
    G1 RT_CPU0_P2_VQPS @T6G_MB_LIB.T6G(SCH_1):RT_CPU0_P2_VQPS     I6 @T6G_MB_LIB.T6G(SCH_1):PAGE420
  BV20 P1V8_CPU0_RT2_1A @T6G_MB_LIB.T6G(SCH_1):P1V8_CPU0_RT2_1A     I6 @T6G_MB_LIB.T6G(SCH_1):PAGE420
  CE17 P1V8_CPU0_RT2_1A @T6G_MB_LIB.T6G(SCH_1):P1V8_CPU0_RT2_1A     I6 @T6G_MB_LIB.T6G(SCH_1):PAGE420
  CE20 P1V8_CPU0_RT2_1A @T6G_MB_LIB.T6G(SCH_1):P1V8_CPU0_RT2_1A     I6 @T6G_MB_LIB.T6G(SCH_1):PAGE420
  CM17 P1V8_CPU0_RT2_1A @T6G_MB_LIB.T6G(SCH_1):P1V8_CPU0_RT2_1A     I6 @T6G_MB_LIB.T6G(SCH_1):PAGE420
  CM20 P1V8_CPU0_RT2_1A @T6G_MB_LIB.T6G(SCH_1):P1V8_CPU0_RT2_1A     I6 @T6G_MB_LIB.T6G(SCH_1):PAGE420
  BL17 P0V9_CPU0_RT_2D @T6G_MB_LIB.T6G(SCH_1):P0V9_CPU0_RT_2D     I6 @T6G_MB_LIB.T6G(SCH_1):PAGE420
  BL20 P0V9_CPU0_RT_2D @T6G_MB_LIB.T6G(SCH_1):P0V9_CPU0_RT_2D     I6 @T6G_MB_LIB.T6G(SCH_1):PAGE420
  CW17 P0V9_CPU0_RT_2D @T6G_MB_LIB.T6G(SCH_1):P0V9_CPU0_RT_2D     I6 @T6G_MB_LIB.T6G(SCH_1):PAGE420
  CW20 P0V9_CPU0_RT_2D @T6G_MB_LIB.T6G(SCH_1):P0V9_CPU0_RT_2D     I6 @T6G_MB_LIB.T6G(SCH_1):PAGE420
  BV17 P1V8_CPU0_RT2_1A_1D @T6G_MB_LIB.T6G(SCH_1):P1V8_CPU0_RT2_1A_1D     I6 @T6G_MB_LIB.T6G(SCH_1):PAGE420
  AC17 P0V9_CPU0_RT2_2A @T6G_MB_LIB.T6G(SCH_1):P0V9_CPU0_RT2_2A     I6 @T6G_MB_LIB.T6G(SCH_1):PAGE420
  AC20 P0V9_CPU0_RT2_2A @T6G_MB_LIB.T6G(SCH_1):P0V9_CPU0_RT2_2A     I6 @T6G_MB_LIB.T6G(SCH_1):PAGE420
  AK17 P0V9_CPU0_RT2_2A @T6G_MB_LIB.T6G(SCH_1):P0V9_CPU0_RT2_2A     I6 @T6G_MB_LIB.T6G(SCH_1):PAGE420
  AK20 P0V9_CPU0_RT2_2A @T6G_MB_LIB.T6G(SCH_1):P0V9_CPU0_RT2_2A     I6 @T6G_MB_LIB.T6G(SCH_1):PAGE420
  AU17 P0V9_CPU0_RT2_2A @T6G_MB_LIB.T6G(SCH_1):P0V9_CPU0_RT2_2A     I6 @T6G_MB_LIB.T6G(SCH_1):PAGE420
  AU20 P0V9_CPU0_RT2_2A @T6G_MB_LIB.T6G(SCH_1):P0V9_CPU0_RT2_2A     I6 @T6G_MB_LIB.T6G(SCH_1):PAGE420
  BD17 P0V9_CPU0_RT2_2A_2D @T6G_MB_LIB.T6G(SCH_1):P0V9_CPU0_RT2_2A_2D     I6 @T6G_MB_LIB.T6G(SCH_1):PAGE420
  BD20 P0V9_CPU0_RT2_2A_2D @T6G_MB_LIB.T6G(SCH_1):P0V9_CPU0_RT2_2A_2D     I6 @T6G_MB_LIB.T6G(SCH_1):PAGE420
  DF17 P0V9_CPU0_RT2_2A_2D @T6G_MB_LIB.T6G(SCH_1):P0V9_CPU0_RT2_2A_2D     I6 @T6G_MB_LIB.T6G(SCH_1):PAGE420
  DF20 P0V9_CPU0_RT2_2A_2D @T6G_MB_LIB.T6G(SCH_1):P0V9_CPU0_RT2_2A_2D     I6 @T6G_MB_LIB.T6G(SCH_1):PAGE420
  DN17 P0V9_CPU0_RT2_2A @T6G_MB_LIB.T6G(SCH_1):P0V9_CPU0_RT2_2A     I6 @T6G_MB_LIB.T6G(SCH_1):PAGE420
  DN20 P0V9_CPU0_RT2_2A @T6G_MB_LIB.T6G(SCH_1):P0V9_CPU0_RT2_2A     I6 @T6G_MB_LIB.T6G(SCH_1):PAGE420
  DY17 P0V9_CPU0_RT2_2A @T6G_MB_LIB.T6G(SCH_1):P0V9_CPU0_RT2_2A     I6 @T6G_MB_LIB.T6G(SCH_1):PAGE420
  DY20 P0V9_CPU0_RT2_2A @T6G_MB_LIB.T6G(SCH_1):P0V9_CPU0_RT2_2A     I6 @T6G_MB_LIB.T6G(SCH_1):PAGE420
  EG17 P0V9_CPU0_RT2_2A @T6G_MB_LIB.T6G(SCH_1):P0V9_CPU0_RT2_2A     I6 @T6G_MB_LIB.T6G(SCH_1):PAGE420
  EG20 P0V9_CPU0_RT2_2A @T6G_MB_LIB.T6G(SCH_1):P0V9_CPU0_RT2_2A     I6 @T6G_MB_LIB.T6G(SCH_1):PAGE420
  EP17 P0V9_CPU0_RT2_2A @T6G_MB_LIB.T6G(SCH_1):P0V9_CPU0_RT2_2A     I6 @T6G_MB_LIB.T6G(SCH_1):PAGE420
  EP20 P0V9_CPU0_RT2_2A @T6G_MB_LIB.T6G(SCH_1):P0V9_CPU0_RT2_2A     I6 @T6G_MB_LIB.T6G(SCH_1):PAGE420
   T17 P0V9_CPU0_RT2_2A @T6G_MB_LIB.T6G(SCH_1):P0V9_CPU0_RT2_2A     I6 @T6G_MB_LIB.T6G(SCH_1):PAGE420
   T20 P0V9_CPU0_RT2_2A @T6G_MB_LIB.T6G(SCH_1):P0V9_CPU0_RT2_2A     I6 @T6G_MB_LIB.T6G(SCH_1):PAGE420
  AC13    GND @T6G_MB_LIB.T6G(SCH_1):GND    I17 @T6G_MB_LIB.T6G(SCH_1):PAGE420
  AC22    GND @T6G_MB_LIB.T6G(SCH_1):GND    I17 @T6G_MB_LIB.T6G(SCH_1):PAGE420
  AC32    GND @T6G_MB_LIB.T6G(SCH_1):GND    I17 @T6G_MB_LIB.T6G(SCH_1):PAGE420
   AC4    GND @T6G_MB_LIB.T6G(SCH_1):GND    I17 @T6G_MB_LIB.T6G(SCH_1):PAGE420
   AD2    GND @T6G_MB_LIB.T6G(SCH_1):GND    I17 @T6G_MB_LIB.T6G(SCH_1):PAGE420
  AD34    GND @T6G_MB_LIB.T6G(SCH_1):GND    I17 @T6G_MB_LIB.T6G(SCH_1):PAGE420
   AE1    GND @T6G_MB_LIB.T6G(SCH_1):GND    I17 @T6G_MB_LIB.T6G(SCH_1):PAGE420
  AE35    GND @T6G_MB_LIB.T6G(SCH_1):GND    I17 @T6G_MB_LIB.T6G(SCH_1):PAGE420
  AK13    GND @T6G_MB_LIB.T6G(SCH_1):GND    I17 @T6G_MB_LIB.T6G(SCH_1):PAGE420
  AK22    GND @T6G_MB_LIB.T6G(SCH_1):GND    I17 @T6G_MB_LIB.T6G(SCH_1):PAGE420
  AK32    GND @T6G_MB_LIB.T6G(SCH_1):GND    I17 @T6G_MB_LIB.T6G(SCH_1):PAGE420
   AK4    GND @T6G_MB_LIB.T6G(SCH_1):GND    I17 @T6G_MB_LIB.T6G(SCH_1):PAGE420
   AL2    GND @T6G_MB_LIB.T6G(SCH_1):GND    I17 @T6G_MB_LIB.T6G(SCH_1):PAGE420
  AL34    GND @T6G_MB_LIB.T6G(SCH_1):GND    I17 @T6G_MB_LIB.T6G(SCH_1):PAGE420
   AM1    GND @T6G_MB_LIB.T6G(SCH_1):GND    I17 @T6G_MB_LIB.T6G(SCH_1):PAGE420
  AM35    GND @T6G_MB_LIB.T6G(SCH_1):GND    I17 @T6G_MB_LIB.T6G(SCH_1):PAGE420
  AU13    GND @T6G_MB_LIB.T6G(SCH_1):GND    I17 @T6G_MB_LIB.T6G(SCH_1):PAGE420
  AU22    GND @T6G_MB_LIB.T6G(SCH_1):GND    I17 @T6G_MB_LIB.T6G(SCH_1):PAGE420
  AU32    GND @T6G_MB_LIB.T6G(SCH_1):GND    I17 @T6G_MB_LIB.T6G(SCH_1):PAGE420
   AU4    GND @T6G_MB_LIB.T6G(SCH_1):GND    I17 @T6G_MB_LIB.T6G(SCH_1):PAGE420
   AV2    GND @T6G_MB_LIB.T6G(SCH_1):GND    I17 @T6G_MB_LIB.T6G(SCH_1):PAGE420
  AV34    GND @T6G_MB_LIB.T6G(SCH_1):GND    I17 @T6G_MB_LIB.T6G(SCH_1):PAGE420
   AW1    GND @T6G_MB_LIB.T6G(SCH_1):GND    I17 @T6G_MB_LIB.T6G(SCH_1):PAGE420
  AW35    GND @T6G_MB_LIB.T6G(SCH_1):GND    I17 @T6G_MB_LIB.T6G(SCH_1):PAGE420
   B19    GND @T6G_MB_LIB.T6G(SCH_1):GND    I17 @T6G_MB_LIB.T6G(SCH_1):PAGE420
  BD13    GND @T6G_MB_LIB.T6G(SCH_1):GND    I17 @T6G_MB_LIB.T6G(SCH_1):PAGE420
  BD22    GND @T6G_MB_LIB.T6G(SCH_1):GND    I17 @T6G_MB_LIB.T6G(SCH_1):PAGE420
  BD32    GND @T6G_MB_LIB.T6G(SCH_1):GND    I17 @T6G_MB_LIB.T6G(SCH_1):PAGE420
   BD4    GND @T6G_MB_LIB.T6G(SCH_1):GND    I17 @T6G_MB_LIB.T6G(SCH_1):PAGE420
   BE2    GND @T6G_MB_LIB.T6G(SCH_1):GND    I17 @T6G_MB_LIB.T6G(SCH_1):PAGE420
  BE34    GND @T6G_MB_LIB.T6G(SCH_1):GND    I17 @T6G_MB_LIB.T6G(SCH_1):PAGE420
   BF1    GND @T6G_MB_LIB.T6G(SCH_1):GND    I17 @T6G_MB_LIB.T6G(SCH_1):PAGE420
  BF35    GND @T6G_MB_LIB.T6G(SCH_1):GND    I17 @T6G_MB_LIB.T6G(SCH_1):PAGE420
  BL13    GND @T6G_MB_LIB.T6G(SCH_1):GND    I17 @T6G_MB_LIB.T6G(SCH_1):PAGE420
  BL22    GND @T6G_MB_LIB.T6G(SCH_1):GND    I17 @T6G_MB_LIB.T6G(SCH_1):PAGE420
  BL32    GND @T6G_MB_LIB.T6G(SCH_1):GND    I17 @T6G_MB_LIB.T6G(SCH_1):PAGE420
   BL4    GND @T6G_MB_LIB.T6G(SCH_1):GND    I17 @T6G_MB_LIB.T6G(SCH_1):PAGE420
   BM2    GND @T6G_MB_LIB.T6G(SCH_1):GND    I17 @T6G_MB_LIB.T6G(SCH_1):PAGE420
  BM34    GND @T6G_MB_LIB.T6G(SCH_1):GND    I17 @T6G_MB_LIB.T6G(SCH_1):PAGE420
   BN1    GND @T6G_MB_LIB.T6G(SCH_1):GND    I17 @T6G_MB_LIB.T6G(SCH_1):PAGE420
  BN35    GND @T6G_MB_LIB.T6G(SCH_1):GND    I17 @T6G_MB_LIB.T6G(SCH_1):PAGE420
  BV13    GND @T6G_MB_LIB.T6G(SCH_1):GND    I17 @T6G_MB_LIB.T6G(SCH_1):PAGE420
  BV22    GND @T6G_MB_LIB.T6G(SCH_1):GND    I17 @T6G_MB_LIB.T6G(SCH_1):PAGE420
  BV32    GND @T6G_MB_LIB.T6G(SCH_1):GND    I17 @T6G_MB_LIB.T6G(SCH_1):PAGE420
   BV4    GND @T6G_MB_LIB.T6G(SCH_1):GND    I17 @T6G_MB_LIB.T6G(SCH_1):PAGE420
   BW2    GND @T6G_MB_LIB.T6G(SCH_1):GND    I17 @T6G_MB_LIB.T6G(SCH_1):PAGE420
  BW34    GND @T6G_MB_LIB.T6G(SCH_1):GND    I17 @T6G_MB_LIB.T6G(SCH_1):PAGE420
   BY1    GND @T6G_MB_LIB.T6G(SCH_1):GND    I17 @T6G_MB_LIB.T6G(SCH_1):PAGE420
  BY35    GND @T6G_MB_LIB.T6G(SCH_1):GND    I17 @T6G_MB_LIB.T6G(SCH_1):PAGE420
  CE13    GND @T6G_MB_LIB.T6G(SCH_1):GND    I17 @T6G_MB_LIB.T6G(SCH_1):PAGE420
  CE22    GND @T6G_MB_LIB.T6G(SCH_1):GND    I17 @T6G_MB_LIB.T6G(SCH_1):PAGE420
  CE32    GND @T6G_MB_LIB.T6G(SCH_1):GND    I17 @T6G_MB_LIB.T6G(SCH_1):PAGE420
   CE4    GND @T6G_MB_LIB.T6G(SCH_1):GND    I17 @T6G_MB_LIB.T6G(SCH_1):PAGE420
   CF2    GND @T6G_MB_LIB.T6G(SCH_1):GND    I17 @T6G_MB_LIB.T6G(SCH_1):PAGE420
  CF34    GND @T6G_MB_LIB.T6G(SCH_1):GND    I17 @T6G_MB_LIB.T6G(SCH_1):PAGE420
   CG1    GND @T6G_MB_LIB.T6G(SCH_1):GND    I17 @T6G_MB_LIB.T6G(SCH_1):PAGE420
  CG35    GND @T6G_MB_LIB.T6G(SCH_1):GND    I17 @T6G_MB_LIB.T6G(SCH_1):PAGE420
  CM13    GND @T6G_MB_LIB.T6G(SCH_1):GND    I17 @T6G_MB_LIB.T6G(SCH_1):PAGE420
  CM22    GND @T6G_MB_LIB.T6G(SCH_1):GND    I17 @T6G_MB_LIB.T6G(SCH_1):PAGE420
  CM32    GND @T6G_MB_LIB.T6G(SCH_1):GND    I17 @T6G_MB_LIB.T6G(SCH_1):PAGE420
   CM4    GND @T6G_MB_LIB.T6G(SCH_1):GND    I17 @T6G_MB_LIB.T6G(SCH_1):PAGE420
   CN2    GND @T6G_MB_LIB.T6G(SCH_1):GND    I17 @T6G_MB_LIB.T6G(SCH_1):PAGE420
  CN34    GND @T6G_MB_LIB.T6G(SCH_1):GND    I17 @T6G_MB_LIB.T6G(SCH_1):PAGE420
   CP1    GND @T6G_MB_LIB.T6G(SCH_1):GND    I17 @T6G_MB_LIB.T6G(SCH_1):PAGE420
  CP35    GND @T6G_MB_LIB.T6G(SCH_1):GND    I17 @T6G_MB_LIB.T6G(SCH_1):PAGE420
  CW13    GND @T6G_MB_LIB.T6G(SCH_1):GND    I17 @T6G_MB_LIB.T6G(SCH_1):PAGE420
  CW22    GND @T6G_MB_LIB.T6G(SCH_1):GND    I17 @T6G_MB_LIB.T6G(SCH_1):PAGE420
  CW32    GND @T6G_MB_LIB.T6G(SCH_1):GND    I17 @T6G_MB_LIB.T6G(SCH_1):PAGE420
   CW4    GND @T6G_MB_LIB.T6G(SCH_1):GND    I17 @T6G_MB_LIB.T6G(SCH_1):PAGE420
   CY2    GND @T6G_MB_LIB.T6G(SCH_1):GND    I17 @T6G_MB_LIB.T6G(SCH_1):PAGE420
  CY34    GND @T6G_MB_LIB.T6G(SCH_1):GND    I17 @T6G_MB_LIB.T6G(SCH_1):PAGE420
   DA1    GND @T6G_MB_LIB.T6G(SCH_1):GND    I17 @T6G_MB_LIB.T6G(SCH_1):PAGE420
  DA35    GND @T6G_MB_LIB.T6G(SCH_1):GND    I17 @T6G_MB_LIB.T6G(SCH_1):PAGE420
  DF13    GND @T6G_MB_LIB.T6G(SCH_1):GND    I17 @T6G_MB_LIB.T6G(SCH_1):PAGE420
  DF22    GND @T6G_MB_LIB.T6G(SCH_1):GND    I17 @T6G_MB_LIB.T6G(SCH_1):PAGE420
  DF32    GND @T6G_MB_LIB.T6G(SCH_1):GND    I17 @T6G_MB_LIB.T6G(SCH_1):PAGE420
   DF4    GND @T6G_MB_LIB.T6G(SCH_1):GND    I17 @T6G_MB_LIB.T6G(SCH_1):PAGE420
   DG2    GND @T6G_MB_LIB.T6G(SCH_1):GND    I17 @T6G_MB_LIB.T6G(SCH_1):PAGE420
  DG34    GND @T6G_MB_LIB.T6G(SCH_1):GND    I17 @T6G_MB_LIB.T6G(SCH_1):PAGE420
   DH1    GND @T6G_MB_LIB.T6G(SCH_1):GND    I17 @T6G_MB_LIB.T6G(SCH_1):PAGE420
  DH35    GND @T6G_MB_LIB.T6G(SCH_1):GND    I17 @T6G_MB_LIB.T6G(SCH_1):PAGE420
  DN13    GND @T6G_MB_LIB.T6G(SCH_1):GND    I17 @T6G_MB_LIB.T6G(SCH_1):PAGE420
    A1 NCF_A1_CPU0_P2_GND @T6G_MB_LIB.T6G(SCH_1):NCF_A1_CPU0_P2_GND    I17 @T6G_MB_LIB.T6G(SCH_1):PAGE420
   A35 NCF_CPU0_P2_GND @T6G_MB_LIB.T6G(SCH_1):NCF_CPU0_P2_GND    I17 @T6G_MB_LIB.T6G(SCH_1):PAGE420
    C2 NCF_CPU0_P2_GND @T6G_MB_LIB.T6G(SCH_1):NCF_CPU0_P2_GND    I17 @T6G_MB_LIB.T6G(SCH_1):PAGE420
   C34 NCF_CPU0_P2_GND @T6G_MB_LIB.T6G(SCH_1):NCF_CPU0_P2_GND    I17 @T6G_MB_LIB.T6G(SCH_1):PAGE420
    D1 NCF_CPU0_P2_GND @T6G_MB_LIB.T6G(SCH_1):NCF_CPU0_P2_GND    I17 @T6G_MB_LIB.T6G(SCH_1):PAGE420
   D35 NCF_CPU0_P2_GND @T6G_MB_LIB.T6G(SCH_1):NCF_CPU0_P2_GND    I17 @T6G_MB_LIB.T6G(SCH_1):PAGE420
   FE2 NCF_CPU0_P2_GND @T6G_MB_LIB.T6G(SCH_1):NCF_CPU0_P2_GND    I17 @T6G_MB_LIB.T6G(SCH_1):PAGE420
  FE34 NCF_CPU0_P2_GND @T6G_MB_LIB.T6G(SCH_1):NCF_CPU0_P2_GND    I17 @T6G_MB_LIB.T6G(SCH_1):PAGE420
   FG1 NCF_CPU0_P2_GND @T6G_MB_LIB.T6G(SCH_1):NCF_CPU0_P2_GND    I17 @T6G_MB_LIB.T6G(SCH_1):PAGE420
  FG35 NCF_CPU0_P2_GND @T6G_MB_LIB.T6G(SCH_1):NCF_CPU0_P2_GND    I17 @T6G_MB_LIB.T6G(SCH_1):PAGE420
   FH2 NCF_CPU0_P2_GND @T6G_MB_LIB.T6G(SCH_1):NCF_CPU0_P2_GND    I17 @T6G_MB_LIB.T6G(SCH_1):PAGE420
  FH34 NCF_CPU0_P2_GND @T6G_MB_LIB.T6G(SCH_1):NCF_CPU0_P2_GND    I17 @T6G_MB_LIB.T6G(SCH_1):PAGE420
  DN22    GND @T6G_MB_LIB.T6G(SCH_1):GND    I17 @T6G_MB_LIB.T6G(SCH_1):PAGE420
  DN32    GND @T6G_MB_LIB.T6G(SCH_1):GND    I17 @T6G_MB_LIB.T6G(SCH_1):PAGE420
   DN4    GND @T6G_MB_LIB.T6G(SCH_1):GND    I17 @T6G_MB_LIB.T6G(SCH_1):PAGE420
   DP2    GND @T6G_MB_LIB.T6G(SCH_1):GND    I17 @T6G_MB_LIB.T6G(SCH_1):PAGE420
  DP34    GND @T6G_MB_LIB.T6G(SCH_1):GND    I17 @T6G_MB_LIB.T6G(SCH_1):PAGE420
   DR1    GND @T6G_MB_LIB.T6G(SCH_1):GND    I17 @T6G_MB_LIB.T6G(SCH_1):PAGE420
  DR35    GND @T6G_MB_LIB.T6G(SCH_1):GND    I17 @T6G_MB_LIB.T6G(SCH_1):PAGE420
  DY13    GND @T6G_MB_LIB.T6G(SCH_1):GND    I17 @T6G_MB_LIB.T6G(SCH_1):PAGE420
  DY22    GND @T6G_MB_LIB.T6G(SCH_1):GND    I17 @T6G_MB_LIB.T6G(SCH_1):PAGE420
  DY32    GND @T6G_MB_LIB.T6G(SCH_1):GND    I17 @T6G_MB_LIB.T6G(SCH_1):PAGE420
   DY4    GND @T6G_MB_LIB.T6G(SCH_1):GND    I17 @T6G_MB_LIB.T6G(SCH_1):PAGE420
   E14    GND @T6G_MB_LIB.T6G(SCH_1):GND    I17 @T6G_MB_LIB.T6G(SCH_1):PAGE420
   E27    GND @T6G_MB_LIB.T6G(SCH_1):GND    I17 @T6G_MB_LIB.T6G(SCH_1):PAGE420
   E33    GND @T6G_MB_LIB.T6G(SCH_1):GND    I17 @T6G_MB_LIB.T6G(SCH_1):PAGE420
   EA2    GND @T6G_MB_LIB.T6G(SCH_1):GND    I17 @T6G_MB_LIB.T6G(SCH_1):PAGE420
  EA34    GND @T6G_MB_LIB.T6G(SCH_1):GND    I17 @T6G_MB_LIB.T6G(SCH_1):PAGE420
   EB1    GND @T6G_MB_LIB.T6G(SCH_1):GND    I17 @T6G_MB_LIB.T6G(SCH_1):PAGE420
  EB35    GND @T6G_MB_LIB.T6G(SCH_1):GND    I17 @T6G_MB_LIB.T6G(SCH_1):PAGE420
  EG13    GND @T6G_MB_LIB.T6G(SCH_1):GND    I17 @T6G_MB_LIB.T6G(SCH_1):PAGE420
  EG22    GND @T6G_MB_LIB.T6G(SCH_1):GND    I17 @T6G_MB_LIB.T6G(SCH_1):PAGE420
  EG32    GND @T6G_MB_LIB.T6G(SCH_1):GND    I17 @T6G_MB_LIB.T6G(SCH_1):PAGE420
   EG4    GND @T6G_MB_LIB.T6G(SCH_1):GND    I17 @T6G_MB_LIB.T6G(SCH_1):PAGE420
   EH2    GND @T6G_MB_LIB.T6G(SCH_1):GND    I17 @T6G_MB_LIB.T6G(SCH_1):PAGE420
  EH34    GND @T6G_MB_LIB.T6G(SCH_1):GND    I17 @T6G_MB_LIB.T6G(SCH_1):PAGE420
   EJ1    GND @T6G_MB_LIB.T6G(SCH_1):GND    I17 @T6G_MB_LIB.T6G(SCH_1):PAGE420
  EJ35    GND @T6G_MB_LIB.T6G(SCH_1):GND    I17 @T6G_MB_LIB.T6G(SCH_1):PAGE420
  EP13    GND @T6G_MB_LIB.T6G(SCH_1):GND    I17 @T6G_MB_LIB.T6G(SCH_1):PAGE420
  EP22    GND @T6G_MB_LIB.T6G(SCH_1):GND    I17 @T6G_MB_LIB.T6G(SCH_1):PAGE420
  EP32    GND @T6G_MB_LIB.T6G(SCH_1):GND    I17 @T6G_MB_LIB.T6G(SCH_1):PAGE420
   EP4    GND @T6G_MB_LIB.T6G(SCH_1):GND    I17 @T6G_MB_LIB.T6G(SCH_1):PAGE420
   ER2    GND @T6G_MB_LIB.T6G(SCH_1):GND    I17 @T6G_MB_LIB.T6G(SCH_1):PAGE420
  ER34    GND @T6G_MB_LIB.T6G(SCH_1):GND    I17 @T6G_MB_LIB.T6G(SCH_1):PAGE420
   ET1    GND @T6G_MB_LIB.T6G(SCH_1):GND    I17 @T6G_MB_LIB.T6G(SCH_1):PAGE420
  ET35    GND @T6G_MB_LIB.T6G(SCH_1):GND    I17 @T6G_MB_LIB.T6G(SCH_1):PAGE420
  FA15    GND @T6G_MB_LIB.T6G(SCH_1):GND    I17 @T6G_MB_LIB.T6G(SCH_1):PAGE420
  FA32    GND @T6G_MB_LIB.T6G(SCH_1):GND    I17 @T6G_MB_LIB.T6G(SCH_1):PAGE420
   FB2    GND @T6G_MB_LIB.T6G(SCH_1):GND    I17 @T6G_MB_LIB.T6G(SCH_1):PAGE420
  FB34    GND @T6G_MB_LIB.T6G(SCH_1):GND    I17 @T6G_MB_LIB.T6G(SCH_1):PAGE420
  FC19    GND @T6G_MB_LIB.T6G(SCH_1):GND    I17 @T6G_MB_LIB.T6G(SCH_1):PAGE420
  FC23    GND @T6G_MB_LIB.T6G(SCH_1):GND    I17 @T6G_MB_LIB.T6G(SCH_1):PAGE420
  FC25    GND @T6G_MB_LIB.T6G(SCH_1):GND    I17 @T6G_MB_LIB.T6G(SCH_1):PAGE420
  FC28    GND @T6G_MB_LIB.T6G(SCH_1):GND    I17 @T6G_MB_LIB.T6G(SCH_1):PAGE420
   FC3    GND @T6G_MB_LIB.T6G(SCH_1):GND    I17 @T6G_MB_LIB.T6G(SCH_1):PAGE420
   FC6    GND @T6G_MB_LIB.T6G(SCH_1):GND    I17 @T6G_MB_LIB.T6G(SCH_1):PAGE420
   FC9    GND @T6G_MB_LIB.T6G(SCH_1):GND    I17 @T6G_MB_LIB.T6G(SCH_1):PAGE420
   FD1    GND @T6G_MB_LIB.T6G(SCH_1):GND    I17 @T6G_MB_LIB.T6G(SCH_1):PAGE420
  FD35    GND @T6G_MB_LIB.T6G(SCH_1):GND    I17 @T6G_MB_LIB.T6G(SCH_1):PAGE420
  FF14    GND @T6G_MB_LIB.T6G(SCH_1):GND    I17 @T6G_MB_LIB.T6G(SCH_1):PAGE420
  FF21    GND @T6G_MB_LIB.T6G(SCH_1):GND    I17 @T6G_MB_LIB.T6G(SCH_1):PAGE420
  FJ12    GND @T6G_MB_LIB.T6G(SCH_1):GND    I17 @T6G_MB_LIB.T6G(SCH_1):PAGE420
  FJ19    GND @T6G_MB_LIB.T6G(SCH_1):GND    I17 @T6G_MB_LIB.T6G(SCH_1):PAGE420
   H12    GND @T6G_MB_LIB.T6G(SCH_1):GND    I17 @T6G_MB_LIB.T6G(SCH_1):PAGE420
   H16    GND @T6G_MB_LIB.T6G(SCH_1):GND    I17 @T6G_MB_LIB.T6G(SCH_1):PAGE420
   H19    GND @T6G_MB_LIB.T6G(SCH_1):GND    I17 @T6G_MB_LIB.T6G(SCH_1):PAGE420
   H31    GND @T6G_MB_LIB.T6G(SCH_1):GND    I17 @T6G_MB_LIB.T6G(SCH_1):PAGE420
   J22    GND @T6G_MB_LIB.T6G(SCH_1):GND    I17 @T6G_MB_LIB.T6G(SCH_1):PAGE420
    J4    GND @T6G_MB_LIB.T6G(SCH_1):GND    I17 @T6G_MB_LIB.T6G(SCH_1):PAGE420
    K2    GND @T6G_MB_LIB.T6G(SCH_1):GND    I17 @T6G_MB_LIB.T6G(SCH_1):PAGE420
   K34    GND @T6G_MB_LIB.T6G(SCH_1):GND    I17 @T6G_MB_LIB.T6G(SCH_1):PAGE420
    L1    GND @T6G_MB_LIB.T6G(SCH_1):GND    I17 @T6G_MB_LIB.T6G(SCH_1):PAGE420
   L35    GND @T6G_MB_LIB.T6G(SCH_1):GND    I17 @T6G_MB_LIB.T6G(SCH_1):PAGE420
   T13    GND @T6G_MB_LIB.T6G(SCH_1):GND    I17 @T6G_MB_LIB.T6G(SCH_1):PAGE420
   T22    GND @T6G_MB_LIB.T6G(SCH_1):GND    I17 @T6G_MB_LIB.T6G(SCH_1):PAGE420
   T32    GND @T6G_MB_LIB.T6G(SCH_1):GND    I17 @T6G_MB_LIB.T6G(SCH_1):PAGE420
    T4    GND @T6G_MB_LIB.T6G(SCH_1):GND    I17 @T6G_MB_LIB.T6G(SCH_1):PAGE420
    U2    GND @T6G_MB_LIB.T6G(SCH_1):GND    I17 @T6G_MB_LIB.T6G(SCH_1):PAGE420
   U34    GND @T6G_MB_LIB.T6G(SCH_1):GND    I17 @T6G_MB_LIB.T6G(SCH_1):PAGE420
    V1    GND @T6G_MB_LIB.T6G(SCH_1):GND    I17 @T6G_MB_LIB.T6G(SCH_1):PAGE420
   V35    GND @T6G_MB_LIB.T6G(SCH_1):GND    I17 @T6G_MB_LIB.T6G(SCH_1):PAGE420
   M26 P5E_CPU0_P2_RX_DP<15> @T6G_MB_LIB.T6G(SCH_1):P5E_CPU0_P2_RX_DP(15)     I1 @T6G_MB_LIB.T6G(SCH_1):PAGE416
   P29 P5E_CPU0_P2_RX_DN<15> @T6G_MB_LIB.T6G(SCH_1):P5E_CPU0_P2_RX_DN(15)     I1 @T6G_MB_LIB.T6G(SCH_1):PAGE416
   W26 P5E_CPU0_P2_RX_DP<14> @T6G_MB_LIB.T6G(SCH_1):P5E_CPU0_P2_RX_DP(14)     I1 @T6G_MB_LIB.T6G(SCH_1):PAGE416
  AA29 P5E_CPU0_P2_RX_DN<14> @T6G_MB_LIB.T6G(SCH_1):P5E_CPU0_P2_RX_DN(14)     I1 @T6G_MB_LIB.T6G(SCH_1):PAGE416
  AF26 P5E_CPU0_P2_RX_DP<13> @T6G_MB_LIB.T6G(SCH_1):P5E_CPU0_P2_RX_DP(13)     I1 @T6G_MB_LIB.T6G(SCH_1):PAGE416
  AH29 P5E_CPU0_P2_RX_DN<13> @T6G_MB_LIB.T6G(SCH_1):P5E_CPU0_P2_RX_DN(13)     I1 @T6G_MB_LIB.T6G(SCH_1):PAGE416
  AN26 P5E_CPU0_P2_RX_DP<12> @T6G_MB_LIB.T6G(SCH_1):P5E_CPU0_P2_RX_DP(12)     I1 @T6G_MB_LIB.T6G(SCH_1):PAGE416
  AR29 P5E_CPU0_P2_RX_DN<12> @T6G_MB_LIB.T6G(SCH_1):P5E_CPU0_P2_RX_DN(12)     I1 @T6G_MB_LIB.T6G(SCH_1):PAGE416
  AY26 P5E_CPU0_P2_RX_DP<11> @T6G_MB_LIB.T6G(SCH_1):P5E_CPU0_P2_RX_DP(11)     I1 @T6G_MB_LIB.T6G(SCH_1):PAGE416
  BB29 P5E_CPU0_P2_RX_DN<11> @T6G_MB_LIB.T6G(SCH_1):P5E_CPU0_P2_RX_DN(11)     I1 @T6G_MB_LIB.T6G(SCH_1):PAGE416
  BG26 P5E_CPU0_P2_RX_DP<10> @T6G_MB_LIB.T6G(SCH_1):P5E_CPU0_P2_RX_DP(10)     I1 @T6G_MB_LIB.T6G(SCH_1):PAGE416
  BJ29 P5E_CPU0_P2_RX_DN<10> @T6G_MB_LIB.T6G(SCH_1):P5E_CPU0_P2_RX_DN(10)     I1 @T6G_MB_LIB.T6G(SCH_1):PAGE416
  BP26 P5E_CPU0_P2_RX_DP<9> @T6G_MB_LIB.T6G(SCH_1):P5E_CPU0_P2_RX_DP(9)     I1 @T6G_MB_LIB.T6G(SCH_1):PAGE416
  BT29 P5E_CPU0_P2_RX_DN<9> @T6G_MB_LIB.T6G(SCH_1):P5E_CPU0_P2_RX_DN(9)     I1 @T6G_MB_LIB.T6G(SCH_1):PAGE416
  CA26 P5E_CPU0_P2_RX_DP<8> @T6G_MB_LIB.T6G(SCH_1):P5E_CPU0_P2_RX_DP(8)     I1 @T6G_MB_LIB.T6G(SCH_1):PAGE416
  CC29 P5E_CPU0_P2_RX_DN<8> @T6G_MB_LIB.T6G(SCH_1):P5E_CPU0_P2_RX_DN(8)     I1 @T6G_MB_LIB.T6G(SCH_1):PAGE416
  CH26 P5E_CPU0_P2_RX_DP<7> @T6G_MB_LIB.T6G(SCH_1):P5E_CPU0_P2_RX_DP(7)    I38 @T6G_MB_LIB.T6G(SCH_1):PAGE416
  CK29 P5E_CPU0_P2_RX_DN<7> @T6G_MB_LIB.T6G(SCH_1):P5E_CPU0_P2_RX_DN(7)    I38 @T6G_MB_LIB.T6G(SCH_1):PAGE416
  CR26 P5E_CPU0_P2_RX_DP<6> @T6G_MB_LIB.T6G(SCH_1):P5E_CPU0_P2_RX_DP(6)    I38 @T6G_MB_LIB.T6G(SCH_1):PAGE416
  CU29 P5E_CPU0_P2_RX_DN<6> @T6G_MB_LIB.T6G(SCH_1):P5E_CPU0_P2_RX_DN(6)    I38 @T6G_MB_LIB.T6G(SCH_1):PAGE416
  DB26 P5E_CPU0_P2_RX_DP<5> @T6G_MB_LIB.T6G(SCH_1):P5E_CPU0_P2_RX_DP(5)    I38 @T6G_MB_LIB.T6G(SCH_1):PAGE416
  DD29 P5E_CPU0_P2_RX_DN<5> @T6G_MB_LIB.T6G(SCH_1):P5E_CPU0_P2_RX_DN(5)    I38 @T6G_MB_LIB.T6G(SCH_1):PAGE416
  DJ26 P5E_CPU0_P2_RX_DP<4> @T6G_MB_LIB.T6G(SCH_1):P5E_CPU0_P2_RX_DP(4)    I38 @T6G_MB_LIB.T6G(SCH_1):PAGE416
  DL29 P5E_CPU0_P2_RX_DN<4> @T6G_MB_LIB.T6G(SCH_1):P5E_CPU0_P2_RX_DN(4)    I38 @T6G_MB_LIB.T6G(SCH_1):PAGE416
  DT26 P5E_CPU0_P2_RX_DP<3> @T6G_MB_LIB.T6G(SCH_1):P5E_CPU0_P2_RX_DP(3)    I38 @T6G_MB_LIB.T6G(SCH_1):PAGE416
  DV29 P5E_CPU0_P2_RX_DN<3> @T6G_MB_LIB.T6G(SCH_1):P5E_CPU0_P2_RX_DN(3)    I38 @T6G_MB_LIB.T6G(SCH_1):PAGE416
  EC26 P5E_CPU0_P2_RX_DP<2> @T6G_MB_LIB.T6G(SCH_1):P5E_CPU0_P2_RX_DP(2)    I38 @T6G_MB_LIB.T6G(SCH_1):PAGE416
  EE29 P5E_CPU0_P2_RX_DN<2> @T6G_MB_LIB.T6G(SCH_1):P5E_CPU0_P2_RX_DN(2)    I38 @T6G_MB_LIB.T6G(SCH_1):PAGE416
  EK26 P5E_CPU0_P2_RX_DP<1> @T6G_MB_LIB.T6G(SCH_1):P5E_CPU0_P2_RX_DP(1)    I38 @T6G_MB_LIB.T6G(SCH_1):PAGE416
  EM29 P5E_CPU0_P2_RX_DN<1> @T6G_MB_LIB.T6G(SCH_1):P5E_CPU0_P2_RX_DN(1)    I38 @T6G_MB_LIB.T6G(SCH_1):PAGE416
  EU26 P5E_CPU0_P2_RX_DP<0> @T6G_MB_LIB.T6G(SCH_1):P5E_CPU0_P2_RX_DP(0)    I38 @T6G_MB_LIB.T6G(SCH_1):PAGE416
  EW29 P5E_CPU0_P2_RX_DN<0> @T6G_MB_LIB.T6G(SCH_1):P5E_CPU0_P2_RX_DN(0)    I38 @T6G_MB_LIB.T6G(SCH_1):PAGE416
   N34 P5E_CPU0_P2_TX_C_DN<15> @T6G_MB_LIB.T6G(SCH_1):P5E_CPU0_P2_TX_C_DN(15)    I38 @T6G_MB_LIB.T6G(SCH_1):PAGE415
   R35 P5E_CPU0_P2_TX_C_DP<15> @T6G_MB_LIB.T6G(SCH_1):P5E_CPU0_P2_TX_C_DP(15)    I38 @T6G_MB_LIB.T6G(SCH_1):PAGE415
   Y34 P5E_CPU0_P2_TX_C_DN<14> @T6G_MB_LIB.T6G(SCH_1):P5E_CPU0_P2_TX_C_DN(14)    I38 @T6G_MB_LIB.T6G(SCH_1):PAGE415
  AB35 P5E_CPU0_P2_TX_C_DP<14> @T6G_MB_LIB.T6G(SCH_1):P5E_CPU0_P2_TX_C_DP(14)    I38 @T6G_MB_LIB.T6G(SCH_1):PAGE415
  AG34 P5E_CPU0_P2_TX_C_DN<13> @T6G_MB_LIB.T6G(SCH_1):P5E_CPU0_P2_TX_C_DN(13)    I38 @T6G_MB_LIB.T6G(SCH_1):PAGE415
  AJ35 P5E_CPU0_P2_TX_C_DP<13> @T6G_MB_LIB.T6G(SCH_1):P5E_CPU0_P2_TX_C_DP(13)    I38 @T6G_MB_LIB.T6G(SCH_1):PAGE415
  AP34 P5E_CPU0_P2_TX_C_DN<12> @T6G_MB_LIB.T6G(SCH_1):P5E_CPU0_P2_TX_C_DN(12)    I38 @T6G_MB_LIB.T6G(SCH_1):PAGE415
  AT35 P5E_CPU0_P2_TX_C_DP<12> @T6G_MB_LIB.T6G(SCH_1):P5E_CPU0_P2_TX_C_DP(12)    I38 @T6G_MB_LIB.T6G(SCH_1):PAGE415
  BA34 P5E_CPU0_P2_TX_C_DN<11> @T6G_MB_LIB.T6G(SCH_1):P5E_CPU0_P2_TX_C_DN(11)    I38 @T6G_MB_LIB.T6G(SCH_1):PAGE415
  BC35 P5E_CPU0_P2_TX_C_DP<11> @T6G_MB_LIB.T6G(SCH_1):P5E_CPU0_P2_TX_C_DP(11)    I38 @T6G_MB_LIB.T6G(SCH_1):PAGE415
  BH34 P5E_CPU0_P2_TX_C_DN<10> @T6G_MB_LIB.T6G(SCH_1):P5E_CPU0_P2_TX_C_DN(10)    I38 @T6G_MB_LIB.T6G(SCH_1):PAGE415
  BK35 P5E_CPU0_P2_TX_C_DP<10> @T6G_MB_LIB.T6G(SCH_1):P5E_CPU0_P2_TX_C_DP(10)    I38 @T6G_MB_LIB.T6G(SCH_1):PAGE415
  BR34 P5E_CPU0_P2_TX_C_DN<9> @T6G_MB_LIB.T6G(SCH_1):P5E_CPU0_P2_TX_C_DN(9)    I38 @T6G_MB_LIB.T6G(SCH_1):PAGE415
  BU35 P5E_CPU0_P2_TX_C_DP<9> @T6G_MB_LIB.T6G(SCH_1):P5E_CPU0_P2_TX_C_DP(9)    I38 @T6G_MB_LIB.T6G(SCH_1):PAGE415
  CB34 P5E_CPU0_P2_TX_C_DN<8> @T6G_MB_LIB.T6G(SCH_1):P5E_CPU0_P2_TX_C_DN(8)    I38 @T6G_MB_LIB.T6G(SCH_1):PAGE415
  CD35 P5E_CPU0_P2_TX_C_DP<8> @T6G_MB_LIB.T6G(SCH_1):P5E_CPU0_P2_TX_C_DP(8)    I38 @T6G_MB_LIB.T6G(SCH_1):PAGE415
  CJ34 P5E_CPU0_P2_TX_C_DN<7> @T6G_MB_LIB.T6G(SCH_1):P5E_CPU0_P2_TX_C_DN(7)    I37 @T6G_MB_LIB.T6G(SCH_1):PAGE415
  CL35 P5E_CPU0_P2_TX_C_DP<7> @T6G_MB_LIB.T6G(SCH_1):P5E_CPU0_P2_TX_C_DP(7)    I37 @T6G_MB_LIB.T6G(SCH_1):PAGE415
  CT34 P5E_CPU0_P2_TX_C_DN<6> @T6G_MB_LIB.T6G(SCH_1):P5E_CPU0_P2_TX_C_DN(6)    I37 @T6G_MB_LIB.T6G(SCH_1):PAGE415
  CV35 P5E_CPU0_P2_TX_C_DP<6> @T6G_MB_LIB.T6G(SCH_1):P5E_CPU0_P2_TX_C_DP(6)    I37 @T6G_MB_LIB.T6G(SCH_1):PAGE415
  DC34 P5E_CPU0_P2_TX_C_DN<5> @T6G_MB_LIB.T6G(SCH_1):P5E_CPU0_P2_TX_C_DN(5)    I37 @T6G_MB_LIB.T6G(SCH_1):PAGE415
  DE35 P5E_CPU0_P2_TX_C_DP<5> @T6G_MB_LIB.T6G(SCH_1):P5E_CPU0_P2_TX_C_DP(5)    I37 @T6G_MB_LIB.T6G(SCH_1):PAGE415
  DK34 P5E_CPU0_P2_TX_C_DN<4> @T6G_MB_LIB.T6G(SCH_1):P5E_CPU0_P2_TX_C_DN(4)    I37 @T6G_MB_LIB.T6G(SCH_1):PAGE415
  DM35 P5E_CPU0_P2_TX_C_DP<4> @T6G_MB_LIB.T6G(SCH_1):P5E_CPU0_P2_TX_C_DP(4)    I37 @T6G_MB_LIB.T6G(SCH_1):PAGE415
  DU34 P5E_CPU0_P2_TX_C_DN<3> @T6G_MB_LIB.T6G(SCH_1):P5E_CPU0_P2_TX_C_DN(3)    I37 @T6G_MB_LIB.T6G(SCH_1):PAGE415
  DW35 P5E_CPU0_P2_TX_C_DP<3> @T6G_MB_LIB.T6G(SCH_1):P5E_CPU0_P2_TX_C_DP(3)    I37 @T6G_MB_LIB.T6G(SCH_1):PAGE415
  ED34 P5E_CPU0_P2_TX_C_DN<2> @T6G_MB_LIB.T6G(SCH_1):P5E_CPU0_P2_TX_C_DN(2)    I37 @T6G_MB_LIB.T6G(SCH_1):PAGE415
  EF35 P5E_CPU0_P2_TX_C_DP<2> @T6G_MB_LIB.T6G(SCH_1):P5E_CPU0_P2_TX_C_DP(2)    I37 @T6G_MB_LIB.T6G(SCH_1):PAGE415
  EL34 P5E_CPU0_P2_TX_C_DP<1> @T6G_MB_LIB.T6G(SCH_1):P5E_CPU0_P2_TX_C_DP(1)    I37 @T6G_MB_LIB.T6G(SCH_1):PAGE415
  EN35 P5E_CPU0_P2_TX_C_DN<1> @T6G_MB_LIB.T6G(SCH_1):P5E_CPU0_P2_TX_C_DN(1)    I37 @T6G_MB_LIB.T6G(SCH_1):PAGE415
  EV34 P5E_CPU0_P2_TX_C_DN<0> @T6G_MB_LIB.T6G(SCH_1):P5E_CPU0_P2_TX_C_DN(0)    I37 @T6G_MB_LIB.T6G(SCH_1):PAGE415
  EY35 P5E_CPU0_P2_TX_C_DP<0> @T6G_MB_LIB.T6G(SCH_1):P5E_CPU0_P2_TX_C_DP(0)    I37 @T6G_MB_LIB.T6G(SCH_1):PAGE415
    M7 P5E_CPU0_P2_TX_BUF_DP<15> @T6G_MB_LIB.T6G(SCH_1):P5E_CPU0_P2_TX_BUF_DP(15)    I47 @T6G_MB_LIB.T6G(SCH_1):PAGE418
   P10 P5E_CPU0_P2_TX_BUF_DN<15> @T6G_MB_LIB.T6G(SCH_1):P5E_CPU0_P2_TX_BUF_DN(15)    I47 @T6G_MB_LIB.T6G(SCH_1):PAGE418
    W7 P5E_CPU0_P2_TX_BUF_DP<14> @T6G_MB_LIB.T6G(SCH_1):P5E_CPU0_P2_TX_BUF_DP(14)    I47 @T6G_MB_LIB.T6G(SCH_1):PAGE418
  AA10 P5E_CPU0_P2_TX_BUF_DN<14> @T6G_MB_LIB.T6G(SCH_1):P5E_CPU0_P2_TX_BUF_DN(14)    I47 @T6G_MB_LIB.T6G(SCH_1):PAGE418
   AF7 P5E_CPU0_P2_TX_BUF_DP<13> @T6G_MB_LIB.T6G(SCH_1):P5E_CPU0_P2_TX_BUF_DP(13)    I47 @T6G_MB_LIB.T6G(SCH_1):PAGE418
  AH10 P5E_CPU0_P2_TX_BUF_DN<13> @T6G_MB_LIB.T6G(SCH_1):P5E_CPU0_P2_TX_BUF_DN(13)    I47 @T6G_MB_LIB.T6G(SCH_1):PAGE418
   AN7 P5E_CPU0_P2_TX_BUF_DP<12> @T6G_MB_LIB.T6G(SCH_1):P5E_CPU0_P2_TX_BUF_DP(12)    I47 @T6G_MB_LIB.T6G(SCH_1):PAGE418
  AR10 P5E_CPU0_P2_TX_BUF_DN<12> @T6G_MB_LIB.T6G(SCH_1):P5E_CPU0_P2_TX_BUF_DN(12)    I47 @T6G_MB_LIB.T6G(SCH_1):PAGE418
   AY7 P5E_CPU0_P2_TX_BUF_DP<11> @T6G_MB_LIB.T6G(SCH_1):P5E_CPU0_P2_TX_BUF_DP(11)    I47 @T6G_MB_LIB.T6G(SCH_1):PAGE418
  BB10 P5E_CPU0_P2_TX_BUF_DN<11> @T6G_MB_LIB.T6G(SCH_1):P5E_CPU0_P2_TX_BUF_DN(11)    I47 @T6G_MB_LIB.T6G(SCH_1):PAGE418
   BG7 P5E_CPU0_P2_TX_BUF_DP<10> @T6G_MB_LIB.T6G(SCH_1):P5E_CPU0_P2_TX_BUF_DP(10)    I47 @T6G_MB_LIB.T6G(SCH_1):PAGE418
  BJ10 P5E_CPU0_P2_TX_BUF_DN<10> @T6G_MB_LIB.T6G(SCH_1):P5E_CPU0_P2_TX_BUF_DN(10)    I47 @T6G_MB_LIB.T6G(SCH_1):PAGE418
   BP7 P5E_CPU0_P2_TX_BUF_DP<9> @T6G_MB_LIB.T6G(SCH_1):P5E_CPU0_P2_TX_BUF_DP(9)    I47 @T6G_MB_LIB.T6G(SCH_1):PAGE418
  BT10 P5E_CPU0_P2_TX_BUF_DN<9> @T6G_MB_LIB.T6G(SCH_1):P5E_CPU0_P2_TX_BUF_DN(9)    I47 @T6G_MB_LIB.T6G(SCH_1):PAGE418
   CA7 P5E_CPU0_P2_TX_BUF_DP<8> @T6G_MB_LIB.T6G(SCH_1):P5E_CPU0_P2_TX_BUF_DP(8)    I47 @T6G_MB_LIB.T6G(SCH_1):PAGE418
  CC10 P5E_CPU0_P2_TX_BUF_DN<8> @T6G_MB_LIB.T6G(SCH_1):P5E_CPU0_P2_TX_BUF_DN(8)    I47 @T6G_MB_LIB.T6G(SCH_1):PAGE418
   CH7 P5E_CPU0_P2_TX_BUF_DP<7> @T6G_MB_LIB.T6G(SCH_1):P5E_CPU0_P2_TX_BUF_DP(7)   I142 @T6G_MB_LIB.T6G(SCH_1):PAGE418
  CK10 P5E_CPU0_P2_TX_BUF_DN<7> @T6G_MB_LIB.T6G(SCH_1):P5E_CPU0_P2_TX_BUF_DN(7)   I142 @T6G_MB_LIB.T6G(SCH_1):PAGE418
   CR7 P5E_CPU0_P2_TX_BUF_DP<6> @T6G_MB_LIB.T6G(SCH_1):P5E_CPU0_P2_TX_BUF_DP(6)   I142 @T6G_MB_LIB.T6G(SCH_1):PAGE418
  CU10 P5E_CPU0_P2_TX_BUF_DN<6> @T6G_MB_LIB.T6G(SCH_1):P5E_CPU0_P2_TX_BUF_DN(6)   I142 @T6G_MB_LIB.T6G(SCH_1):PAGE418
   DB7 P5E_CPU0_P2_TX_BUF_DP<5> @T6G_MB_LIB.T6G(SCH_1):P5E_CPU0_P2_TX_BUF_DP(5)   I142 @T6G_MB_LIB.T6G(SCH_1):PAGE418
  DD10 P5E_CPU0_P2_TX_BUF_DN<5> @T6G_MB_LIB.T6G(SCH_1):P5E_CPU0_P2_TX_BUF_DN(5)   I142 @T6G_MB_LIB.T6G(SCH_1):PAGE418
   DJ7 P5E_CPU0_P2_TX_BUF_DP<4> @T6G_MB_LIB.T6G(SCH_1):P5E_CPU0_P2_TX_BUF_DP(4)   I142 @T6G_MB_LIB.T6G(SCH_1):PAGE418
  DL10 P5E_CPU0_P2_TX_BUF_DN<4> @T6G_MB_LIB.T6G(SCH_1):P5E_CPU0_P2_TX_BUF_DN(4)   I142 @T6G_MB_LIB.T6G(SCH_1):PAGE418
   DT7 P5E_CPU0_P2_TX_BUF_DP<3> @T6G_MB_LIB.T6G(SCH_1):P5E_CPU0_P2_TX_BUF_DP(3)   I142 @T6G_MB_LIB.T6G(SCH_1):PAGE418
  DV10 P5E_CPU0_P2_TX_BUF_DN<3> @T6G_MB_LIB.T6G(SCH_1):P5E_CPU0_P2_TX_BUF_DN(3)   I142 @T6G_MB_LIB.T6G(SCH_1):PAGE418
   EC7 P5E_CPU0_P2_TX_BUF_DP<2> @T6G_MB_LIB.T6G(SCH_1):P5E_CPU0_P2_TX_BUF_DP(2)   I142 @T6G_MB_LIB.T6G(SCH_1):PAGE418
  EE10 P5E_CPU0_P2_TX_BUF_DN<2> @T6G_MB_LIB.T6G(SCH_1):P5E_CPU0_P2_TX_BUF_DN(2)   I142 @T6G_MB_LIB.T6G(SCH_1):PAGE418
   EK7 P5E_CPU0_P2_TX_BUF_DP<1> @T6G_MB_LIB.T6G(SCH_1):P5E_CPU0_P2_TX_BUF_DP(1)   I142 @T6G_MB_LIB.T6G(SCH_1):PAGE418
  EM10 P5E_CPU0_P2_TX_BUF_DN<1> @T6G_MB_LIB.T6G(SCH_1):P5E_CPU0_P2_TX_BUF_DN(1)   I142 @T6G_MB_LIB.T6G(SCH_1):PAGE418
   EU7 P5E_CPU0_P2_TX_BUF_DP<0> @T6G_MB_LIB.T6G(SCH_1):P5E_CPU0_P2_TX_BUF_DP(0)   I142 @T6G_MB_LIB.T6G(SCH_1):PAGE418
  EW10 P5E_CPU0_P2_TX_BUF_DN<0> @T6G_MB_LIB.T6G(SCH_1):P5E_CPU0_P2_TX_BUF_DN(0)   I142 @T6G_MB_LIB.T6G(SCH_1):PAGE418

U6013 PT5161LRS-PT5161LRS,SMLF,IC,AJ051610U03
    R1 P5E_CPU0_P3_RX_BUF_DP<15> @T6G_MB_LIB.T6G(SCH_1):P5E_CPU0_P3_RX_BUF_DP(15)     I1 @T6G_MB_LIB.T6G(SCH_1):PAGE428
    N2 P5E_CPU0_P3_RX_BUF_DN<15> @T6G_MB_LIB.T6G(SCH_1):P5E_CPU0_P3_RX_BUF_DN(15)     I1 @T6G_MB_LIB.T6G(SCH_1):PAGE428
   AB1 P5E_CPU0_P3_RX_BUF_DP<14> @T6G_MB_LIB.T6G(SCH_1):P5E_CPU0_P3_RX_BUF_DP(14)     I1 @T6G_MB_LIB.T6G(SCH_1):PAGE428
    Y2 P5E_CPU0_P3_RX_BUF_DN<14> @T6G_MB_LIB.T6G(SCH_1):P5E_CPU0_P3_RX_BUF_DN(14)     I1 @T6G_MB_LIB.T6G(SCH_1):PAGE428
   AJ1 P5E_CPU0_P3_RX_BUF_DP<13> @T6G_MB_LIB.T6G(SCH_1):P5E_CPU0_P3_RX_BUF_DP(13)     I1 @T6G_MB_LIB.T6G(SCH_1):PAGE428
   AG2 P5E_CPU0_P3_RX_BUF_DN<13> @T6G_MB_LIB.T6G(SCH_1):P5E_CPU0_P3_RX_BUF_DN(13)     I1 @T6G_MB_LIB.T6G(SCH_1):PAGE428
   AT1 P5E_CPU0_P3_RX_BUF_DP<12> @T6G_MB_LIB.T6G(SCH_1):P5E_CPU0_P3_RX_BUF_DP(12)     I1 @T6G_MB_LIB.T6G(SCH_1):PAGE428
   AP2 P5E_CPU0_P3_RX_BUF_DN<12> @T6G_MB_LIB.T6G(SCH_1):P5E_CPU0_P3_RX_BUF_DN(12)     I1 @T6G_MB_LIB.T6G(SCH_1):PAGE428
   BC1 P5E_CPU0_P3_RX_BUF_DP<11> @T6G_MB_LIB.T6G(SCH_1):P5E_CPU0_P3_RX_BUF_DP(11)     I1 @T6G_MB_LIB.T6G(SCH_1):PAGE428
   BA2 P5E_CPU0_P3_RX_BUF_DN<11> @T6G_MB_LIB.T6G(SCH_1):P5E_CPU0_P3_RX_BUF_DN(11)     I1 @T6G_MB_LIB.T6G(SCH_1):PAGE428
   BK1 P5E_CPU0_P3_RX_BUF_DP<10> @T6G_MB_LIB.T6G(SCH_1):P5E_CPU0_P3_RX_BUF_DP(10)     I1 @T6G_MB_LIB.T6G(SCH_1):PAGE428
   BH2 P5E_CPU0_P3_RX_BUF_DN<10> @T6G_MB_LIB.T6G(SCH_1):P5E_CPU0_P3_RX_BUF_DN(10)     I1 @T6G_MB_LIB.T6G(SCH_1):PAGE428
   BU1 P5E_CPU0_P3_RX_BUF_DP<9> @T6G_MB_LIB.T6G(SCH_1):P5E_CPU0_P3_RX_BUF_DP(9)     I1 @T6G_MB_LIB.T6G(SCH_1):PAGE428
   BR2 P5E_CPU0_P3_RX_BUF_DN<9> @T6G_MB_LIB.T6G(SCH_1):P5E_CPU0_P3_RX_BUF_DN(9)     I1 @T6G_MB_LIB.T6G(SCH_1):PAGE428
   CD1 P5E_CPU0_P3_RX_BUF_DP<8> @T6G_MB_LIB.T6G(SCH_1):P5E_CPU0_P3_RX_BUF_DP(8)     I1 @T6G_MB_LIB.T6G(SCH_1):PAGE428
   CB2 P5E_CPU0_P3_RX_BUF_DN<8> @T6G_MB_LIB.T6G(SCH_1):P5E_CPU0_P3_RX_BUF_DN(8)     I1 @T6G_MB_LIB.T6G(SCH_1):PAGE428
   CL1 P5E_CPU0_P3_RX_BUF_DP<7> @T6G_MB_LIB.T6G(SCH_1):P5E_CPU0_P3_RX_BUF_DP(7)    I38 @T6G_MB_LIB.T6G(SCH_1):PAGE428
   CJ2 P5E_CPU0_P3_RX_BUF_DN<7> @T6G_MB_LIB.T6G(SCH_1):P5E_CPU0_P3_RX_BUF_DN(7)    I38 @T6G_MB_LIB.T6G(SCH_1):PAGE428
   CV1 P5E_CPU0_P3_RX_BUF_DP<6> @T6G_MB_LIB.T6G(SCH_1):P5E_CPU0_P3_RX_BUF_DP(6)    I38 @T6G_MB_LIB.T6G(SCH_1):PAGE428
   CT2 P5E_CPU0_P3_RX_BUF_DN<6> @T6G_MB_LIB.T6G(SCH_1):P5E_CPU0_P3_RX_BUF_DN(6)    I38 @T6G_MB_LIB.T6G(SCH_1):PAGE428
   DE1 P5E_CPU0_P3_RX_BUF_DP<5> @T6G_MB_LIB.T6G(SCH_1):P5E_CPU0_P3_RX_BUF_DP(5)    I38 @T6G_MB_LIB.T6G(SCH_1):PAGE428
   DC2 P5E_CPU0_P3_RX_BUF_DN<5> @T6G_MB_LIB.T6G(SCH_1):P5E_CPU0_P3_RX_BUF_DN(5)    I38 @T6G_MB_LIB.T6G(SCH_1):PAGE428
   DM1 P5E_CPU0_P3_RX_BUF_DP<4> @T6G_MB_LIB.T6G(SCH_1):P5E_CPU0_P3_RX_BUF_DP(4)    I38 @T6G_MB_LIB.T6G(SCH_1):PAGE428
   DK2 P5E_CPU0_P3_RX_BUF_DN<4> @T6G_MB_LIB.T6G(SCH_1):P5E_CPU0_P3_RX_BUF_DN(4)    I38 @T6G_MB_LIB.T6G(SCH_1):PAGE428
   DW1 P5E_CPU0_P3_RX_BUF_DP<3> @T6G_MB_LIB.T6G(SCH_1):P5E_CPU0_P3_RX_BUF_DP(3)    I38 @T6G_MB_LIB.T6G(SCH_1):PAGE428
   DU2 P5E_CPU0_P3_RX_BUF_DN<3> @T6G_MB_LIB.T6G(SCH_1):P5E_CPU0_P3_RX_BUF_DN(3)    I38 @T6G_MB_LIB.T6G(SCH_1):PAGE428
   EF1 P5E_CPU0_P3_RX_BUF_DP<2> @T6G_MB_LIB.T6G(SCH_1):P5E_CPU0_P3_RX_BUF_DP(2)    I38 @T6G_MB_LIB.T6G(SCH_1):PAGE428
   ED2 P5E_CPU0_P3_RX_BUF_DN<2> @T6G_MB_LIB.T6G(SCH_1):P5E_CPU0_P3_RX_BUF_DN(2)    I38 @T6G_MB_LIB.T6G(SCH_1):PAGE428
   EN1 P5E_CPU0_P3_RX_BUF_DP<1> @T6G_MB_LIB.T6G(SCH_1):P5E_CPU0_P3_RX_BUF_DP(1)    I38 @T6G_MB_LIB.T6G(SCH_1):PAGE428
   EL2 P5E_CPU0_P3_RX_BUF_DN<1> @T6G_MB_LIB.T6G(SCH_1):P5E_CPU0_P3_RX_BUF_DN(1)    I38 @T6G_MB_LIB.T6G(SCH_1):PAGE428
   EY1 P5E_CPU0_P3_RX_BUF_DP<0> @T6G_MB_LIB.T6G(SCH_1):P5E_CPU0_P3_RX_BUF_DP(0)    I38 @T6G_MB_LIB.T6G(SCH_1):PAGE428
   EV2 P5E_CPU0_P3_RX_BUF_DN<0> @T6G_MB_LIB.T6G(SCH_1):P5E_CPU0_P3_RX_BUF_DN(0)    I38 @T6G_MB_LIB.T6G(SCH_1):PAGE428
   FJ6     NC     NC    I83 @T6G_MB_LIB.T6G(SCH_1):PAGE430
  FJ23     NC     NC    I83 @T6G_MB_LIB.T6G(SCH_1):PAGE430
  FJ25 GPIO2_RT_CPU0_P3 @T6G_MB_LIB.T6G(SCH_1):GPIO2_RT_CPU0_P3    I83 @T6G_MB_LIB.T6G(SCH_1):PAGE430
  FJ28 GPIO3_RT_CPU0_P3 @T6G_MB_LIB.T6G(SCH_1):GPIO3_RT_CPU0_P3    I83 @T6G_MB_LIB.T6G(SCH_1):PAGE430
  FJ31     NC     NC    I83 @T6G_MB_LIB.T6G(SCH_1):PAGE430
    B3 JTAG_TCK_RT_CPU0_P3 @T6G_MB_LIB.T6G(SCH_1):JTAG_TCK_RT_CPU0_P3    I83 @T6G_MB_LIB.T6G(SCH_1):PAGE430
    B6 JTAG_TDI_RT_CPU0_P3 @T6G_MB_LIB.T6G(SCH_1):JTAG_TDI_RT_CPU0_P3    I83 @T6G_MB_LIB.T6G(SCH_1):PAGE430
    B9 JTAG_TDO_RT_CPU0_P3 @T6G_MB_LIB.T6G(SCH_1):JTAG_TDO_RT_CPU0_P3    I83 @T6G_MB_LIB.T6G(SCH_1):PAGE430
   FF8 JTAG_TEST_MODE_RT_CPU0_P3 @T6G_MB_LIB.T6G(SCH_1):JTAG_TEST_MODE_RT_CPU0_P3    I83 @T6G_MB_LIB.T6G(SCH_1):PAGE430
   B12 JTAG_TMS_RT_CPU0_P3 @T6G_MB_LIB.T6G(SCH_1):JTAG_TMS_RT_CPU0_P3    I83 @T6G_MB_LIB.T6G(SCH_1):PAGE430
    E8 JTAG_TRST_RT_CPU0_P3_N @T6G_MB_LIB.T6G(SCH_1):JTAG_TRST_RT_CPU0_P3_N    I83 @T6G_MB_LIB.T6G(SCH_1):PAGE430
   FJ9 MODE_RT_CPU0_P3 @T6G_MB_LIB.T6G(SCH_1):MODE_RT_CPU0_P3    I83 @T6G_MB_LIB.T6G(SCH_1):PAGE430
    F2 RST_RT_CPU0_P3_PERST_N @T6G_MB_LIB.T6G(SCH_1):RST_RT_CPU0_P3_PERST_N    I83 @T6G_MB_LIB.T6G(SCH_1):PAGE430
   E18     NC     NC    I83 @T6G_MB_LIB.T6G(SCH_1):PAGE430
   B16     NC     NC    I83 @T6G_MB_LIB.T6G(SCH_1):PAGE430
  FF18 CLK_100M_RETIMER_CPU0_P3_DN @T6G_MB_LIB.T6G(SCH_1):CLK_100M_RETIMER_CPU0_P3_DN    I83 @T6G_MB_LIB.T6G(SCH_1):PAGE430
  FJ16 CLK_100M_RETIMER_CPU0_P3_DP @T6G_MB_LIB.T6G(SCH_1):CLK_100M_RETIMER_CPU0_P3_DP    I83 @T6G_MB_LIB.T6G(SCH_1):PAGE430
  FF11 RST_RT_CPU0_P3_RESET_N @T6G_MB_LIB.T6G(SCH_1):RST_RT_CPU0_P3_RESET_N    I83 @T6G_MB_LIB.T6G(SCH_1):PAGE430
   E11 RXDET_BYP_RT_CPU0_P3 @T6G_MB_LIB.T6G(SCH_1):RXDET_BYP_RT_CPU0_P3    I83 @T6G_MB_LIB.T6G(SCH_1):PAGE430
  FF33 RT_CPU0_P3_SCAN_MODE @T6G_MB_LIB.T6G(SCH_1):RT_CPU0_P3_SCAN_MODE    I83 @T6G_MB_LIB.T6G(SCH_1):PAGE430
   F34 RT_CPU0_P3_ADDR1 @T6G_MB_LIB.T6G(SCH_1):RT_CPU0_P3_ADDR1    I83 @T6G_MB_LIB.T6G(SCH_1):PAGE430
   B23 RT_CPU0_P3_ADDR2 @T6G_MB_LIB.T6G(SCH_1):RT_CPU0_P3_ADDR2    I83 @T6G_MB_LIB.T6G(SCH_1):PAGE430
   B25 RT_CPU0_P3_ADDR3 @T6G_MB_LIB.T6G(SCH_1):RT_CPU0_P3_ADDR3    I83 @T6G_MB_LIB.T6G(SCH_1):PAGE430
   B31 SMB_RT_CPU0_P3_R2_SCL @T6G_MB_LIB.T6G(SCH_1):SMB_RT_CPU0_P3_R2_SCL    I83 @T6G_MB_LIB.T6G(SCH_1):PAGE430
   B28 SMB_RT_CPU0_P3_R2_SDA @T6G_MB_LIB.T6G(SCH_1):SMB_RT_CPU0_P3_R2_SDA    I83 @T6G_MB_LIB.T6G(SCH_1):PAGE430
   E30    GND @T6G_MB_LIB.T6G(SCH_1):GND    I83 @T6G_MB_LIB.T6G(SCH_1):PAGE430
  FF24 TEST0_RT_CPU0_P3 @T6G_MB_LIB.T6G(SCH_1):TEST0_RT_CPU0_P3    I83 @T6G_MB_LIB.T6G(SCH_1):PAGE430
  FF27 TEST1_RT_CPU0_P3 @T6G_MB_LIB.T6G(SCH_1):TEST1_RT_CPU0_P3    I83 @T6G_MB_LIB.T6G(SCH_1):PAGE430
  FF30 TEST2_RT_CPU0_P3 @T6G_MB_LIB.T6G(SCH_1):TEST2_RT_CPU0_P3    I83 @T6G_MB_LIB.T6G(SCH_1):PAGE430
   G35 CLKREQ_RT_CPU0_P3_N @T6G_MB_LIB.T6G(SCH_1):CLKREQ_RT_CPU0_P3_N    I83 @T6G_MB_LIB.T6G(SCH_1):PAGE430
   FF5 SMB_RT_CPU0_P3_ROM_MUX_1D_R_SCL @T6G_MB_LIB.T6G(SCH_1):SMB_RT_CPU0_P3_ROM_MUX_1D_R_SCL    I83 @T6G_MB_LIB.T6G(SCH_1):PAGE430
   FJ3 SMB_RT_CPU0_P3_ROM_MUX_1D_R_SDA @T6G_MB_LIB.T6G(SCH_1):SMB_RT_CPU0_P3_ROM_MUX_1D_R_SDA    I83 @T6G_MB_LIB.T6G(SCH_1):PAGE430
    G1 RT_CPU0_P3_VQPS @T6G_MB_LIB.T6G(SCH_1):RT_CPU0_P3_VQPS     I6 @T6G_MB_LIB.T6G(SCH_1):PAGE431
  BV20 P1V8_CPU0_RT3_1A @T6G_MB_LIB.T6G(SCH_1):P1V8_CPU0_RT3_1A     I6 @T6G_MB_LIB.T6G(SCH_1):PAGE431
  CE17 P1V8_CPU0_RT3_1A @T6G_MB_LIB.T6G(SCH_1):P1V8_CPU0_RT3_1A     I6 @T6G_MB_LIB.T6G(SCH_1):PAGE431
  CE20 P1V8_CPU0_RT3_1A @T6G_MB_LIB.T6G(SCH_1):P1V8_CPU0_RT3_1A     I6 @T6G_MB_LIB.T6G(SCH_1):PAGE431
  CM17 P1V8_CPU0_RT3_1A @T6G_MB_LIB.T6G(SCH_1):P1V8_CPU0_RT3_1A     I6 @T6G_MB_LIB.T6G(SCH_1):PAGE431
  CM20 P1V8_CPU0_RT3_1A @T6G_MB_LIB.T6G(SCH_1):P1V8_CPU0_RT3_1A     I6 @T6G_MB_LIB.T6G(SCH_1):PAGE431
  BL17 P0V9_CPU0_RT_2D @T6G_MB_LIB.T6G(SCH_1):P0V9_CPU0_RT_2D     I6 @T6G_MB_LIB.T6G(SCH_1):PAGE431
  BL20 P0V9_CPU0_RT_2D @T6G_MB_LIB.T6G(SCH_1):P0V9_CPU0_RT_2D     I6 @T6G_MB_LIB.T6G(SCH_1):PAGE431
  CW17 P0V9_CPU0_RT_2D @T6G_MB_LIB.T6G(SCH_1):P0V9_CPU0_RT_2D     I6 @T6G_MB_LIB.T6G(SCH_1):PAGE431
  CW20 P0V9_CPU0_RT_2D @T6G_MB_LIB.T6G(SCH_1):P0V9_CPU0_RT_2D     I6 @T6G_MB_LIB.T6G(SCH_1):PAGE431
  BV17 P1V8_CPU0_RT3_1A_1D @T6G_MB_LIB.T6G(SCH_1):P1V8_CPU0_RT3_1A_1D     I6 @T6G_MB_LIB.T6G(SCH_1):PAGE431
  AC17 P0V9_CPU0_RT3_2A @T6G_MB_LIB.T6G(SCH_1):P0V9_CPU0_RT3_2A     I6 @T6G_MB_LIB.T6G(SCH_1):PAGE431
  AC20 P0V9_CPU0_RT3_2A @T6G_MB_LIB.T6G(SCH_1):P0V9_CPU0_RT3_2A     I6 @T6G_MB_LIB.T6G(SCH_1):PAGE431
  AK17 P0V9_CPU0_RT3_2A @T6G_MB_LIB.T6G(SCH_1):P0V9_CPU0_RT3_2A     I6 @T6G_MB_LIB.T6G(SCH_1):PAGE431
  AK20 P0V9_CPU0_RT3_2A @T6G_MB_LIB.T6G(SCH_1):P0V9_CPU0_RT3_2A     I6 @T6G_MB_LIB.T6G(SCH_1):PAGE431
  AU17 P0V9_CPU0_RT3_2A @T6G_MB_LIB.T6G(SCH_1):P0V9_CPU0_RT3_2A     I6 @T6G_MB_LIB.T6G(SCH_1):PAGE431
  AU20 P0V9_CPU0_RT3_2A @T6G_MB_LIB.T6G(SCH_1):P0V9_CPU0_RT3_2A     I6 @T6G_MB_LIB.T6G(SCH_1):PAGE431
  BD17 P0V9_CPU0_RT3_2A_2D @T6G_MB_LIB.T6G(SCH_1):P0V9_CPU0_RT3_2A_2D     I6 @T6G_MB_LIB.T6G(SCH_1):PAGE431
  BD20 P0V9_CPU0_RT3_2A_2D @T6G_MB_LIB.T6G(SCH_1):P0V9_CPU0_RT3_2A_2D     I6 @T6G_MB_LIB.T6G(SCH_1):PAGE431
  DF17 P0V9_CPU0_RT3_2A_2D @T6G_MB_LIB.T6G(SCH_1):P0V9_CPU0_RT3_2A_2D     I6 @T6G_MB_LIB.T6G(SCH_1):PAGE431
  DF20 P0V9_CPU0_RT3_2A_2D @T6G_MB_LIB.T6G(SCH_1):P0V9_CPU0_RT3_2A_2D     I6 @T6G_MB_LIB.T6G(SCH_1):PAGE431
  DN17 P0V9_CPU0_RT3_2A @T6G_MB_LIB.T6G(SCH_1):P0V9_CPU0_RT3_2A     I6 @T6G_MB_LIB.T6G(SCH_1):PAGE431
  DN20 P0V9_CPU0_RT3_2A @T6G_MB_LIB.T6G(SCH_1):P0V9_CPU0_RT3_2A     I6 @T6G_MB_LIB.T6G(SCH_1):PAGE431
  DY17 P0V9_CPU0_RT3_2A @T6G_MB_LIB.T6G(SCH_1):P0V9_CPU0_RT3_2A     I6 @T6G_MB_LIB.T6G(SCH_1):PAGE431
  DY20 P0V9_CPU0_RT3_2A @T6G_MB_LIB.T6G(SCH_1):P0V9_CPU0_RT3_2A     I6 @T6G_MB_LIB.T6G(SCH_1):PAGE431
  EG17 P0V9_CPU0_RT3_2A @T6G_MB_LIB.T6G(SCH_1):P0V9_CPU0_RT3_2A     I6 @T6G_MB_LIB.T6G(SCH_1):PAGE431
  EG20 P0V9_CPU0_RT3_2A @T6G_MB_LIB.T6G(SCH_1):P0V9_CPU0_RT3_2A     I6 @T6G_MB_LIB.T6G(SCH_1):PAGE431
  EP17 P0V9_CPU0_RT3_2A @T6G_MB_LIB.T6G(SCH_1):P0V9_CPU0_RT3_2A     I6 @T6G_MB_LIB.T6G(SCH_1):PAGE431
  EP20 P0V9_CPU0_RT3_2A @T6G_MB_LIB.T6G(SCH_1):P0V9_CPU0_RT3_2A     I6 @T6G_MB_LIB.T6G(SCH_1):PAGE431
   T17 P0V9_CPU0_RT3_2A @T6G_MB_LIB.T6G(SCH_1):P0V9_CPU0_RT3_2A     I6 @T6G_MB_LIB.T6G(SCH_1):PAGE431
   T20 P0V9_CPU0_RT3_2A @T6G_MB_LIB.T6G(SCH_1):P0V9_CPU0_RT3_2A     I6 @T6G_MB_LIB.T6G(SCH_1):PAGE431
  AC13    GND @T6G_MB_LIB.T6G(SCH_1):GND    I17 @T6G_MB_LIB.T6G(SCH_1):PAGE431
  AC22    GND @T6G_MB_LIB.T6G(SCH_1):GND    I17 @T6G_MB_LIB.T6G(SCH_1):PAGE431
  AC32    GND @T6G_MB_LIB.T6G(SCH_1):GND    I17 @T6G_MB_LIB.T6G(SCH_1):PAGE431
   AC4    GND @T6G_MB_LIB.T6G(SCH_1):GND    I17 @T6G_MB_LIB.T6G(SCH_1):PAGE431
   AD2    GND @T6G_MB_LIB.T6G(SCH_1):GND    I17 @T6G_MB_LIB.T6G(SCH_1):PAGE431
  AD34    GND @T6G_MB_LIB.T6G(SCH_1):GND    I17 @T6G_MB_LIB.T6G(SCH_1):PAGE431
   AE1    GND @T6G_MB_LIB.T6G(SCH_1):GND    I17 @T6G_MB_LIB.T6G(SCH_1):PAGE431
  AE35    GND @T6G_MB_LIB.T6G(SCH_1):GND    I17 @T6G_MB_LIB.T6G(SCH_1):PAGE431
  AK13    GND @T6G_MB_LIB.T6G(SCH_1):GND    I17 @T6G_MB_LIB.T6G(SCH_1):PAGE431
  AK22    GND @T6G_MB_LIB.T6G(SCH_1):GND    I17 @T6G_MB_LIB.T6G(SCH_1):PAGE431
  AK32    GND @T6G_MB_LIB.T6G(SCH_1):GND    I17 @T6G_MB_LIB.T6G(SCH_1):PAGE431
   AK4    GND @T6G_MB_LIB.T6G(SCH_1):GND    I17 @T6G_MB_LIB.T6G(SCH_1):PAGE431
   AL2    GND @T6G_MB_LIB.T6G(SCH_1):GND    I17 @T6G_MB_LIB.T6G(SCH_1):PAGE431
  AL34    GND @T6G_MB_LIB.T6G(SCH_1):GND    I17 @T6G_MB_LIB.T6G(SCH_1):PAGE431
   AM1    GND @T6G_MB_LIB.T6G(SCH_1):GND    I17 @T6G_MB_LIB.T6G(SCH_1):PAGE431
  AM35    GND @T6G_MB_LIB.T6G(SCH_1):GND    I17 @T6G_MB_LIB.T6G(SCH_1):PAGE431
  AU13    GND @T6G_MB_LIB.T6G(SCH_1):GND    I17 @T6G_MB_LIB.T6G(SCH_1):PAGE431
  AU22    GND @T6G_MB_LIB.T6G(SCH_1):GND    I17 @T6G_MB_LIB.T6G(SCH_1):PAGE431
  AU32    GND @T6G_MB_LIB.T6G(SCH_1):GND    I17 @T6G_MB_LIB.T6G(SCH_1):PAGE431
   AU4    GND @T6G_MB_LIB.T6G(SCH_1):GND    I17 @T6G_MB_LIB.T6G(SCH_1):PAGE431
   AV2    GND @T6G_MB_LIB.T6G(SCH_1):GND    I17 @T6G_MB_LIB.T6G(SCH_1):PAGE431
  AV34    GND @T6G_MB_LIB.T6G(SCH_1):GND    I17 @T6G_MB_LIB.T6G(SCH_1):PAGE431
   AW1    GND @T6G_MB_LIB.T6G(SCH_1):GND    I17 @T6G_MB_LIB.T6G(SCH_1):PAGE431
  AW35    GND @T6G_MB_LIB.T6G(SCH_1):GND    I17 @T6G_MB_LIB.T6G(SCH_1):PAGE431
   B19    GND @T6G_MB_LIB.T6G(SCH_1):GND    I17 @T6G_MB_LIB.T6G(SCH_1):PAGE431
  BD13    GND @T6G_MB_LIB.T6G(SCH_1):GND    I17 @T6G_MB_LIB.T6G(SCH_1):PAGE431
  BD22    GND @T6G_MB_LIB.T6G(SCH_1):GND    I17 @T6G_MB_LIB.T6G(SCH_1):PAGE431
  BD32    GND @T6G_MB_LIB.T6G(SCH_1):GND    I17 @T6G_MB_LIB.T6G(SCH_1):PAGE431
   BD4    GND @T6G_MB_LIB.T6G(SCH_1):GND    I17 @T6G_MB_LIB.T6G(SCH_1):PAGE431
   BE2    GND @T6G_MB_LIB.T6G(SCH_1):GND    I17 @T6G_MB_LIB.T6G(SCH_1):PAGE431
  BE34    GND @T6G_MB_LIB.T6G(SCH_1):GND    I17 @T6G_MB_LIB.T6G(SCH_1):PAGE431
   BF1    GND @T6G_MB_LIB.T6G(SCH_1):GND    I17 @T6G_MB_LIB.T6G(SCH_1):PAGE431
  BF35    GND @T6G_MB_LIB.T6G(SCH_1):GND    I17 @T6G_MB_LIB.T6G(SCH_1):PAGE431
  BL13    GND @T6G_MB_LIB.T6G(SCH_1):GND    I17 @T6G_MB_LIB.T6G(SCH_1):PAGE431
  BL22    GND @T6G_MB_LIB.T6G(SCH_1):GND    I17 @T6G_MB_LIB.T6G(SCH_1):PAGE431
  BL32    GND @T6G_MB_LIB.T6G(SCH_1):GND    I17 @T6G_MB_LIB.T6G(SCH_1):PAGE431
   BL4    GND @T6G_MB_LIB.T6G(SCH_1):GND    I17 @T6G_MB_LIB.T6G(SCH_1):PAGE431
   BM2    GND @T6G_MB_LIB.T6G(SCH_1):GND    I17 @T6G_MB_LIB.T6G(SCH_1):PAGE431
  BM34    GND @T6G_MB_LIB.T6G(SCH_1):GND    I17 @T6G_MB_LIB.T6G(SCH_1):PAGE431
   BN1    GND @T6G_MB_LIB.T6G(SCH_1):GND    I17 @T6G_MB_LIB.T6G(SCH_1):PAGE431
  BN35    GND @T6G_MB_LIB.T6G(SCH_1):GND    I17 @T6G_MB_LIB.T6G(SCH_1):PAGE431
  BV13    GND @T6G_MB_LIB.T6G(SCH_1):GND    I17 @T6G_MB_LIB.T6G(SCH_1):PAGE431
  BV22    GND @T6G_MB_LIB.T6G(SCH_1):GND    I17 @T6G_MB_LIB.T6G(SCH_1):PAGE431
  BV32    GND @T6G_MB_LIB.T6G(SCH_1):GND    I17 @T6G_MB_LIB.T6G(SCH_1):PAGE431
   BV4    GND @T6G_MB_LIB.T6G(SCH_1):GND    I17 @T6G_MB_LIB.T6G(SCH_1):PAGE431
   BW2    GND @T6G_MB_LIB.T6G(SCH_1):GND    I17 @T6G_MB_LIB.T6G(SCH_1):PAGE431
  BW34    GND @T6G_MB_LIB.T6G(SCH_1):GND    I17 @T6G_MB_LIB.T6G(SCH_1):PAGE431
   BY1    GND @T6G_MB_LIB.T6G(SCH_1):GND    I17 @T6G_MB_LIB.T6G(SCH_1):PAGE431
  BY35    GND @T6G_MB_LIB.T6G(SCH_1):GND    I17 @T6G_MB_LIB.T6G(SCH_1):PAGE431
  CE13    GND @T6G_MB_LIB.T6G(SCH_1):GND    I17 @T6G_MB_LIB.T6G(SCH_1):PAGE431
  CE22    GND @T6G_MB_LIB.T6G(SCH_1):GND    I17 @T6G_MB_LIB.T6G(SCH_1):PAGE431
  CE32    GND @T6G_MB_LIB.T6G(SCH_1):GND    I17 @T6G_MB_LIB.T6G(SCH_1):PAGE431
   CE4    GND @T6G_MB_LIB.T6G(SCH_1):GND    I17 @T6G_MB_LIB.T6G(SCH_1):PAGE431
   CF2    GND @T6G_MB_LIB.T6G(SCH_1):GND    I17 @T6G_MB_LIB.T6G(SCH_1):PAGE431
  CF34    GND @T6G_MB_LIB.T6G(SCH_1):GND    I17 @T6G_MB_LIB.T6G(SCH_1):PAGE431
   CG1    GND @T6G_MB_LIB.T6G(SCH_1):GND    I17 @T6G_MB_LIB.T6G(SCH_1):PAGE431
  CG35    GND @T6G_MB_LIB.T6G(SCH_1):GND    I17 @T6G_MB_LIB.T6G(SCH_1):PAGE431
  CM13    GND @T6G_MB_LIB.T6G(SCH_1):GND    I17 @T6G_MB_LIB.T6G(SCH_1):PAGE431
  CM22    GND @T6G_MB_LIB.T6G(SCH_1):GND    I17 @T6G_MB_LIB.T6G(SCH_1):PAGE431
  CM32    GND @T6G_MB_LIB.T6G(SCH_1):GND    I17 @T6G_MB_LIB.T6G(SCH_1):PAGE431
   CM4    GND @T6G_MB_LIB.T6G(SCH_1):GND    I17 @T6G_MB_LIB.T6G(SCH_1):PAGE431
   CN2    GND @T6G_MB_LIB.T6G(SCH_1):GND    I17 @T6G_MB_LIB.T6G(SCH_1):PAGE431
  CN34    GND @T6G_MB_LIB.T6G(SCH_1):GND    I17 @T6G_MB_LIB.T6G(SCH_1):PAGE431
   CP1    GND @T6G_MB_LIB.T6G(SCH_1):GND    I17 @T6G_MB_LIB.T6G(SCH_1):PAGE431
  CP35    GND @T6G_MB_LIB.T6G(SCH_1):GND    I17 @T6G_MB_LIB.T6G(SCH_1):PAGE431
  CW13    GND @T6G_MB_LIB.T6G(SCH_1):GND    I17 @T6G_MB_LIB.T6G(SCH_1):PAGE431
  CW22    GND @T6G_MB_LIB.T6G(SCH_1):GND    I17 @T6G_MB_LIB.T6G(SCH_1):PAGE431
  CW32    GND @T6G_MB_LIB.T6G(SCH_1):GND    I17 @T6G_MB_LIB.T6G(SCH_1):PAGE431
   CW4    GND @T6G_MB_LIB.T6G(SCH_1):GND    I17 @T6G_MB_LIB.T6G(SCH_1):PAGE431
   CY2    GND @T6G_MB_LIB.T6G(SCH_1):GND    I17 @T6G_MB_LIB.T6G(SCH_1):PAGE431
  CY34    GND @T6G_MB_LIB.T6G(SCH_1):GND    I17 @T6G_MB_LIB.T6G(SCH_1):PAGE431
   DA1    GND @T6G_MB_LIB.T6G(SCH_1):GND    I17 @T6G_MB_LIB.T6G(SCH_1):PAGE431
  DA35    GND @T6G_MB_LIB.T6G(SCH_1):GND    I17 @T6G_MB_LIB.T6G(SCH_1):PAGE431
  DF13    GND @T6G_MB_LIB.T6G(SCH_1):GND    I17 @T6G_MB_LIB.T6G(SCH_1):PAGE431
  DF22    GND @T6G_MB_LIB.T6G(SCH_1):GND    I17 @T6G_MB_LIB.T6G(SCH_1):PAGE431
  DF32    GND @T6G_MB_LIB.T6G(SCH_1):GND    I17 @T6G_MB_LIB.T6G(SCH_1):PAGE431
   DF4    GND @T6G_MB_LIB.T6G(SCH_1):GND    I17 @T6G_MB_LIB.T6G(SCH_1):PAGE431
   DG2    GND @T6G_MB_LIB.T6G(SCH_1):GND    I17 @T6G_MB_LIB.T6G(SCH_1):PAGE431
  DG34    GND @T6G_MB_LIB.T6G(SCH_1):GND    I17 @T6G_MB_LIB.T6G(SCH_1):PAGE431
   DH1    GND @T6G_MB_LIB.T6G(SCH_1):GND    I17 @T6G_MB_LIB.T6G(SCH_1):PAGE431
  DH35    GND @T6G_MB_LIB.T6G(SCH_1):GND    I17 @T6G_MB_LIB.T6G(SCH_1):PAGE431
  DN13    GND @T6G_MB_LIB.T6G(SCH_1):GND    I17 @T6G_MB_LIB.T6G(SCH_1):PAGE431
    A1 NCF_A1_CPU0_P3_GND @T6G_MB_LIB.T6G(SCH_1):NCF_A1_CPU0_P3_GND    I17 @T6G_MB_LIB.T6G(SCH_1):PAGE431
   A35 NCF_CPU0_P3_GND @T6G_MB_LIB.T6G(SCH_1):NCF_CPU0_P3_GND    I17 @T6G_MB_LIB.T6G(SCH_1):PAGE431
    C2 NCF_CPU0_P3_GND @T6G_MB_LIB.T6G(SCH_1):NCF_CPU0_P3_GND    I17 @T6G_MB_LIB.T6G(SCH_1):PAGE431
   C34 NCF_CPU0_P3_GND @T6G_MB_LIB.T6G(SCH_1):NCF_CPU0_P3_GND    I17 @T6G_MB_LIB.T6G(SCH_1):PAGE431
    D1 NCF_CPU0_P3_GND @T6G_MB_LIB.T6G(SCH_1):NCF_CPU0_P3_GND    I17 @T6G_MB_LIB.T6G(SCH_1):PAGE431
   D35 NCF_CPU0_P3_GND @T6G_MB_LIB.T6G(SCH_1):NCF_CPU0_P3_GND    I17 @T6G_MB_LIB.T6G(SCH_1):PAGE431
   FE2 NCF_CPU0_P3_GND @T6G_MB_LIB.T6G(SCH_1):NCF_CPU0_P3_GND    I17 @T6G_MB_LIB.T6G(SCH_1):PAGE431
  FE34 NCF_CPU0_P3_GND @T6G_MB_LIB.T6G(SCH_1):NCF_CPU0_P3_GND    I17 @T6G_MB_LIB.T6G(SCH_1):PAGE431
   FG1 NCF_CPU0_P3_GND @T6G_MB_LIB.T6G(SCH_1):NCF_CPU0_P3_GND    I17 @T6G_MB_LIB.T6G(SCH_1):PAGE431
  FG35 NCF_CPU0_P3_GND @T6G_MB_LIB.T6G(SCH_1):NCF_CPU0_P3_GND    I17 @T6G_MB_LIB.T6G(SCH_1):PAGE431
   FH2 NCF_CPU0_P3_GND @T6G_MB_LIB.T6G(SCH_1):NCF_CPU0_P3_GND    I17 @T6G_MB_LIB.T6G(SCH_1):PAGE431
  FH34 NCF_CPU0_P3_GND @T6G_MB_LIB.T6G(SCH_1):NCF_CPU0_P3_GND    I17 @T6G_MB_LIB.T6G(SCH_1):PAGE431
  DN22    GND @T6G_MB_LIB.T6G(SCH_1):GND    I17 @T6G_MB_LIB.T6G(SCH_1):PAGE431
  DN32    GND @T6G_MB_LIB.T6G(SCH_1):GND    I17 @T6G_MB_LIB.T6G(SCH_1):PAGE431
   DN4    GND @T6G_MB_LIB.T6G(SCH_1):GND    I17 @T6G_MB_LIB.T6G(SCH_1):PAGE431
   DP2    GND @T6G_MB_LIB.T6G(SCH_1):GND    I17 @T6G_MB_LIB.T6G(SCH_1):PAGE431
  DP34    GND @T6G_MB_LIB.T6G(SCH_1):GND    I17 @T6G_MB_LIB.T6G(SCH_1):PAGE431
   DR1    GND @T6G_MB_LIB.T6G(SCH_1):GND    I17 @T6G_MB_LIB.T6G(SCH_1):PAGE431
  DR35    GND @T6G_MB_LIB.T6G(SCH_1):GND    I17 @T6G_MB_LIB.T6G(SCH_1):PAGE431
  DY13    GND @T6G_MB_LIB.T6G(SCH_1):GND    I17 @T6G_MB_LIB.T6G(SCH_1):PAGE431
  DY22    GND @T6G_MB_LIB.T6G(SCH_1):GND    I17 @T6G_MB_LIB.T6G(SCH_1):PAGE431
  DY32    GND @T6G_MB_LIB.T6G(SCH_1):GND    I17 @T6G_MB_LIB.T6G(SCH_1):PAGE431
   DY4    GND @T6G_MB_LIB.T6G(SCH_1):GND    I17 @T6G_MB_LIB.T6G(SCH_1):PAGE431
   E14    GND @T6G_MB_LIB.T6G(SCH_1):GND    I17 @T6G_MB_LIB.T6G(SCH_1):PAGE431
   E27    GND @T6G_MB_LIB.T6G(SCH_1):GND    I17 @T6G_MB_LIB.T6G(SCH_1):PAGE431
   E33    GND @T6G_MB_LIB.T6G(SCH_1):GND    I17 @T6G_MB_LIB.T6G(SCH_1):PAGE431
   EA2    GND @T6G_MB_LIB.T6G(SCH_1):GND    I17 @T6G_MB_LIB.T6G(SCH_1):PAGE431
  EA34    GND @T6G_MB_LIB.T6G(SCH_1):GND    I17 @T6G_MB_LIB.T6G(SCH_1):PAGE431
   EB1    GND @T6G_MB_LIB.T6G(SCH_1):GND    I17 @T6G_MB_LIB.T6G(SCH_1):PAGE431
  EB35    GND @T6G_MB_LIB.T6G(SCH_1):GND    I17 @T6G_MB_LIB.T6G(SCH_1):PAGE431
  EG13    GND @T6G_MB_LIB.T6G(SCH_1):GND    I17 @T6G_MB_LIB.T6G(SCH_1):PAGE431
  EG22    GND @T6G_MB_LIB.T6G(SCH_1):GND    I17 @T6G_MB_LIB.T6G(SCH_1):PAGE431
  EG32    GND @T6G_MB_LIB.T6G(SCH_1):GND    I17 @T6G_MB_LIB.T6G(SCH_1):PAGE431
   EG4    GND @T6G_MB_LIB.T6G(SCH_1):GND    I17 @T6G_MB_LIB.T6G(SCH_1):PAGE431
   EH2    GND @T6G_MB_LIB.T6G(SCH_1):GND    I17 @T6G_MB_LIB.T6G(SCH_1):PAGE431
  EH34    GND @T6G_MB_LIB.T6G(SCH_1):GND    I17 @T6G_MB_LIB.T6G(SCH_1):PAGE431
   EJ1    GND @T6G_MB_LIB.T6G(SCH_1):GND    I17 @T6G_MB_LIB.T6G(SCH_1):PAGE431
  EJ35    GND @T6G_MB_LIB.T6G(SCH_1):GND    I17 @T6G_MB_LIB.T6G(SCH_1):PAGE431
  EP13    GND @T6G_MB_LIB.T6G(SCH_1):GND    I17 @T6G_MB_LIB.T6G(SCH_1):PAGE431
  EP22    GND @T6G_MB_LIB.T6G(SCH_1):GND    I17 @T6G_MB_LIB.T6G(SCH_1):PAGE431
  EP32    GND @T6G_MB_LIB.T6G(SCH_1):GND    I17 @T6G_MB_LIB.T6G(SCH_1):PAGE431
   EP4    GND @T6G_MB_LIB.T6G(SCH_1):GND    I17 @T6G_MB_LIB.T6G(SCH_1):PAGE431
   ER2    GND @T6G_MB_LIB.T6G(SCH_1):GND    I17 @T6G_MB_LIB.T6G(SCH_1):PAGE431
  ER34    GND @T6G_MB_LIB.T6G(SCH_1):GND    I17 @T6G_MB_LIB.T6G(SCH_1):PAGE431
   ET1    GND @T6G_MB_LIB.T6G(SCH_1):GND    I17 @T6G_MB_LIB.T6G(SCH_1):PAGE431
  ET35    GND @T6G_MB_LIB.T6G(SCH_1):GND    I17 @T6G_MB_LIB.T6G(SCH_1):PAGE431
  FA15    GND @T6G_MB_LIB.T6G(SCH_1):GND    I17 @T6G_MB_LIB.T6G(SCH_1):PAGE431
  FA32    GND @T6G_MB_LIB.T6G(SCH_1):GND    I17 @T6G_MB_LIB.T6G(SCH_1):PAGE431
   FB2    GND @T6G_MB_LIB.T6G(SCH_1):GND    I17 @T6G_MB_LIB.T6G(SCH_1):PAGE431
  FB34    GND @T6G_MB_LIB.T6G(SCH_1):GND    I17 @T6G_MB_LIB.T6G(SCH_1):PAGE431
  FC19    GND @T6G_MB_LIB.T6G(SCH_1):GND    I17 @T6G_MB_LIB.T6G(SCH_1):PAGE431
  FC23    GND @T6G_MB_LIB.T6G(SCH_1):GND    I17 @T6G_MB_LIB.T6G(SCH_1):PAGE431
  FC25    GND @T6G_MB_LIB.T6G(SCH_1):GND    I17 @T6G_MB_LIB.T6G(SCH_1):PAGE431
  FC28    GND @T6G_MB_LIB.T6G(SCH_1):GND    I17 @T6G_MB_LIB.T6G(SCH_1):PAGE431
   FC3    GND @T6G_MB_LIB.T6G(SCH_1):GND    I17 @T6G_MB_LIB.T6G(SCH_1):PAGE431
   FC6    GND @T6G_MB_LIB.T6G(SCH_1):GND    I17 @T6G_MB_LIB.T6G(SCH_1):PAGE431
   FC9    GND @T6G_MB_LIB.T6G(SCH_1):GND    I17 @T6G_MB_LIB.T6G(SCH_1):PAGE431
   FD1    GND @T6G_MB_LIB.T6G(SCH_1):GND    I17 @T6G_MB_LIB.T6G(SCH_1):PAGE431
  FD35    GND @T6G_MB_LIB.T6G(SCH_1):GND    I17 @T6G_MB_LIB.T6G(SCH_1):PAGE431
  FF14    GND @T6G_MB_LIB.T6G(SCH_1):GND    I17 @T6G_MB_LIB.T6G(SCH_1):PAGE431
  FF21    GND @T6G_MB_LIB.T6G(SCH_1):GND    I17 @T6G_MB_LIB.T6G(SCH_1):PAGE431
  FJ12    GND @T6G_MB_LIB.T6G(SCH_1):GND    I17 @T6G_MB_LIB.T6G(SCH_1):PAGE431
  FJ19    GND @T6G_MB_LIB.T6G(SCH_1):GND    I17 @T6G_MB_LIB.T6G(SCH_1):PAGE431
   H12    GND @T6G_MB_LIB.T6G(SCH_1):GND    I17 @T6G_MB_LIB.T6G(SCH_1):PAGE431
   H16    GND @T6G_MB_LIB.T6G(SCH_1):GND    I17 @T6G_MB_LIB.T6G(SCH_1):PAGE431
   H19    GND @T6G_MB_LIB.T6G(SCH_1):GND    I17 @T6G_MB_LIB.T6G(SCH_1):PAGE431
   H31    GND @T6G_MB_LIB.T6G(SCH_1):GND    I17 @T6G_MB_LIB.T6G(SCH_1):PAGE431
   J22    GND @T6G_MB_LIB.T6G(SCH_1):GND    I17 @T6G_MB_LIB.T6G(SCH_1):PAGE431
    J4    GND @T6G_MB_LIB.T6G(SCH_1):GND    I17 @T6G_MB_LIB.T6G(SCH_1):PAGE431
    K2    GND @T6G_MB_LIB.T6G(SCH_1):GND    I17 @T6G_MB_LIB.T6G(SCH_1):PAGE431
   K34    GND @T6G_MB_LIB.T6G(SCH_1):GND    I17 @T6G_MB_LIB.T6G(SCH_1):PAGE431
    L1    GND @T6G_MB_LIB.T6G(SCH_1):GND    I17 @T6G_MB_LIB.T6G(SCH_1):PAGE431
   L35    GND @T6G_MB_LIB.T6G(SCH_1):GND    I17 @T6G_MB_LIB.T6G(SCH_1):PAGE431
   T13    GND @T6G_MB_LIB.T6G(SCH_1):GND    I17 @T6G_MB_LIB.T6G(SCH_1):PAGE431
   T22    GND @T6G_MB_LIB.T6G(SCH_1):GND    I17 @T6G_MB_LIB.T6G(SCH_1):PAGE431
   T32    GND @T6G_MB_LIB.T6G(SCH_1):GND    I17 @T6G_MB_LIB.T6G(SCH_1):PAGE431
    T4    GND @T6G_MB_LIB.T6G(SCH_1):GND    I17 @T6G_MB_LIB.T6G(SCH_1):PAGE431
    U2    GND @T6G_MB_LIB.T6G(SCH_1):GND    I17 @T6G_MB_LIB.T6G(SCH_1):PAGE431
   U34    GND @T6G_MB_LIB.T6G(SCH_1):GND    I17 @T6G_MB_LIB.T6G(SCH_1):PAGE431
    V1    GND @T6G_MB_LIB.T6G(SCH_1):GND    I17 @T6G_MB_LIB.T6G(SCH_1):PAGE431
   V35    GND @T6G_MB_LIB.T6G(SCH_1):GND    I17 @T6G_MB_LIB.T6G(SCH_1):PAGE431
   M26 P5E_CPU0_P3_RX_DP<15> @T6G_MB_LIB.T6G(SCH_1):P5E_CPU0_P3_RX_DP(15)     I1 @T6G_MB_LIB.T6G(SCH_1):PAGE427
   P29 P5E_CPU0_P3_RX_DN<15> @T6G_MB_LIB.T6G(SCH_1):P5E_CPU0_P3_RX_DN(15)     I1 @T6G_MB_LIB.T6G(SCH_1):PAGE427
   W26 P5E_CPU0_P3_RX_DP<14> @T6G_MB_LIB.T6G(SCH_1):P5E_CPU0_P3_RX_DP(14)     I1 @T6G_MB_LIB.T6G(SCH_1):PAGE427
  AA29 P5E_CPU0_P3_RX_DN<14> @T6G_MB_LIB.T6G(SCH_1):P5E_CPU0_P3_RX_DN(14)     I1 @T6G_MB_LIB.T6G(SCH_1):PAGE427
  AF26 P5E_CPU0_P3_RX_DP<13> @T6G_MB_LIB.T6G(SCH_1):P5E_CPU0_P3_RX_DP(13)     I1 @T6G_MB_LIB.T6G(SCH_1):PAGE427
  AH29 P5E_CPU0_P3_RX_DN<13> @T6G_MB_LIB.T6G(SCH_1):P5E_CPU0_P3_RX_DN(13)     I1 @T6G_MB_LIB.T6G(SCH_1):PAGE427
  AN26 P5E_CPU0_P3_RX_DP<12> @T6G_MB_LIB.T6G(SCH_1):P5E_CPU0_P3_RX_DP(12)     I1 @T6G_MB_LIB.T6G(SCH_1):PAGE427
  AR29 P5E_CPU0_P3_RX_DN<12> @T6G_MB_LIB.T6G(SCH_1):P5E_CPU0_P3_RX_DN(12)     I1 @T6G_MB_LIB.T6G(SCH_1):PAGE427
  AY26 P5E_CPU0_P3_RX_DP<11> @T6G_MB_LIB.T6G(SCH_1):P5E_CPU0_P3_RX_DP(11)     I1 @T6G_MB_LIB.T6G(SCH_1):PAGE427
  BB29 P5E_CPU0_P3_RX_DN<11> @T6G_MB_LIB.T6G(SCH_1):P5E_CPU0_P3_RX_DN(11)     I1 @T6G_MB_LIB.T6G(SCH_1):PAGE427
  BG26 P5E_CPU0_P3_RX_DP<10> @T6G_MB_LIB.T6G(SCH_1):P5E_CPU0_P3_RX_DP(10)     I1 @T6G_MB_LIB.T6G(SCH_1):PAGE427
  BJ29 P5E_CPU0_P3_RX_DN<10> @T6G_MB_LIB.T6G(SCH_1):P5E_CPU0_P3_RX_DN(10)     I1 @T6G_MB_LIB.T6G(SCH_1):PAGE427
  BP26 P5E_CPU0_P3_RX_DP<9> @T6G_MB_LIB.T6G(SCH_1):P5E_CPU0_P3_RX_DP(9)     I1 @T6G_MB_LIB.T6G(SCH_1):PAGE427
  BT29 P5E_CPU0_P3_RX_DN<9> @T6G_MB_LIB.T6G(SCH_1):P5E_CPU0_P3_RX_DN(9)     I1 @T6G_MB_LIB.T6G(SCH_1):PAGE427
  CA26 P5E_CPU0_P3_RX_DP<8> @T6G_MB_LIB.T6G(SCH_1):P5E_CPU0_P3_RX_DP(8)     I1 @T6G_MB_LIB.T6G(SCH_1):PAGE427
  CC29 P5E_CPU0_P3_RX_DN<8> @T6G_MB_LIB.T6G(SCH_1):P5E_CPU0_P3_RX_DN(8)     I1 @T6G_MB_LIB.T6G(SCH_1):PAGE427
  CH26 P5E_CPU0_P3_RX_DP<7> @T6G_MB_LIB.T6G(SCH_1):P5E_CPU0_P3_RX_DP(7)    I38 @T6G_MB_LIB.T6G(SCH_1):PAGE427
  CK29 P5E_CPU0_P3_RX_DN<7> @T6G_MB_LIB.T6G(SCH_1):P5E_CPU0_P3_RX_DN(7)    I38 @T6G_MB_LIB.T6G(SCH_1):PAGE427
  CR26 P5E_CPU0_P3_RX_DP<6> @T6G_MB_LIB.T6G(SCH_1):P5E_CPU0_P3_RX_DP(6)    I38 @T6G_MB_LIB.T6G(SCH_1):PAGE427
  CU29 P5E_CPU0_P3_RX_DN<6> @T6G_MB_LIB.T6G(SCH_1):P5E_CPU0_P3_RX_DN(6)    I38 @T6G_MB_LIB.T6G(SCH_1):PAGE427
  DB26 P5E_CPU0_P3_RX_DP<5> @T6G_MB_LIB.T6G(SCH_1):P5E_CPU0_P3_RX_DP(5)    I38 @T6G_MB_LIB.T6G(SCH_1):PAGE427
  DD29 P5E_CPU0_P3_RX_DN<5> @T6G_MB_LIB.T6G(SCH_1):P5E_CPU0_P3_RX_DN(5)    I38 @T6G_MB_LIB.T6G(SCH_1):PAGE427
  DJ26 P5E_CPU0_P3_RX_DP<4> @T6G_MB_LIB.T6G(SCH_1):P5E_CPU0_P3_RX_DP(4)    I38 @T6G_MB_LIB.T6G(SCH_1):PAGE427
  DL29 P5E_CPU0_P3_RX_DN<4> @T6G_MB_LIB.T6G(SCH_1):P5E_CPU0_P3_RX_DN(4)    I38 @T6G_MB_LIB.T6G(SCH_1):PAGE427
  DT26 P5E_CPU0_P3_RX_DP<3> @T6G_MB_LIB.T6G(SCH_1):P5E_CPU0_P3_RX_DP(3)    I38 @T6G_MB_LIB.T6G(SCH_1):PAGE427
  DV29 P5E_CPU0_P3_RX_DN<3> @T6G_MB_LIB.T6G(SCH_1):P5E_CPU0_P3_RX_DN(3)    I38 @T6G_MB_LIB.T6G(SCH_1):PAGE427
  EC26 P5E_CPU0_P3_RX_DP<2> @T6G_MB_LIB.T6G(SCH_1):P5E_CPU0_P3_RX_DP(2)    I38 @T6G_MB_LIB.T6G(SCH_1):PAGE427
  EE29 P5E_CPU0_P3_RX_DN<2> @T6G_MB_LIB.T6G(SCH_1):P5E_CPU0_P3_RX_DN(2)    I38 @T6G_MB_LIB.T6G(SCH_1):PAGE427
  EK26 P5E_CPU0_P3_RX_DP<1> @T6G_MB_LIB.T6G(SCH_1):P5E_CPU0_P3_RX_DP(1)    I38 @T6G_MB_LIB.T6G(SCH_1):PAGE427
  EM29 P5E_CPU0_P3_RX_DN<1> @T6G_MB_LIB.T6G(SCH_1):P5E_CPU0_P3_RX_DN(1)    I38 @T6G_MB_LIB.T6G(SCH_1):PAGE427
  EU26 P5E_CPU0_P3_RX_DP<0> @T6G_MB_LIB.T6G(SCH_1):P5E_CPU0_P3_RX_DP(0)    I38 @T6G_MB_LIB.T6G(SCH_1):PAGE427
  EW29 P5E_CPU0_P3_RX_DN<0> @T6G_MB_LIB.T6G(SCH_1):P5E_CPU0_P3_RX_DN(0)    I38 @T6G_MB_LIB.T6G(SCH_1):PAGE427
   N34 P5E_CPU0_P3_TX_C_DN<15> @T6G_MB_LIB.T6G(SCH_1):P5E_CPU0_P3_TX_C_DN(15)     I1 @T6G_MB_LIB.T6G(SCH_1):PAGE426
   R35 P5E_CPU0_P3_TX_C_DP<15> @T6G_MB_LIB.T6G(SCH_1):P5E_CPU0_P3_TX_C_DP(15)     I1 @T6G_MB_LIB.T6G(SCH_1):PAGE426
   Y34 P5E_CPU0_P3_TX_C_DP<14> @T6G_MB_LIB.T6G(SCH_1):P5E_CPU0_P3_TX_C_DP(14)     I1 @T6G_MB_LIB.T6G(SCH_1):PAGE426
  AB35 P5E_CPU0_P3_TX_C_DN<14> @T6G_MB_LIB.T6G(SCH_1):P5E_CPU0_P3_TX_C_DN(14)     I1 @T6G_MB_LIB.T6G(SCH_1):PAGE426
  AG34 P5E_CPU0_P3_TX_C_DN<13> @T6G_MB_LIB.T6G(SCH_1):P5E_CPU0_P3_TX_C_DN(13)     I1 @T6G_MB_LIB.T6G(SCH_1):PAGE426
  AJ35 P5E_CPU0_P3_TX_C_DP<13> @T6G_MB_LIB.T6G(SCH_1):P5E_CPU0_P3_TX_C_DP(13)     I1 @T6G_MB_LIB.T6G(SCH_1):PAGE426
  AP34 P5E_CPU0_P3_TX_C_DN<12> @T6G_MB_LIB.T6G(SCH_1):P5E_CPU0_P3_TX_C_DN(12)     I1 @T6G_MB_LIB.T6G(SCH_1):PAGE426
  AT35 P5E_CPU0_P3_TX_C_DP<12> @T6G_MB_LIB.T6G(SCH_1):P5E_CPU0_P3_TX_C_DP(12)     I1 @T6G_MB_LIB.T6G(SCH_1):PAGE426
  BA34 P5E_CPU0_P3_TX_C_DN<11> @T6G_MB_LIB.T6G(SCH_1):P5E_CPU0_P3_TX_C_DN(11)     I1 @T6G_MB_LIB.T6G(SCH_1):PAGE426
  BC35 P5E_CPU0_P3_TX_C_DP<11> @T6G_MB_LIB.T6G(SCH_1):P5E_CPU0_P3_TX_C_DP(11)     I1 @T6G_MB_LIB.T6G(SCH_1):PAGE426
  BH34 P5E_CPU0_P3_TX_C_DN<10> @T6G_MB_LIB.T6G(SCH_1):P5E_CPU0_P3_TX_C_DN(10)     I1 @T6G_MB_LIB.T6G(SCH_1):PAGE426
  BK35 P5E_CPU0_P3_TX_C_DP<10> @T6G_MB_LIB.T6G(SCH_1):P5E_CPU0_P3_TX_C_DP(10)     I1 @T6G_MB_LIB.T6G(SCH_1):PAGE426
  BR34 P5E_CPU0_P3_TX_C_DN<9> @T6G_MB_LIB.T6G(SCH_1):P5E_CPU0_P3_TX_C_DN(9)     I1 @T6G_MB_LIB.T6G(SCH_1):PAGE426
  BU35 P5E_CPU0_P3_TX_C_DP<9> @T6G_MB_LIB.T6G(SCH_1):P5E_CPU0_P3_TX_C_DP(9)     I1 @T6G_MB_LIB.T6G(SCH_1):PAGE426
  CB34 P5E_CPU0_P3_TX_C_DN<8> @T6G_MB_LIB.T6G(SCH_1):P5E_CPU0_P3_TX_C_DN(8)     I1 @T6G_MB_LIB.T6G(SCH_1):PAGE426
  CD35 P5E_CPU0_P3_TX_C_DP<8> @T6G_MB_LIB.T6G(SCH_1):P5E_CPU0_P3_TX_C_DP(8)     I1 @T6G_MB_LIB.T6G(SCH_1):PAGE426
  CJ34 P5E_CPU0_P3_TX_C_DN<7> @T6G_MB_LIB.T6G(SCH_1):P5E_CPU0_P3_TX_C_DN(7)    I38 @T6G_MB_LIB.T6G(SCH_1):PAGE426
  CL35 P5E_CPU0_P3_TX_C_DP<7> @T6G_MB_LIB.T6G(SCH_1):P5E_CPU0_P3_TX_C_DP(7)    I38 @T6G_MB_LIB.T6G(SCH_1):PAGE426
  CT34 P5E_CPU0_P3_TX_C_DN<6> @T6G_MB_LIB.T6G(SCH_1):P5E_CPU0_P3_TX_C_DN(6)    I38 @T6G_MB_LIB.T6G(SCH_1):PAGE426
  CV35 P5E_CPU0_P3_TX_C_DP<6> @T6G_MB_LIB.T6G(SCH_1):P5E_CPU0_P3_TX_C_DP(6)    I38 @T6G_MB_LIB.T6G(SCH_1):PAGE426
  DC34 P5E_CPU0_P3_TX_C_DN<5> @T6G_MB_LIB.T6G(SCH_1):P5E_CPU0_P3_TX_C_DN(5)    I38 @T6G_MB_LIB.T6G(SCH_1):PAGE426
  DE35 P5E_CPU0_P3_TX_C_DP<5> @T6G_MB_LIB.T6G(SCH_1):P5E_CPU0_P3_TX_C_DP(5)    I38 @T6G_MB_LIB.T6G(SCH_1):PAGE426
  DK34 P5E_CPU0_P3_TX_C_DN<4> @T6G_MB_LIB.T6G(SCH_1):P5E_CPU0_P3_TX_C_DN(4)    I38 @T6G_MB_LIB.T6G(SCH_1):PAGE426
  DM35 P5E_CPU0_P3_TX_C_DP<4> @T6G_MB_LIB.T6G(SCH_1):P5E_CPU0_P3_TX_C_DP(4)    I38 @T6G_MB_LIB.T6G(SCH_1):PAGE426
  DU34 P5E_CPU0_P3_TX_C_DN<3> @T6G_MB_LIB.T6G(SCH_1):P5E_CPU0_P3_TX_C_DN(3)    I38 @T6G_MB_LIB.T6G(SCH_1):PAGE426
  DW35 P5E_CPU0_P3_TX_C_DP<3> @T6G_MB_LIB.T6G(SCH_1):P5E_CPU0_P3_TX_C_DP(3)    I38 @T6G_MB_LIB.T6G(SCH_1):PAGE426
  ED34 P5E_CPU0_P3_TX_C_DN<2> @T6G_MB_LIB.T6G(SCH_1):P5E_CPU0_P3_TX_C_DN(2)    I38 @T6G_MB_LIB.T6G(SCH_1):PAGE426
  EF35 P5E_CPU0_P3_TX_C_DP<2> @T6G_MB_LIB.T6G(SCH_1):P5E_CPU0_P3_TX_C_DP(2)    I38 @T6G_MB_LIB.T6G(SCH_1):PAGE426
  EL34 P5E_CPU0_P3_TX_C_DP<1> @T6G_MB_LIB.T6G(SCH_1):P5E_CPU0_P3_TX_C_DP(1)    I38 @T6G_MB_LIB.T6G(SCH_1):PAGE426
  EN35 P5E_CPU0_P3_TX_C_DN<1> @T6G_MB_LIB.T6G(SCH_1):P5E_CPU0_P3_TX_C_DN(1)    I38 @T6G_MB_LIB.T6G(SCH_1):PAGE426
  EV34 P5E_CPU0_P3_TX_C_DN<0> @T6G_MB_LIB.T6G(SCH_1):P5E_CPU0_P3_TX_C_DN(0)    I38 @T6G_MB_LIB.T6G(SCH_1):PAGE426
  EY35 P5E_CPU0_P3_TX_C_DP<0> @T6G_MB_LIB.T6G(SCH_1):P5E_CPU0_P3_TX_C_DP(0)    I38 @T6G_MB_LIB.T6G(SCH_1):PAGE426
    M7 P5E_CPU0_P3_TX_BUF_DP<15> @T6G_MB_LIB.T6G(SCH_1):P5E_CPU0_P3_TX_BUF_DP(15)    I51 @T6G_MB_LIB.T6G(SCH_1):PAGE429
   P10 P5E_CPU0_P3_TX_BUF_DN<15> @T6G_MB_LIB.T6G(SCH_1):P5E_CPU0_P3_TX_BUF_DN(15)    I51 @T6G_MB_LIB.T6G(SCH_1):PAGE429
    W7 P5E_CPU0_P3_TX_BUF_DP<14> @T6G_MB_LIB.T6G(SCH_1):P5E_CPU0_P3_TX_BUF_DP(14)    I51 @T6G_MB_LIB.T6G(SCH_1):PAGE429
  AA10 P5E_CPU0_P3_TX_BUF_DN<14> @T6G_MB_LIB.T6G(SCH_1):P5E_CPU0_P3_TX_BUF_DN(14)    I51 @T6G_MB_LIB.T6G(SCH_1):PAGE429
   AF7 P5E_CPU0_P3_TX_BUF_DP<13> @T6G_MB_LIB.T6G(SCH_1):P5E_CPU0_P3_TX_BUF_DP(13)    I51 @T6G_MB_LIB.T6G(SCH_1):PAGE429
  AH10 P5E_CPU0_P3_TX_BUF_DN<13> @T6G_MB_LIB.T6G(SCH_1):P5E_CPU0_P3_TX_BUF_DN(13)    I51 @T6G_MB_LIB.T6G(SCH_1):PAGE429
   AN7 P5E_CPU0_P3_TX_BUF_DP<12> @T6G_MB_LIB.T6G(SCH_1):P5E_CPU0_P3_TX_BUF_DP(12)    I51 @T6G_MB_LIB.T6G(SCH_1):PAGE429
  AR10 P5E_CPU0_P3_TX_BUF_DN<12> @T6G_MB_LIB.T6G(SCH_1):P5E_CPU0_P3_TX_BUF_DN(12)    I51 @T6G_MB_LIB.T6G(SCH_1):PAGE429
   AY7 P5E_CPU0_P3_TX_BUF_DP<11> @T6G_MB_LIB.T6G(SCH_1):P5E_CPU0_P3_TX_BUF_DP(11)    I51 @T6G_MB_LIB.T6G(SCH_1):PAGE429
  BB10 P5E_CPU0_P3_TX_BUF_DN<11> @T6G_MB_LIB.T6G(SCH_1):P5E_CPU0_P3_TX_BUF_DN(11)    I51 @T6G_MB_LIB.T6G(SCH_1):PAGE429
   BG7 P5E_CPU0_P3_TX_BUF_DP<10> @T6G_MB_LIB.T6G(SCH_1):P5E_CPU0_P3_TX_BUF_DP(10)    I51 @T6G_MB_LIB.T6G(SCH_1):PAGE429
  BJ10 P5E_CPU0_P3_TX_BUF_DN<10> @T6G_MB_LIB.T6G(SCH_1):P5E_CPU0_P3_TX_BUF_DN(10)    I51 @T6G_MB_LIB.T6G(SCH_1):PAGE429
   BP7 P5E_CPU0_P3_TX_BUF_DP<9> @T6G_MB_LIB.T6G(SCH_1):P5E_CPU0_P3_TX_BUF_DP(9)    I51 @T6G_MB_LIB.T6G(SCH_1):PAGE429
  BT10 P5E_CPU0_P3_TX_BUF_DN<9> @T6G_MB_LIB.T6G(SCH_1):P5E_CPU0_P3_TX_BUF_DN(9)    I51 @T6G_MB_LIB.T6G(SCH_1):PAGE429
   CA7 P5E_CPU0_P3_TX_BUF_DP<8> @T6G_MB_LIB.T6G(SCH_1):P5E_CPU0_P3_TX_BUF_DP(8)    I51 @T6G_MB_LIB.T6G(SCH_1):PAGE429
  CC10 P5E_CPU0_P3_TX_BUF_DN<8> @T6G_MB_LIB.T6G(SCH_1):P5E_CPU0_P3_TX_BUF_DN(8)    I51 @T6G_MB_LIB.T6G(SCH_1):PAGE429
   CH7 P5E_CPU0_P3_TX_BUF_DP<7> @T6G_MB_LIB.T6G(SCH_1):P5E_CPU0_P3_TX_BUF_DP(7)   I142 @T6G_MB_LIB.T6G(SCH_1):PAGE429
  CK10 P5E_CPU0_P3_TX_BUF_DN<7> @T6G_MB_LIB.T6G(SCH_1):P5E_CPU0_P3_TX_BUF_DN(7)   I142 @T6G_MB_LIB.T6G(SCH_1):PAGE429
   CR7 P5E_CPU0_P3_TX_BUF_DP<6> @T6G_MB_LIB.T6G(SCH_1):P5E_CPU0_P3_TX_BUF_DP(6)   I142 @T6G_MB_LIB.T6G(SCH_1):PAGE429
  CU10 P5E_CPU0_P3_TX_BUF_DN<6> @T6G_MB_LIB.T6G(SCH_1):P5E_CPU0_P3_TX_BUF_DN(6)   I142 @T6G_MB_LIB.T6G(SCH_1):PAGE429
   DB7 P5E_CPU0_P3_TX_BUF_DP<5> @T6G_MB_LIB.T6G(SCH_1):P5E_CPU0_P3_TX_BUF_DP(5)   I142 @T6G_MB_LIB.T6G(SCH_1):PAGE429
  DD10 P5E_CPU0_P3_TX_BUF_DN<5> @T6G_MB_LIB.T6G(SCH_1):P5E_CPU0_P3_TX_BUF_DN(5)   I142 @T6G_MB_LIB.T6G(SCH_1):PAGE429
   DJ7 P5E_CPU0_P3_TX_BUF_DP<4> @T6G_MB_LIB.T6G(SCH_1):P5E_CPU0_P3_TX_BUF_DP(4)   I142 @T6G_MB_LIB.T6G(SCH_1):PAGE429
  DL10 P5E_CPU0_P3_TX_BUF_DN<4> @T6G_MB_LIB.T6G(SCH_1):P5E_CPU0_P3_TX_BUF_DN(4)   I142 @T6G_MB_LIB.T6G(SCH_1):PAGE429
   DT7 P5E_CPU0_P3_TX_BUF_DP<3> @T6G_MB_LIB.T6G(SCH_1):P5E_CPU0_P3_TX_BUF_DP(3)   I142 @T6G_MB_LIB.T6G(SCH_1):PAGE429
  DV10 P5E_CPU0_P3_TX_BUF_DN<3> @T6G_MB_LIB.T6G(SCH_1):P5E_CPU0_P3_TX_BUF_DN(3)   I142 @T6G_MB_LIB.T6G(SCH_1):PAGE429
   EC7 P5E_CPU0_P3_TX_BUF_DP<2> @T6G_MB_LIB.T6G(SCH_1):P5E_CPU0_P3_TX_BUF_DP(2)   I142 @T6G_MB_LIB.T6G(SCH_1):PAGE429
  EE10 P5E_CPU0_P3_TX_BUF_DN<2> @T6G_MB_LIB.T6G(SCH_1):P5E_CPU0_P3_TX_BUF_DN(2)   I142 @T6G_MB_LIB.T6G(SCH_1):PAGE429
   EK7 P5E_CPU0_P3_TX_BUF_DP<1> @T6G_MB_LIB.T6G(SCH_1):P5E_CPU0_P3_TX_BUF_DP(1)   I142 @T6G_MB_LIB.T6G(SCH_1):PAGE429
  EM10 P5E_CPU0_P3_TX_BUF_DN<1> @T6G_MB_LIB.T6G(SCH_1):P5E_CPU0_P3_TX_BUF_DN(1)   I142 @T6G_MB_LIB.T6G(SCH_1):PAGE429
   EU7 P5E_CPU0_P3_TX_BUF_DP<0> @T6G_MB_LIB.T6G(SCH_1):P5E_CPU0_P3_TX_BUF_DP(0)   I142 @T6G_MB_LIB.T6G(SCH_1):PAGE429
  EW10 P5E_CPU0_P3_TX_BUF_DN<0> @T6G_MB_LIB.T6G(SCH_1):P5E_CPU0_P3_TX_BUF_DN(0)   I142 @T6G_MB_LIB.T6G(SCH_1):PAGE429

U6014 PT5161LRS-PT5161LRS,SMLF,IC,AJ051610U03
    R1 P5E_CPU1_P0_RX_BUF_DP<15> @T6G_MB_LIB.T6G(SCH_1):P5E_CPU1_P0_RX_BUF_DP(15)     I1 @T6G_MB_LIB.T6G(SCH_1):PAGE402
    N2 P5E_CPU1_P0_RX_BUF_DN<15> @T6G_MB_LIB.T6G(SCH_1):P5E_CPU1_P0_RX_BUF_DN(15)     I1 @T6G_MB_LIB.T6G(SCH_1):PAGE402
   AB1 P5E_CPU1_P0_RX_BUF_DP<14> @T6G_MB_LIB.T6G(SCH_1):P5E_CPU1_P0_RX_BUF_DP(14)     I1 @T6G_MB_LIB.T6G(SCH_1):PAGE402
    Y2 P5E_CPU1_P0_RX_BUF_DN<14> @T6G_MB_LIB.T6G(SCH_1):P5E_CPU1_P0_RX_BUF_DN(14)     I1 @T6G_MB_LIB.T6G(SCH_1):PAGE402
   AJ1 P5E_CPU1_P0_RX_BUF_DP<13> @T6G_MB_LIB.T6G(SCH_1):P5E_CPU1_P0_RX_BUF_DP(13)     I1 @T6G_MB_LIB.T6G(SCH_1):PAGE402
   AG2 P5E_CPU1_P0_RX_BUF_DN<13> @T6G_MB_LIB.T6G(SCH_1):P5E_CPU1_P0_RX_BUF_DN(13)     I1 @T6G_MB_LIB.T6G(SCH_1):PAGE402
   AT1 P5E_CPU1_P0_RX_BUF_DP<12> @T6G_MB_LIB.T6G(SCH_1):P5E_CPU1_P0_RX_BUF_DP(12)     I1 @T6G_MB_LIB.T6G(SCH_1):PAGE402
   AP2 P5E_CPU1_P0_RX_BUF_DN<12> @T6G_MB_LIB.T6G(SCH_1):P5E_CPU1_P0_RX_BUF_DN(12)     I1 @T6G_MB_LIB.T6G(SCH_1):PAGE402
   BC1 P5E_CPU1_P0_RX_BUF_DP<11> @T6G_MB_LIB.T6G(SCH_1):P5E_CPU1_P0_RX_BUF_DP(11)     I1 @T6G_MB_LIB.T6G(SCH_1):PAGE402
   BA2 P5E_CPU1_P0_RX_BUF_DN<11> @T6G_MB_LIB.T6G(SCH_1):P5E_CPU1_P0_RX_BUF_DN(11)     I1 @T6G_MB_LIB.T6G(SCH_1):PAGE402
   BK1 P5E_CPU1_P0_RX_BUF_DP<10> @T6G_MB_LIB.T6G(SCH_1):P5E_CPU1_P0_RX_BUF_DP(10)     I1 @T6G_MB_LIB.T6G(SCH_1):PAGE402
   BH2 P5E_CPU1_P0_RX_BUF_DN<10> @T6G_MB_LIB.T6G(SCH_1):P5E_CPU1_P0_RX_BUF_DN(10)     I1 @T6G_MB_LIB.T6G(SCH_1):PAGE402
   BU1 P5E_CPU1_P0_RX_BUF_DP<9> @T6G_MB_LIB.T6G(SCH_1):P5E_CPU1_P0_RX_BUF_DP(9)     I1 @T6G_MB_LIB.T6G(SCH_1):PAGE402
   BR2 P5E_CPU1_P0_RX_BUF_DN<9> @T6G_MB_LIB.T6G(SCH_1):P5E_CPU1_P0_RX_BUF_DN(9)     I1 @T6G_MB_LIB.T6G(SCH_1):PAGE402
   CD1 P5E_CPU1_P0_RX_BUF_DP<8> @T6G_MB_LIB.T6G(SCH_1):P5E_CPU1_P0_RX_BUF_DP(8)     I1 @T6G_MB_LIB.T6G(SCH_1):PAGE402
   CB2 P5E_CPU1_P0_RX_BUF_DN<8> @T6G_MB_LIB.T6G(SCH_1):P5E_CPU1_P0_RX_BUF_DN(8)     I1 @T6G_MB_LIB.T6G(SCH_1):PAGE402
   CL1 P5E_CPU1_P0_RX_BUF_DP<7> @T6G_MB_LIB.T6G(SCH_1):P5E_CPU1_P0_RX_BUF_DP(7)    I38 @T6G_MB_LIB.T6G(SCH_1):PAGE402
   CJ2 P5E_CPU1_P0_RX_BUF_DN<7> @T6G_MB_LIB.T6G(SCH_1):P5E_CPU1_P0_RX_BUF_DN(7)    I38 @T6G_MB_LIB.T6G(SCH_1):PAGE402
   CV1 P5E_CPU1_P0_RX_BUF_DP<6> @T6G_MB_LIB.T6G(SCH_1):P5E_CPU1_P0_RX_BUF_DP(6)    I38 @T6G_MB_LIB.T6G(SCH_1):PAGE402
   CT2 P5E_CPU1_P0_RX_BUF_DN<6> @T6G_MB_LIB.T6G(SCH_1):P5E_CPU1_P0_RX_BUF_DN(6)    I38 @T6G_MB_LIB.T6G(SCH_1):PAGE402
   DE1 P5E_CPU1_P0_RX_BUF_DP<5> @T6G_MB_LIB.T6G(SCH_1):P5E_CPU1_P0_RX_BUF_DP(5)    I38 @T6G_MB_LIB.T6G(SCH_1):PAGE402
   DC2 P5E_CPU1_P0_RX_BUF_DN<5> @T6G_MB_LIB.T6G(SCH_1):P5E_CPU1_P0_RX_BUF_DN(5)    I38 @T6G_MB_LIB.T6G(SCH_1):PAGE402
   DM1 P5E_CPU1_P0_RX_BUF_DP<4> @T6G_MB_LIB.T6G(SCH_1):P5E_CPU1_P0_RX_BUF_DP(4)    I38 @T6G_MB_LIB.T6G(SCH_1):PAGE402
   DK2 P5E_CPU1_P0_RX_BUF_DN<4> @T6G_MB_LIB.T6G(SCH_1):P5E_CPU1_P0_RX_BUF_DN(4)    I38 @T6G_MB_LIB.T6G(SCH_1):PAGE402
   DW1 P5E_CPU1_P0_RX_BUF_DP<3> @T6G_MB_LIB.T6G(SCH_1):P5E_CPU1_P0_RX_BUF_DP(3)    I38 @T6G_MB_LIB.T6G(SCH_1):PAGE402
   DU2 P5E_CPU1_P0_RX_BUF_DN<3> @T6G_MB_LIB.T6G(SCH_1):P5E_CPU1_P0_RX_BUF_DN(3)    I38 @T6G_MB_LIB.T6G(SCH_1):PAGE402
   EF1 P5E_CPU1_P0_RX_BUF_DP<2> @T6G_MB_LIB.T6G(SCH_1):P5E_CPU1_P0_RX_BUF_DP(2)    I38 @T6G_MB_LIB.T6G(SCH_1):PAGE402
   ED2 P5E_CPU1_P0_RX_BUF_DN<2> @T6G_MB_LIB.T6G(SCH_1):P5E_CPU1_P0_RX_BUF_DN(2)    I38 @T6G_MB_LIB.T6G(SCH_1):PAGE402
   EN1 P5E_CPU1_P0_RX_BUF_DP<1> @T6G_MB_LIB.T6G(SCH_1):P5E_CPU1_P0_RX_BUF_DP(1)    I38 @T6G_MB_LIB.T6G(SCH_1):PAGE402
   EL2 P5E_CPU1_P0_RX_BUF_DN<1> @T6G_MB_LIB.T6G(SCH_1):P5E_CPU1_P0_RX_BUF_DN(1)    I38 @T6G_MB_LIB.T6G(SCH_1):PAGE402
   EY1 P5E_CPU1_P0_RX_BUF_DP<0> @T6G_MB_LIB.T6G(SCH_1):P5E_CPU1_P0_RX_BUF_DP(0)    I38 @T6G_MB_LIB.T6G(SCH_1):PAGE402
   EV2 P5E_CPU1_P0_RX_BUF_DN<0> @T6G_MB_LIB.T6G(SCH_1):P5E_CPU1_P0_RX_BUF_DN(0)    I38 @T6G_MB_LIB.T6G(SCH_1):PAGE402
   FJ6     NC     NC     I1 @T6G_MB_LIB.T6G(SCH_1):PAGE401
  FJ23     NC     NC     I1 @T6G_MB_LIB.T6G(SCH_1):PAGE401
  FJ25 GPIO2_RT_CPU1_P0 @T6G_MB_LIB.T6G(SCH_1):GPIO2_RT_CPU1_P0     I1 @T6G_MB_LIB.T6G(SCH_1):PAGE401
  FJ28 GPIO3_RT_CPU1_P0 @T6G_MB_LIB.T6G(SCH_1):GPIO3_RT_CPU1_P0     I1 @T6G_MB_LIB.T6G(SCH_1):PAGE401
  FJ31     NC     NC     I1 @T6G_MB_LIB.T6G(SCH_1):PAGE401
    B3 JTAG_TCK_RT_CPU1_P0 @T6G_MB_LIB.T6G(SCH_1):JTAG_TCK_RT_CPU1_P0     I1 @T6G_MB_LIB.T6G(SCH_1):PAGE401
    B6 JTAG_TDI_RT_CPU1_P0 @T6G_MB_LIB.T6G(SCH_1):JTAG_TDI_RT_CPU1_P0     I1 @T6G_MB_LIB.T6G(SCH_1):PAGE401
    B9 JTAG_TDO_RT_CPU1_P0 @T6G_MB_LIB.T6G(SCH_1):JTAG_TDO_RT_CPU1_P0     I1 @T6G_MB_LIB.T6G(SCH_1):PAGE401
   FF8 JTAG_TEST_MODE_RT_CPU1_P0 @T6G_MB_LIB.T6G(SCH_1):JTAG_TEST_MODE_RT_CPU1_P0     I1 @T6G_MB_LIB.T6G(SCH_1):PAGE401
   B12 JTAG_TMS_RT_CPU1_P0 @T6G_MB_LIB.T6G(SCH_1):JTAG_TMS_RT_CPU1_P0     I1 @T6G_MB_LIB.T6G(SCH_1):PAGE401
    E8 JTAG_TRST_RT_CPU1_P0_N @T6G_MB_LIB.T6G(SCH_1):JTAG_TRST_RT_CPU1_P0_N     I1 @T6G_MB_LIB.T6G(SCH_1):PAGE401
   FJ9 MODE_RT_CPU1_P0 @T6G_MB_LIB.T6G(SCH_1):MODE_RT_CPU1_P0     I1 @T6G_MB_LIB.T6G(SCH_1):PAGE401
    F2 RST_RT_CPU1_P0_PERST_N @T6G_MB_LIB.T6G(SCH_1):RST_RT_CPU1_P0_PERST_N     I1 @T6G_MB_LIB.T6G(SCH_1):PAGE401
   E18     NC     NC     I1 @T6G_MB_LIB.T6G(SCH_1):PAGE401
   B16     NC     NC     I1 @T6G_MB_LIB.T6G(SCH_1):PAGE401
  FF18 CLK_100M_RETIMER_CPU1_P0_DN @T6G_MB_LIB.T6G(SCH_1):CLK_100M_RETIMER_CPU1_P0_DN     I1 @T6G_MB_LIB.T6G(SCH_1):PAGE401
  FJ16 CLK_100M_RETIMER_CPU1_P0_DP @T6G_MB_LIB.T6G(SCH_1):CLK_100M_RETIMER_CPU1_P0_DP     I1 @T6G_MB_LIB.T6G(SCH_1):PAGE401
  FF11 RST_RT_CPU1_P0_RESET_N @T6G_MB_LIB.T6G(SCH_1):RST_RT_CPU1_P0_RESET_N     I1 @T6G_MB_LIB.T6G(SCH_1):PAGE401
   E11 RXDET_BYP_RT_CPU1_P0 @T6G_MB_LIB.T6G(SCH_1):RXDET_BYP_RT_CPU1_P0     I1 @T6G_MB_LIB.T6G(SCH_1):PAGE401
  FF33 RT_CPU1_P0_SCAN_MODE @T6G_MB_LIB.T6G(SCH_1):RT_CPU1_P0_SCAN_MODE     I1 @T6G_MB_LIB.T6G(SCH_1):PAGE401
   F34 RT_CPU1_P0_ADDR1 @T6G_MB_LIB.T6G(SCH_1):RT_CPU1_P0_ADDR1     I1 @T6G_MB_LIB.T6G(SCH_1):PAGE401
   B23 RT_CPU1_P0_ADDR2 @T6G_MB_LIB.T6G(SCH_1):RT_CPU1_P0_ADDR2     I1 @T6G_MB_LIB.T6G(SCH_1):PAGE401
   B25 RT_CPU1_P0_ADDR3 @T6G_MB_LIB.T6G(SCH_1):RT_CPU1_P0_ADDR3     I1 @T6G_MB_LIB.T6G(SCH_1):PAGE401
   B31 SMB_RT_CPU1_P0_R2_SCL @T6G_MB_LIB.T6G(SCH_1):SMB_RT_CPU1_P0_R2_SCL     I1 @T6G_MB_LIB.T6G(SCH_1):PAGE401
   B28 SMB_RT_CPU1_P0_R2_SDA @T6G_MB_LIB.T6G(SCH_1):SMB_RT_CPU1_P0_R2_SDA     I1 @T6G_MB_LIB.T6G(SCH_1):PAGE401
   E30    GND @T6G_MB_LIB.T6G(SCH_1):GND     I1 @T6G_MB_LIB.T6G(SCH_1):PAGE401
  FF24 TEST0_RT_CPU1_P0 @T6G_MB_LIB.T6G(SCH_1):TEST0_RT_CPU1_P0     I1 @T6G_MB_LIB.T6G(SCH_1):PAGE401
  FF27 TEST1_RT_CPU1_P0 @T6G_MB_LIB.T6G(SCH_1):TEST1_RT_CPU1_P0     I1 @T6G_MB_LIB.T6G(SCH_1):PAGE401
  FF30 TEST2_RT_CPU1_P0 @T6G_MB_LIB.T6G(SCH_1):TEST2_RT_CPU1_P0     I1 @T6G_MB_LIB.T6G(SCH_1):PAGE401
   G35 CLKREQ_RT_CPU1_P0_N @T6G_MB_LIB.T6G(SCH_1):CLKREQ_RT_CPU1_P0_N     I1 @T6G_MB_LIB.T6G(SCH_1):PAGE401
   FF5 SMB_RT_CPU1_P0_ROM_MUX_1D_R_SCL @T6G_MB_LIB.T6G(SCH_1):SMB_RT_CPU1_P0_ROM_MUX_1D_R_SCL     I1 @T6G_MB_LIB.T6G(SCH_1):PAGE401
   FJ3 SMB_RT_CPU1_P0_ROM_MUX_1D_R_SDA @T6G_MB_LIB.T6G(SCH_1):SMB_RT_CPU1_P0_ROM_MUX_1D_R_SDA     I1 @T6G_MB_LIB.T6G(SCH_1):PAGE401
    G1 RT_CPU1_P0_VQPS @T6G_MB_LIB.T6G(SCH_1):RT_CPU1_P0_VQPS     I1 @T6G_MB_LIB.T6G(SCH_1):PAGE400
  BV20 P1V8_CPU1_RT0_1A @T6G_MB_LIB.T6G(SCH_1):P1V8_CPU1_RT0_1A     I1 @T6G_MB_LIB.T6G(SCH_1):PAGE400
  CE17 P1V8_CPU1_RT0_1A @T6G_MB_LIB.T6G(SCH_1):P1V8_CPU1_RT0_1A     I1 @T6G_MB_LIB.T6G(SCH_1):PAGE400
  CE20 P1V8_CPU1_RT0_1A @T6G_MB_LIB.T6G(SCH_1):P1V8_CPU1_RT0_1A     I1 @T6G_MB_LIB.T6G(SCH_1):PAGE400
  CM17 P1V8_CPU1_RT0_1A @T6G_MB_LIB.T6G(SCH_1):P1V8_CPU1_RT0_1A     I1 @T6G_MB_LIB.T6G(SCH_1):PAGE400
  CM20 P1V8_CPU1_RT0_1A @T6G_MB_LIB.T6G(SCH_1):P1V8_CPU1_RT0_1A     I1 @T6G_MB_LIB.T6G(SCH_1):PAGE400
  BL17 P0V9_CPU1_RT_2D @T6G_MB_LIB.T6G(SCH_1):P0V9_CPU1_RT_2D     I1 @T6G_MB_LIB.T6G(SCH_1):PAGE400
  BL20 P0V9_CPU1_RT_2D @T6G_MB_LIB.T6G(SCH_1):P0V9_CPU1_RT_2D     I1 @T6G_MB_LIB.T6G(SCH_1):PAGE400
  CW17 P0V9_CPU1_RT_2D @T6G_MB_LIB.T6G(SCH_1):P0V9_CPU1_RT_2D     I1 @T6G_MB_LIB.T6G(SCH_1):PAGE400
  CW20 P0V9_CPU1_RT_2D @T6G_MB_LIB.T6G(SCH_1):P0V9_CPU1_RT_2D     I1 @T6G_MB_LIB.T6G(SCH_1):PAGE400
  BV17 P1V8_CPU1_RT0_1A_1D @T6G_MB_LIB.T6G(SCH_1):P1V8_CPU1_RT0_1A_1D     I1 @T6G_MB_LIB.T6G(SCH_1):PAGE400
  AC17 P0V9_CPU1_RT0_2A @T6G_MB_LIB.T6G(SCH_1):P0V9_CPU1_RT0_2A     I1 @T6G_MB_LIB.T6G(SCH_1):PAGE400
  AC20 P0V9_CPU1_RT0_2A @T6G_MB_LIB.T6G(SCH_1):P0V9_CPU1_RT0_2A     I1 @T6G_MB_LIB.T6G(SCH_1):PAGE400
  AK17 P0V9_CPU1_RT0_2A @T6G_MB_LIB.T6G(SCH_1):P0V9_CPU1_RT0_2A     I1 @T6G_MB_LIB.T6G(SCH_1):PAGE400
  AK20 P0V9_CPU1_RT0_2A @T6G_MB_LIB.T6G(SCH_1):P0V9_CPU1_RT0_2A     I1 @T6G_MB_LIB.T6G(SCH_1):PAGE400
  AU17 P0V9_CPU1_RT0_2A @T6G_MB_LIB.T6G(SCH_1):P0V9_CPU1_RT0_2A     I1 @T6G_MB_LIB.T6G(SCH_1):PAGE400
  AU20 P0V9_CPU1_RT0_2A @T6G_MB_LIB.T6G(SCH_1):P0V9_CPU1_RT0_2A     I1 @T6G_MB_LIB.T6G(SCH_1):PAGE400
  BD17 P0V9_CPU1_RT0_2A_2D @T6G_MB_LIB.T6G(SCH_1):P0V9_CPU1_RT0_2A_2D     I1 @T6G_MB_LIB.T6G(SCH_1):PAGE400
  BD20 P0V9_CPU1_RT0_2A_2D @T6G_MB_LIB.T6G(SCH_1):P0V9_CPU1_RT0_2A_2D     I1 @T6G_MB_LIB.T6G(SCH_1):PAGE400
  DF17 P0V9_CPU1_RT0_2A_2D @T6G_MB_LIB.T6G(SCH_1):P0V9_CPU1_RT0_2A_2D     I1 @T6G_MB_LIB.T6G(SCH_1):PAGE400
  DF20 P0V9_CPU1_RT0_2A_2D @T6G_MB_LIB.T6G(SCH_1):P0V9_CPU1_RT0_2A_2D     I1 @T6G_MB_LIB.T6G(SCH_1):PAGE400
  DN17 P0V9_CPU1_RT0_2A @T6G_MB_LIB.T6G(SCH_1):P0V9_CPU1_RT0_2A     I1 @T6G_MB_LIB.T6G(SCH_1):PAGE400
  DN20 P0V9_CPU1_RT0_2A @T6G_MB_LIB.T6G(SCH_1):P0V9_CPU1_RT0_2A     I1 @T6G_MB_LIB.T6G(SCH_1):PAGE400
  DY17 P0V9_CPU1_RT0_2A @T6G_MB_LIB.T6G(SCH_1):P0V9_CPU1_RT0_2A     I1 @T6G_MB_LIB.T6G(SCH_1):PAGE400
  DY20 P0V9_CPU1_RT0_2A @T6G_MB_LIB.T6G(SCH_1):P0V9_CPU1_RT0_2A     I1 @T6G_MB_LIB.T6G(SCH_1):PAGE400
  EG17 P0V9_CPU1_RT0_2A @T6G_MB_LIB.T6G(SCH_1):P0V9_CPU1_RT0_2A     I1 @T6G_MB_LIB.T6G(SCH_1):PAGE400
  EG20 P0V9_CPU1_RT0_2A @T6G_MB_LIB.T6G(SCH_1):P0V9_CPU1_RT0_2A     I1 @T6G_MB_LIB.T6G(SCH_1):PAGE400
  EP17 P0V9_CPU1_RT0_2A @T6G_MB_LIB.T6G(SCH_1):P0V9_CPU1_RT0_2A     I1 @T6G_MB_LIB.T6G(SCH_1):PAGE400
  EP20 P0V9_CPU1_RT0_2A @T6G_MB_LIB.T6G(SCH_1):P0V9_CPU1_RT0_2A     I1 @T6G_MB_LIB.T6G(SCH_1):PAGE400
   T17 P0V9_CPU1_RT0_2A @T6G_MB_LIB.T6G(SCH_1):P0V9_CPU1_RT0_2A     I1 @T6G_MB_LIB.T6G(SCH_1):PAGE400
   T20 P0V9_CPU1_RT0_2A @T6G_MB_LIB.T6G(SCH_1):P0V9_CPU1_RT0_2A     I1 @T6G_MB_LIB.T6G(SCH_1):PAGE400
  AC13    GND @T6G_MB_LIB.T6G(SCH_1):GND     I2 @T6G_MB_LIB.T6G(SCH_1):PAGE400
  AC22    GND @T6G_MB_LIB.T6G(SCH_1):GND     I2 @T6G_MB_LIB.T6G(SCH_1):PAGE400
  AC32    GND @T6G_MB_LIB.T6G(SCH_1):GND     I2 @T6G_MB_LIB.T6G(SCH_1):PAGE400
   AC4    GND @T6G_MB_LIB.T6G(SCH_1):GND     I2 @T6G_MB_LIB.T6G(SCH_1):PAGE400
   AD2    GND @T6G_MB_LIB.T6G(SCH_1):GND     I2 @T6G_MB_LIB.T6G(SCH_1):PAGE400
  AD34    GND @T6G_MB_LIB.T6G(SCH_1):GND     I2 @T6G_MB_LIB.T6G(SCH_1):PAGE400
   AE1    GND @T6G_MB_LIB.T6G(SCH_1):GND     I2 @T6G_MB_LIB.T6G(SCH_1):PAGE400
  AE35    GND @T6G_MB_LIB.T6G(SCH_1):GND     I2 @T6G_MB_LIB.T6G(SCH_1):PAGE400
  AK13    GND @T6G_MB_LIB.T6G(SCH_1):GND     I2 @T6G_MB_LIB.T6G(SCH_1):PAGE400
  AK22    GND @T6G_MB_LIB.T6G(SCH_1):GND     I2 @T6G_MB_LIB.T6G(SCH_1):PAGE400
  AK32    GND @T6G_MB_LIB.T6G(SCH_1):GND     I2 @T6G_MB_LIB.T6G(SCH_1):PAGE400
   AK4    GND @T6G_MB_LIB.T6G(SCH_1):GND     I2 @T6G_MB_LIB.T6G(SCH_1):PAGE400
   AL2    GND @T6G_MB_LIB.T6G(SCH_1):GND     I2 @T6G_MB_LIB.T6G(SCH_1):PAGE400
  AL34    GND @T6G_MB_LIB.T6G(SCH_1):GND     I2 @T6G_MB_LIB.T6G(SCH_1):PAGE400
   AM1    GND @T6G_MB_LIB.T6G(SCH_1):GND     I2 @T6G_MB_LIB.T6G(SCH_1):PAGE400
  AM35    GND @T6G_MB_LIB.T6G(SCH_1):GND     I2 @T6G_MB_LIB.T6G(SCH_1):PAGE400
  AU13    GND @T6G_MB_LIB.T6G(SCH_1):GND     I2 @T6G_MB_LIB.T6G(SCH_1):PAGE400
  AU22    GND @T6G_MB_LIB.T6G(SCH_1):GND     I2 @T6G_MB_LIB.T6G(SCH_1):PAGE400
  AU32    GND @T6G_MB_LIB.T6G(SCH_1):GND     I2 @T6G_MB_LIB.T6G(SCH_1):PAGE400
   AU4    GND @T6G_MB_LIB.T6G(SCH_1):GND     I2 @T6G_MB_LIB.T6G(SCH_1):PAGE400
   AV2    GND @T6G_MB_LIB.T6G(SCH_1):GND     I2 @T6G_MB_LIB.T6G(SCH_1):PAGE400
  AV34    GND @T6G_MB_LIB.T6G(SCH_1):GND     I2 @T6G_MB_LIB.T6G(SCH_1):PAGE400
   AW1    GND @T6G_MB_LIB.T6G(SCH_1):GND     I2 @T6G_MB_LIB.T6G(SCH_1):PAGE400
  AW35    GND @T6G_MB_LIB.T6G(SCH_1):GND     I2 @T6G_MB_LIB.T6G(SCH_1):PAGE400
   B19    GND @T6G_MB_LIB.T6G(SCH_1):GND     I2 @T6G_MB_LIB.T6G(SCH_1):PAGE400
  BD13    GND @T6G_MB_LIB.T6G(SCH_1):GND     I2 @T6G_MB_LIB.T6G(SCH_1):PAGE400
  BD22    GND @T6G_MB_LIB.T6G(SCH_1):GND     I2 @T6G_MB_LIB.T6G(SCH_1):PAGE400
  BD32    GND @T6G_MB_LIB.T6G(SCH_1):GND     I2 @T6G_MB_LIB.T6G(SCH_1):PAGE400
   BD4    GND @T6G_MB_LIB.T6G(SCH_1):GND     I2 @T6G_MB_LIB.T6G(SCH_1):PAGE400
   BE2    GND @T6G_MB_LIB.T6G(SCH_1):GND     I2 @T6G_MB_LIB.T6G(SCH_1):PAGE400
  BE34    GND @T6G_MB_LIB.T6G(SCH_1):GND     I2 @T6G_MB_LIB.T6G(SCH_1):PAGE400
   BF1    GND @T6G_MB_LIB.T6G(SCH_1):GND     I2 @T6G_MB_LIB.T6G(SCH_1):PAGE400
  BF35    GND @T6G_MB_LIB.T6G(SCH_1):GND     I2 @T6G_MB_LIB.T6G(SCH_1):PAGE400
  BL13    GND @T6G_MB_LIB.T6G(SCH_1):GND     I2 @T6G_MB_LIB.T6G(SCH_1):PAGE400
  BL22    GND @T6G_MB_LIB.T6G(SCH_1):GND     I2 @T6G_MB_LIB.T6G(SCH_1):PAGE400
  BL32    GND @T6G_MB_LIB.T6G(SCH_1):GND     I2 @T6G_MB_LIB.T6G(SCH_1):PAGE400
   BL4    GND @T6G_MB_LIB.T6G(SCH_1):GND     I2 @T6G_MB_LIB.T6G(SCH_1):PAGE400
   BM2    GND @T6G_MB_LIB.T6G(SCH_1):GND     I2 @T6G_MB_LIB.T6G(SCH_1):PAGE400
  BM34    GND @T6G_MB_LIB.T6G(SCH_1):GND     I2 @T6G_MB_LIB.T6G(SCH_1):PAGE400
   BN1    GND @T6G_MB_LIB.T6G(SCH_1):GND     I2 @T6G_MB_LIB.T6G(SCH_1):PAGE400
  BN35    GND @T6G_MB_LIB.T6G(SCH_1):GND     I2 @T6G_MB_LIB.T6G(SCH_1):PAGE400
  BV13    GND @T6G_MB_LIB.T6G(SCH_1):GND     I2 @T6G_MB_LIB.T6G(SCH_1):PAGE400
  BV22    GND @T6G_MB_LIB.T6G(SCH_1):GND     I2 @T6G_MB_LIB.T6G(SCH_1):PAGE400
  BV32    GND @T6G_MB_LIB.T6G(SCH_1):GND     I2 @T6G_MB_LIB.T6G(SCH_1):PAGE400
   BV4    GND @T6G_MB_LIB.T6G(SCH_1):GND     I2 @T6G_MB_LIB.T6G(SCH_1):PAGE400
   BW2    GND @T6G_MB_LIB.T6G(SCH_1):GND     I2 @T6G_MB_LIB.T6G(SCH_1):PAGE400
  BW34    GND @T6G_MB_LIB.T6G(SCH_1):GND     I2 @T6G_MB_LIB.T6G(SCH_1):PAGE400
   BY1    GND @T6G_MB_LIB.T6G(SCH_1):GND     I2 @T6G_MB_LIB.T6G(SCH_1):PAGE400
  BY35    GND @T6G_MB_LIB.T6G(SCH_1):GND     I2 @T6G_MB_LIB.T6G(SCH_1):PAGE400
  CE13    GND @T6G_MB_LIB.T6G(SCH_1):GND     I2 @T6G_MB_LIB.T6G(SCH_1):PAGE400
  CE22    GND @T6G_MB_LIB.T6G(SCH_1):GND     I2 @T6G_MB_LIB.T6G(SCH_1):PAGE400
  CE32    GND @T6G_MB_LIB.T6G(SCH_1):GND     I2 @T6G_MB_LIB.T6G(SCH_1):PAGE400
   CE4    GND @T6G_MB_LIB.T6G(SCH_1):GND     I2 @T6G_MB_LIB.T6G(SCH_1):PAGE400
   CF2    GND @T6G_MB_LIB.T6G(SCH_1):GND     I2 @T6G_MB_LIB.T6G(SCH_1):PAGE400
  CF34    GND @T6G_MB_LIB.T6G(SCH_1):GND     I2 @T6G_MB_LIB.T6G(SCH_1):PAGE400
   CG1    GND @T6G_MB_LIB.T6G(SCH_1):GND     I2 @T6G_MB_LIB.T6G(SCH_1):PAGE400
  CG35    GND @T6G_MB_LIB.T6G(SCH_1):GND     I2 @T6G_MB_LIB.T6G(SCH_1):PAGE400
  CM13    GND @T6G_MB_LIB.T6G(SCH_1):GND     I2 @T6G_MB_LIB.T6G(SCH_1):PAGE400
  CM22    GND @T6G_MB_LIB.T6G(SCH_1):GND     I2 @T6G_MB_LIB.T6G(SCH_1):PAGE400
  CM32    GND @T6G_MB_LIB.T6G(SCH_1):GND     I2 @T6G_MB_LIB.T6G(SCH_1):PAGE400
   CM4    GND @T6G_MB_LIB.T6G(SCH_1):GND     I2 @T6G_MB_LIB.T6G(SCH_1):PAGE400
   CN2    GND @T6G_MB_LIB.T6G(SCH_1):GND     I2 @T6G_MB_LIB.T6G(SCH_1):PAGE400
  CN34    GND @T6G_MB_LIB.T6G(SCH_1):GND     I2 @T6G_MB_LIB.T6G(SCH_1):PAGE400
   CP1    GND @T6G_MB_LIB.T6G(SCH_1):GND     I2 @T6G_MB_LIB.T6G(SCH_1):PAGE400
  CP35    GND @T6G_MB_LIB.T6G(SCH_1):GND     I2 @T6G_MB_LIB.T6G(SCH_1):PAGE400
  CW13    GND @T6G_MB_LIB.T6G(SCH_1):GND     I2 @T6G_MB_LIB.T6G(SCH_1):PAGE400
  CW22    GND @T6G_MB_LIB.T6G(SCH_1):GND     I2 @T6G_MB_LIB.T6G(SCH_1):PAGE400
  CW32    GND @T6G_MB_LIB.T6G(SCH_1):GND     I2 @T6G_MB_LIB.T6G(SCH_1):PAGE400
   CW4    GND @T6G_MB_LIB.T6G(SCH_1):GND     I2 @T6G_MB_LIB.T6G(SCH_1):PAGE400
   CY2    GND @T6G_MB_LIB.T6G(SCH_1):GND     I2 @T6G_MB_LIB.T6G(SCH_1):PAGE400
  CY34    GND @T6G_MB_LIB.T6G(SCH_1):GND     I2 @T6G_MB_LIB.T6G(SCH_1):PAGE400
   DA1    GND @T6G_MB_LIB.T6G(SCH_1):GND     I2 @T6G_MB_LIB.T6G(SCH_1):PAGE400
  DA35    GND @T6G_MB_LIB.T6G(SCH_1):GND     I2 @T6G_MB_LIB.T6G(SCH_1):PAGE400
  DF13    GND @T6G_MB_LIB.T6G(SCH_1):GND     I2 @T6G_MB_LIB.T6G(SCH_1):PAGE400
  DF22    GND @T6G_MB_LIB.T6G(SCH_1):GND     I2 @T6G_MB_LIB.T6G(SCH_1):PAGE400
  DF32    GND @T6G_MB_LIB.T6G(SCH_1):GND     I2 @T6G_MB_LIB.T6G(SCH_1):PAGE400
   DF4    GND @T6G_MB_LIB.T6G(SCH_1):GND     I2 @T6G_MB_LIB.T6G(SCH_1):PAGE400
   DG2    GND @T6G_MB_LIB.T6G(SCH_1):GND     I2 @T6G_MB_LIB.T6G(SCH_1):PAGE400
  DG34    GND @T6G_MB_LIB.T6G(SCH_1):GND     I2 @T6G_MB_LIB.T6G(SCH_1):PAGE400
   DH1    GND @T6G_MB_LIB.T6G(SCH_1):GND     I2 @T6G_MB_LIB.T6G(SCH_1):PAGE400
  DH35    GND @T6G_MB_LIB.T6G(SCH_1):GND     I2 @T6G_MB_LIB.T6G(SCH_1):PAGE400
  DN13    GND @T6G_MB_LIB.T6G(SCH_1):GND     I2 @T6G_MB_LIB.T6G(SCH_1):PAGE400
    A1 NCF_A1_CPU1_P0_GND @T6G_MB_LIB.T6G(SCH_1):NCF_A1_CPU1_P0_GND     I2 @T6G_MB_LIB.T6G(SCH_1):PAGE400
   A35 NCF_CPU1_P0_GND @T6G_MB_LIB.T6G(SCH_1):NCF_CPU1_P0_GND     I2 @T6G_MB_LIB.T6G(SCH_1):PAGE400
    C2 NCF_CPU1_P0_GND @T6G_MB_LIB.T6G(SCH_1):NCF_CPU1_P0_GND     I2 @T6G_MB_LIB.T6G(SCH_1):PAGE400
   C34 NCF_CPU1_P0_GND @T6G_MB_LIB.T6G(SCH_1):NCF_CPU1_P0_GND     I2 @T6G_MB_LIB.T6G(SCH_1):PAGE400
    D1 NCF_CPU1_P0_GND @T6G_MB_LIB.T6G(SCH_1):NCF_CPU1_P0_GND     I2 @T6G_MB_LIB.T6G(SCH_1):PAGE400
   D35 NCF_CPU1_P0_GND @T6G_MB_LIB.T6G(SCH_1):NCF_CPU1_P0_GND     I2 @T6G_MB_LIB.T6G(SCH_1):PAGE400
   FE2 NCF_CPU1_P0_GND @T6G_MB_LIB.T6G(SCH_1):NCF_CPU1_P0_GND     I2 @T6G_MB_LIB.T6G(SCH_1):PAGE400
  FE34 NCF_CPU1_P0_GND @T6G_MB_LIB.T6G(SCH_1):NCF_CPU1_P0_GND     I2 @T6G_MB_LIB.T6G(SCH_1):PAGE400
   FG1 NCF_CPU1_P0_GND @T6G_MB_LIB.T6G(SCH_1):NCF_CPU1_P0_GND     I2 @T6G_MB_LIB.T6G(SCH_1):PAGE400
  FG35 NCF_CPU1_P0_GND @T6G_MB_LIB.T6G(SCH_1):NCF_CPU1_P0_GND     I2 @T6G_MB_LIB.T6G(SCH_1):PAGE400
   FH2 NCF_CPU1_P0_GND @T6G_MB_LIB.T6G(SCH_1):NCF_CPU1_P0_GND     I2 @T6G_MB_LIB.T6G(SCH_1):PAGE400
  FH34 NCF_CPU1_P0_GND @T6G_MB_LIB.T6G(SCH_1):NCF_CPU1_P0_GND     I2 @T6G_MB_LIB.T6G(SCH_1):PAGE400
  DN22    GND @T6G_MB_LIB.T6G(SCH_1):GND     I2 @T6G_MB_LIB.T6G(SCH_1):PAGE400
  DN32    GND @T6G_MB_LIB.T6G(SCH_1):GND     I2 @T6G_MB_LIB.T6G(SCH_1):PAGE400
   DN4    GND @T6G_MB_LIB.T6G(SCH_1):GND     I2 @T6G_MB_LIB.T6G(SCH_1):PAGE400
   DP2    GND @T6G_MB_LIB.T6G(SCH_1):GND     I2 @T6G_MB_LIB.T6G(SCH_1):PAGE400
  DP34    GND @T6G_MB_LIB.T6G(SCH_1):GND     I2 @T6G_MB_LIB.T6G(SCH_1):PAGE400
   DR1    GND @T6G_MB_LIB.T6G(SCH_1):GND     I2 @T6G_MB_LIB.T6G(SCH_1):PAGE400
  DR35    GND @T6G_MB_LIB.T6G(SCH_1):GND     I2 @T6G_MB_LIB.T6G(SCH_1):PAGE400
  DY13    GND @T6G_MB_LIB.T6G(SCH_1):GND     I2 @T6G_MB_LIB.T6G(SCH_1):PAGE400
  DY22    GND @T6G_MB_LIB.T6G(SCH_1):GND     I2 @T6G_MB_LIB.T6G(SCH_1):PAGE400
  DY32    GND @T6G_MB_LIB.T6G(SCH_1):GND     I2 @T6G_MB_LIB.T6G(SCH_1):PAGE400
   DY4    GND @T6G_MB_LIB.T6G(SCH_1):GND     I2 @T6G_MB_LIB.T6G(SCH_1):PAGE400
   E14    GND @T6G_MB_LIB.T6G(SCH_1):GND     I2 @T6G_MB_LIB.T6G(SCH_1):PAGE400
   E27    GND @T6G_MB_LIB.T6G(SCH_1):GND     I2 @T6G_MB_LIB.T6G(SCH_1):PAGE400
   E33    GND @T6G_MB_LIB.T6G(SCH_1):GND     I2 @T6G_MB_LIB.T6G(SCH_1):PAGE400
   EA2    GND @T6G_MB_LIB.T6G(SCH_1):GND     I2 @T6G_MB_LIB.T6G(SCH_1):PAGE400
  EA34    GND @T6G_MB_LIB.T6G(SCH_1):GND     I2 @T6G_MB_LIB.T6G(SCH_1):PAGE400
   EB1    GND @T6G_MB_LIB.T6G(SCH_1):GND     I2 @T6G_MB_LIB.T6G(SCH_1):PAGE400
  EB35    GND @T6G_MB_LIB.T6G(SCH_1):GND     I2 @T6G_MB_LIB.T6G(SCH_1):PAGE400
  EG13    GND @T6G_MB_LIB.T6G(SCH_1):GND     I2 @T6G_MB_LIB.T6G(SCH_1):PAGE400
  EG22    GND @T6G_MB_LIB.T6G(SCH_1):GND     I2 @T6G_MB_LIB.T6G(SCH_1):PAGE400
  EG32    GND @T6G_MB_LIB.T6G(SCH_1):GND     I2 @T6G_MB_LIB.T6G(SCH_1):PAGE400
   EG4    GND @T6G_MB_LIB.T6G(SCH_1):GND     I2 @T6G_MB_LIB.T6G(SCH_1):PAGE400
   EH2    GND @T6G_MB_LIB.T6G(SCH_1):GND     I2 @T6G_MB_LIB.T6G(SCH_1):PAGE400
  EH34    GND @T6G_MB_LIB.T6G(SCH_1):GND     I2 @T6G_MB_LIB.T6G(SCH_1):PAGE400
   EJ1    GND @T6G_MB_LIB.T6G(SCH_1):GND     I2 @T6G_MB_LIB.T6G(SCH_1):PAGE400
  EJ35    GND @T6G_MB_LIB.T6G(SCH_1):GND     I2 @T6G_MB_LIB.T6G(SCH_1):PAGE400
  EP13    GND @T6G_MB_LIB.T6G(SCH_1):GND     I2 @T6G_MB_LIB.T6G(SCH_1):PAGE400
  EP22    GND @T6G_MB_LIB.T6G(SCH_1):GND     I2 @T6G_MB_LIB.T6G(SCH_1):PAGE400
  EP32    GND @T6G_MB_LIB.T6G(SCH_1):GND     I2 @T6G_MB_LIB.T6G(SCH_1):PAGE400
   EP4    GND @T6G_MB_LIB.T6G(SCH_1):GND     I2 @T6G_MB_LIB.T6G(SCH_1):PAGE400
   ER2    GND @T6G_MB_LIB.T6G(SCH_1):GND     I2 @T6G_MB_LIB.T6G(SCH_1):PAGE400
  ER34    GND @T6G_MB_LIB.T6G(SCH_1):GND     I2 @T6G_MB_LIB.T6G(SCH_1):PAGE400
   ET1    GND @T6G_MB_LIB.T6G(SCH_1):GND     I2 @T6G_MB_LIB.T6G(SCH_1):PAGE400
  ET35    GND @T6G_MB_LIB.T6G(SCH_1):GND     I2 @T6G_MB_LIB.T6G(SCH_1):PAGE400
  FA15    GND @T6G_MB_LIB.T6G(SCH_1):GND     I2 @T6G_MB_LIB.T6G(SCH_1):PAGE400
  FA32    GND @T6G_MB_LIB.T6G(SCH_1):GND     I2 @T6G_MB_LIB.T6G(SCH_1):PAGE400
   FB2    GND @T6G_MB_LIB.T6G(SCH_1):GND     I2 @T6G_MB_LIB.T6G(SCH_1):PAGE400
  FB34    GND @T6G_MB_LIB.T6G(SCH_1):GND     I2 @T6G_MB_LIB.T6G(SCH_1):PAGE400
  FC19    GND @T6G_MB_LIB.T6G(SCH_1):GND     I2 @T6G_MB_LIB.T6G(SCH_1):PAGE400
  FC23    GND @T6G_MB_LIB.T6G(SCH_1):GND     I2 @T6G_MB_LIB.T6G(SCH_1):PAGE400
  FC25    GND @T6G_MB_LIB.T6G(SCH_1):GND     I2 @T6G_MB_LIB.T6G(SCH_1):PAGE400
  FC28    GND @T6G_MB_LIB.T6G(SCH_1):GND     I2 @T6G_MB_LIB.T6G(SCH_1):PAGE400
   FC3    GND @T6G_MB_LIB.T6G(SCH_1):GND     I2 @T6G_MB_LIB.T6G(SCH_1):PAGE400
   FC6    GND @T6G_MB_LIB.T6G(SCH_1):GND     I2 @T6G_MB_LIB.T6G(SCH_1):PAGE400
   FC9    GND @T6G_MB_LIB.T6G(SCH_1):GND     I2 @T6G_MB_LIB.T6G(SCH_1):PAGE400
   FD1    GND @T6G_MB_LIB.T6G(SCH_1):GND     I2 @T6G_MB_LIB.T6G(SCH_1):PAGE400
  FD35    GND @T6G_MB_LIB.T6G(SCH_1):GND     I2 @T6G_MB_LIB.T6G(SCH_1):PAGE400
  FF14    GND @T6G_MB_LIB.T6G(SCH_1):GND     I2 @T6G_MB_LIB.T6G(SCH_1):PAGE400
  FF21    GND @T6G_MB_LIB.T6G(SCH_1):GND     I2 @T6G_MB_LIB.T6G(SCH_1):PAGE400
  FJ12    GND @T6G_MB_LIB.T6G(SCH_1):GND     I2 @T6G_MB_LIB.T6G(SCH_1):PAGE400
  FJ19    GND @T6G_MB_LIB.T6G(SCH_1):GND     I2 @T6G_MB_LIB.T6G(SCH_1):PAGE400
   H12    GND @T6G_MB_LIB.T6G(SCH_1):GND     I2 @T6G_MB_LIB.T6G(SCH_1):PAGE400
   H16    GND @T6G_MB_LIB.T6G(SCH_1):GND     I2 @T6G_MB_LIB.T6G(SCH_1):PAGE400
   H19    GND @T6G_MB_LIB.T6G(SCH_1):GND     I2 @T6G_MB_LIB.T6G(SCH_1):PAGE400
   H31    GND @T6G_MB_LIB.T6G(SCH_1):GND     I2 @T6G_MB_LIB.T6G(SCH_1):PAGE400
   J22    GND @T6G_MB_LIB.T6G(SCH_1):GND     I2 @T6G_MB_LIB.T6G(SCH_1):PAGE400
    J4    GND @T6G_MB_LIB.T6G(SCH_1):GND     I2 @T6G_MB_LIB.T6G(SCH_1):PAGE400
    K2    GND @T6G_MB_LIB.T6G(SCH_1):GND     I2 @T6G_MB_LIB.T6G(SCH_1):PAGE400
   K34    GND @T6G_MB_LIB.T6G(SCH_1):GND     I2 @T6G_MB_LIB.T6G(SCH_1):PAGE400
    L1    GND @T6G_MB_LIB.T6G(SCH_1):GND     I2 @T6G_MB_LIB.T6G(SCH_1):PAGE400
   L35    GND @T6G_MB_LIB.T6G(SCH_1):GND     I2 @T6G_MB_LIB.T6G(SCH_1):PAGE400
   T13    GND @T6G_MB_LIB.T6G(SCH_1):GND     I2 @T6G_MB_LIB.T6G(SCH_1):PAGE400
   T22    GND @T6G_MB_LIB.T6G(SCH_1):GND     I2 @T6G_MB_LIB.T6G(SCH_1):PAGE400
   T32    GND @T6G_MB_LIB.T6G(SCH_1):GND     I2 @T6G_MB_LIB.T6G(SCH_1):PAGE400
    T4    GND @T6G_MB_LIB.T6G(SCH_1):GND     I2 @T6G_MB_LIB.T6G(SCH_1):PAGE400
    U2    GND @T6G_MB_LIB.T6G(SCH_1):GND     I2 @T6G_MB_LIB.T6G(SCH_1):PAGE400
   U34    GND @T6G_MB_LIB.T6G(SCH_1):GND     I2 @T6G_MB_LIB.T6G(SCH_1):PAGE400
    V1    GND @T6G_MB_LIB.T6G(SCH_1):GND     I2 @T6G_MB_LIB.T6G(SCH_1):PAGE400
   V35    GND @T6G_MB_LIB.T6G(SCH_1):GND     I2 @T6G_MB_LIB.T6G(SCH_1):PAGE400
   M26 P5E_CPU1_P0_RX_DP<15> @T6G_MB_LIB.T6G(SCH_1):P5E_CPU1_P0_RX_DP(15)     I1 @T6G_MB_LIB.T6G(SCH_1):PAGE438
   P29 P5E_CPU1_P0_RX_DN<15> @T6G_MB_LIB.T6G(SCH_1):P5E_CPU1_P0_RX_DN(15)     I1 @T6G_MB_LIB.T6G(SCH_1):PAGE438
   W26 P5E_CPU1_P0_RX_DP<14> @T6G_MB_LIB.T6G(SCH_1):P5E_CPU1_P0_RX_DP(14)     I1 @T6G_MB_LIB.T6G(SCH_1):PAGE438
  AA29 P5E_CPU1_P0_RX_DN<14> @T6G_MB_LIB.T6G(SCH_1):P5E_CPU1_P0_RX_DN(14)     I1 @T6G_MB_LIB.T6G(SCH_1):PAGE438
  AF26 P5E_CPU1_P0_RX_DP<13> @T6G_MB_LIB.T6G(SCH_1):P5E_CPU1_P0_RX_DP(13)     I1 @T6G_MB_LIB.T6G(SCH_1):PAGE438
  AH29 P5E_CPU1_P0_RX_DN<13> @T6G_MB_LIB.T6G(SCH_1):P5E_CPU1_P0_RX_DN(13)     I1 @T6G_MB_LIB.T6G(SCH_1):PAGE438
  AN26 P5E_CPU1_P0_RX_DP<12> @T6G_MB_LIB.T6G(SCH_1):P5E_CPU1_P0_RX_DP(12)     I1 @T6G_MB_LIB.T6G(SCH_1):PAGE438
  AR29 P5E_CPU1_P0_RX_DN<12> @T6G_MB_LIB.T6G(SCH_1):P5E_CPU1_P0_RX_DN(12)     I1 @T6G_MB_LIB.T6G(SCH_1):PAGE438
  AY26 P5E_CPU1_P0_RX_DP<11> @T6G_MB_LIB.T6G(SCH_1):P5E_CPU1_P0_RX_DP(11)     I1 @T6G_MB_LIB.T6G(SCH_1):PAGE438
  BB29 P5E_CPU1_P0_RX_DN<11> @T6G_MB_LIB.T6G(SCH_1):P5E_CPU1_P0_RX_DN(11)     I1 @T6G_MB_LIB.T6G(SCH_1):PAGE438
  BG26 P5E_CPU1_P0_RX_DP<10> @T6G_MB_LIB.T6G(SCH_1):P5E_CPU1_P0_RX_DP(10)     I1 @T6G_MB_LIB.T6G(SCH_1):PAGE438
  BJ29 P5E_CPU1_P0_RX_DN<10> @T6G_MB_LIB.T6G(SCH_1):P5E_CPU1_P0_RX_DN(10)     I1 @T6G_MB_LIB.T6G(SCH_1):PAGE438
  BP26 P5E_CPU1_P0_RX_DP<9> @T6G_MB_LIB.T6G(SCH_1):P5E_CPU1_P0_RX_DP(9)     I1 @T6G_MB_LIB.T6G(SCH_1):PAGE438
  BT29 P5E_CPU1_P0_RX_DN<9> @T6G_MB_LIB.T6G(SCH_1):P5E_CPU1_P0_RX_DN(9)     I1 @T6G_MB_LIB.T6G(SCH_1):PAGE438
  CA26 P5E_CPU1_P0_RX_DP<8> @T6G_MB_LIB.T6G(SCH_1):P5E_CPU1_P0_RX_DP(8)     I1 @T6G_MB_LIB.T6G(SCH_1):PAGE438
  CC29 P5E_CPU1_P0_RX_DN<8> @T6G_MB_LIB.T6G(SCH_1):P5E_CPU1_P0_RX_DN(8)     I1 @T6G_MB_LIB.T6G(SCH_1):PAGE438
  CH26 P5E_CPU1_P0_RX_DP<7> @T6G_MB_LIB.T6G(SCH_1):P5E_CPU1_P0_RX_DP(7)    I38 @T6G_MB_LIB.T6G(SCH_1):PAGE438
  CK29 P5E_CPU1_P0_RX_DN<7> @T6G_MB_LIB.T6G(SCH_1):P5E_CPU1_P0_RX_DN(7)    I38 @T6G_MB_LIB.T6G(SCH_1):PAGE438
  CR26 P5E_CPU1_P0_RX_DP<6> @T6G_MB_LIB.T6G(SCH_1):P5E_CPU1_P0_RX_DP(6)    I38 @T6G_MB_LIB.T6G(SCH_1):PAGE438
  CU29 P5E_CPU1_P0_RX_DN<6> @T6G_MB_LIB.T6G(SCH_1):P5E_CPU1_P0_RX_DN(6)    I38 @T6G_MB_LIB.T6G(SCH_1):PAGE438
  DB26 P5E_CPU1_P0_RX_DP<5> @T6G_MB_LIB.T6G(SCH_1):P5E_CPU1_P0_RX_DP(5)    I38 @T6G_MB_LIB.T6G(SCH_1):PAGE438
  DD29 P5E_CPU1_P0_RX_DN<5> @T6G_MB_LIB.T6G(SCH_1):P5E_CPU1_P0_RX_DN(5)    I38 @T6G_MB_LIB.T6G(SCH_1):PAGE438
  DJ26 P5E_CPU1_P0_RX_DP<4> @T6G_MB_LIB.T6G(SCH_1):P5E_CPU1_P0_RX_DP(4)    I38 @T6G_MB_LIB.T6G(SCH_1):PAGE438
  DL29 P5E_CPU1_P0_RX_DN<4> @T6G_MB_LIB.T6G(SCH_1):P5E_CPU1_P0_RX_DN(4)    I38 @T6G_MB_LIB.T6G(SCH_1):PAGE438
  DT26 P5E_CPU1_P0_RX_DP<3> @T6G_MB_LIB.T6G(SCH_1):P5E_CPU1_P0_RX_DP(3)    I38 @T6G_MB_LIB.T6G(SCH_1):PAGE438
  DV29 P5E_CPU1_P0_RX_DN<3> @T6G_MB_LIB.T6G(SCH_1):P5E_CPU1_P0_RX_DN(3)    I38 @T6G_MB_LIB.T6G(SCH_1):PAGE438
  EC26 P5E_CPU1_P0_RX_DP<2> @T6G_MB_LIB.T6G(SCH_1):P5E_CPU1_P0_RX_DP(2)    I38 @T6G_MB_LIB.T6G(SCH_1):PAGE438
  EE29 P5E_CPU1_P0_RX_DN<2> @T6G_MB_LIB.T6G(SCH_1):P5E_CPU1_P0_RX_DN(2)    I38 @T6G_MB_LIB.T6G(SCH_1):PAGE438
  EK26 P5E_CPU1_P0_RX_DP<1> @T6G_MB_LIB.T6G(SCH_1):P5E_CPU1_P0_RX_DP(1)    I38 @T6G_MB_LIB.T6G(SCH_1):PAGE438
  EM29 P5E_CPU1_P0_RX_DN<1> @T6G_MB_LIB.T6G(SCH_1):P5E_CPU1_P0_RX_DN(1)    I38 @T6G_MB_LIB.T6G(SCH_1):PAGE438
  EU26 P5E_CPU1_P0_RX_DP<0> @T6G_MB_LIB.T6G(SCH_1):P5E_CPU1_P0_RX_DP(0)    I38 @T6G_MB_LIB.T6G(SCH_1):PAGE438
  EW29 P5E_CPU1_P0_RX_DN<0> @T6G_MB_LIB.T6G(SCH_1):P5E_CPU1_P0_RX_DN(0)    I38 @T6G_MB_LIB.T6G(SCH_1):PAGE438
   N34 P5E_CPU1_P0_TX_C_DN<15> @T6G_MB_LIB.T6G(SCH_1):P5E_CPU1_P0_TX_C_DN(15)     I1 @T6G_MB_LIB.T6G(SCH_1):PAGE437
   R35 P5E_CPU1_P0_TX_C_DP<15> @T6G_MB_LIB.T6G(SCH_1):P5E_CPU1_P0_TX_C_DP(15)     I1 @T6G_MB_LIB.T6G(SCH_1):PAGE437
   Y34 P5E_CPU1_P0_TX_C_DN<14> @T6G_MB_LIB.T6G(SCH_1):P5E_CPU1_P0_TX_C_DN(14)     I1 @T6G_MB_LIB.T6G(SCH_1):PAGE437
  AB35 P5E_CPU1_P0_TX_C_DP<14> @T6G_MB_LIB.T6G(SCH_1):P5E_CPU1_P0_TX_C_DP(14)     I1 @T6G_MB_LIB.T6G(SCH_1):PAGE437
  AG34 P5E_CPU1_P0_TX_C_DP<13> @T6G_MB_LIB.T6G(SCH_1):P5E_CPU1_P0_TX_C_DP(13)     I1 @T6G_MB_LIB.T6G(SCH_1):PAGE437
  AJ35 P5E_CPU1_P0_TX_C_DN<13> @T6G_MB_LIB.T6G(SCH_1):P5E_CPU1_P0_TX_C_DN(13)     I1 @T6G_MB_LIB.T6G(SCH_1):PAGE437
  AP34 P5E_CPU1_P0_TX_C_DN<12> @T6G_MB_LIB.T6G(SCH_1):P5E_CPU1_P0_TX_C_DN(12)     I1 @T6G_MB_LIB.T6G(SCH_1):PAGE437
  AT35 P5E_CPU1_P0_TX_C_DP<12> @T6G_MB_LIB.T6G(SCH_1):P5E_CPU1_P0_TX_C_DP(12)     I1 @T6G_MB_LIB.T6G(SCH_1):PAGE437
  BA34 P5E_CPU1_P0_TX_C_DN<11> @T6G_MB_LIB.T6G(SCH_1):P5E_CPU1_P0_TX_C_DN(11)     I1 @T6G_MB_LIB.T6G(SCH_1):PAGE437
  BC35 P5E_CPU1_P0_TX_C_DP<11> @T6G_MB_LIB.T6G(SCH_1):P5E_CPU1_P0_TX_C_DP(11)     I1 @T6G_MB_LIB.T6G(SCH_1):PAGE437
  BH34 P5E_CPU1_P0_TX_C_DN<10> @T6G_MB_LIB.T6G(SCH_1):P5E_CPU1_P0_TX_C_DN(10)     I1 @T6G_MB_LIB.T6G(SCH_1):PAGE437
  BK35 P5E_CPU1_P0_TX_C_DP<10> @T6G_MB_LIB.T6G(SCH_1):P5E_CPU1_P0_TX_C_DP(10)     I1 @T6G_MB_LIB.T6G(SCH_1):PAGE437
  BR34 P5E_CPU1_P0_TX_C_DN<9> @T6G_MB_LIB.T6G(SCH_1):P5E_CPU1_P0_TX_C_DN(9)     I1 @T6G_MB_LIB.T6G(SCH_1):PAGE437
  BU35 P5E_CPU1_P0_TX_C_DP<9> @T6G_MB_LIB.T6G(SCH_1):P5E_CPU1_P0_TX_C_DP(9)     I1 @T6G_MB_LIB.T6G(SCH_1):PAGE437
  CB34 P5E_CPU1_P0_TX_C_DN<8> @T6G_MB_LIB.T6G(SCH_1):P5E_CPU1_P0_TX_C_DN(8)     I1 @T6G_MB_LIB.T6G(SCH_1):PAGE437
  CD35 P5E_CPU1_P0_TX_C_DP<8> @T6G_MB_LIB.T6G(SCH_1):P5E_CPU1_P0_TX_C_DP(8)     I1 @T6G_MB_LIB.T6G(SCH_1):PAGE437
  CJ34 P5E_CPU1_P0_TX_C_DN<7> @T6G_MB_LIB.T6G(SCH_1):P5E_CPU1_P0_TX_C_DN(7)    I38 @T6G_MB_LIB.T6G(SCH_1):PAGE437
  CL35 P5E_CPU1_P0_TX_C_DP<7> @T6G_MB_LIB.T6G(SCH_1):P5E_CPU1_P0_TX_C_DP(7)    I38 @T6G_MB_LIB.T6G(SCH_1):PAGE437
  CT34 P5E_CPU1_P0_TX_C_DN<6> @T6G_MB_LIB.T6G(SCH_1):P5E_CPU1_P0_TX_C_DN(6)    I38 @T6G_MB_LIB.T6G(SCH_1):PAGE437
  CV35 P5E_CPU1_P0_TX_C_DP<6> @T6G_MB_LIB.T6G(SCH_1):P5E_CPU1_P0_TX_C_DP(6)    I38 @T6G_MB_LIB.T6G(SCH_1):PAGE437
  DC34 P5E_CPU1_P0_TX_C_DN<5> @T6G_MB_LIB.T6G(SCH_1):P5E_CPU1_P0_TX_C_DN(5)    I38 @T6G_MB_LIB.T6G(SCH_1):PAGE437
  DE35 P5E_CPU1_P0_TX_C_DP<5> @T6G_MB_LIB.T6G(SCH_1):P5E_CPU1_P0_TX_C_DP(5)    I38 @T6G_MB_LIB.T6G(SCH_1):PAGE437
  DK34 P5E_CPU1_P0_TX_C_DN<4> @T6G_MB_LIB.T6G(SCH_1):P5E_CPU1_P0_TX_C_DN(4)    I38 @T6G_MB_LIB.T6G(SCH_1):PAGE437
  DM35 P5E_CPU1_P0_TX_C_DP<4> @T6G_MB_LIB.T6G(SCH_1):P5E_CPU1_P0_TX_C_DP(4)    I38 @T6G_MB_LIB.T6G(SCH_1):PAGE437
  DU34 P5E_CPU1_P0_TX_C_DN<3> @T6G_MB_LIB.T6G(SCH_1):P5E_CPU1_P0_TX_C_DN(3)    I38 @T6G_MB_LIB.T6G(SCH_1):PAGE437
  DW35 P5E_CPU1_P0_TX_C_DP<3> @T6G_MB_LIB.T6G(SCH_1):P5E_CPU1_P0_TX_C_DP(3)    I38 @T6G_MB_LIB.T6G(SCH_1):PAGE437
  ED34 P5E_CPU1_P0_TX_C_DN<2> @T6G_MB_LIB.T6G(SCH_1):P5E_CPU1_P0_TX_C_DN(2)    I38 @T6G_MB_LIB.T6G(SCH_1):PAGE437
  EF35 P5E_CPU1_P0_TX_C_DP<2> @T6G_MB_LIB.T6G(SCH_1):P5E_CPU1_P0_TX_C_DP(2)    I38 @T6G_MB_LIB.T6G(SCH_1):PAGE437
  EL34 P5E_CPU1_P0_TX_C_DP<1> @T6G_MB_LIB.T6G(SCH_1):P5E_CPU1_P0_TX_C_DP(1)    I38 @T6G_MB_LIB.T6G(SCH_1):PAGE437
  EN35 P5E_CPU1_P0_TX_C_DN<1> @T6G_MB_LIB.T6G(SCH_1):P5E_CPU1_P0_TX_C_DN(1)    I38 @T6G_MB_LIB.T6G(SCH_1):PAGE437
  EV34 P5E_CPU1_P0_TX_C_DN<0> @T6G_MB_LIB.T6G(SCH_1):P5E_CPU1_P0_TX_C_DN(0)    I38 @T6G_MB_LIB.T6G(SCH_1):PAGE437
  EY35 P5E_CPU1_P0_TX_C_DP<0> @T6G_MB_LIB.T6G(SCH_1):P5E_CPU1_P0_TX_C_DP(0)    I38 @T6G_MB_LIB.T6G(SCH_1):PAGE437
    M7 P5E_CPU1_P0_TX_BUF_DP<15> @T6G_MB_LIB.T6G(SCH_1):P5E_CPU1_P0_TX_BUF_DP(15)    I43 @T6G_MB_LIB.T6G(SCH_1):PAGE439
   P10 P5E_CPU1_P0_TX_BUF_DN<15> @T6G_MB_LIB.T6G(SCH_1):P5E_CPU1_P0_TX_BUF_DN(15)    I43 @T6G_MB_LIB.T6G(SCH_1):PAGE439
    W7 P5E_CPU1_P0_TX_BUF_DP<14> @T6G_MB_LIB.T6G(SCH_1):P5E_CPU1_P0_TX_BUF_DP(14)    I43 @T6G_MB_LIB.T6G(SCH_1):PAGE439
  AA10 P5E_CPU1_P0_TX_BUF_DN<14> @T6G_MB_LIB.T6G(SCH_1):P5E_CPU1_P0_TX_BUF_DN(14)    I43 @T6G_MB_LIB.T6G(SCH_1):PAGE439
   AF7 P5E_CPU1_P0_TX_BUF_DP<13> @T6G_MB_LIB.T6G(SCH_1):P5E_CPU1_P0_TX_BUF_DP(13)    I43 @T6G_MB_LIB.T6G(SCH_1):PAGE439
  AH10 P5E_CPU1_P0_TX_BUF_DN<13> @T6G_MB_LIB.T6G(SCH_1):P5E_CPU1_P0_TX_BUF_DN(13)    I43 @T6G_MB_LIB.T6G(SCH_1):PAGE439
   AN7 P5E_CPU1_P0_TX_BUF_DP<12> @T6G_MB_LIB.T6G(SCH_1):P5E_CPU1_P0_TX_BUF_DP(12)    I43 @T6G_MB_LIB.T6G(SCH_1):PAGE439
  AR10 P5E_CPU1_P0_TX_BUF_DN<12> @T6G_MB_LIB.T6G(SCH_1):P5E_CPU1_P0_TX_BUF_DN(12)    I43 @T6G_MB_LIB.T6G(SCH_1):PAGE439
   AY7 P5E_CPU1_P0_TX_BUF_DP<11> @T6G_MB_LIB.T6G(SCH_1):P5E_CPU1_P0_TX_BUF_DP(11)    I43 @T6G_MB_LIB.T6G(SCH_1):PAGE439
  BB10 P5E_CPU1_P0_TX_BUF_DN<11> @T6G_MB_LIB.T6G(SCH_1):P5E_CPU1_P0_TX_BUF_DN(11)    I43 @T6G_MB_LIB.T6G(SCH_1):PAGE439
   BG7 P5E_CPU1_P0_TX_BUF_DP<10> @T6G_MB_LIB.T6G(SCH_1):P5E_CPU1_P0_TX_BUF_DP(10)    I43 @T6G_MB_LIB.T6G(SCH_1):PAGE439
  BJ10 P5E_CPU1_P0_TX_BUF_DN<10> @T6G_MB_LIB.T6G(SCH_1):P5E_CPU1_P0_TX_BUF_DN(10)    I43 @T6G_MB_LIB.T6G(SCH_1):PAGE439
   BP7 P5E_CPU1_P0_TX_BUF_DP<9> @T6G_MB_LIB.T6G(SCH_1):P5E_CPU1_P0_TX_BUF_DP(9)    I43 @T6G_MB_LIB.T6G(SCH_1):PAGE439
  BT10 P5E_CPU1_P0_TX_BUF_DN<9> @T6G_MB_LIB.T6G(SCH_1):P5E_CPU1_P0_TX_BUF_DN(9)    I43 @T6G_MB_LIB.T6G(SCH_1):PAGE439
   CA7 P5E_CPU1_P0_TX_BUF_DP<8> @T6G_MB_LIB.T6G(SCH_1):P5E_CPU1_P0_TX_BUF_DP(8)    I43 @T6G_MB_LIB.T6G(SCH_1):PAGE439
  CC10 P5E_CPU1_P0_TX_BUF_DN<8> @T6G_MB_LIB.T6G(SCH_1):P5E_CPU1_P0_TX_BUF_DN(8)    I43 @T6G_MB_LIB.T6G(SCH_1):PAGE439
   CH7 P5E_CPU1_P0_TX_BUF_DP<7> @T6G_MB_LIB.T6G(SCH_1):P5E_CPU1_P0_TX_BUF_DP(7)   I142 @T6G_MB_LIB.T6G(SCH_1):PAGE439
  CK10 P5E_CPU1_P0_TX_BUF_DN<7> @T6G_MB_LIB.T6G(SCH_1):P5E_CPU1_P0_TX_BUF_DN(7)   I142 @T6G_MB_LIB.T6G(SCH_1):PAGE439
   CR7 P5E_CPU1_P0_TX_BUF_DP<6> @T6G_MB_LIB.T6G(SCH_1):P5E_CPU1_P0_TX_BUF_DP(6)   I142 @T6G_MB_LIB.T6G(SCH_1):PAGE439
  CU10 P5E_CPU1_P0_TX_BUF_DN<6> @T6G_MB_LIB.T6G(SCH_1):P5E_CPU1_P0_TX_BUF_DN(6)   I142 @T6G_MB_LIB.T6G(SCH_1):PAGE439
   DB7 P5E_CPU1_P0_TX_BUF_DP<5> @T6G_MB_LIB.T6G(SCH_1):P5E_CPU1_P0_TX_BUF_DP(5)   I142 @T6G_MB_LIB.T6G(SCH_1):PAGE439
  DD10 P5E_CPU1_P0_TX_BUF_DN<5> @T6G_MB_LIB.T6G(SCH_1):P5E_CPU1_P0_TX_BUF_DN(5)   I142 @T6G_MB_LIB.T6G(SCH_1):PAGE439
   DJ7 P5E_CPU1_P0_TX_BUF_DP<4> @T6G_MB_LIB.T6G(SCH_1):P5E_CPU1_P0_TX_BUF_DP(4)   I142 @T6G_MB_LIB.T6G(SCH_1):PAGE439
  DL10 P5E_CPU1_P0_TX_BUF_DN<4> @T6G_MB_LIB.T6G(SCH_1):P5E_CPU1_P0_TX_BUF_DN(4)   I142 @T6G_MB_LIB.T6G(SCH_1):PAGE439
   DT7 P5E_CPU1_P0_TX_BUF_DP<3> @T6G_MB_LIB.T6G(SCH_1):P5E_CPU1_P0_TX_BUF_DP(3)   I142 @T6G_MB_LIB.T6G(SCH_1):PAGE439
  DV10 P5E_CPU1_P0_TX_BUF_DN<3> @T6G_MB_LIB.T6G(SCH_1):P5E_CPU1_P0_TX_BUF_DN(3)   I142 @T6G_MB_LIB.T6G(SCH_1):PAGE439
   EC7 P5E_CPU1_P0_TX_BUF_DP<2> @T6G_MB_LIB.T6G(SCH_1):P5E_CPU1_P0_TX_BUF_DP(2)   I142 @T6G_MB_LIB.T6G(SCH_1):PAGE439
  EE10 P5E_CPU1_P0_TX_BUF_DN<2> @T6G_MB_LIB.T6G(SCH_1):P5E_CPU1_P0_TX_BUF_DN(2)   I142 @T6G_MB_LIB.T6G(SCH_1):PAGE439
   EK7 P5E_CPU1_P0_TX_BUF_DP<1> @T6G_MB_LIB.T6G(SCH_1):P5E_CPU1_P0_TX_BUF_DP(1)   I142 @T6G_MB_LIB.T6G(SCH_1):PAGE439
  EM10 P5E_CPU1_P0_TX_BUF_DN<1> @T6G_MB_LIB.T6G(SCH_1):P5E_CPU1_P0_TX_BUF_DN(1)   I142 @T6G_MB_LIB.T6G(SCH_1):PAGE439
   EU7 P5E_CPU1_P0_TX_BUF_DP<0> @T6G_MB_LIB.T6G(SCH_1):P5E_CPU1_P0_TX_BUF_DP(0)   I142 @T6G_MB_LIB.T6G(SCH_1):PAGE439
  EW10 P5E_CPU1_P0_TX_BUF_DN<0> @T6G_MB_LIB.T6G(SCH_1):P5E_CPU1_P0_TX_BUF_DN(0)   I142 @T6G_MB_LIB.T6G(SCH_1):PAGE439

U6015 PT5161LRS-PT5161LRS,SMLF,IC,AJ051610U03
    R1 P5E_CPU1_P1_RX_BUF_DP<15> @T6G_MB_LIB.T6G(SCH_1):P5E_CPU1_P1_RX_BUF_DP(15)     I1 @T6G_MB_LIB.T6G(SCH_1):PAGE394
    N2 P5E_CPU1_P1_RX_BUF_DN<15> @T6G_MB_LIB.T6G(SCH_1):P5E_CPU1_P1_RX_BUF_DN(15)     I1 @T6G_MB_LIB.T6G(SCH_1):PAGE394
   AB1 P5E_CPU1_P1_RX_BUF_DP<14> @T6G_MB_LIB.T6G(SCH_1):P5E_CPU1_P1_RX_BUF_DP(14)     I1 @T6G_MB_LIB.T6G(SCH_1):PAGE394
    Y2 P5E_CPU1_P1_RX_BUF_DN<14> @T6G_MB_LIB.T6G(SCH_1):P5E_CPU1_P1_RX_BUF_DN(14)     I1 @T6G_MB_LIB.T6G(SCH_1):PAGE394
   AJ1 P5E_CPU1_P1_RX_BUF_DP<13> @T6G_MB_LIB.T6G(SCH_1):P5E_CPU1_P1_RX_BUF_DP(13)     I1 @T6G_MB_LIB.T6G(SCH_1):PAGE394
   AG2 P5E_CPU1_P1_RX_BUF_DN<13> @T6G_MB_LIB.T6G(SCH_1):P5E_CPU1_P1_RX_BUF_DN(13)     I1 @T6G_MB_LIB.T6G(SCH_1):PAGE394
   AT1 P5E_CPU1_P1_RX_BUF_DP<12> @T6G_MB_LIB.T6G(SCH_1):P5E_CPU1_P1_RX_BUF_DP(12)     I1 @T6G_MB_LIB.T6G(SCH_1):PAGE394
   AP2 P5E_CPU1_P1_RX_BUF_DN<12> @T6G_MB_LIB.T6G(SCH_1):P5E_CPU1_P1_RX_BUF_DN(12)     I1 @T6G_MB_LIB.T6G(SCH_1):PAGE394
   BC1 P5E_CPU1_P1_RX_BUF_DP<11> @T6G_MB_LIB.T6G(SCH_1):P5E_CPU1_P1_RX_BUF_DP(11)     I1 @T6G_MB_LIB.T6G(SCH_1):PAGE394
   BA2 P5E_CPU1_P1_RX_BUF_DN<11> @T6G_MB_LIB.T6G(SCH_1):P5E_CPU1_P1_RX_BUF_DN(11)     I1 @T6G_MB_LIB.T6G(SCH_1):PAGE394
   BK1 P5E_CPU1_P1_RX_BUF_DP<10> @T6G_MB_LIB.T6G(SCH_1):P5E_CPU1_P1_RX_BUF_DP(10)     I1 @T6G_MB_LIB.T6G(SCH_1):PAGE394
   BH2 P5E_CPU1_P1_RX_BUF_DN<10> @T6G_MB_LIB.T6G(SCH_1):P5E_CPU1_P1_RX_BUF_DN(10)     I1 @T6G_MB_LIB.T6G(SCH_1):PAGE394
   BU1 P5E_CPU1_P1_RX_BUF_DP<9> @T6G_MB_LIB.T6G(SCH_1):P5E_CPU1_P1_RX_BUF_DP(9)     I1 @T6G_MB_LIB.T6G(SCH_1):PAGE394
   BR2 P5E_CPU1_P1_RX_BUF_DN<9> @T6G_MB_LIB.T6G(SCH_1):P5E_CPU1_P1_RX_BUF_DN(9)     I1 @T6G_MB_LIB.T6G(SCH_1):PAGE394
   CD1 P5E_CPU1_P1_RX_BUF_DP<8> @T6G_MB_LIB.T6G(SCH_1):P5E_CPU1_P1_RX_BUF_DP(8)     I1 @T6G_MB_LIB.T6G(SCH_1):PAGE394
   CB2 P5E_CPU1_P1_RX_BUF_DN<8> @T6G_MB_LIB.T6G(SCH_1):P5E_CPU1_P1_RX_BUF_DN(8)     I1 @T6G_MB_LIB.T6G(SCH_1):PAGE394
   CL1 P5E_CPU1_P1_RX_BUF_DP<7> @T6G_MB_LIB.T6G(SCH_1):P5E_CPU1_P1_RX_BUF_DP(7)    I38 @T6G_MB_LIB.T6G(SCH_1):PAGE394
   CJ2 P5E_CPU1_P1_RX_BUF_DN<7> @T6G_MB_LIB.T6G(SCH_1):P5E_CPU1_P1_RX_BUF_DN(7)    I38 @T6G_MB_LIB.T6G(SCH_1):PAGE394
   CV1 P5E_CPU1_P1_RX_BUF_DP<6> @T6G_MB_LIB.T6G(SCH_1):P5E_CPU1_P1_RX_BUF_DP(6)    I38 @T6G_MB_LIB.T6G(SCH_1):PAGE394
   CT2 P5E_CPU1_P1_RX_BUF_DN<6> @T6G_MB_LIB.T6G(SCH_1):P5E_CPU1_P1_RX_BUF_DN(6)    I38 @T6G_MB_LIB.T6G(SCH_1):PAGE394
   DE1 P5E_CPU1_P1_RX_BUF_DP<5> @T6G_MB_LIB.T6G(SCH_1):P5E_CPU1_P1_RX_BUF_DP(5)    I38 @T6G_MB_LIB.T6G(SCH_1):PAGE394
   DC2 P5E_CPU1_P1_RX_BUF_DN<5> @T6G_MB_LIB.T6G(SCH_1):P5E_CPU1_P1_RX_BUF_DN(5)    I38 @T6G_MB_LIB.T6G(SCH_1):PAGE394
   DM1 P5E_CPU1_P1_RX_BUF_DP<4> @T6G_MB_LIB.T6G(SCH_1):P5E_CPU1_P1_RX_BUF_DP(4)    I38 @T6G_MB_LIB.T6G(SCH_1):PAGE394
   DK2 P5E_CPU1_P1_RX_BUF_DN<4> @T6G_MB_LIB.T6G(SCH_1):P5E_CPU1_P1_RX_BUF_DN(4)    I38 @T6G_MB_LIB.T6G(SCH_1):PAGE394
   DW1 P5E_CPU1_P1_RX_BUF_DP<3> @T6G_MB_LIB.T6G(SCH_1):P5E_CPU1_P1_RX_BUF_DP(3)    I38 @T6G_MB_LIB.T6G(SCH_1):PAGE394
   DU2 P5E_CPU1_P1_RX_BUF_DN<3> @T6G_MB_LIB.T6G(SCH_1):P5E_CPU1_P1_RX_BUF_DN(3)    I38 @T6G_MB_LIB.T6G(SCH_1):PAGE394
   EF1 P5E_CPU1_P1_RX_BUF_DP<2> @T6G_MB_LIB.T6G(SCH_1):P5E_CPU1_P1_RX_BUF_DP(2)    I38 @T6G_MB_LIB.T6G(SCH_1):PAGE394
   ED2 P5E_CPU1_P1_RX_BUF_DN<2> @T6G_MB_LIB.T6G(SCH_1):P5E_CPU1_P1_RX_BUF_DN(2)    I38 @T6G_MB_LIB.T6G(SCH_1):PAGE394
   EN1 P5E_CPU1_P1_RX_BUF_DP<1> @T6G_MB_LIB.T6G(SCH_1):P5E_CPU1_P1_RX_BUF_DP(1)    I38 @T6G_MB_LIB.T6G(SCH_1):PAGE394
   EL2 P5E_CPU1_P1_RX_BUF_DN<1> @T6G_MB_LIB.T6G(SCH_1):P5E_CPU1_P1_RX_BUF_DN(1)    I38 @T6G_MB_LIB.T6G(SCH_1):PAGE394
   EY1 P5E_CPU1_P1_RX_BUF_DP<0> @T6G_MB_LIB.T6G(SCH_1):P5E_CPU1_P1_RX_BUF_DP(0)    I38 @T6G_MB_LIB.T6G(SCH_1):PAGE394
   EV2 P5E_CPU1_P1_RX_BUF_DN<0> @T6G_MB_LIB.T6G(SCH_1):P5E_CPU1_P1_RX_BUF_DN(0)    I38 @T6G_MB_LIB.T6G(SCH_1):PAGE394
   FJ6     NC     NC    I47 @T6G_MB_LIB.T6G(SCH_1):PAGE392
  FJ23     NC     NC    I47 @T6G_MB_LIB.T6G(SCH_1):PAGE392
  FJ25 GPIO2_RT_CPU1_P1 @T6G_MB_LIB.T6G(SCH_1):GPIO2_RT_CPU1_P1    I47 @T6G_MB_LIB.T6G(SCH_1):PAGE392
  FJ28 GPIO3_RT_CPU1_P1 @T6G_MB_LIB.T6G(SCH_1):GPIO3_RT_CPU1_P1    I47 @T6G_MB_LIB.T6G(SCH_1):PAGE392
  FJ31     NC     NC    I47 @T6G_MB_LIB.T6G(SCH_1):PAGE392
    B3 JTAG_TCK_RT_CPU1_P1 @T6G_MB_LIB.T6G(SCH_1):JTAG_TCK_RT_CPU1_P1    I47 @T6G_MB_LIB.T6G(SCH_1):PAGE392
    B6 JTAG_TDI_RT_CPU1_P1 @T6G_MB_LIB.T6G(SCH_1):JTAG_TDI_RT_CPU1_P1    I47 @T6G_MB_LIB.T6G(SCH_1):PAGE392
    B9 JTAG_TDO_RT_CPU1_P1 @T6G_MB_LIB.T6G(SCH_1):JTAG_TDO_RT_CPU1_P1    I47 @T6G_MB_LIB.T6G(SCH_1):PAGE392
   FF8 JTAG_TEST_MODE_RT_CPU1_P1 @T6G_MB_LIB.T6G(SCH_1):JTAG_TEST_MODE_RT_CPU1_P1    I47 @T6G_MB_LIB.T6G(SCH_1):PAGE392
   B12 JTAG_TMS_RT_CPU1_P1 @T6G_MB_LIB.T6G(SCH_1):JTAG_TMS_RT_CPU1_P1    I47 @T6G_MB_LIB.T6G(SCH_1):PAGE392
    E8 JTAG_TRST_RT_CPU1_P1_N @T6G_MB_LIB.T6G(SCH_1):JTAG_TRST_RT_CPU1_P1_N    I47 @T6G_MB_LIB.T6G(SCH_1):PAGE392
   FJ9 MODE_RT_CPU1_P1 @T6G_MB_LIB.T6G(SCH_1):MODE_RT_CPU1_P1    I47 @T6G_MB_LIB.T6G(SCH_1):PAGE392
    F2 RST_RT_CPU1_P1_PERST_N @T6G_MB_LIB.T6G(SCH_1):RST_RT_CPU1_P1_PERST_N    I47 @T6G_MB_LIB.T6G(SCH_1):PAGE392
   E18     NC     NC    I47 @T6G_MB_LIB.T6G(SCH_1):PAGE392
   B16     NC     NC    I47 @T6G_MB_LIB.T6G(SCH_1):PAGE392
  FF18 CLK_100M_RETIMER_CPU1_P1_DN @T6G_MB_LIB.T6G(SCH_1):CLK_100M_RETIMER_CPU1_P1_DN    I47 @T6G_MB_LIB.T6G(SCH_1):PAGE392
  FJ16 CLK_100M_RETIMER_CPU1_P1_DP @T6G_MB_LIB.T6G(SCH_1):CLK_100M_RETIMER_CPU1_P1_DP    I47 @T6G_MB_LIB.T6G(SCH_1):PAGE392
  FF11 RST_RT_CPU1_P1_RESET_N @T6G_MB_LIB.T6G(SCH_1):RST_RT_CPU1_P1_RESET_N    I47 @T6G_MB_LIB.T6G(SCH_1):PAGE392
   E11 RXDET_BYP_RT_CPU1_P1 @T6G_MB_LIB.T6G(SCH_1):RXDET_BYP_RT_CPU1_P1    I47 @T6G_MB_LIB.T6G(SCH_1):PAGE392
  FF33 RT_CPU1_P1_SCAN_MODE @T6G_MB_LIB.T6G(SCH_1):RT_CPU1_P1_SCAN_MODE    I47 @T6G_MB_LIB.T6G(SCH_1):PAGE392
   F34 RT_CPU1_P1_ADDR1 @T6G_MB_LIB.T6G(SCH_1):RT_CPU1_P1_ADDR1    I47 @T6G_MB_LIB.T6G(SCH_1):PAGE392
   B23 RT_CPU1_P1_ADDR2 @T6G_MB_LIB.T6G(SCH_1):RT_CPU1_P1_ADDR2    I47 @T6G_MB_LIB.T6G(SCH_1):PAGE392
   B25 RT_CPU1_P1_ADDR3 @T6G_MB_LIB.T6G(SCH_1):RT_CPU1_P1_ADDR3    I47 @T6G_MB_LIB.T6G(SCH_1):PAGE392
   B31 SMB_RT_CPU1_P1_R2_SCL @T6G_MB_LIB.T6G(SCH_1):SMB_RT_CPU1_P1_R2_SCL    I47 @T6G_MB_LIB.T6G(SCH_1):PAGE392
   B28 SMB_RT_CPU1_P1_R2_SDA @T6G_MB_LIB.T6G(SCH_1):SMB_RT_CPU1_P1_R2_SDA    I47 @T6G_MB_LIB.T6G(SCH_1):PAGE392
   E30    GND @T6G_MB_LIB.T6G(SCH_1):GND    I47 @T6G_MB_LIB.T6G(SCH_1):PAGE392
  FF24 TEST0_RT_CPU1_P1 @T6G_MB_LIB.T6G(SCH_1):TEST0_RT_CPU1_P1    I47 @T6G_MB_LIB.T6G(SCH_1):PAGE392
  FF27 TEST1_RT_CPU1_P1 @T6G_MB_LIB.T6G(SCH_1):TEST1_RT_CPU1_P1    I47 @T6G_MB_LIB.T6G(SCH_1):PAGE392
  FF30 TEST2_RT_CPU1_P1 @T6G_MB_LIB.T6G(SCH_1):TEST2_RT_CPU1_P1    I47 @T6G_MB_LIB.T6G(SCH_1):PAGE392
   G35 CLKREQ_RT_CPU1_P1_N @T6G_MB_LIB.T6G(SCH_1):CLKREQ_RT_CPU1_P1_N    I47 @T6G_MB_LIB.T6G(SCH_1):PAGE392
   FF5 SMB_RT_CPU1_P1_ROM_MUX_1D_R_SCL @T6G_MB_LIB.T6G(SCH_1):SMB_RT_CPU1_P1_ROM_MUX_1D_R_SCL    I47 @T6G_MB_LIB.T6G(SCH_1):PAGE392
   FJ3 SMB_RT_CPU1_P1_ROM_MUX_1D_R_SDA @T6G_MB_LIB.T6G(SCH_1):SMB_RT_CPU1_P1_ROM_MUX_1D_R_SDA    I47 @T6G_MB_LIB.T6G(SCH_1):PAGE392
    G1 RT_CPU1_P1_VQPS @T6G_MB_LIB.T6G(SCH_1):RT_CPU1_P1_VQPS     I5 @T6G_MB_LIB.T6G(SCH_1):PAGE391
  BV20 P1V8_CPU1_RT1_1A @T6G_MB_LIB.T6G(SCH_1):P1V8_CPU1_RT1_1A     I5 @T6G_MB_LIB.T6G(SCH_1):PAGE391
  CE17 P1V8_CPU1_RT1_1A @T6G_MB_LIB.T6G(SCH_1):P1V8_CPU1_RT1_1A     I5 @T6G_MB_LIB.T6G(SCH_1):PAGE391
  CE20 P1V8_CPU1_RT1_1A @T6G_MB_LIB.T6G(SCH_1):P1V8_CPU1_RT1_1A     I5 @T6G_MB_LIB.T6G(SCH_1):PAGE391
  CM17 P1V8_CPU1_RT1_1A @T6G_MB_LIB.T6G(SCH_1):P1V8_CPU1_RT1_1A     I5 @T6G_MB_LIB.T6G(SCH_1):PAGE391
  CM20 P1V8_CPU1_RT1_1A @T6G_MB_LIB.T6G(SCH_1):P1V8_CPU1_RT1_1A     I5 @T6G_MB_LIB.T6G(SCH_1):PAGE391
  BL17 P0V9_CPU1_RT_2D @T6G_MB_LIB.T6G(SCH_1):P0V9_CPU1_RT_2D     I5 @T6G_MB_LIB.T6G(SCH_1):PAGE391
  BL20 P0V9_CPU1_RT_2D @T6G_MB_LIB.T6G(SCH_1):P0V9_CPU1_RT_2D     I5 @T6G_MB_LIB.T6G(SCH_1):PAGE391
  CW17 P0V9_CPU1_RT_2D @T6G_MB_LIB.T6G(SCH_1):P0V9_CPU1_RT_2D     I5 @T6G_MB_LIB.T6G(SCH_1):PAGE391
  CW20 P0V9_CPU1_RT_2D @T6G_MB_LIB.T6G(SCH_1):P0V9_CPU1_RT_2D     I5 @T6G_MB_LIB.T6G(SCH_1):PAGE391
  BV17 P1V8_CPU1_RT1_1A_1D @T6G_MB_LIB.T6G(SCH_1):P1V8_CPU1_RT1_1A_1D     I5 @T6G_MB_LIB.T6G(SCH_1):PAGE391
  AC17 P0V9_CPU1_RT1_2A @T6G_MB_LIB.T6G(SCH_1):P0V9_CPU1_RT1_2A     I5 @T6G_MB_LIB.T6G(SCH_1):PAGE391
  AC20 P0V9_CPU1_RT1_2A @T6G_MB_LIB.T6G(SCH_1):P0V9_CPU1_RT1_2A     I5 @T6G_MB_LIB.T6G(SCH_1):PAGE391
  AK17 P0V9_CPU1_RT1_2A @T6G_MB_LIB.T6G(SCH_1):P0V9_CPU1_RT1_2A     I5 @T6G_MB_LIB.T6G(SCH_1):PAGE391
  AK20 P0V9_CPU1_RT1_2A @T6G_MB_LIB.T6G(SCH_1):P0V9_CPU1_RT1_2A     I5 @T6G_MB_LIB.T6G(SCH_1):PAGE391
  AU17 P0V9_CPU1_RT1_2A @T6G_MB_LIB.T6G(SCH_1):P0V9_CPU1_RT1_2A     I5 @T6G_MB_LIB.T6G(SCH_1):PAGE391
  AU20 P0V9_CPU1_RT1_2A @T6G_MB_LIB.T6G(SCH_1):P0V9_CPU1_RT1_2A     I5 @T6G_MB_LIB.T6G(SCH_1):PAGE391
  BD17 P0V9_CPU1_RT1_2A_2D @T6G_MB_LIB.T6G(SCH_1):P0V9_CPU1_RT1_2A_2D     I5 @T6G_MB_LIB.T6G(SCH_1):PAGE391
  BD20 P0V9_CPU1_RT1_2A_2D @T6G_MB_LIB.T6G(SCH_1):P0V9_CPU1_RT1_2A_2D     I5 @T6G_MB_LIB.T6G(SCH_1):PAGE391
  DF17 P0V9_CPU1_RT1_2A_2D @T6G_MB_LIB.T6G(SCH_1):P0V9_CPU1_RT1_2A_2D     I5 @T6G_MB_LIB.T6G(SCH_1):PAGE391
  DF20 P0V9_CPU1_RT1_2A_2D @T6G_MB_LIB.T6G(SCH_1):P0V9_CPU1_RT1_2A_2D     I5 @T6G_MB_LIB.T6G(SCH_1):PAGE391
  DN17 P0V9_CPU1_RT1_2A @T6G_MB_LIB.T6G(SCH_1):P0V9_CPU1_RT1_2A     I5 @T6G_MB_LIB.T6G(SCH_1):PAGE391
  DN20 P0V9_CPU1_RT1_2A @T6G_MB_LIB.T6G(SCH_1):P0V9_CPU1_RT1_2A     I5 @T6G_MB_LIB.T6G(SCH_1):PAGE391
  DY17 P0V9_CPU1_RT1_2A @T6G_MB_LIB.T6G(SCH_1):P0V9_CPU1_RT1_2A     I5 @T6G_MB_LIB.T6G(SCH_1):PAGE391
  DY20 P0V9_CPU1_RT1_2A @T6G_MB_LIB.T6G(SCH_1):P0V9_CPU1_RT1_2A     I5 @T6G_MB_LIB.T6G(SCH_1):PAGE391
  EG17 P0V9_CPU1_RT1_2A @T6G_MB_LIB.T6G(SCH_1):P0V9_CPU1_RT1_2A     I5 @T6G_MB_LIB.T6G(SCH_1):PAGE391
  EG20 P0V9_CPU1_RT1_2A @T6G_MB_LIB.T6G(SCH_1):P0V9_CPU1_RT1_2A     I5 @T6G_MB_LIB.T6G(SCH_1):PAGE391
  EP17 P0V9_CPU1_RT1_2A @T6G_MB_LIB.T6G(SCH_1):P0V9_CPU1_RT1_2A     I5 @T6G_MB_LIB.T6G(SCH_1):PAGE391
  EP20 P0V9_CPU1_RT1_2A @T6G_MB_LIB.T6G(SCH_1):P0V9_CPU1_RT1_2A     I5 @T6G_MB_LIB.T6G(SCH_1):PAGE391
   T17 P0V9_CPU1_RT1_2A @T6G_MB_LIB.T6G(SCH_1):P0V9_CPU1_RT1_2A     I5 @T6G_MB_LIB.T6G(SCH_1):PAGE391
   T20 P0V9_CPU1_RT1_2A @T6G_MB_LIB.T6G(SCH_1):P0V9_CPU1_RT1_2A     I5 @T6G_MB_LIB.T6G(SCH_1):PAGE391
  AC13    GND @T6G_MB_LIB.T6G(SCH_1):GND    I19 @T6G_MB_LIB.T6G(SCH_1):PAGE391
  AC22    GND @T6G_MB_LIB.T6G(SCH_1):GND    I19 @T6G_MB_LIB.T6G(SCH_1):PAGE391
  AC32    GND @T6G_MB_LIB.T6G(SCH_1):GND    I19 @T6G_MB_LIB.T6G(SCH_1):PAGE391
   AC4    GND @T6G_MB_LIB.T6G(SCH_1):GND    I19 @T6G_MB_LIB.T6G(SCH_1):PAGE391
   AD2    GND @T6G_MB_LIB.T6G(SCH_1):GND    I19 @T6G_MB_LIB.T6G(SCH_1):PAGE391
  AD34    GND @T6G_MB_LIB.T6G(SCH_1):GND    I19 @T6G_MB_LIB.T6G(SCH_1):PAGE391
   AE1    GND @T6G_MB_LIB.T6G(SCH_1):GND    I19 @T6G_MB_LIB.T6G(SCH_1):PAGE391
  AE35    GND @T6G_MB_LIB.T6G(SCH_1):GND    I19 @T6G_MB_LIB.T6G(SCH_1):PAGE391
  AK13    GND @T6G_MB_LIB.T6G(SCH_1):GND    I19 @T6G_MB_LIB.T6G(SCH_1):PAGE391
  AK22    GND @T6G_MB_LIB.T6G(SCH_1):GND    I19 @T6G_MB_LIB.T6G(SCH_1):PAGE391
  AK32    GND @T6G_MB_LIB.T6G(SCH_1):GND    I19 @T6G_MB_LIB.T6G(SCH_1):PAGE391
   AK4    GND @T6G_MB_LIB.T6G(SCH_1):GND    I19 @T6G_MB_LIB.T6G(SCH_1):PAGE391
   AL2    GND @T6G_MB_LIB.T6G(SCH_1):GND    I19 @T6G_MB_LIB.T6G(SCH_1):PAGE391
  AL34    GND @T6G_MB_LIB.T6G(SCH_1):GND    I19 @T6G_MB_LIB.T6G(SCH_1):PAGE391
   AM1    GND @T6G_MB_LIB.T6G(SCH_1):GND    I19 @T6G_MB_LIB.T6G(SCH_1):PAGE391
  AM35    GND @T6G_MB_LIB.T6G(SCH_1):GND    I19 @T6G_MB_LIB.T6G(SCH_1):PAGE391
  AU13    GND @T6G_MB_LIB.T6G(SCH_1):GND    I19 @T6G_MB_LIB.T6G(SCH_1):PAGE391
  AU22    GND @T6G_MB_LIB.T6G(SCH_1):GND    I19 @T6G_MB_LIB.T6G(SCH_1):PAGE391
  AU32    GND @T6G_MB_LIB.T6G(SCH_1):GND    I19 @T6G_MB_LIB.T6G(SCH_1):PAGE391
   AU4    GND @T6G_MB_LIB.T6G(SCH_1):GND    I19 @T6G_MB_LIB.T6G(SCH_1):PAGE391
   AV2    GND @T6G_MB_LIB.T6G(SCH_1):GND    I19 @T6G_MB_LIB.T6G(SCH_1):PAGE391
  AV34    GND @T6G_MB_LIB.T6G(SCH_1):GND    I19 @T6G_MB_LIB.T6G(SCH_1):PAGE391
   AW1    GND @T6G_MB_LIB.T6G(SCH_1):GND    I19 @T6G_MB_LIB.T6G(SCH_1):PAGE391
  AW35    GND @T6G_MB_LIB.T6G(SCH_1):GND    I19 @T6G_MB_LIB.T6G(SCH_1):PAGE391
   B19    GND @T6G_MB_LIB.T6G(SCH_1):GND    I19 @T6G_MB_LIB.T6G(SCH_1):PAGE391
  BD13    GND @T6G_MB_LIB.T6G(SCH_1):GND    I19 @T6G_MB_LIB.T6G(SCH_1):PAGE391
  BD22    GND @T6G_MB_LIB.T6G(SCH_1):GND    I19 @T6G_MB_LIB.T6G(SCH_1):PAGE391
  BD32    GND @T6G_MB_LIB.T6G(SCH_1):GND    I19 @T6G_MB_LIB.T6G(SCH_1):PAGE391
   BD4    GND @T6G_MB_LIB.T6G(SCH_1):GND    I19 @T6G_MB_LIB.T6G(SCH_1):PAGE391
   BE2    GND @T6G_MB_LIB.T6G(SCH_1):GND    I19 @T6G_MB_LIB.T6G(SCH_1):PAGE391
  BE34    GND @T6G_MB_LIB.T6G(SCH_1):GND    I19 @T6G_MB_LIB.T6G(SCH_1):PAGE391
   BF1    GND @T6G_MB_LIB.T6G(SCH_1):GND    I19 @T6G_MB_LIB.T6G(SCH_1):PAGE391
  BF35    GND @T6G_MB_LIB.T6G(SCH_1):GND    I19 @T6G_MB_LIB.T6G(SCH_1):PAGE391
  BL13    GND @T6G_MB_LIB.T6G(SCH_1):GND    I19 @T6G_MB_LIB.T6G(SCH_1):PAGE391
  BL22    GND @T6G_MB_LIB.T6G(SCH_1):GND    I19 @T6G_MB_LIB.T6G(SCH_1):PAGE391
  BL32    GND @T6G_MB_LIB.T6G(SCH_1):GND    I19 @T6G_MB_LIB.T6G(SCH_1):PAGE391
   BL4    GND @T6G_MB_LIB.T6G(SCH_1):GND    I19 @T6G_MB_LIB.T6G(SCH_1):PAGE391
   BM2    GND @T6G_MB_LIB.T6G(SCH_1):GND    I19 @T6G_MB_LIB.T6G(SCH_1):PAGE391
  BM34    GND @T6G_MB_LIB.T6G(SCH_1):GND    I19 @T6G_MB_LIB.T6G(SCH_1):PAGE391
   BN1    GND @T6G_MB_LIB.T6G(SCH_1):GND    I19 @T6G_MB_LIB.T6G(SCH_1):PAGE391
  BN35    GND @T6G_MB_LIB.T6G(SCH_1):GND    I19 @T6G_MB_LIB.T6G(SCH_1):PAGE391
  BV13    GND @T6G_MB_LIB.T6G(SCH_1):GND    I19 @T6G_MB_LIB.T6G(SCH_1):PAGE391
  BV22    GND @T6G_MB_LIB.T6G(SCH_1):GND    I19 @T6G_MB_LIB.T6G(SCH_1):PAGE391
  BV32    GND @T6G_MB_LIB.T6G(SCH_1):GND    I19 @T6G_MB_LIB.T6G(SCH_1):PAGE391
   BV4    GND @T6G_MB_LIB.T6G(SCH_1):GND    I19 @T6G_MB_LIB.T6G(SCH_1):PAGE391
   BW2    GND @T6G_MB_LIB.T6G(SCH_1):GND    I19 @T6G_MB_LIB.T6G(SCH_1):PAGE391
  BW34    GND @T6G_MB_LIB.T6G(SCH_1):GND    I19 @T6G_MB_LIB.T6G(SCH_1):PAGE391
   BY1    GND @T6G_MB_LIB.T6G(SCH_1):GND    I19 @T6G_MB_LIB.T6G(SCH_1):PAGE391
  BY35    GND @T6G_MB_LIB.T6G(SCH_1):GND    I19 @T6G_MB_LIB.T6G(SCH_1):PAGE391
  CE13    GND @T6G_MB_LIB.T6G(SCH_1):GND    I19 @T6G_MB_LIB.T6G(SCH_1):PAGE391
  CE22    GND @T6G_MB_LIB.T6G(SCH_1):GND    I19 @T6G_MB_LIB.T6G(SCH_1):PAGE391
  CE32    GND @T6G_MB_LIB.T6G(SCH_1):GND    I19 @T6G_MB_LIB.T6G(SCH_1):PAGE391
   CE4    GND @T6G_MB_LIB.T6G(SCH_1):GND    I19 @T6G_MB_LIB.T6G(SCH_1):PAGE391
   CF2    GND @T6G_MB_LIB.T6G(SCH_1):GND    I19 @T6G_MB_LIB.T6G(SCH_1):PAGE391
  CF34    GND @T6G_MB_LIB.T6G(SCH_1):GND    I19 @T6G_MB_LIB.T6G(SCH_1):PAGE391
   CG1    GND @T6G_MB_LIB.T6G(SCH_1):GND    I19 @T6G_MB_LIB.T6G(SCH_1):PAGE391
  CG35    GND @T6G_MB_LIB.T6G(SCH_1):GND    I19 @T6G_MB_LIB.T6G(SCH_1):PAGE391
  CM13    GND @T6G_MB_LIB.T6G(SCH_1):GND    I19 @T6G_MB_LIB.T6G(SCH_1):PAGE391
  CM22    GND @T6G_MB_LIB.T6G(SCH_1):GND    I19 @T6G_MB_LIB.T6G(SCH_1):PAGE391
  CM32    GND @T6G_MB_LIB.T6G(SCH_1):GND    I19 @T6G_MB_LIB.T6G(SCH_1):PAGE391
   CM4    GND @T6G_MB_LIB.T6G(SCH_1):GND    I19 @T6G_MB_LIB.T6G(SCH_1):PAGE391
   CN2    GND @T6G_MB_LIB.T6G(SCH_1):GND    I19 @T6G_MB_LIB.T6G(SCH_1):PAGE391
  CN34    GND @T6G_MB_LIB.T6G(SCH_1):GND    I19 @T6G_MB_LIB.T6G(SCH_1):PAGE391
   CP1    GND @T6G_MB_LIB.T6G(SCH_1):GND    I19 @T6G_MB_LIB.T6G(SCH_1):PAGE391
  CP35    GND @T6G_MB_LIB.T6G(SCH_1):GND    I19 @T6G_MB_LIB.T6G(SCH_1):PAGE391
  CW13    GND @T6G_MB_LIB.T6G(SCH_1):GND    I19 @T6G_MB_LIB.T6G(SCH_1):PAGE391
  CW22    GND @T6G_MB_LIB.T6G(SCH_1):GND    I19 @T6G_MB_LIB.T6G(SCH_1):PAGE391
  CW32    GND @T6G_MB_LIB.T6G(SCH_1):GND    I19 @T6G_MB_LIB.T6G(SCH_1):PAGE391
   CW4    GND @T6G_MB_LIB.T6G(SCH_1):GND    I19 @T6G_MB_LIB.T6G(SCH_1):PAGE391
   CY2    GND @T6G_MB_LIB.T6G(SCH_1):GND    I19 @T6G_MB_LIB.T6G(SCH_1):PAGE391
  CY34    GND @T6G_MB_LIB.T6G(SCH_1):GND    I19 @T6G_MB_LIB.T6G(SCH_1):PAGE391
   DA1    GND @T6G_MB_LIB.T6G(SCH_1):GND    I19 @T6G_MB_LIB.T6G(SCH_1):PAGE391
  DA35    GND @T6G_MB_LIB.T6G(SCH_1):GND    I19 @T6G_MB_LIB.T6G(SCH_1):PAGE391
  DF13    GND @T6G_MB_LIB.T6G(SCH_1):GND    I19 @T6G_MB_LIB.T6G(SCH_1):PAGE391
  DF22    GND @T6G_MB_LIB.T6G(SCH_1):GND    I19 @T6G_MB_LIB.T6G(SCH_1):PAGE391
  DF32    GND @T6G_MB_LIB.T6G(SCH_1):GND    I19 @T6G_MB_LIB.T6G(SCH_1):PAGE391
   DF4    GND @T6G_MB_LIB.T6G(SCH_1):GND    I19 @T6G_MB_LIB.T6G(SCH_1):PAGE391
   DG2    GND @T6G_MB_LIB.T6G(SCH_1):GND    I19 @T6G_MB_LIB.T6G(SCH_1):PAGE391
  DG34    GND @T6G_MB_LIB.T6G(SCH_1):GND    I19 @T6G_MB_LIB.T6G(SCH_1):PAGE391
   DH1    GND @T6G_MB_LIB.T6G(SCH_1):GND    I19 @T6G_MB_LIB.T6G(SCH_1):PAGE391
  DH35    GND @T6G_MB_LIB.T6G(SCH_1):GND    I19 @T6G_MB_LIB.T6G(SCH_1):PAGE391
  DN13    GND @T6G_MB_LIB.T6G(SCH_1):GND    I19 @T6G_MB_LIB.T6G(SCH_1):PAGE391
    A1 NCF_A1_CPU1_P1_GND @T6G_MB_LIB.T6G(SCH_1):NCF_A1_CPU1_P1_GND    I19 @T6G_MB_LIB.T6G(SCH_1):PAGE391
   A35 NCF_CPU1_P1_GND @T6G_MB_LIB.T6G(SCH_1):NCF_CPU1_P1_GND    I19 @T6G_MB_LIB.T6G(SCH_1):PAGE391
    C2 NCF_CPU1_P1_GND @T6G_MB_LIB.T6G(SCH_1):NCF_CPU1_P1_GND    I19 @T6G_MB_LIB.T6G(SCH_1):PAGE391
   C34 NCF_CPU1_P1_GND @T6G_MB_LIB.T6G(SCH_1):NCF_CPU1_P1_GND    I19 @T6G_MB_LIB.T6G(SCH_1):PAGE391
    D1 NCF_CPU1_P1_GND @T6G_MB_LIB.T6G(SCH_1):NCF_CPU1_P1_GND    I19 @T6G_MB_LIB.T6G(SCH_1):PAGE391
   D35 NCF_CPU1_P1_GND @T6G_MB_LIB.T6G(SCH_1):NCF_CPU1_P1_GND    I19 @T6G_MB_LIB.T6G(SCH_1):PAGE391
   FE2 NCF_CPU1_P1_GND @T6G_MB_LIB.T6G(SCH_1):NCF_CPU1_P1_GND    I19 @T6G_MB_LIB.T6G(SCH_1):PAGE391
  FE34 NCF_CPU1_P1_GND @T6G_MB_LIB.T6G(SCH_1):NCF_CPU1_P1_GND    I19 @T6G_MB_LIB.T6G(SCH_1):PAGE391
   FG1 NCF_CPU1_P1_GND @T6G_MB_LIB.T6G(SCH_1):NCF_CPU1_P1_GND    I19 @T6G_MB_LIB.T6G(SCH_1):PAGE391
  FG35 NCF_CPU1_P1_GND @T6G_MB_LIB.T6G(SCH_1):NCF_CPU1_P1_GND    I19 @T6G_MB_LIB.T6G(SCH_1):PAGE391
   FH2 NCF_CPU1_P1_GND @T6G_MB_LIB.T6G(SCH_1):NCF_CPU1_P1_GND    I19 @T6G_MB_LIB.T6G(SCH_1):PAGE391
  FH34 NCF_CPU1_P1_GND @T6G_MB_LIB.T6G(SCH_1):NCF_CPU1_P1_GND    I19 @T6G_MB_LIB.T6G(SCH_1):PAGE391
  DN22    GND @T6G_MB_LIB.T6G(SCH_1):GND    I19 @T6G_MB_LIB.T6G(SCH_1):PAGE391
  DN32    GND @T6G_MB_LIB.T6G(SCH_1):GND    I19 @T6G_MB_LIB.T6G(SCH_1):PAGE391
   DN4    GND @T6G_MB_LIB.T6G(SCH_1):GND    I19 @T6G_MB_LIB.T6G(SCH_1):PAGE391
   DP2    GND @T6G_MB_LIB.T6G(SCH_1):GND    I19 @T6G_MB_LIB.T6G(SCH_1):PAGE391
  DP34    GND @T6G_MB_LIB.T6G(SCH_1):GND    I19 @T6G_MB_LIB.T6G(SCH_1):PAGE391
   DR1    GND @T6G_MB_LIB.T6G(SCH_1):GND    I19 @T6G_MB_LIB.T6G(SCH_1):PAGE391
  DR35    GND @T6G_MB_LIB.T6G(SCH_1):GND    I19 @T6G_MB_LIB.T6G(SCH_1):PAGE391
  DY13    GND @T6G_MB_LIB.T6G(SCH_1):GND    I19 @T6G_MB_LIB.T6G(SCH_1):PAGE391
  DY22    GND @T6G_MB_LIB.T6G(SCH_1):GND    I19 @T6G_MB_LIB.T6G(SCH_1):PAGE391
  DY32    GND @T6G_MB_LIB.T6G(SCH_1):GND    I19 @T6G_MB_LIB.T6G(SCH_1):PAGE391
   DY4    GND @T6G_MB_LIB.T6G(SCH_1):GND    I19 @T6G_MB_LIB.T6G(SCH_1):PAGE391
   E14    GND @T6G_MB_LIB.T6G(SCH_1):GND    I19 @T6G_MB_LIB.T6G(SCH_1):PAGE391
   E27    GND @T6G_MB_LIB.T6G(SCH_1):GND    I19 @T6G_MB_LIB.T6G(SCH_1):PAGE391
   E33    GND @T6G_MB_LIB.T6G(SCH_1):GND    I19 @T6G_MB_LIB.T6G(SCH_1):PAGE391
   EA2    GND @T6G_MB_LIB.T6G(SCH_1):GND    I19 @T6G_MB_LIB.T6G(SCH_1):PAGE391
  EA34    GND @T6G_MB_LIB.T6G(SCH_1):GND    I19 @T6G_MB_LIB.T6G(SCH_1):PAGE391
   EB1    GND @T6G_MB_LIB.T6G(SCH_1):GND    I19 @T6G_MB_LIB.T6G(SCH_1):PAGE391
  EB35    GND @T6G_MB_LIB.T6G(SCH_1):GND    I19 @T6G_MB_LIB.T6G(SCH_1):PAGE391
  EG13    GND @T6G_MB_LIB.T6G(SCH_1):GND    I19 @T6G_MB_LIB.T6G(SCH_1):PAGE391
  EG22    GND @T6G_MB_LIB.T6G(SCH_1):GND    I19 @T6G_MB_LIB.T6G(SCH_1):PAGE391
  EG32    GND @T6G_MB_LIB.T6G(SCH_1):GND    I19 @T6G_MB_LIB.T6G(SCH_1):PAGE391
   EG4    GND @T6G_MB_LIB.T6G(SCH_1):GND    I19 @T6G_MB_LIB.T6G(SCH_1):PAGE391
   EH2    GND @T6G_MB_LIB.T6G(SCH_1):GND    I19 @T6G_MB_LIB.T6G(SCH_1):PAGE391
  EH34    GND @T6G_MB_LIB.T6G(SCH_1):GND    I19 @T6G_MB_LIB.T6G(SCH_1):PAGE391
   EJ1    GND @T6G_MB_LIB.T6G(SCH_1):GND    I19 @T6G_MB_LIB.T6G(SCH_1):PAGE391
  EJ35    GND @T6G_MB_LIB.T6G(SCH_1):GND    I19 @T6G_MB_LIB.T6G(SCH_1):PAGE391
  EP13    GND @T6G_MB_LIB.T6G(SCH_1):GND    I19 @T6G_MB_LIB.T6G(SCH_1):PAGE391
  EP22    GND @T6G_MB_LIB.T6G(SCH_1):GND    I19 @T6G_MB_LIB.T6G(SCH_1):PAGE391
  EP32    GND @T6G_MB_LIB.T6G(SCH_1):GND    I19 @T6G_MB_LIB.T6G(SCH_1):PAGE391
   EP4    GND @T6G_MB_LIB.T6G(SCH_1):GND    I19 @T6G_MB_LIB.T6G(SCH_1):PAGE391
   ER2    GND @T6G_MB_LIB.T6G(SCH_1):GND    I19 @T6G_MB_LIB.T6G(SCH_1):PAGE391
  ER34    GND @T6G_MB_LIB.T6G(SCH_1):GND    I19 @T6G_MB_LIB.T6G(SCH_1):PAGE391
   ET1    GND @T6G_MB_LIB.T6G(SCH_1):GND    I19 @T6G_MB_LIB.T6G(SCH_1):PAGE391
  ET35    GND @T6G_MB_LIB.T6G(SCH_1):GND    I19 @T6G_MB_LIB.T6G(SCH_1):PAGE391
  FA15    GND @T6G_MB_LIB.T6G(SCH_1):GND    I19 @T6G_MB_LIB.T6G(SCH_1):PAGE391
  FA32    GND @T6G_MB_LIB.T6G(SCH_1):GND    I19 @T6G_MB_LIB.T6G(SCH_1):PAGE391
   FB2    GND @T6G_MB_LIB.T6G(SCH_1):GND    I19 @T6G_MB_LIB.T6G(SCH_1):PAGE391
  FB34    GND @T6G_MB_LIB.T6G(SCH_1):GND    I19 @T6G_MB_LIB.T6G(SCH_1):PAGE391
  FC19    GND @T6G_MB_LIB.T6G(SCH_1):GND    I19 @T6G_MB_LIB.T6G(SCH_1):PAGE391
  FC23    GND @T6G_MB_LIB.T6G(SCH_1):GND    I19 @T6G_MB_LIB.T6G(SCH_1):PAGE391
  FC25    GND @T6G_MB_LIB.T6G(SCH_1):GND    I19 @T6G_MB_LIB.T6G(SCH_1):PAGE391
  FC28    GND @T6G_MB_LIB.T6G(SCH_1):GND    I19 @T6G_MB_LIB.T6G(SCH_1):PAGE391
   FC3    GND @T6G_MB_LIB.T6G(SCH_1):GND    I19 @T6G_MB_LIB.T6G(SCH_1):PAGE391
   FC6    GND @T6G_MB_LIB.T6G(SCH_1):GND    I19 @T6G_MB_LIB.T6G(SCH_1):PAGE391
   FC9    GND @T6G_MB_LIB.T6G(SCH_1):GND    I19 @T6G_MB_LIB.T6G(SCH_1):PAGE391
   FD1    GND @T6G_MB_LIB.T6G(SCH_1):GND    I19 @T6G_MB_LIB.T6G(SCH_1):PAGE391
  FD35    GND @T6G_MB_LIB.T6G(SCH_1):GND    I19 @T6G_MB_LIB.T6G(SCH_1):PAGE391
  FF14    GND @T6G_MB_LIB.T6G(SCH_1):GND    I19 @T6G_MB_LIB.T6G(SCH_1):PAGE391
  FF21    GND @T6G_MB_LIB.T6G(SCH_1):GND    I19 @T6G_MB_LIB.T6G(SCH_1):PAGE391
  FJ12    GND @T6G_MB_LIB.T6G(SCH_1):GND    I19 @T6G_MB_LIB.T6G(SCH_1):PAGE391
  FJ19    GND @T6G_MB_LIB.T6G(SCH_1):GND    I19 @T6G_MB_LIB.T6G(SCH_1):PAGE391
   H12    GND @T6G_MB_LIB.T6G(SCH_1):GND    I19 @T6G_MB_LIB.T6G(SCH_1):PAGE391
   H16    GND @T6G_MB_LIB.T6G(SCH_1):GND    I19 @T6G_MB_LIB.T6G(SCH_1):PAGE391
   H19    GND @T6G_MB_LIB.T6G(SCH_1):GND    I19 @T6G_MB_LIB.T6G(SCH_1):PAGE391
   H31    GND @T6G_MB_LIB.T6G(SCH_1):GND    I19 @T6G_MB_LIB.T6G(SCH_1):PAGE391
   J22    GND @T6G_MB_LIB.T6G(SCH_1):GND    I19 @T6G_MB_LIB.T6G(SCH_1):PAGE391
    J4    GND @T6G_MB_LIB.T6G(SCH_1):GND    I19 @T6G_MB_LIB.T6G(SCH_1):PAGE391
    K2    GND @T6G_MB_LIB.T6G(SCH_1):GND    I19 @T6G_MB_LIB.T6G(SCH_1):PAGE391
   K34    GND @T6G_MB_LIB.T6G(SCH_1):GND    I19 @T6G_MB_LIB.T6G(SCH_1):PAGE391
    L1    GND @T6G_MB_LIB.T6G(SCH_1):GND    I19 @T6G_MB_LIB.T6G(SCH_1):PAGE391
   L35    GND @T6G_MB_LIB.T6G(SCH_1):GND    I19 @T6G_MB_LIB.T6G(SCH_1):PAGE391
   T13    GND @T6G_MB_LIB.T6G(SCH_1):GND    I19 @T6G_MB_LIB.T6G(SCH_1):PAGE391
   T22    GND @T6G_MB_LIB.T6G(SCH_1):GND    I19 @T6G_MB_LIB.T6G(SCH_1):PAGE391
   T32    GND @T6G_MB_LIB.T6G(SCH_1):GND    I19 @T6G_MB_LIB.T6G(SCH_1):PAGE391
    T4    GND @T6G_MB_LIB.T6G(SCH_1):GND    I19 @T6G_MB_LIB.T6G(SCH_1):PAGE391
    U2    GND @T6G_MB_LIB.T6G(SCH_1):GND    I19 @T6G_MB_LIB.T6G(SCH_1):PAGE391
   U34    GND @T6G_MB_LIB.T6G(SCH_1):GND    I19 @T6G_MB_LIB.T6G(SCH_1):PAGE391
    V1    GND @T6G_MB_LIB.T6G(SCH_1):GND    I19 @T6G_MB_LIB.T6G(SCH_1):PAGE391
   V35    GND @T6G_MB_LIB.T6G(SCH_1):GND    I19 @T6G_MB_LIB.T6G(SCH_1):PAGE391
   M26 P5E_CPU1_P1_RX_DP<15> @T6G_MB_LIB.T6G(SCH_1):P5E_CPU1_P1_RX_DP(15)     I1 @T6G_MB_LIB.T6G(SCH_1):PAGE395
   P29 P5E_CPU1_P1_RX_DN<15> @T6G_MB_LIB.T6G(SCH_1):P5E_CPU1_P1_RX_DN(15)     I1 @T6G_MB_LIB.T6G(SCH_1):PAGE395
   W26 P5E_CPU1_P1_RX_DP<14> @T6G_MB_LIB.T6G(SCH_1):P5E_CPU1_P1_RX_DP(14)     I1 @T6G_MB_LIB.T6G(SCH_1):PAGE395
  AA29 P5E_CPU1_P1_RX_DN<14> @T6G_MB_LIB.T6G(SCH_1):P5E_CPU1_P1_RX_DN(14)     I1 @T6G_MB_LIB.T6G(SCH_1):PAGE395
  AF26 P5E_CPU1_P1_RX_DP<13> @T6G_MB_LIB.T6G(SCH_1):P5E_CPU1_P1_RX_DP(13)     I1 @T6G_MB_LIB.T6G(SCH_1):PAGE395
  AH29 P5E_CPU1_P1_RX_DN<13> @T6G_MB_LIB.T6G(SCH_1):P5E_CPU1_P1_RX_DN(13)     I1 @T6G_MB_LIB.T6G(SCH_1):PAGE395
  AN26 P5E_CPU1_P1_RX_DP<12> @T6G_MB_LIB.T6G(SCH_1):P5E_CPU1_P1_RX_DP(12)     I1 @T6G_MB_LIB.T6G(SCH_1):PAGE395
  AR29 P5E_CPU1_P1_RX_DN<12> @T6G_MB_LIB.T6G(SCH_1):P5E_CPU1_P1_RX_DN(12)     I1 @T6G_MB_LIB.T6G(SCH_1):PAGE395
  AY26 P5E_CPU1_P1_RX_DP<11> @T6G_MB_LIB.T6G(SCH_1):P5E_CPU1_P1_RX_DP(11)     I1 @T6G_MB_LIB.T6G(SCH_1):PAGE395
  BB29 P5E_CPU1_P1_RX_DN<11> @T6G_MB_LIB.T6G(SCH_1):P5E_CPU1_P1_RX_DN(11)     I1 @T6G_MB_LIB.T6G(SCH_1):PAGE395
  BG26 P5E_CPU1_P1_RX_DP<10> @T6G_MB_LIB.T6G(SCH_1):P5E_CPU1_P1_RX_DP(10)     I1 @T6G_MB_LIB.T6G(SCH_1):PAGE395
  BJ29 P5E_CPU1_P1_RX_DN<10> @T6G_MB_LIB.T6G(SCH_1):P5E_CPU1_P1_RX_DN(10)     I1 @T6G_MB_LIB.T6G(SCH_1):PAGE395
  BP26 P5E_CPU1_P1_RX_DP<9> @T6G_MB_LIB.T6G(SCH_1):P5E_CPU1_P1_RX_DP(9)     I1 @T6G_MB_LIB.T6G(SCH_1):PAGE395
  BT29 P5E_CPU1_P1_RX_DN<9> @T6G_MB_LIB.T6G(SCH_1):P5E_CPU1_P1_RX_DN(9)     I1 @T6G_MB_LIB.T6G(SCH_1):PAGE395
  CA26 P5E_CPU1_P1_RX_DP<8> @T6G_MB_LIB.T6G(SCH_1):P5E_CPU1_P1_RX_DP(8)     I1 @T6G_MB_LIB.T6G(SCH_1):PAGE395
  CC29 P5E_CPU1_P1_RX_DN<8> @T6G_MB_LIB.T6G(SCH_1):P5E_CPU1_P1_RX_DN(8)     I1 @T6G_MB_LIB.T6G(SCH_1):PAGE395
  CH26 P5E_CPU1_P1_RX_DP<7> @T6G_MB_LIB.T6G(SCH_1):P5E_CPU1_P1_RX_DP(7)    I38 @T6G_MB_LIB.T6G(SCH_1):PAGE395
  CK29 P5E_CPU1_P1_RX_DN<7> @T6G_MB_LIB.T6G(SCH_1):P5E_CPU1_P1_RX_DN(7)    I38 @T6G_MB_LIB.T6G(SCH_1):PAGE395
  CR26 P5E_CPU1_P1_RX_DP<6> @T6G_MB_LIB.T6G(SCH_1):P5E_CPU1_P1_RX_DP(6)    I38 @T6G_MB_LIB.T6G(SCH_1):PAGE395
  CU29 P5E_CPU1_P1_RX_DN<6> @T6G_MB_LIB.T6G(SCH_1):P5E_CPU1_P1_RX_DN(6)    I38 @T6G_MB_LIB.T6G(SCH_1):PAGE395
  DB26 P5E_CPU1_P1_RX_DP<5> @T6G_MB_LIB.T6G(SCH_1):P5E_CPU1_P1_RX_DP(5)    I38 @T6G_MB_LIB.T6G(SCH_1):PAGE395
  DD29 P5E_CPU1_P1_RX_DN<5> @T6G_MB_LIB.T6G(SCH_1):P5E_CPU1_P1_RX_DN(5)    I38 @T6G_MB_LIB.T6G(SCH_1):PAGE395
  DJ26 P5E_CPU1_P1_RX_DP<4> @T6G_MB_LIB.T6G(SCH_1):P5E_CPU1_P1_RX_DP(4)    I38 @T6G_MB_LIB.T6G(SCH_1):PAGE395
  DL29 P5E_CPU1_P1_RX_DN<4> @T6G_MB_LIB.T6G(SCH_1):P5E_CPU1_P1_RX_DN(4)    I38 @T6G_MB_LIB.T6G(SCH_1):PAGE395
  DT26 P5E_CPU1_P1_RX_DP<3> @T6G_MB_LIB.T6G(SCH_1):P5E_CPU1_P1_RX_DP(3)    I38 @T6G_MB_LIB.T6G(SCH_1):PAGE395
  DV29 P5E_CPU1_P1_RX_DN<3> @T6G_MB_LIB.T6G(SCH_1):P5E_CPU1_P1_RX_DN(3)    I38 @T6G_MB_LIB.T6G(SCH_1):PAGE395
  EC26 P5E_CPU1_P1_RX_DP<2> @T6G_MB_LIB.T6G(SCH_1):P5E_CPU1_P1_RX_DP(2)    I38 @T6G_MB_LIB.T6G(SCH_1):PAGE395
  EE29 P5E_CPU1_P1_RX_DN<2> @T6G_MB_LIB.T6G(SCH_1):P5E_CPU1_P1_RX_DN(2)    I38 @T6G_MB_LIB.T6G(SCH_1):PAGE395
  EK26 P5E_CPU1_P1_RX_DP<1> @T6G_MB_LIB.T6G(SCH_1):P5E_CPU1_P1_RX_DP(1)    I38 @T6G_MB_LIB.T6G(SCH_1):PAGE395
  EM29 P5E_CPU1_P1_RX_DN<1> @T6G_MB_LIB.T6G(SCH_1):P5E_CPU1_P1_RX_DN(1)    I38 @T6G_MB_LIB.T6G(SCH_1):PAGE395
  EU26 P5E_CPU1_P1_RX_DP<0> @T6G_MB_LIB.T6G(SCH_1):P5E_CPU1_P1_RX_DP(0)    I38 @T6G_MB_LIB.T6G(SCH_1):PAGE395
  EW29 P5E_CPU1_P1_RX_DN<0> @T6G_MB_LIB.T6G(SCH_1):P5E_CPU1_P1_RX_DN(0)    I38 @T6G_MB_LIB.T6G(SCH_1):PAGE395
   N34 P5E_CPU1_P1_TX_C_DN<15> @T6G_MB_LIB.T6G(SCH_1):P5E_CPU1_P1_TX_C_DN(15)     I1 @T6G_MB_LIB.T6G(SCH_1):PAGE396
   R35 P5E_CPU1_P1_TX_C_DP<15> @T6G_MB_LIB.T6G(SCH_1):P5E_CPU1_P1_TX_C_DP(15)     I1 @T6G_MB_LIB.T6G(SCH_1):PAGE396
   Y34 P5E_CPU1_P1_TX_C_DP<14> @T6G_MB_LIB.T6G(SCH_1):P5E_CPU1_P1_TX_C_DP(14)     I1 @T6G_MB_LIB.T6G(SCH_1):PAGE396
  AB35 P5E_CPU1_P1_TX_C_DN<14> @T6G_MB_LIB.T6G(SCH_1):P5E_CPU1_P1_TX_C_DN(14)     I1 @T6G_MB_LIB.T6G(SCH_1):PAGE396
  AG34 P5E_CPU1_P1_TX_C_DN<13> @T6G_MB_LIB.T6G(SCH_1):P5E_CPU1_P1_TX_C_DN(13)     I1 @T6G_MB_LIB.T6G(SCH_1):PAGE396
  AJ35 P5E_CPU1_P1_TX_C_DP<13> @T6G_MB_LIB.T6G(SCH_1):P5E_CPU1_P1_TX_C_DP(13)     I1 @T6G_MB_LIB.T6G(SCH_1):PAGE396
  AP34 P5E_CPU1_P1_TX_C_DN<12> @T6G_MB_LIB.T6G(SCH_1):P5E_CPU1_P1_TX_C_DN(12)     I1 @T6G_MB_LIB.T6G(SCH_1):PAGE396
  AT35 P5E_CPU1_P1_TX_C_DP<12> @T6G_MB_LIB.T6G(SCH_1):P5E_CPU1_P1_TX_C_DP(12)     I1 @T6G_MB_LIB.T6G(SCH_1):PAGE396
  BA34 P5E_CPU1_P1_TX_C_DN<11> @T6G_MB_LIB.T6G(SCH_1):P5E_CPU1_P1_TX_C_DN(11)     I1 @T6G_MB_LIB.T6G(SCH_1):PAGE396
  BC35 P5E_CPU1_P1_TX_C_DP<11> @T6G_MB_LIB.T6G(SCH_1):P5E_CPU1_P1_TX_C_DP(11)     I1 @T6G_MB_LIB.T6G(SCH_1):PAGE396
  BH34 P5E_CPU1_P1_TX_C_DN<10> @T6G_MB_LIB.T6G(SCH_1):P5E_CPU1_P1_TX_C_DN(10)     I1 @T6G_MB_LIB.T6G(SCH_1):PAGE396
  BK35 P5E_CPU1_P1_TX_C_DP<10> @T6G_MB_LIB.T6G(SCH_1):P5E_CPU1_P1_TX_C_DP(10)     I1 @T6G_MB_LIB.T6G(SCH_1):PAGE396
  BR34 P5E_CPU1_P1_TX_C_DN<9> @T6G_MB_LIB.T6G(SCH_1):P5E_CPU1_P1_TX_C_DN(9)     I1 @T6G_MB_LIB.T6G(SCH_1):PAGE396
  BU35 P5E_CPU1_P1_TX_C_DP<9> @T6G_MB_LIB.T6G(SCH_1):P5E_CPU1_P1_TX_C_DP(9)     I1 @T6G_MB_LIB.T6G(SCH_1):PAGE396
  CB34 P5E_CPU1_P1_TX_C_DN<8> @T6G_MB_LIB.T6G(SCH_1):P5E_CPU1_P1_TX_C_DN(8)     I1 @T6G_MB_LIB.T6G(SCH_1):PAGE396
  CD35 P5E_CPU1_P1_TX_C_DP<8> @T6G_MB_LIB.T6G(SCH_1):P5E_CPU1_P1_TX_C_DP(8)     I1 @T6G_MB_LIB.T6G(SCH_1):PAGE396
  CJ34 P5E_CPU1_P1_TX_C_DN<7> @T6G_MB_LIB.T6G(SCH_1):P5E_CPU1_P1_TX_C_DN(7)    I38 @T6G_MB_LIB.T6G(SCH_1):PAGE396
  CL35 P5E_CPU1_P1_TX_C_DP<7> @T6G_MB_LIB.T6G(SCH_1):P5E_CPU1_P1_TX_C_DP(7)    I38 @T6G_MB_LIB.T6G(SCH_1):PAGE396
  CT34 P5E_CPU1_P1_TX_C_DN<6> @T6G_MB_LIB.T6G(SCH_1):P5E_CPU1_P1_TX_C_DN(6)    I38 @T6G_MB_LIB.T6G(SCH_1):PAGE396
  CV35 P5E_CPU1_P1_TX_C_DP<6> @T6G_MB_LIB.T6G(SCH_1):P5E_CPU1_P1_TX_C_DP(6)    I38 @T6G_MB_LIB.T6G(SCH_1):PAGE396
  DC34 P5E_CPU1_P1_TX_C_DN<5> @T6G_MB_LIB.T6G(SCH_1):P5E_CPU1_P1_TX_C_DN(5)    I38 @T6G_MB_LIB.T6G(SCH_1):PAGE396
  DE35 P5E_CPU1_P1_TX_C_DP<5> @T6G_MB_LIB.T6G(SCH_1):P5E_CPU1_P1_TX_C_DP(5)    I38 @T6G_MB_LIB.T6G(SCH_1):PAGE396
  DK34 P5E_CPU1_P1_TX_C_DN<4> @T6G_MB_LIB.T6G(SCH_1):P5E_CPU1_P1_TX_C_DN(4)    I38 @T6G_MB_LIB.T6G(SCH_1):PAGE396
  DM35 P5E_CPU1_P1_TX_C_DP<4> @T6G_MB_LIB.T6G(SCH_1):P5E_CPU1_P1_TX_C_DP(4)    I38 @T6G_MB_LIB.T6G(SCH_1):PAGE396
  DU34 P5E_CPU1_P1_TX_C_DN<3> @T6G_MB_LIB.T6G(SCH_1):P5E_CPU1_P1_TX_C_DN(3)    I38 @T6G_MB_LIB.T6G(SCH_1):PAGE396
  DW35 P5E_CPU1_P1_TX_C_DP<3> @T6G_MB_LIB.T6G(SCH_1):P5E_CPU1_P1_TX_C_DP(3)    I38 @T6G_MB_LIB.T6G(SCH_1):PAGE396
  ED34 P5E_CPU1_P1_TX_C_DN<2> @T6G_MB_LIB.T6G(SCH_1):P5E_CPU1_P1_TX_C_DN(2)    I38 @T6G_MB_LIB.T6G(SCH_1):PAGE396
  EF35 P5E_CPU1_P1_TX_C_DP<2> @T6G_MB_LIB.T6G(SCH_1):P5E_CPU1_P1_TX_C_DP(2)    I38 @T6G_MB_LIB.T6G(SCH_1):PAGE396
  EL34 P5E_CPU1_P1_TX_C_DP<1> @T6G_MB_LIB.T6G(SCH_1):P5E_CPU1_P1_TX_C_DP(1)    I38 @T6G_MB_LIB.T6G(SCH_1):PAGE396
  EN35 P5E_CPU1_P1_TX_C_DN<1> @T6G_MB_LIB.T6G(SCH_1):P5E_CPU1_P1_TX_C_DN(1)    I38 @T6G_MB_LIB.T6G(SCH_1):PAGE396
  EV34 P5E_CPU1_P1_TX_C_DN<0> @T6G_MB_LIB.T6G(SCH_1):P5E_CPU1_P1_TX_C_DN(0)    I38 @T6G_MB_LIB.T6G(SCH_1):PAGE396
  EY35 P5E_CPU1_P1_TX_C_DP<0> @T6G_MB_LIB.T6G(SCH_1):P5E_CPU1_P1_TX_C_DP(0)    I38 @T6G_MB_LIB.T6G(SCH_1):PAGE396
    M7 P5E_CPU1_P1_TX_BUF_DP<15> @T6G_MB_LIB.T6G(SCH_1):P5E_CPU1_P1_TX_BUF_DP(15)    I41 @T6G_MB_LIB.T6G(SCH_1):PAGE393
   P10 P5E_CPU1_P1_TX_BUF_DN<15> @T6G_MB_LIB.T6G(SCH_1):P5E_CPU1_P1_TX_BUF_DN(15)    I41 @T6G_MB_LIB.T6G(SCH_1):PAGE393
    W7 P5E_CPU1_P1_TX_BUF_DP<14> @T6G_MB_LIB.T6G(SCH_1):P5E_CPU1_P1_TX_BUF_DP(14)    I41 @T6G_MB_LIB.T6G(SCH_1):PAGE393
  AA10 P5E_CPU1_P1_TX_BUF_DN<14> @T6G_MB_LIB.T6G(SCH_1):P5E_CPU1_P1_TX_BUF_DN(14)    I41 @T6G_MB_LIB.T6G(SCH_1):PAGE393
   AF7 P5E_CPU1_P1_TX_BUF_DP<13> @T6G_MB_LIB.T6G(SCH_1):P5E_CPU1_P1_TX_BUF_DP(13)    I41 @T6G_MB_LIB.T6G(SCH_1):PAGE393
  AH10 P5E_CPU1_P1_TX_BUF_DN<13> @T6G_MB_LIB.T6G(SCH_1):P5E_CPU1_P1_TX_BUF_DN(13)    I41 @T6G_MB_LIB.T6G(SCH_1):PAGE393
   AN7 P5E_CPU1_P1_TX_BUF_DP<12> @T6G_MB_LIB.T6G(SCH_1):P5E_CPU1_P1_TX_BUF_DP(12)    I41 @T6G_MB_LIB.T6G(SCH_1):PAGE393
  AR10 P5E_CPU1_P1_TX_BUF_DN<12> @T6G_MB_LIB.T6G(SCH_1):P5E_CPU1_P1_TX_BUF_DN(12)    I41 @T6G_MB_LIB.T6G(SCH_1):PAGE393
   AY7 P5E_CPU1_P1_TX_BUF_DP<11> @T6G_MB_LIB.T6G(SCH_1):P5E_CPU1_P1_TX_BUF_DP(11)    I41 @T6G_MB_LIB.T6G(SCH_1):PAGE393
  BB10 P5E_CPU1_P1_TX_BUF_DN<11> @T6G_MB_LIB.T6G(SCH_1):P5E_CPU1_P1_TX_BUF_DN(11)    I41 @T6G_MB_LIB.T6G(SCH_1):PAGE393
   BG7 P5E_CPU1_P1_TX_BUF_DP<10> @T6G_MB_LIB.T6G(SCH_1):P5E_CPU1_P1_TX_BUF_DP(10)    I41 @T6G_MB_LIB.T6G(SCH_1):PAGE393
  BJ10 P5E_CPU1_P1_TX_BUF_DN<10> @T6G_MB_LIB.T6G(SCH_1):P5E_CPU1_P1_TX_BUF_DN(10)    I41 @T6G_MB_LIB.T6G(SCH_1):PAGE393
   BP7 P5E_CPU1_P1_TX_BUF_DP<9> @T6G_MB_LIB.T6G(SCH_1):P5E_CPU1_P1_TX_BUF_DP(9)    I41 @T6G_MB_LIB.T6G(SCH_1):PAGE393
  BT10 P5E_CPU1_P1_TX_BUF_DN<9> @T6G_MB_LIB.T6G(SCH_1):P5E_CPU1_P1_TX_BUF_DN(9)    I41 @T6G_MB_LIB.T6G(SCH_1):PAGE393
   CA7 P5E_CPU1_P1_TX_BUF_DP<8> @T6G_MB_LIB.T6G(SCH_1):P5E_CPU1_P1_TX_BUF_DP(8)    I41 @T6G_MB_LIB.T6G(SCH_1):PAGE393
  CC10 P5E_CPU1_P1_TX_BUF_DN<8> @T6G_MB_LIB.T6G(SCH_1):P5E_CPU1_P1_TX_BUF_DN(8)    I41 @T6G_MB_LIB.T6G(SCH_1):PAGE393
   CH7 P5E_CPU1_P1_TX_BUF_DP<7> @T6G_MB_LIB.T6G(SCH_1):P5E_CPU1_P1_TX_BUF_DP(7)   I142 @T6G_MB_LIB.T6G(SCH_1):PAGE393
  CK10 P5E_CPU1_P1_TX_BUF_DN<7> @T6G_MB_LIB.T6G(SCH_1):P5E_CPU1_P1_TX_BUF_DN(7)   I142 @T6G_MB_LIB.T6G(SCH_1):PAGE393
   CR7 P5E_CPU1_P1_TX_BUF_DP<6> @T6G_MB_LIB.T6G(SCH_1):P5E_CPU1_P1_TX_BUF_DP(6)   I142 @T6G_MB_LIB.T6G(SCH_1):PAGE393
  CU10 P5E_CPU1_P1_TX_BUF_DN<6> @T6G_MB_LIB.T6G(SCH_1):P5E_CPU1_P1_TX_BUF_DN(6)   I142 @T6G_MB_LIB.T6G(SCH_1):PAGE393
   DB7 P5E_CPU1_P1_TX_BUF_DP<5> @T6G_MB_LIB.T6G(SCH_1):P5E_CPU1_P1_TX_BUF_DP(5)   I142 @T6G_MB_LIB.T6G(SCH_1):PAGE393
  DD10 P5E_CPU1_P1_TX_BUF_DN<5> @T6G_MB_LIB.T6G(SCH_1):P5E_CPU1_P1_TX_BUF_DN(5)   I142 @T6G_MB_LIB.T6G(SCH_1):PAGE393
   DJ7 P5E_CPU1_P1_TX_BUF_DP<4> @T6G_MB_LIB.T6G(SCH_1):P5E_CPU1_P1_TX_BUF_DP(4)   I142 @T6G_MB_LIB.T6G(SCH_1):PAGE393
  DL10 P5E_CPU1_P1_TX_BUF_DN<4> @T6G_MB_LIB.T6G(SCH_1):P5E_CPU1_P1_TX_BUF_DN(4)   I142 @T6G_MB_LIB.T6G(SCH_1):PAGE393
   DT7 P5E_CPU1_P1_TX_BUF_DP<3> @T6G_MB_LIB.T6G(SCH_1):P5E_CPU1_P1_TX_BUF_DP(3)   I142 @T6G_MB_LIB.T6G(SCH_1):PAGE393
  DV10 P5E_CPU1_P1_TX_BUF_DN<3> @T6G_MB_LIB.T6G(SCH_1):P5E_CPU1_P1_TX_BUF_DN(3)   I142 @T6G_MB_LIB.T6G(SCH_1):PAGE393
   EC7 P5E_CPU1_P1_TX_BUF_DP<2> @T6G_MB_LIB.T6G(SCH_1):P5E_CPU1_P1_TX_BUF_DP(2)   I142 @T6G_MB_LIB.T6G(SCH_1):PAGE393
  EE10 P5E_CPU1_P1_TX_BUF_DN<2> @T6G_MB_LIB.T6G(SCH_1):P5E_CPU1_P1_TX_BUF_DN(2)   I142 @T6G_MB_LIB.T6G(SCH_1):PAGE393
   EK7 P5E_CPU1_P1_TX_BUF_DP<1> @T6G_MB_LIB.T6G(SCH_1):P5E_CPU1_P1_TX_BUF_DP(1)   I142 @T6G_MB_LIB.T6G(SCH_1):PAGE393
  EM10 P5E_CPU1_P1_TX_BUF_DN<1> @T6G_MB_LIB.T6G(SCH_1):P5E_CPU1_P1_TX_BUF_DN(1)   I142 @T6G_MB_LIB.T6G(SCH_1):PAGE393
   EU7 P5E_CPU1_P1_TX_BUF_DP<0> @T6G_MB_LIB.T6G(SCH_1):P5E_CPU1_P1_TX_BUF_DP(0)   I142 @T6G_MB_LIB.T6G(SCH_1):PAGE393
  EW10 P5E_CPU1_P1_TX_BUF_DN<0> @T6G_MB_LIB.T6G(SCH_1):P5E_CPU1_P1_TX_BUF_DN(0)   I142 @T6G_MB_LIB.T6G(SCH_1):PAGE393

U6016 PT5161LRS-PT5161LRS,SMLF,IC,AJ051610U03
    R1 P5E_CPU1_P2_RX_BUF_DP<15> @T6G_MB_LIB.T6G(SCH_1):P5E_CPU1_P2_RX_BUF_DP(15)     I1 @T6G_MB_LIB.T6G(SCH_1):PAGE449
    N2 P5E_CPU1_P2_RX_BUF_DN<15> @T6G_MB_LIB.T6G(SCH_1):P5E_CPU1_P2_RX_BUF_DN(15)     I1 @T6G_MB_LIB.T6G(SCH_1):PAGE449
   AB1 P5E_CPU1_P2_RX_BUF_DP<14> @T6G_MB_LIB.T6G(SCH_1):P5E_CPU1_P2_RX_BUF_DP(14)     I1 @T6G_MB_LIB.T6G(SCH_1):PAGE449
    Y2 P5E_CPU1_P2_RX_BUF_DN<14> @T6G_MB_LIB.T6G(SCH_1):P5E_CPU1_P2_RX_BUF_DN(14)     I1 @T6G_MB_LIB.T6G(SCH_1):PAGE449
   AJ1 P5E_CPU1_P2_RX_BUF_DP<13> @T6G_MB_LIB.T6G(SCH_1):P5E_CPU1_P2_RX_BUF_DP(13)     I1 @T6G_MB_LIB.T6G(SCH_1):PAGE449
   AG2 P5E_CPU1_P2_RX_BUF_DN<13> @T6G_MB_LIB.T6G(SCH_1):P5E_CPU1_P2_RX_BUF_DN(13)     I1 @T6G_MB_LIB.T6G(SCH_1):PAGE449
   AT1 P5E_CPU1_P2_RX_BUF_DP<12> @T6G_MB_LIB.T6G(SCH_1):P5E_CPU1_P2_RX_BUF_DP(12)     I1 @T6G_MB_LIB.T6G(SCH_1):PAGE449
   AP2 P5E_CPU1_P2_RX_BUF_DN<12> @T6G_MB_LIB.T6G(SCH_1):P5E_CPU1_P2_RX_BUF_DN(12)     I1 @T6G_MB_LIB.T6G(SCH_1):PAGE449
   BC1 P5E_CPU1_P2_RX_BUF_DP<11> @T6G_MB_LIB.T6G(SCH_1):P5E_CPU1_P2_RX_BUF_DP(11)     I1 @T6G_MB_LIB.T6G(SCH_1):PAGE449
   BA2 P5E_CPU1_P2_RX_BUF_DN<11> @T6G_MB_LIB.T6G(SCH_1):P5E_CPU1_P2_RX_BUF_DN(11)     I1 @T6G_MB_LIB.T6G(SCH_1):PAGE449
   BK1 P5E_CPU1_P2_RX_BUF_DP<10> @T6G_MB_LIB.T6G(SCH_1):P5E_CPU1_P2_RX_BUF_DP(10)     I1 @T6G_MB_LIB.T6G(SCH_1):PAGE449
   BH2 P5E_CPU1_P2_RX_BUF_DN<10> @T6G_MB_LIB.T6G(SCH_1):P5E_CPU1_P2_RX_BUF_DN(10)     I1 @T6G_MB_LIB.T6G(SCH_1):PAGE449
   BU1 P5E_CPU1_P2_RX_BUF_DP<9> @T6G_MB_LIB.T6G(SCH_1):P5E_CPU1_P2_RX_BUF_DP(9)     I1 @T6G_MB_LIB.T6G(SCH_1):PAGE449
   BR2 P5E_CPU1_P2_RX_BUF_DN<9> @T6G_MB_LIB.T6G(SCH_1):P5E_CPU1_P2_RX_BUF_DN(9)     I1 @T6G_MB_LIB.T6G(SCH_1):PAGE449
   CD1 P5E_CPU1_P2_RX_BUF_DP<8> @T6G_MB_LIB.T6G(SCH_1):P5E_CPU1_P2_RX_BUF_DP(8)     I1 @T6G_MB_LIB.T6G(SCH_1):PAGE449
   CB2 P5E_CPU1_P2_RX_BUF_DN<8> @T6G_MB_LIB.T6G(SCH_1):P5E_CPU1_P2_RX_BUF_DN(8)     I1 @T6G_MB_LIB.T6G(SCH_1):PAGE449
   CL1 P5E_CPU1_P2_RX_BUF_DP<7> @T6G_MB_LIB.T6G(SCH_1):P5E_CPU1_P2_RX_BUF_DP(7)    I38 @T6G_MB_LIB.T6G(SCH_1):PAGE449
   CJ2 P5E_CPU1_P2_RX_BUF_DN<7> @T6G_MB_LIB.T6G(SCH_1):P5E_CPU1_P2_RX_BUF_DN(7)    I38 @T6G_MB_LIB.T6G(SCH_1):PAGE449
   CV1 P5E_CPU1_P2_RX_BUF_DP<6> @T6G_MB_LIB.T6G(SCH_1):P5E_CPU1_P2_RX_BUF_DP(6)    I38 @T6G_MB_LIB.T6G(SCH_1):PAGE449
   CT2 P5E_CPU1_P2_RX_BUF_DN<6> @T6G_MB_LIB.T6G(SCH_1):P5E_CPU1_P2_RX_BUF_DN(6)    I38 @T6G_MB_LIB.T6G(SCH_1):PAGE449
   DE1 P5E_CPU1_P2_RX_BUF_DP<5> @T6G_MB_LIB.T6G(SCH_1):P5E_CPU1_P2_RX_BUF_DP(5)    I38 @T6G_MB_LIB.T6G(SCH_1):PAGE449
   DC2 P5E_CPU1_P2_RX_BUF_DN<5> @T6G_MB_LIB.T6G(SCH_1):P5E_CPU1_P2_RX_BUF_DN(5)    I38 @T6G_MB_LIB.T6G(SCH_1):PAGE449
   DM1 P5E_CPU1_P2_RX_BUF_DP<4> @T6G_MB_LIB.T6G(SCH_1):P5E_CPU1_P2_RX_BUF_DP(4)    I38 @T6G_MB_LIB.T6G(SCH_1):PAGE449
   DK2 P5E_CPU1_P2_RX_BUF_DN<4> @T6G_MB_LIB.T6G(SCH_1):P5E_CPU1_P2_RX_BUF_DN(4)    I38 @T6G_MB_LIB.T6G(SCH_1):PAGE449
   DW1 P5E_CPU1_P2_RX_BUF_DP<3> @T6G_MB_LIB.T6G(SCH_1):P5E_CPU1_P2_RX_BUF_DP(3)    I38 @T6G_MB_LIB.T6G(SCH_1):PAGE449
   DU2 P5E_CPU1_P2_RX_BUF_DN<3> @T6G_MB_LIB.T6G(SCH_1):P5E_CPU1_P2_RX_BUF_DN(3)    I38 @T6G_MB_LIB.T6G(SCH_1):PAGE449
   EF1 P5E_CPU1_P2_RX_BUF_DP<2> @T6G_MB_LIB.T6G(SCH_1):P5E_CPU1_P2_RX_BUF_DP(2)    I38 @T6G_MB_LIB.T6G(SCH_1):PAGE449
   ED2 P5E_CPU1_P2_RX_BUF_DN<2> @T6G_MB_LIB.T6G(SCH_1):P5E_CPU1_P2_RX_BUF_DN(2)    I38 @T6G_MB_LIB.T6G(SCH_1):PAGE449
   EN1 P5E_CPU1_P2_RX_BUF_DP<1> @T6G_MB_LIB.T6G(SCH_1):P5E_CPU1_P2_RX_BUF_DP(1)    I38 @T6G_MB_LIB.T6G(SCH_1):PAGE449
   EL2 P5E_CPU1_P2_RX_BUF_DN<1> @T6G_MB_LIB.T6G(SCH_1):P5E_CPU1_P2_RX_BUF_DN(1)    I38 @T6G_MB_LIB.T6G(SCH_1):PAGE449
   EY1 P5E_CPU1_P2_RX_BUF_DP<0> @T6G_MB_LIB.T6G(SCH_1):P5E_CPU1_P2_RX_BUF_DP(0)    I38 @T6G_MB_LIB.T6G(SCH_1):PAGE449
   EV2 P5E_CPU1_P2_RX_BUF_DN<0> @T6G_MB_LIB.T6G(SCH_1):P5E_CPU1_P2_RX_BUF_DN(0)    I38 @T6G_MB_LIB.T6G(SCH_1):PAGE449
   FJ6     NC     NC    I97 @T6G_MB_LIB.T6G(SCH_1):PAGE451
  FJ23     NC     NC    I97 @T6G_MB_LIB.T6G(SCH_1):PAGE451
  FJ25 GPIO2_RT_CPU1_P2 @T6G_MB_LIB.T6G(SCH_1):GPIO2_RT_CPU1_P2    I97 @T6G_MB_LIB.T6G(SCH_1):PAGE451
  FJ28 GPIO3_RT_CPU1_P2 @T6G_MB_LIB.T6G(SCH_1):GPIO3_RT_CPU1_P2    I97 @T6G_MB_LIB.T6G(SCH_1):PAGE451
  FJ31     NC     NC    I97 @T6G_MB_LIB.T6G(SCH_1):PAGE451
    B3 JTAG_TCK_RT_CPU1_P2 @T6G_MB_LIB.T6G(SCH_1):JTAG_TCK_RT_CPU1_P2    I97 @T6G_MB_LIB.T6G(SCH_1):PAGE451
    B6 JTAG_TDI_RT_CPU1_P2 @T6G_MB_LIB.T6G(SCH_1):JTAG_TDI_RT_CPU1_P2    I97 @T6G_MB_LIB.T6G(SCH_1):PAGE451
    B9 JTAG_TDO_RT_CPU1_P2 @T6G_MB_LIB.T6G(SCH_1):JTAG_TDO_RT_CPU1_P2    I97 @T6G_MB_LIB.T6G(SCH_1):PAGE451
   FF8 JTAG_TEST_MODE_RT_CPU1_P2 @T6G_MB_LIB.T6G(SCH_1):JTAG_TEST_MODE_RT_CPU1_P2    I97 @T6G_MB_LIB.T6G(SCH_1):PAGE451
   B12 JTAG_TMS_RT_CPU1_P2 @T6G_MB_LIB.T6G(SCH_1):JTAG_TMS_RT_CPU1_P2    I97 @T6G_MB_LIB.T6G(SCH_1):PAGE451
    E8 JTAG_TRST_RT_CPU1_P2_N @T6G_MB_LIB.T6G(SCH_1):JTAG_TRST_RT_CPU1_P2_N    I97 @T6G_MB_LIB.T6G(SCH_1):PAGE451
   FJ9 MODE_RT_CPU1_P2 @T6G_MB_LIB.T6G(SCH_1):MODE_RT_CPU1_P2    I97 @T6G_MB_LIB.T6G(SCH_1):PAGE451
    F2 RST_RT_CPU1_P2_PERST_N @T6G_MB_LIB.T6G(SCH_1):RST_RT_CPU1_P2_PERST_N    I97 @T6G_MB_LIB.T6G(SCH_1):PAGE451
   E18     NC     NC    I97 @T6G_MB_LIB.T6G(SCH_1):PAGE451
   B16     NC     NC    I97 @T6G_MB_LIB.T6G(SCH_1):PAGE451
  FF18 CLK_100M_RETIMER_CPU1_P2_DN @T6G_MB_LIB.T6G(SCH_1):CLK_100M_RETIMER_CPU1_P2_DN    I97 @T6G_MB_LIB.T6G(SCH_1):PAGE451
  FJ16 CLK_100M_RETIMER_CPU1_P2_DP @T6G_MB_LIB.T6G(SCH_1):CLK_100M_RETIMER_CPU1_P2_DP    I97 @T6G_MB_LIB.T6G(SCH_1):PAGE451
  FF11 RST_RT_CPU1_P2_RESET_N @T6G_MB_LIB.T6G(SCH_1):RST_RT_CPU1_P2_RESET_N    I97 @T6G_MB_LIB.T6G(SCH_1):PAGE451
   E11 RXDET_BYP_RT_CPU1_P2 @T6G_MB_LIB.T6G(SCH_1):RXDET_BYP_RT_CPU1_P2    I97 @T6G_MB_LIB.T6G(SCH_1):PAGE451
  FF33 RT_CPU1_P2_SCAN_MODE @T6G_MB_LIB.T6G(SCH_1):RT_CPU1_P2_SCAN_MODE    I97 @T6G_MB_LIB.T6G(SCH_1):PAGE451
   F34 RT_CPU1_P2_ADDR1 @T6G_MB_LIB.T6G(SCH_1):RT_CPU1_P2_ADDR1    I97 @T6G_MB_LIB.T6G(SCH_1):PAGE451
   B23 RT_CPU1_P2_ADDR2 @T6G_MB_LIB.T6G(SCH_1):RT_CPU1_P2_ADDR2    I97 @T6G_MB_LIB.T6G(SCH_1):PAGE451
   B25 RT_CPU1_P2_ADDR3 @T6G_MB_LIB.T6G(SCH_1):RT_CPU1_P2_ADDR3    I97 @T6G_MB_LIB.T6G(SCH_1):PAGE451
   B31 SMB_RT_CPU1_P2_R2_SCL @T6G_MB_LIB.T6G(SCH_1):SMB_RT_CPU1_P2_R2_SCL    I97 @T6G_MB_LIB.T6G(SCH_1):PAGE451
   B28 SMB_RT_CPU1_P2_R2_SDA @T6G_MB_LIB.T6G(SCH_1):SMB_RT_CPU1_P2_R2_SDA    I97 @T6G_MB_LIB.T6G(SCH_1):PAGE451
   E30    GND @T6G_MB_LIB.T6G(SCH_1):GND    I97 @T6G_MB_LIB.T6G(SCH_1):PAGE451
  FF24 TEST0_RT_CPU1_P2 @T6G_MB_LIB.T6G(SCH_1):TEST0_RT_CPU1_P2    I97 @T6G_MB_LIB.T6G(SCH_1):PAGE451
  FF27 TEST1_RT_CPU1_P2 @T6G_MB_LIB.T6G(SCH_1):TEST1_RT_CPU1_P2    I97 @T6G_MB_LIB.T6G(SCH_1):PAGE451
  FF30 TEST2_RT_CPU1_P2 @T6G_MB_LIB.T6G(SCH_1):TEST2_RT_CPU1_P2    I97 @T6G_MB_LIB.T6G(SCH_1):PAGE451
   G35 CLKREQ_RT_CPU1_P2_N @T6G_MB_LIB.T6G(SCH_1):CLKREQ_RT_CPU1_P2_N    I97 @T6G_MB_LIB.T6G(SCH_1):PAGE451
   FF5 SMB_RT_CPU1_P2_ROM_MUX_1D_R_SCL @T6G_MB_LIB.T6G(SCH_1):SMB_RT_CPU1_P2_ROM_MUX_1D_R_SCL    I97 @T6G_MB_LIB.T6G(SCH_1):PAGE451
   FJ3 SMB_RT_CPU1_P2_ROM_MUX_1D_R_SDA @T6G_MB_LIB.T6G(SCH_1):SMB_RT_CPU1_P2_ROM_MUX_1D_R_SDA    I97 @T6G_MB_LIB.T6G(SCH_1):PAGE451
    G1 RT_CPU1_P2_VQPS @T6G_MB_LIB.T6G(SCH_1):RT_CPU1_P2_VQPS     I7 @T6G_MB_LIB.T6G(SCH_1):PAGE452
  BV20 P1V8_CPU1_RT2_1A @T6G_MB_LIB.T6G(SCH_1):P1V8_CPU1_RT2_1A     I7 @T6G_MB_LIB.T6G(SCH_1):PAGE452
  CE17 P1V8_CPU1_RT2_1A @T6G_MB_LIB.T6G(SCH_1):P1V8_CPU1_RT2_1A     I7 @T6G_MB_LIB.T6G(SCH_1):PAGE452
  CE20 P1V8_CPU1_RT2_1A @T6G_MB_LIB.T6G(SCH_1):P1V8_CPU1_RT2_1A     I7 @T6G_MB_LIB.T6G(SCH_1):PAGE452
  CM17 P1V8_CPU1_RT2_1A @T6G_MB_LIB.T6G(SCH_1):P1V8_CPU1_RT2_1A     I7 @T6G_MB_LIB.T6G(SCH_1):PAGE452
  CM20 P1V8_CPU1_RT2_1A @T6G_MB_LIB.T6G(SCH_1):P1V8_CPU1_RT2_1A     I7 @T6G_MB_LIB.T6G(SCH_1):PAGE452
  BL17 P0V9_CPU1_RT_2D @T6G_MB_LIB.T6G(SCH_1):P0V9_CPU1_RT_2D     I7 @T6G_MB_LIB.T6G(SCH_1):PAGE452
  BL20 P0V9_CPU1_RT_2D @T6G_MB_LIB.T6G(SCH_1):P0V9_CPU1_RT_2D     I7 @T6G_MB_LIB.T6G(SCH_1):PAGE452
  CW17 P0V9_CPU1_RT_2D @T6G_MB_LIB.T6G(SCH_1):P0V9_CPU1_RT_2D     I7 @T6G_MB_LIB.T6G(SCH_1):PAGE452
  CW20 P0V9_CPU1_RT_2D @T6G_MB_LIB.T6G(SCH_1):P0V9_CPU1_RT_2D     I7 @T6G_MB_LIB.T6G(SCH_1):PAGE452
  BV17 P1V8_CPU1_RT2_1A_1D @T6G_MB_LIB.T6G(SCH_1):P1V8_CPU1_RT2_1A_1D     I7 @T6G_MB_LIB.T6G(SCH_1):PAGE452
  AC17 P0V9_CPU1_RT2_2A @T6G_MB_LIB.T6G(SCH_1):P0V9_CPU1_RT2_2A     I7 @T6G_MB_LIB.T6G(SCH_1):PAGE452
  AC20 P0V9_CPU1_RT2_2A @T6G_MB_LIB.T6G(SCH_1):P0V9_CPU1_RT2_2A     I7 @T6G_MB_LIB.T6G(SCH_1):PAGE452
  AK17 P0V9_CPU1_RT2_2A @T6G_MB_LIB.T6G(SCH_1):P0V9_CPU1_RT2_2A     I7 @T6G_MB_LIB.T6G(SCH_1):PAGE452
  AK20 P0V9_CPU1_RT2_2A @T6G_MB_LIB.T6G(SCH_1):P0V9_CPU1_RT2_2A     I7 @T6G_MB_LIB.T6G(SCH_1):PAGE452
  AU17 P0V9_CPU1_RT2_2A @T6G_MB_LIB.T6G(SCH_1):P0V9_CPU1_RT2_2A     I7 @T6G_MB_LIB.T6G(SCH_1):PAGE452
  AU20 P0V9_CPU1_RT2_2A @T6G_MB_LIB.T6G(SCH_1):P0V9_CPU1_RT2_2A     I7 @T6G_MB_LIB.T6G(SCH_1):PAGE452
  BD17 P0V9_CPU1_RT2_2A_2D @T6G_MB_LIB.T6G(SCH_1):P0V9_CPU1_RT2_2A_2D     I7 @T6G_MB_LIB.T6G(SCH_1):PAGE452
  BD20 P0V9_CPU1_RT2_2A_2D @T6G_MB_LIB.T6G(SCH_1):P0V9_CPU1_RT2_2A_2D     I7 @T6G_MB_LIB.T6G(SCH_1):PAGE452
  DF17 P0V9_CPU1_RT2_2A_2D @T6G_MB_LIB.T6G(SCH_1):P0V9_CPU1_RT2_2A_2D     I7 @T6G_MB_LIB.T6G(SCH_1):PAGE452
  DF20 P0V9_CPU1_RT2_2A_2D @T6G_MB_LIB.T6G(SCH_1):P0V9_CPU1_RT2_2A_2D     I7 @T6G_MB_LIB.T6G(SCH_1):PAGE452
  DN17 P0V9_CPU1_RT2_2A @T6G_MB_LIB.T6G(SCH_1):P0V9_CPU1_RT2_2A     I7 @T6G_MB_LIB.T6G(SCH_1):PAGE452
  DN20 P0V9_CPU1_RT2_2A @T6G_MB_LIB.T6G(SCH_1):P0V9_CPU1_RT2_2A     I7 @T6G_MB_LIB.T6G(SCH_1):PAGE452
  DY17 P0V9_CPU1_RT2_2A @T6G_MB_LIB.T6G(SCH_1):P0V9_CPU1_RT2_2A     I7 @T6G_MB_LIB.T6G(SCH_1):PAGE452
  DY20 P0V9_CPU1_RT2_2A @T6G_MB_LIB.T6G(SCH_1):P0V9_CPU1_RT2_2A     I7 @T6G_MB_LIB.T6G(SCH_1):PAGE452
  EG17 P0V9_CPU1_RT2_2A @T6G_MB_LIB.T6G(SCH_1):P0V9_CPU1_RT2_2A     I7 @T6G_MB_LIB.T6G(SCH_1):PAGE452
  EG20 P0V9_CPU1_RT2_2A @T6G_MB_LIB.T6G(SCH_1):P0V9_CPU1_RT2_2A     I7 @T6G_MB_LIB.T6G(SCH_1):PAGE452
  EP17 P0V9_CPU1_RT2_2A @T6G_MB_LIB.T6G(SCH_1):P0V9_CPU1_RT2_2A     I7 @T6G_MB_LIB.T6G(SCH_1):PAGE452
  EP20 P0V9_CPU1_RT2_2A @T6G_MB_LIB.T6G(SCH_1):P0V9_CPU1_RT2_2A     I7 @T6G_MB_LIB.T6G(SCH_1):PAGE452
   T17 P0V9_CPU1_RT2_2A @T6G_MB_LIB.T6G(SCH_1):P0V9_CPU1_RT2_2A     I7 @T6G_MB_LIB.T6G(SCH_1):PAGE452
   T20 P0V9_CPU1_RT2_2A @T6G_MB_LIB.T6G(SCH_1):P0V9_CPU1_RT2_2A     I7 @T6G_MB_LIB.T6G(SCH_1):PAGE452
  AC13    GND @T6G_MB_LIB.T6G(SCH_1):GND    I19 @T6G_MB_LIB.T6G(SCH_1):PAGE452
  AC22    GND @T6G_MB_LIB.T6G(SCH_1):GND    I19 @T6G_MB_LIB.T6G(SCH_1):PAGE452
  AC32    GND @T6G_MB_LIB.T6G(SCH_1):GND    I19 @T6G_MB_LIB.T6G(SCH_1):PAGE452
   AC4    GND @T6G_MB_LIB.T6G(SCH_1):GND    I19 @T6G_MB_LIB.T6G(SCH_1):PAGE452
   AD2    GND @T6G_MB_LIB.T6G(SCH_1):GND    I19 @T6G_MB_LIB.T6G(SCH_1):PAGE452
  AD34    GND @T6G_MB_LIB.T6G(SCH_1):GND    I19 @T6G_MB_LIB.T6G(SCH_1):PAGE452
   AE1    GND @T6G_MB_LIB.T6G(SCH_1):GND    I19 @T6G_MB_LIB.T6G(SCH_1):PAGE452
  AE35    GND @T6G_MB_LIB.T6G(SCH_1):GND    I19 @T6G_MB_LIB.T6G(SCH_1):PAGE452
  AK13    GND @T6G_MB_LIB.T6G(SCH_1):GND    I19 @T6G_MB_LIB.T6G(SCH_1):PAGE452
  AK22    GND @T6G_MB_LIB.T6G(SCH_1):GND    I19 @T6G_MB_LIB.T6G(SCH_1):PAGE452
  AK32    GND @T6G_MB_LIB.T6G(SCH_1):GND    I19 @T6G_MB_LIB.T6G(SCH_1):PAGE452
   AK4    GND @T6G_MB_LIB.T6G(SCH_1):GND    I19 @T6G_MB_LIB.T6G(SCH_1):PAGE452
   AL2    GND @T6G_MB_LIB.T6G(SCH_1):GND    I19 @T6G_MB_LIB.T6G(SCH_1):PAGE452
  AL34    GND @T6G_MB_LIB.T6G(SCH_1):GND    I19 @T6G_MB_LIB.T6G(SCH_1):PAGE452
   AM1    GND @T6G_MB_LIB.T6G(SCH_1):GND    I19 @T6G_MB_LIB.T6G(SCH_1):PAGE452
  AM35    GND @T6G_MB_LIB.T6G(SCH_1):GND    I19 @T6G_MB_LIB.T6G(SCH_1):PAGE452
  AU13    GND @T6G_MB_LIB.T6G(SCH_1):GND    I19 @T6G_MB_LIB.T6G(SCH_1):PAGE452
  AU22    GND @T6G_MB_LIB.T6G(SCH_1):GND    I19 @T6G_MB_LIB.T6G(SCH_1):PAGE452
  AU32    GND @T6G_MB_LIB.T6G(SCH_1):GND    I19 @T6G_MB_LIB.T6G(SCH_1):PAGE452
   AU4    GND @T6G_MB_LIB.T6G(SCH_1):GND    I19 @T6G_MB_LIB.T6G(SCH_1):PAGE452
   AV2    GND @T6G_MB_LIB.T6G(SCH_1):GND    I19 @T6G_MB_LIB.T6G(SCH_1):PAGE452
  AV34    GND @T6G_MB_LIB.T6G(SCH_1):GND    I19 @T6G_MB_LIB.T6G(SCH_1):PAGE452
   AW1    GND @T6G_MB_LIB.T6G(SCH_1):GND    I19 @T6G_MB_LIB.T6G(SCH_1):PAGE452
  AW35    GND @T6G_MB_LIB.T6G(SCH_1):GND    I19 @T6G_MB_LIB.T6G(SCH_1):PAGE452
   B19    GND @T6G_MB_LIB.T6G(SCH_1):GND    I19 @T6G_MB_LIB.T6G(SCH_1):PAGE452
  BD13    GND @T6G_MB_LIB.T6G(SCH_1):GND    I19 @T6G_MB_LIB.T6G(SCH_1):PAGE452
  BD22    GND @T6G_MB_LIB.T6G(SCH_1):GND    I19 @T6G_MB_LIB.T6G(SCH_1):PAGE452
  BD32    GND @T6G_MB_LIB.T6G(SCH_1):GND    I19 @T6G_MB_LIB.T6G(SCH_1):PAGE452
   BD4    GND @T6G_MB_LIB.T6G(SCH_1):GND    I19 @T6G_MB_LIB.T6G(SCH_1):PAGE452
   BE2    GND @T6G_MB_LIB.T6G(SCH_1):GND    I19 @T6G_MB_LIB.T6G(SCH_1):PAGE452
  BE34    GND @T6G_MB_LIB.T6G(SCH_1):GND    I19 @T6G_MB_LIB.T6G(SCH_1):PAGE452
   BF1    GND @T6G_MB_LIB.T6G(SCH_1):GND    I19 @T6G_MB_LIB.T6G(SCH_1):PAGE452
  BF35    GND @T6G_MB_LIB.T6G(SCH_1):GND    I19 @T6G_MB_LIB.T6G(SCH_1):PAGE452
  BL13    GND @T6G_MB_LIB.T6G(SCH_1):GND    I19 @T6G_MB_LIB.T6G(SCH_1):PAGE452
  BL22    GND @T6G_MB_LIB.T6G(SCH_1):GND    I19 @T6G_MB_LIB.T6G(SCH_1):PAGE452
  BL32    GND @T6G_MB_LIB.T6G(SCH_1):GND    I19 @T6G_MB_LIB.T6G(SCH_1):PAGE452
   BL4    GND @T6G_MB_LIB.T6G(SCH_1):GND    I19 @T6G_MB_LIB.T6G(SCH_1):PAGE452
   BM2    GND @T6G_MB_LIB.T6G(SCH_1):GND    I19 @T6G_MB_LIB.T6G(SCH_1):PAGE452
  BM34    GND @T6G_MB_LIB.T6G(SCH_1):GND    I19 @T6G_MB_LIB.T6G(SCH_1):PAGE452
   BN1    GND @T6G_MB_LIB.T6G(SCH_1):GND    I19 @T6G_MB_LIB.T6G(SCH_1):PAGE452
  BN35    GND @T6G_MB_LIB.T6G(SCH_1):GND    I19 @T6G_MB_LIB.T6G(SCH_1):PAGE452
  BV13    GND @T6G_MB_LIB.T6G(SCH_1):GND    I19 @T6G_MB_LIB.T6G(SCH_1):PAGE452
  BV22    GND @T6G_MB_LIB.T6G(SCH_1):GND    I19 @T6G_MB_LIB.T6G(SCH_1):PAGE452
  BV32    GND @T6G_MB_LIB.T6G(SCH_1):GND    I19 @T6G_MB_LIB.T6G(SCH_1):PAGE452
   BV4    GND @T6G_MB_LIB.T6G(SCH_1):GND    I19 @T6G_MB_LIB.T6G(SCH_1):PAGE452
   BW2    GND @T6G_MB_LIB.T6G(SCH_1):GND    I19 @T6G_MB_LIB.T6G(SCH_1):PAGE452
  BW34    GND @T6G_MB_LIB.T6G(SCH_1):GND    I19 @T6G_MB_LIB.T6G(SCH_1):PAGE452
   BY1    GND @T6G_MB_LIB.T6G(SCH_1):GND    I19 @T6G_MB_LIB.T6G(SCH_1):PAGE452
  BY35    GND @T6G_MB_LIB.T6G(SCH_1):GND    I19 @T6G_MB_LIB.T6G(SCH_1):PAGE452
  CE13    GND @T6G_MB_LIB.T6G(SCH_1):GND    I19 @T6G_MB_LIB.T6G(SCH_1):PAGE452
  CE22    GND @T6G_MB_LIB.T6G(SCH_1):GND    I19 @T6G_MB_LIB.T6G(SCH_1):PAGE452
  CE32    GND @T6G_MB_LIB.T6G(SCH_1):GND    I19 @T6G_MB_LIB.T6G(SCH_1):PAGE452
   CE4    GND @T6G_MB_LIB.T6G(SCH_1):GND    I19 @T6G_MB_LIB.T6G(SCH_1):PAGE452
   CF2    GND @T6G_MB_LIB.T6G(SCH_1):GND    I19 @T6G_MB_LIB.T6G(SCH_1):PAGE452
  CF34    GND @T6G_MB_LIB.T6G(SCH_1):GND    I19 @T6G_MB_LIB.T6G(SCH_1):PAGE452
   CG1    GND @T6G_MB_LIB.T6G(SCH_1):GND    I19 @T6G_MB_LIB.T6G(SCH_1):PAGE452
  CG35    GND @T6G_MB_LIB.T6G(SCH_1):GND    I19 @T6G_MB_LIB.T6G(SCH_1):PAGE452
  CM13    GND @T6G_MB_LIB.T6G(SCH_1):GND    I19 @T6G_MB_LIB.T6G(SCH_1):PAGE452
  CM22    GND @T6G_MB_LIB.T6G(SCH_1):GND    I19 @T6G_MB_LIB.T6G(SCH_1):PAGE452
  CM32    GND @T6G_MB_LIB.T6G(SCH_1):GND    I19 @T6G_MB_LIB.T6G(SCH_1):PAGE452
   CM4    GND @T6G_MB_LIB.T6G(SCH_1):GND    I19 @T6G_MB_LIB.T6G(SCH_1):PAGE452
   CN2    GND @T6G_MB_LIB.T6G(SCH_1):GND    I19 @T6G_MB_LIB.T6G(SCH_1):PAGE452
  CN34    GND @T6G_MB_LIB.T6G(SCH_1):GND    I19 @T6G_MB_LIB.T6G(SCH_1):PAGE452
   CP1    GND @T6G_MB_LIB.T6G(SCH_1):GND    I19 @T6G_MB_LIB.T6G(SCH_1):PAGE452
  CP35    GND @T6G_MB_LIB.T6G(SCH_1):GND    I19 @T6G_MB_LIB.T6G(SCH_1):PAGE452
  CW13    GND @T6G_MB_LIB.T6G(SCH_1):GND    I19 @T6G_MB_LIB.T6G(SCH_1):PAGE452
  CW22    GND @T6G_MB_LIB.T6G(SCH_1):GND    I19 @T6G_MB_LIB.T6G(SCH_1):PAGE452
  CW32    GND @T6G_MB_LIB.T6G(SCH_1):GND    I19 @T6G_MB_LIB.T6G(SCH_1):PAGE452
   CW4    GND @T6G_MB_LIB.T6G(SCH_1):GND    I19 @T6G_MB_LIB.T6G(SCH_1):PAGE452
   CY2    GND @T6G_MB_LIB.T6G(SCH_1):GND    I19 @T6G_MB_LIB.T6G(SCH_1):PAGE452
  CY34    GND @T6G_MB_LIB.T6G(SCH_1):GND    I19 @T6G_MB_LIB.T6G(SCH_1):PAGE452
   DA1    GND @T6G_MB_LIB.T6G(SCH_1):GND    I19 @T6G_MB_LIB.T6G(SCH_1):PAGE452
  DA35    GND @T6G_MB_LIB.T6G(SCH_1):GND    I19 @T6G_MB_LIB.T6G(SCH_1):PAGE452
  DF13    GND @T6G_MB_LIB.T6G(SCH_1):GND    I19 @T6G_MB_LIB.T6G(SCH_1):PAGE452
  DF22    GND @T6G_MB_LIB.T6G(SCH_1):GND    I19 @T6G_MB_LIB.T6G(SCH_1):PAGE452
  DF32    GND @T6G_MB_LIB.T6G(SCH_1):GND    I19 @T6G_MB_LIB.T6G(SCH_1):PAGE452
   DF4    GND @T6G_MB_LIB.T6G(SCH_1):GND    I19 @T6G_MB_LIB.T6G(SCH_1):PAGE452
   DG2    GND @T6G_MB_LIB.T6G(SCH_1):GND    I19 @T6G_MB_LIB.T6G(SCH_1):PAGE452
  DG34    GND @T6G_MB_LIB.T6G(SCH_1):GND    I19 @T6G_MB_LIB.T6G(SCH_1):PAGE452
   DH1    GND @T6G_MB_LIB.T6G(SCH_1):GND    I19 @T6G_MB_LIB.T6G(SCH_1):PAGE452
  DH35    GND @T6G_MB_LIB.T6G(SCH_1):GND    I19 @T6G_MB_LIB.T6G(SCH_1):PAGE452
  DN13    GND @T6G_MB_LIB.T6G(SCH_1):GND    I19 @T6G_MB_LIB.T6G(SCH_1):PAGE452
    A1 NCF_A1_CPU1_P2_GND @T6G_MB_LIB.T6G(SCH_1):NCF_A1_CPU1_P2_GND    I19 @T6G_MB_LIB.T6G(SCH_1):PAGE452
   A35 NCF_CPU1_P2_GND @T6G_MB_LIB.T6G(SCH_1):NCF_CPU1_P2_GND    I19 @T6G_MB_LIB.T6G(SCH_1):PAGE452
    C2 NCF_CPU1_P2_GND @T6G_MB_LIB.T6G(SCH_1):NCF_CPU1_P2_GND    I19 @T6G_MB_LIB.T6G(SCH_1):PAGE452
   C34 NCF_CPU1_P2_GND @T6G_MB_LIB.T6G(SCH_1):NCF_CPU1_P2_GND    I19 @T6G_MB_LIB.T6G(SCH_1):PAGE452
    D1 NCF_CPU1_P2_GND @T6G_MB_LIB.T6G(SCH_1):NCF_CPU1_P2_GND    I19 @T6G_MB_LIB.T6G(SCH_1):PAGE452
   D35 NCF_CPU1_P2_GND @T6G_MB_LIB.T6G(SCH_1):NCF_CPU1_P2_GND    I19 @T6G_MB_LIB.T6G(SCH_1):PAGE452
   FE2 NCF_CPU1_P2_GND @T6G_MB_LIB.T6G(SCH_1):NCF_CPU1_P2_GND    I19 @T6G_MB_LIB.T6G(SCH_1):PAGE452
  FE34 NCF_CPU1_P2_GND @T6G_MB_LIB.T6G(SCH_1):NCF_CPU1_P2_GND    I19 @T6G_MB_LIB.T6G(SCH_1):PAGE452
   FG1 NCF_CPU1_P2_GND @T6G_MB_LIB.T6G(SCH_1):NCF_CPU1_P2_GND    I19 @T6G_MB_LIB.T6G(SCH_1):PAGE452
  FG35 NCF_CPU1_P2_GND @T6G_MB_LIB.T6G(SCH_1):NCF_CPU1_P2_GND    I19 @T6G_MB_LIB.T6G(SCH_1):PAGE452
   FH2 NCF_CPU1_P2_GND @T6G_MB_LIB.T6G(SCH_1):NCF_CPU1_P2_GND    I19 @T6G_MB_LIB.T6G(SCH_1):PAGE452
  FH34 NCF_CPU1_P2_GND @T6G_MB_LIB.T6G(SCH_1):NCF_CPU1_P2_GND    I19 @T6G_MB_LIB.T6G(SCH_1):PAGE452
  DN22    GND @T6G_MB_LIB.T6G(SCH_1):GND    I19 @T6G_MB_LIB.T6G(SCH_1):PAGE452
  DN32    GND @T6G_MB_LIB.T6G(SCH_1):GND    I19 @T6G_MB_LIB.T6G(SCH_1):PAGE452
   DN4    GND @T6G_MB_LIB.T6G(SCH_1):GND    I19 @T6G_MB_LIB.T6G(SCH_1):PAGE452
   DP2    GND @T6G_MB_LIB.T6G(SCH_1):GND    I19 @T6G_MB_LIB.T6G(SCH_1):PAGE452
  DP34    GND @T6G_MB_LIB.T6G(SCH_1):GND    I19 @T6G_MB_LIB.T6G(SCH_1):PAGE452
   DR1    GND @T6G_MB_LIB.T6G(SCH_1):GND    I19 @T6G_MB_LIB.T6G(SCH_1):PAGE452
  DR35    GND @T6G_MB_LIB.T6G(SCH_1):GND    I19 @T6G_MB_LIB.T6G(SCH_1):PAGE452
  DY13    GND @T6G_MB_LIB.T6G(SCH_1):GND    I19 @T6G_MB_LIB.T6G(SCH_1):PAGE452
  DY22    GND @T6G_MB_LIB.T6G(SCH_1):GND    I19 @T6G_MB_LIB.T6G(SCH_1):PAGE452
  DY32    GND @T6G_MB_LIB.T6G(SCH_1):GND    I19 @T6G_MB_LIB.T6G(SCH_1):PAGE452
   DY4    GND @T6G_MB_LIB.T6G(SCH_1):GND    I19 @T6G_MB_LIB.T6G(SCH_1):PAGE452
   E14    GND @T6G_MB_LIB.T6G(SCH_1):GND    I19 @T6G_MB_LIB.T6G(SCH_1):PAGE452
   E27    GND @T6G_MB_LIB.T6G(SCH_1):GND    I19 @T6G_MB_LIB.T6G(SCH_1):PAGE452
   E33    GND @T6G_MB_LIB.T6G(SCH_1):GND    I19 @T6G_MB_LIB.T6G(SCH_1):PAGE452
   EA2    GND @T6G_MB_LIB.T6G(SCH_1):GND    I19 @T6G_MB_LIB.T6G(SCH_1):PAGE452
  EA34    GND @T6G_MB_LIB.T6G(SCH_1):GND    I19 @T6G_MB_LIB.T6G(SCH_1):PAGE452
   EB1    GND @T6G_MB_LIB.T6G(SCH_1):GND    I19 @T6G_MB_LIB.T6G(SCH_1):PAGE452
  EB35    GND @T6G_MB_LIB.T6G(SCH_1):GND    I19 @T6G_MB_LIB.T6G(SCH_1):PAGE452
  EG13    GND @T6G_MB_LIB.T6G(SCH_1):GND    I19 @T6G_MB_LIB.T6G(SCH_1):PAGE452
  EG22    GND @T6G_MB_LIB.T6G(SCH_1):GND    I19 @T6G_MB_LIB.T6G(SCH_1):PAGE452
  EG32    GND @T6G_MB_LIB.T6G(SCH_1):GND    I19 @T6G_MB_LIB.T6G(SCH_1):PAGE452
   EG4    GND @T6G_MB_LIB.T6G(SCH_1):GND    I19 @T6G_MB_LIB.T6G(SCH_1):PAGE452
   EH2    GND @T6G_MB_LIB.T6G(SCH_1):GND    I19 @T6G_MB_LIB.T6G(SCH_1):PAGE452
  EH34    GND @T6G_MB_LIB.T6G(SCH_1):GND    I19 @T6G_MB_LIB.T6G(SCH_1):PAGE452
   EJ1    GND @T6G_MB_LIB.T6G(SCH_1):GND    I19 @T6G_MB_LIB.T6G(SCH_1):PAGE452
  EJ35    GND @T6G_MB_LIB.T6G(SCH_1):GND    I19 @T6G_MB_LIB.T6G(SCH_1):PAGE452
  EP13    GND @T6G_MB_LIB.T6G(SCH_1):GND    I19 @T6G_MB_LIB.T6G(SCH_1):PAGE452
  EP22    GND @T6G_MB_LIB.T6G(SCH_1):GND    I19 @T6G_MB_LIB.T6G(SCH_1):PAGE452
  EP32    GND @T6G_MB_LIB.T6G(SCH_1):GND    I19 @T6G_MB_LIB.T6G(SCH_1):PAGE452
   EP4    GND @T6G_MB_LIB.T6G(SCH_1):GND    I19 @T6G_MB_LIB.T6G(SCH_1):PAGE452
   ER2    GND @T6G_MB_LIB.T6G(SCH_1):GND    I19 @T6G_MB_LIB.T6G(SCH_1):PAGE452
  ER34    GND @T6G_MB_LIB.T6G(SCH_1):GND    I19 @T6G_MB_LIB.T6G(SCH_1):PAGE452
   ET1    GND @T6G_MB_LIB.T6G(SCH_1):GND    I19 @T6G_MB_LIB.T6G(SCH_1):PAGE452
  ET35    GND @T6G_MB_LIB.T6G(SCH_1):GND    I19 @T6G_MB_LIB.T6G(SCH_1):PAGE452
  FA15    GND @T6G_MB_LIB.T6G(SCH_1):GND    I19 @T6G_MB_LIB.T6G(SCH_1):PAGE452
  FA32    GND @T6G_MB_LIB.T6G(SCH_1):GND    I19 @T6G_MB_LIB.T6G(SCH_1):PAGE452
   FB2    GND @T6G_MB_LIB.T6G(SCH_1):GND    I19 @T6G_MB_LIB.T6G(SCH_1):PAGE452
  FB34    GND @T6G_MB_LIB.T6G(SCH_1):GND    I19 @T6G_MB_LIB.T6G(SCH_1):PAGE452
  FC19    GND @T6G_MB_LIB.T6G(SCH_1):GND    I19 @T6G_MB_LIB.T6G(SCH_1):PAGE452
  FC23    GND @T6G_MB_LIB.T6G(SCH_1):GND    I19 @T6G_MB_LIB.T6G(SCH_1):PAGE452
  FC25    GND @T6G_MB_LIB.T6G(SCH_1):GND    I19 @T6G_MB_LIB.T6G(SCH_1):PAGE452
  FC28    GND @T6G_MB_LIB.T6G(SCH_1):GND    I19 @T6G_MB_LIB.T6G(SCH_1):PAGE452
   FC3    GND @T6G_MB_LIB.T6G(SCH_1):GND    I19 @T6G_MB_LIB.T6G(SCH_1):PAGE452
   FC6    GND @T6G_MB_LIB.T6G(SCH_1):GND    I19 @T6G_MB_LIB.T6G(SCH_1):PAGE452
   FC9    GND @T6G_MB_LIB.T6G(SCH_1):GND    I19 @T6G_MB_LIB.T6G(SCH_1):PAGE452
   FD1    GND @T6G_MB_LIB.T6G(SCH_1):GND    I19 @T6G_MB_LIB.T6G(SCH_1):PAGE452
  FD35    GND @T6G_MB_LIB.T6G(SCH_1):GND    I19 @T6G_MB_LIB.T6G(SCH_1):PAGE452
  FF14    GND @T6G_MB_LIB.T6G(SCH_1):GND    I19 @T6G_MB_LIB.T6G(SCH_1):PAGE452
  FF21    GND @T6G_MB_LIB.T6G(SCH_1):GND    I19 @T6G_MB_LIB.T6G(SCH_1):PAGE452
  FJ12    GND @T6G_MB_LIB.T6G(SCH_1):GND    I19 @T6G_MB_LIB.T6G(SCH_1):PAGE452
  FJ19    GND @T6G_MB_LIB.T6G(SCH_1):GND    I19 @T6G_MB_LIB.T6G(SCH_1):PAGE452
   H12    GND @T6G_MB_LIB.T6G(SCH_1):GND    I19 @T6G_MB_LIB.T6G(SCH_1):PAGE452
   H16    GND @T6G_MB_LIB.T6G(SCH_1):GND    I19 @T6G_MB_LIB.T6G(SCH_1):PAGE452
   H19    GND @T6G_MB_LIB.T6G(SCH_1):GND    I19 @T6G_MB_LIB.T6G(SCH_1):PAGE452
   H31    GND @T6G_MB_LIB.T6G(SCH_1):GND    I19 @T6G_MB_LIB.T6G(SCH_1):PAGE452
   J22    GND @T6G_MB_LIB.T6G(SCH_1):GND    I19 @T6G_MB_LIB.T6G(SCH_1):PAGE452
    J4    GND @T6G_MB_LIB.T6G(SCH_1):GND    I19 @T6G_MB_LIB.T6G(SCH_1):PAGE452
    K2    GND @T6G_MB_LIB.T6G(SCH_1):GND    I19 @T6G_MB_LIB.T6G(SCH_1):PAGE452
   K34    GND @T6G_MB_LIB.T6G(SCH_1):GND    I19 @T6G_MB_LIB.T6G(SCH_1):PAGE452
    L1    GND @T6G_MB_LIB.T6G(SCH_1):GND    I19 @T6G_MB_LIB.T6G(SCH_1):PAGE452
   L35    GND @T6G_MB_LIB.T6G(SCH_1):GND    I19 @T6G_MB_LIB.T6G(SCH_1):PAGE452
   T13    GND @T6G_MB_LIB.T6G(SCH_1):GND    I19 @T6G_MB_LIB.T6G(SCH_1):PAGE452
   T22    GND @T6G_MB_LIB.T6G(SCH_1):GND    I19 @T6G_MB_LIB.T6G(SCH_1):PAGE452
   T32    GND @T6G_MB_LIB.T6G(SCH_1):GND    I19 @T6G_MB_LIB.T6G(SCH_1):PAGE452
    T4    GND @T6G_MB_LIB.T6G(SCH_1):GND    I19 @T6G_MB_LIB.T6G(SCH_1):PAGE452
    U2    GND @T6G_MB_LIB.T6G(SCH_1):GND    I19 @T6G_MB_LIB.T6G(SCH_1):PAGE452
   U34    GND @T6G_MB_LIB.T6G(SCH_1):GND    I19 @T6G_MB_LIB.T6G(SCH_1):PAGE452
    V1    GND @T6G_MB_LIB.T6G(SCH_1):GND    I19 @T6G_MB_LIB.T6G(SCH_1):PAGE452
   V35    GND @T6G_MB_LIB.T6G(SCH_1):GND    I19 @T6G_MB_LIB.T6G(SCH_1):PAGE452
   M26 P5E_CPU1_P2_RX_DP<15> @T6G_MB_LIB.T6G(SCH_1):P5E_CPU1_P2_RX_DP(15)     I1 @T6G_MB_LIB.T6G(SCH_1):PAGE448
   P29 P5E_CPU1_P2_RX_DN<15> @T6G_MB_LIB.T6G(SCH_1):P5E_CPU1_P2_RX_DN(15)     I1 @T6G_MB_LIB.T6G(SCH_1):PAGE448
   W26 P5E_CPU1_P2_RX_DP<14> @T6G_MB_LIB.T6G(SCH_1):P5E_CPU1_P2_RX_DP(14)     I1 @T6G_MB_LIB.T6G(SCH_1):PAGE448
  AA29 P5E_CPU1_P2_RX_DN<14> @T6G_MB_LIB.T6G(SCH_1):P5E_CPU1_P2_RX_DN(14)     I1 @T6G_MB_LIB.T6G(SCH_1):PAGE448
  AF26 P5E_CPU1_P2_RX_DP<13> @T6G_MB_LIB.T6G(SCH_1):P5E_CPU1_P2_RX_DP(13)     I1 @T6G_MB_LIB.T6G(SCH_1):PAGE448
  AH29 P5E_CPU1_P2_RX_DN<13> @T6G_MB_LIB.T6G(SCH_1):P5E_CPU1_P2_RX_DN(13)     I1 @T6G_MB_LIB.T6G(SCH_1):PAGE448
  AN26 P5E_CPU1_P2_RX_DP<12> @T6G_MB_LIB.T6G(SCH_1):P5E_CPU1_P2_RX_DP(12)     I1 @T6G_MB_LIB.T6G(SCH_1):PAGE448
  AR29 P5E_CPU1_P2_RX_DN<12> @T6G_MB_LIB.T6G(SCH_1):P5E_CPU1_P2_RX_DN(12)     I1 @T6G_MB_LIB.T6G(SCH_1):PAGE448
  AY26 P5E_CPU1_P2_RX_DP<11> @T6G_MB_LIB.T6G(SCH_1):P5E_CPU1_P2_RX_DP(11)     I1 @T6G_MB_LIB.T6G(SCH_1):PAGE448
  BB29 P5E_CPU1_P2_RX_DN<11> @T6G_MB_LIB.T6G(SCH_1):P5E_CPU1_P2_RX_DN(11)     I1 @T6G_MB_LIB.T6G(SCH_1):PAGE448
  BG26 P5E_CPU1_P2_RX_DP<10> @T6G_MB_LIB.T6G(SCH_1):P5E_CPU1_P2_RX_DP(10)     I1 @T6G_MB_LIB.T6G(SCH_1):PAGE448
  BJ29 P5E_CPU1_P2_RX_DN<10> @T6G_MB_LIB.T6G(SCH_1):P5E_CPU1_P2_RX_DN(10)     I1 @T6G_MB_LIB.T6G(SCH_1):PAGE448
  BP26 P5E_CPU1_P2_RX_DP<9> @T6G_MB_LIB.T6G(SCH_1):P5E_CPU1_P2_RX_DP(9)     I1 @T6G_MB_LIB.T6G(SCH_1):PAGE448
  BT29 P5E_CPU1_P2_RX_DN<9> @T6G_MB_LIB.T6G(SCH_1):P5E_CPU1_P2_RX_DN(9)     I1 @T6G_MB_LIB.T6G(SCH_1):PAGE448
  CA26 P5E_CPU1_P2_RX_DP<8> @T6G_MB_LIB.T6G(SCH_1):P5E_CPU1_P2_RX_DP(8)     I1 @T6G_MB_LIB.T6G(SCH_1):PAGE448
  CC29 P5E_CPU1_P2_RX_DN<8> @T6G_MB_LIB.T6G(SCH_1):P5E_CPU1_P2_RX_DN(8)     I1 @T6G_MB_LIB.T6G(SCH_1):PAGE448
  CH26 P5E_CPU1_P2_RX_DP<7> @T6G_MB_LIB.T6G(SCH_1):P5E_CPU1_P2_RX_DP(7)    I38 @T6G_MB_LIB.T6G(SCH_1):PAGE448
  CK29 P5E_CPU1_P2_RX_DN<7> @T6G_MB_LIB.T6G(SCH_1):P5E_CPU1_P2_RX_DN(7)    I38 @T6G_MB_LIB.T6G(SCH_1):PAGE448
  CR26 P5E_CPU1_P2_RX_DP<6> @T6G_MB_LIB.T6G(SCH_1):P5E_CPU1_P2_RX_DP(6)    I38 @T6G_MB_LIB.T6G(SCH_1):PAGE448
  CU29 P5E_CPU1_P2_RX_DN<6> @T6G_MB_LIB.T6G(SCH_1):P5E_CPU1_P2_RX_DN(6)    I38 @T6G_MB_LIB.T6G(SCH_1):PAGE448
  DB26 P5E_CPU1_P2_RX_DP<5> @T6G_MB_LIB.T6G(SCH_1):P5E_CPU1_P2_RX_DP(5)    I38 @T6G_MB_LIB.T6G(SCH_1):PAGE448
  DD29 P5E_CPU1_P2_RX_DN<5> @T6G_MB_LIB.T6G(SCH_1):P5E_CPU1_P2_RX_DN(5)    I38 @T6G_MB_LIB.T6G(SCH_1):PAGE448
  DJ26 P5E_CPU1_P2_RX_DP<4> @T6G_MB_LIB.T6G(SCH_1):P5E_CPU1_P2_RX_DP(4)    I38 @T6G_MB_LIB.T6G(SCH_1):PAGE448
  DL29 P5E_CPU1_P2_RX_DN<4> @T6G_MB_LIB.T6G(SCH_1):P5E_CPU1_P2_RX_DN(4)    I38 @T6G_MB_LIB.T6G(SCH_1):PAGE448
  DT26 P5E_CPU1_P2_RX_DP<3> @T6G_MB_LIB.T6G(SCH_1):P5E_CPU1_P2_RX_DP(3)    I38 @T6G_MB_LIB.T6G(SCH_1):PAGE448
  DV29 P5E_CPU1_P2_RX_DN<3> @T6G_MB_LIB.T6G(SCH_1):P5E_CPU1_P2_RX_DN(3)    I38 @T6G_MB_LIB.T6G(SCH_1):PAGE448
  EC26 P5E_CPU1_P2_RX_DP<2> @T6G_MB_LIB.T6G(SCH_1):P5E_CPU1_P2_RX_DP(2)    I38 @T6G_MB_LIB.T6G(SCH_1):PAGE448
  EE29 P5E_CPU1_P2_RX_DN<2> @T6G_MB_LIB.T6G(SCH_1):P5E_CPU1_P2_RX_DN(2)    I38 @T6G_MB_LIB.T6G(SCH_1):PAGE448
  EK26 P5E_CPU1_P2_RX_DP<1> @T6G_MB_LIB.T6G(SCH_1):P5E_CPU1_P2_RX_DP(1)    I38 @T6G_MB_LIB.T6G(SCH_1):PAGE448
  EM29 P5E_CPU1_P2_RX_DN<1> @T6G_MB_LIB.T6G(SCH_1):P5E_CPU1_P2_RX_DN(1)    I38 @T6G_MB_LIB.T6G(SCH_1):PAGE448
  EU26 P5E_CPU1_P2_RX_DP<0> @T6G_MB_LIB.T6G(SCH_1):P5E_CPU1_P2_RX_DP(0)    I38 @T6G_MB_LIB.T6G(SCH_1):PAGE448
  EW29 P5E_CPU1_P2_RX_DN<0> @T6G_MB_LIB.T6G(SCH_1):P5E_CPU1_P2_RX_DN(0)    I38 @T6G_MB_LIB.T6G(SCH_1):PAGE448
   N34 P5E_CPU1_P2_TX_C_DN<15> @T6G_MB_LIB.T6G(SCH_1):P5E_CPU1_P2_TX_C_DN(15)     I1 @T6G_MB_LIB.T6G(SCH_1):PAGE447
   R35 P5E_CPU1_P2_TX_C_DP<15> @T6G_MB_LIB.T6G(SCH_1):P5E_CPU1_P2_TX_C_DP(15)     I1 @T6G_MB_LIB.T6G(SCH_1):PAGE447
   Y34 P5E_CPU1_P2_TX_C_DN<14> @T6G_MB_LIB.T6G(SCH_1):P5E_CPU1_P2_TX_C_DN(14)     I1 @T6G_MB_LIB.T6G(SCH_1):PAGE447
  AB35 P5E_CPU1_P2_TX_C_DP<14> @T6G_MB_LIB.T6G(SCH_1):P5E_CPU1_P2_TX_C_DP(14)     I1 @T6G_MB_LIB.T6G(SCH_1):PAGE447
  AG34 P5E_CPU1_P2_TX_C_DN<13> @T6G_MB_LIB.T6G(SCH_1):P5E_CPU1_P2_TX_C_DN(13)     I1 @T6G_MB_LIB.T6G(SCH_1):PAGE447
  AJ35 P5E_CPU1_P2_TX_C_DP<13> @T6G_MB_LIB.T6G(SCH_1):P5E_CPU1_P2_TX_C_DP(13)     I1 @T6G_MB_LIB.T6G(SCH_1):PAGE447
  AP34 P5E_CPU1_P2_TX_C_DN<12> @T6G_MB_LIB.T6G(SCH_1):P5E_CPU1_P2_TX_C_DN(12)     I1 @T6G_MB_LIB.T6G(SCH_1):PAGE447
  AT35 P5E_CPU1_P2_TX_C_DP<12> @T6G_MB_LIB.T6G(SCH_1):P5E_CPU1_P2_TX_C_DP(12)     I1 @T6G_MB_LIB.T6G(SCH_1):PAGE447
  BA34 P5E_CPU1_P2_TX_C_DN<11> @T6G_MB_LIB.T6G(SCH_1):P5E_CPU1_P2_TX_C_DN(11)     I1 @T6G_MB_LIB.T6G(SCH_1):PAGE447
  BC35 P5E_CPU1_P2_TX_C_DP<11> @T6G_MB_LIB.T6G(SCH_1):P5E_CPU1_P2_TX_C_DP(11)     I1 @T6G_MB_LIB.T6G(SCH_1):PAGE447
  BH34 P5E_CPU1_P2_TX_C_DN<10> @T6G_MB_LIB.T6G(SCH_1):P5E_CPU1_P2_TX_C_DN(10)     I1 @T6G_MB_LIB.T6G(SCH_1):PAGE447
  BK35 P5E_CPU1_P2_TX_C_DP<10> @T6G_MB_LIB.T6G(SCH_1):P5E_CPU1_P2_TX_C_DP(10)     I1 @T6G_MB_LIB.T6G(SCH_1):PAGE447
  BR34 P5E_CPU1_P2_TX_C_DN<9> @T6G_MB_LIB.T6G(SCH_1):P5E_CPU1_P2_TX_C_DN(9)     I1 @T6G_MB_LIB.T6G(SCH_1):PAGE447
  BU35 P5E_CPU1_P2_TX_C_DP<9> @T6G_MB_LIB.T6G(SCH_1):P5E_CPU1_P2_TX_C_DP(9)     I1 @T6G_MB_LIB.T6G(SCH_1):PAGE447
  CB34 P5E_CPU1_P2_TX_C_DN<8> @T6G_MB_LIB.T6G(SCH_1):P5E_CPU1_P2_TX_C_DN(8)     I1 @T6G_MB_LIB.T6G(SCH_1):PAGE447
  CD35 P5E_CPU1_P2_TX_C_DP<8> @T6G_MB_LIB.T6G(SCH_1):P5E_CPU1_P2_TX_C_DP(8)     I1 @T6G_MB_LIB.T6G(SCH_1):PAGE447
  CJ34 P5E_CPU1_P2_TX_C_DN<7> @T6G_MB_LIB.T6G(SCH_1):P5E_CPU1_P2_TX_C_DN(7)    I38 @T6G_MB_LIB.T6G(SCH_1):PAGE447
  CL35 P5E_CPU1_P2_TX_C_DP<7> @T6G_MB_LIB.T6G(SCH_1):P5E_CPU1_P2_TX_C_DP(7)    I38 @T6G_MB_LIB.T6G(SCH_1):PAGE447
  CT34 P5E_CPU1_P2_TX_C_DN<6> @T6G_MB_LIB.T6G(SCH_1):P5E_CPU1_P2_TX_C_DN(6)    I38 @T6G_MB_LIB.T6G(SCH_1):PAGE447
  CV35 P5E_CPU1_P2_TX_C_DP<6> @T6G_MB_LIB.T6G(SCH_1):P5E_CPU1_P2_TX_C_DP(6)    I38 @T6G_MB_LIB.T6G(SCH_1):PAGE447
  DC34 P5E_CPU1_P2_TX_C_DN<5> @T6G_MB_LIB.T6G(SCH_1):P5E_CPU1_P2_TX_C_DN(5)    I38 @T6G_MB_LIB.T6G(SCH_1):PAGE447
  DE35 P5E_CPU1_P2_TX_C_DP<5> @T6G_MB_LIB.T6G(SCH_1):P5E_CPU1_P2_TX_C_DP(5)    I38 @T6G_MB_LIB.T6G(SCH_1):PAGE447
  DK34 P5E_CPU1_P2_TX_C_DN<4> @T6G_MB_LIB.T6G(SCH_1):P5E_CPU1_P2_TX_C_DN(4)    I38 @T6G_MB_LIB.T6G(SCH_1):PAGE447
  DM35 P5E_CPU1_P2_TX_C_DP<4> @T6G_MB_LIB.T6G(SCH_1):P5E_CPU1_P2_TX_C_DP(4)    I38 @T6G_MB_LIB.T6G(SCH_1):PAGE447
  DU34 P5E_CPU1_P2_TX_C_DN<3> @T6G_MB_LIB.T6G(SCH_1):P5E_CPU1_P2_TX_C_DN(3)    I38 @T6G_MB_LIB.T6G(SCH_1):PAGE447
  DW35 P5E_CPU1_P2_TX_C_DP<3> @T6G_MB_LIB.T6G(SCH_1):P5E_CPU1_P2_TX_C_DP(3)    I38 @T6G_MB_LIB.T6G(SCH_1):PAGE447
  ED34 P5E_CPU1_P2_TX_C_DN<2> @T6G_MB_LIB.T6G(SCH_1):P5E_CPU1_P2_TX_C_DN(2)    I38 @T6G_MB_LIB.T6G(SCH_1):PAGE447
  EF35 P5E_CPU1_P2_TX_C_DP<2> @T6G_MB_LIB.T6G(SCH_1):P5E_CPU1_P2_TX_C_DP(2)    I38 @T6G_MB_LIB.T6G(SCH_1):PAGE447
  EL34 P5E_CPU1_P2_TX_C_DP<1> @T6G_MB_LIB.T6G(SCH_1):P5E_CPU1_P2_TX_C_DP(1)    I38 @T6G_MB_LIB.T6G(SCH_1):PAGE447
  EN35 P5E_CPU1_P2_TX_C_DN<1> @T6G_MB_LIB.T6G(SCH_1):P5E_CPU1_P2_TX_C_DN(1)    I38 @T6G_MB_LIB.T6G(SCH_1):PAGE447
  EV34 P5E_CPU1_P2_TX_C_DN<0> @T6G_MB_LIB.T6G(SCH_1):P5E_CPU1_P2_TX_C_DN(0)    I38 @T6G_MB_LIB.T6G(SCH_1):PAGE447
  EY35 P5E_CPU1_P2_TX_C_DP<0> @T6G_MB_LIB.T6G(SCH_1):P5E_CPU1_P2_TX_C_DP(0)    I38 @T6G_MB_LIB.T6G(SCH_1):PAGE447
    M7 P5E_CPU1_P2_TX_BUF_DP<15> @T6G_MB_LIB.T6G(SCH_1):P5E_CPU1_P2_TX_BUF_DP(15)    I33 @T6G_MB_LIB.T6G(SCH_1):PAGE450
   P10 P5E_CPU1_P2_TX_BUF_DN<15> @T6G_MB_LIB.T6G(SCH_1):P5E_CPU1_P2_TX_BUF_DN(15)    I33 @T6G_MB_LIB.T6G(SCH_1):PAGE450
    W7 P5E_CPU1_P2_TX_BUF_DP<14> @T6G_MB_LIB.T6G(SCH_1):P5E_CPU1_P2_TX_BUF_DP(14)    I33 @T6G_MB_LIB.T6G(SCH_1):PAGE450
  AA10 P5E_CPU1_P2_TX_BUF_DN<14> @T6G_MB_LIB.T6G(SCH_1):P5E_CPU1_P2_TX_BUF_DN(14)    I33 @T6G_MB_LIB.T6G(SCH_1):PAGE450
   AF7 P5E_CPU1_P2_TX_BUF_DP<13> @T6G_MB_LIB.T6G(SCH_1):P5E_CPU1_P2_TX_BUF_DP(13)    I33 @T6G_MB_LIB.T6G(SCH_1):PAGE450
  AH10 P5E_CPU1_P2_TX_BUF_DN<13> @T6G_MB_LIB.T6G(SCH_1):P5E_CPU1_P2_TX_BUF_DN(13)    I33 @T6G_MB_LIB.T6G(SCH_1):PAGE450
   AN7 P5E_CPU1_P2_TX_BUF_DP<12> @T6G_MB_LIB.T6G(SCH_1):P5E_CPU1_P2_TX_BUF_DP(12)    I33 @T6G_MB_LIB.T6G(SCH_1):PAGE450
  AR10 P5E_CPU1_P2_TX_BUF_DN<12> @T6G_MB_LIB.T6G(SCH_1):P5E_CPU1_P2_TX_BUF_DN(12)    I33 @T6G_MB_LIB.T6G(SCH_1):PAGE450
   AY7 P5E_CPU1_P2_TX_BUF_DP<11> @T6G_MB_LIB.T6G(SCH_1):P5E_CPU1_P2_TX_BUF_DP(11)    I33 @T6G_MB_LIB.T6G(SCH_1):PAGE450
  BB10 P5E_CPU1_P2_TX_BUF_DN<11> @T6G_MB_LIB.T6G(SCH_1):P5E_CPU1_P2_TX_BUF_DN(11)    I33 @T6G_MB_LIB.T6G(SCH_1):PAGE450
   BG7 P5E_CPU1_P2_TX_BUF_DP<10> @T6G_MB_LIB.T6G(SCH_1):P5E_CPU1_P2_TX_BUF_DP(10)    I33 @T6G_MB_LIB.T6G(SCH_1):PAGE450
  BJ10 P5E_CPU1_P2_TX_BUF_DN<10> @T6G_MB_LIB.T6G(SCH_1):P5E_CPU1_P2_TX_BUF_DN(10)    I33 @T6G_MB_LIB.T6G(SCH_1):PAGE450
   BP7 P5E_CPU1_P2_TX_BUF_DP<9> @T6G_MB_LIB.T6G(SCH_1):P5E_CPU1_P2_TX_BUF_DP(9)    I33 @T6G_MB_LIB.T6G(SCH_1):PAGE450
  BT10 P5E_CPU1_P2_TX_BUF_DN<9> @T6G_MB_LIB.T6G(SCH_1):P5E_CPU1_P2_TX_BUF_DN(9)    I33 @T6G_MB_LIB.T6G(SCH_1):PAGE450
   CA7 P5E_CPU1_P2_TX_BUF_DP<8> @T6G_MB_LIB.T6G(SCH_1):P5E_CPU1_P2_TX_BUF_DP(8)    I33 @T6G_MB_LIB.T6G(SCH_1):PAGE450
  CC10 P5E_CPU1_P2_TX_BUF_DN<8> @T6G_MB_LIB.T6G(SCH_1):P5E_CPU1_P2_TX_BUF_DN(8)    I33 @T6G_MB_LIB.T6G(SCH_1):PAGE450
   CH7 P5E_CPU1_P2_TX_BUF_DP<7> @T6G_MB_LIB.T6G(SCH_1):P5E_CPU1_P2_TX_BUF_DP(7)   I142 @T6G_MB_LIB.T6G(SCH_1):PAGE450
  CK10 P5E_CPU1_P2_TX_BUF_DN<7> @T6G_MB_LIB.T6G(SCH_1):P5E_CPU1_P2_TX_BUF_DN(7)   I142 @T6G_MB_LIB.T6G(SCH_1):PAGE450
   CR7 P5E_CPU1_P2_TX_BUF_DP<6> @T6G_MB_LIB.T6G(SCH_1):P5E_CPU1_P2_TX_BUF_DP(6)   I142 @T6G_MB_LIB.T6G(SCH_1):PAGE450
  CU10 P5E_CPU1_P2_TX_BUF_DN<6> @T6G_MB_LIB.T6G(SCH_1):P5E_CPU1_P2_TX_BUF_DN(6)   I142 @T6G_MB_LIB.T6G(SCH_1):PAGE450
   DB7 P5E_CPU1_P2_TX_BUF_DP<5> @T6G_MB_LIB.T6G(SCH_1):P5E_CPU1_P2_TX_BUF_DP(5)   I142 @T6G_MB_LIB.T6G(SCH_1):PAGE450
  DD10 P5E_CPU1_P2_TX_BUF_DN<5> @T6G_MB_LIB.T6G(SCH_1):P5E_CPU1_P2_TX_BUF_DN(5)   I142 @T6G_MB_LIB.T6G(SCH_1):PAGE450
   DJ7 P5E_CPU1_P2_TX_BUF_DP<4> @T6G_MB_LIB.T6G(SCH_1):P5E_CPU1_P2_TX_BUF_DP(4)   I142 @T6G_MB_LIB.T6G(SCH_1):PAGE450
  DL10 P5E_CPU1_P2_TX_BUF_DN<4> @T6G_MB_LIB.T6G(SCH_1):P5E_CPU1_P2_TX_BUF_DN(4)   I142 @T6G_MB_LIB.T6G(SCH_1):PAGE450
   DT7 P5E_CPU1_P2_TX_BUF_DP<3> @T6G_MB_LIB.T6G(SCH_1):P5E_CPU1_P2_TX_BUF_DP(3)   I142 @T6G_MB_LIB.T6G(SCH_1):PAGE450
  DV10 P5E_CPU1_P2_TX_BUF_DN<3> @T6G_MB_LIB.T6G(SCH_1):P5E_CPU1_P2_TX_BUF_DN(3)   I142 @T6G_MB_LIB.T6G(SCH_1):PAGE450
   EC7 P5E_CPU1_P2_TX_BUF_DP<2> @T6G_MB_LIB.T6G(SCH_1):P5E_CPU1_P2_TX_BUF_DP(2)   I142 @T6G_MB_LIB.T6G(SCH_1):PAGE450
  EE10 P5E_CPU1_P2_TX_BUF_DN<2> @T6G_MB_LIB.T6G(SCH_1):P5E_CPU1_P2_TX_BUF_DN(2)   I142 @T6G_MB_LIB.T6G(SCH_1):PAGE450
   EK7 P5E_CPU1_P2_TX_BUF_DP<1> @T6G_MB_LIB.T6G(SCH_1):P5E_CPU1_P2_TX_BUF_DP(1)   I142 @T6G_MB_LIB.T6G(SCH_1):PAGE450
  EM10 P5E_CPU1_P2_TX_BUF_DN<1> @T6G_MB_LIB.T6G(SCH_1):P5E_CPU1_P2_TX_BUF_DN(1)   I142 @T6G_MB_LIB.T6G(SCH_1):PAGE450
   EU7 P5E_CPU1_P2_TX_BUF_DP<0> @T6G_MB_LIB.T6G(SCH_1):P5E_CPU1_P2_TX_BUF_DP(0)   I142 @T6G_MB_LIB.T6G(SCH_1):PAGE450
  EW10 P5E_CPU1_P2_TX_BUF_DN<0> @T6G_MB_LIB.T6G(SCH_1):P5E_CPU1_P2_TX_BUF_DN(0)   I142 @T6G_MB_LIB.T6G(SCH_1):PAGE450

U6017 PT5161LRS-PT5161LRS,SMLF,IC,AJ051610U03
    R1 P5E_CPU1_P3_RX_BUF_DP<15> @T6G_MB_LIB.T6G(SCH_1):P5E_CPU1_P3_RX_BUF_DP(15)     I1 @T6G_MB_LIB.T6G(SCH_1):PAGE460
    N2 P5E_CPU1_P3_RX_BUF_DN<15> @T6G_MB_LIB.T6G(SCH_1):P5E_CPU1_P3_RX_BUF_DN(15)     I1 @T6G_MB_LIB.T6G(SCH_1):PAGE460
   AB1 P5E_CPU1_P3_RX_BUF_DP<14> @T6G_MB_LIB.T6G(SCH_1):P5E_CPU1_P3_RX_BUF_DP(14)     I1 @T6G_MB_LIB.T6G(SCH_1):PAGE460
    Y2 P5E_CPU1_P3_RX_BUF_DN<14> @T6G_MB_LIB.T6G(SCH_1):P5E_CPU1_P3_RX_BUF_DN(14)     I1 @T6G_MB_LIB.T6G(SCH_1):PAGE460
   AJ1 P5E_CPU1_P3_RX_BUF_DP<13> @T6G_MB_LIB.T6G(SCH_1):P5E_CPU1_P3_RX_BUF_DP(13)     I1 @T6G_MB_LIB.T6G(SCH_1):PAGE460
   AG2 P5E_CPU1_P3_RX_BUF_DN<13> @T6G_MB_LIB.T6G(SCH_1):P5E_CPU1_P3_RX_BUF_DN(13)     I1 @T6G_MB_LIB.T6G(SCH_1):PAGE460
   AT1 P5E_CPU1_P3_RX_BUF_DP<12> @T6G_MB_LIB.T6G(SCH_1):P5E_CPU1_P3_RX_BUF_DP(12)     I1 @T6G_MB_LIB.T6G(SCH_1):PAGE460
   AP2 P5E_CPU1_P3_RX_BUF_DN<12> @T6G_MB_LIB.T6G(SCH_1):P5E_CPU1_P3_RX_BUF_DN(12)     I1 @T6G_MB_LIB.T6G(SCH_1):PAGE460
   BC1 P5E_CPU1_P3_RX_BUF_DP<11> @T6G_MB_LIB.T6G(SCH_1):P5E_CPU1_P3_RX_BUF_DP(11)     I1 @T6G_MB_LIB.T6G(SCH_1):PAGE460
   BA2 P5E_CPU1_P3_RX_BUF_DN<11> @T6G_MB_LIB.T6G(SCH_1):P5E_CPU1_P3_RX_BUF_DN(11)     I1 @T6G_MB_LIB.T6G(SCH_1):PAGE460
   BK1 P5E_CPU1_P3_RX_BUF_DP<10> @T6G_MB_LIB.T6G(SCH_1):P5E_CPU1_P3_RX_BUF_DP(10)     I1 @T6G_MB_LIB.T6G(SCH_1):PAGE460
   BH2 P5E_CPU1_P3_RX_BUF_DN<10> @T6G_MB_LIB.T6G(SCH_1):P5E_CPU1_P3_RX_BUF_DN(10)     I1 @T6G_MB_LIB.T6G(SCH_1):PAGE460
   BU1 P5E_CPU1_P3_RX_BUF_DP<9> @T6G_MB_LIB.T6G(SCH_1):P5E_CPU1_P3_RX_BUF_DP(9)     I1 @T6G_MB_LIB.T6G(SCH_1):PAGE460
   BR2 P5E_CPU1_P3_RX_BUF_DN<9> @T6G_MB_LIB.T6G(SCH_1):P5E_CPU1_P3_RX_BUF_DN(9)     I1 @T6G_MB_LIB.T6G(SCH_1):PAGE460
   CD1 P5E_CPU1_P3_RX_BUF_DP<8> @T6G_MB_LIB.T6G(SCH_1):P5E_CPU1_P3_RX_BUF_DP(8)     I1 @T6G_MB_LIB.T6G(SCH_1):PAGE460
   CB2 P5E_CPU1_P3_RX_BUF_DN<8> @T6G_MB_LIB.T6G(SCH_1):P5E_CPU1_P3_RX_BUF_DN(8)     I1 @T6G_MB_LIB.T6G(SCH_1):PAGE460
   CL1 P5E_CPU1_P3_RX_BUF_DP<7> @T6G_MB_LIB.T6G(SCH_1):P5E_CPU1_P3_RX_BUF_DP(7)    I38 @T6G_MB_LIB.T6G(SCH_1):PAGE460
   CJ2 P5E_CPU1_P3_RX_BUF_DN<7> @T6G_MB_LIB.T6G(SCH_1):P5E_CPU1_P3_RX_BUF_DN(7)    I38 @T6G_MB_LIB.T6G(SCH_1):PAGE460
   CV1 P5E_CPU1_P3_RX_BUF_DP<6> @T6G_MB_LIB.T6G(SCH_1):P5E_CPU1_P3_RX_BUF_DP(6)    I38 @T6G_MB_LIB.T6G(SCH_1):PAGE460
   CT2 P5E_CPU1_P3_RX_BUF_DN<6> @T6G_MB_LIB.T6G(SCH_1):P5E_CPU1_P3_RX_BUF_DN(6)    I38 @T6G_MB_LIB.T6G(SCH_1):PAGE460
   DE1 P5E_CPU1_P3_RX_BUF_DP<5> @T6G_MB_LIB.T6G(SCH_1):P5E_CPU1_P3_RX_BUF_DP(5)    I38 @T6G_MB_LIB.T6G(SCH_1):PAGE460
   DC2 P5E_CPU1_P3_RX_BUF_DN<5> @T6G_MB_LIB.T6G(SCH_1):P5E_CPU1_P3_RX_BUF_DN(5)    I38 @T6G_MB_LIB.T6G(SCH_1):PAGE460
   DM1 P5E_CPU1_P3_RX_BUF_DP<4> @T6G_MB_LIB.T6G(SCH_1):P5E_CPU1_P3_RX_BUF_DP(4)    I38 @T6G_MB_LIB.T6G(SCH_1):PAGE460
   DK2 P5E_CPU1_P3_RX_BUF_DN<4> @T6G_MB_LIB.T6G(SCH_1):P5E_CPU1_P3_RX_BUF_DN(4)    I38 @T6G_MB_LIB.T6G(SCH_1):PAGE460
   DW1 P5E_CPU1_P3_RX_BUF_DP<3> @T6G_MB_LIB.T6G(SCH_1):P5E_CPU1_P3_RX_BUF_DP(3)    I38 @T6G_MB_LIB.T6G(SCH_1):PAGE460
   DU2 P5E_CPU1_P3_RX_BUF_DN<3> @T6G_MB_LIB.T6G(SCH_1):P5E_CPU1_P3_RX_BUF_DN(3)    I38 @T6G_MB_LIB.T6G(SCH_1):PAGE460
   EF1 P5E_CPU1_P3_RX_BUF_DP<2> @T6G_MB_LIB.T6G(SCH_1):P5E_CPU1_P3_RX_BUF_DP(2)    I38 @T6G_MB_LIB.T6G(SCH_1):PAGE460
   ED2 P5E_CPU1_P3_RX_BUF_DN<2> @T6G_MB_LIB.T6G(SCH_1):P5E_CPU1_P3_RX_BUF_DN(2)    I38 @T6G_MB_LIB.T6G(SCH_1):PAGE460
   EN1 P5E_CPU1_P3_RX_BUF_DP<1> @T6G_MB_LIB.T6G(SCH_1):P5E_CPU1_P3_RX_BUF_DP(1)    I38 @T6G_MB_LIB.T6G(SCH_1):PAGE460
   EL2 P5E_CPU1_P3_RX_BUF_DN<1> @T6G_MB_LIB.T6G(SCH_1):P5E_CPU1_P3_RX_BUF_DN(1)    I38 @T6G_MB_LIB.T6G(SCH_1):PAGE460
   EY1 P5E_CPU1_P3_RX_BUF_DP<0> @T6G_MB_LIB.T6G(SCH_1):P5E_CPU1_P3_RX_BUF_DP(0)    I38 @T6G_MB_LIB.T6G(SCH_1):PAGE460
   EV2 P5E_CPU1_P3_RX_BUF_DN<0> @T6G_MB_LIB.T6G(SCH_1):P5E_CPU1_P3_RX_BUF_DN(0)    I38 @T6G_MB_LIB.T6G(SCH_1):PAGE460
   FJ6     NC     NC    I97 @T6G_MB_LIB.T6G(SCH_1):PAGE462
  FJ23     NC     NC    I97 @T6G_MB_LIB.T6G(SCH_1):PAGE462
  FJ25 GPIO2_RT_CPU1_P3 @T6G_MB_LIB.T6G(SCH_1):GPIO2_RT_CPU1_P3    I97 @T6G_MB_LIB.T6G(SCH_1):PAGE462
  FJ28 GPIO3_RT_CPU1_P3 @T6G_MB_LIB.T6G(SCH_1):GPIO3_RT_CPU1_P3    I97 @T6G_MB_LIB.T6G(SCH_1):PAGE462
  FJ31     NC     NC    I97 @T6G_MB_LIB.T6G(SCH_1):PAGE462
    B3 JTAG_TCK_RT_CPU1_P3 @T6G_MB_LIB.T6G(SCH_1):JTAG_TCK_RT_CPU1_P3    I97 @T6G_MB_LIB.T6G(SCH_1):PAGE462
    B6 JTAG_TDI_RT_CPU1_P3 @T6G_MB_LIB.T6G(SCH_1):JTAG_TDI_RT_CPU1_P3    I97 @T6G_MB_LIB.T6G(SCH_1):PAGE462
    B9 JTAG_TDO_RT_CPU1_P3 @T6G_MB_LIB.T6G(SCH_1):JTAG_TDO_RT_CPU1_P3    I97 @T6G_MB_LIB.T6G(SCH_1):PAGE462
   FF8 JTAG_TEST_MODE_RT_CPU1_P3 @T6G_MB_LIB.T6G(SCH_1):JTAG_TEST_MODE_RT_CPU1_P3    I97 @T6G_MB_LIB.T6G(SCH_1):PAGE462
   B12 JTAG_TMS_RT_CPU1_P3 @T6G_MB_LIB.T6G(SCH_1):JTAG_TMS_RT_CPU1_P3    I97 @T6G_MB_LIB.T6G(SCH_1):PAGE462
    E8 JTAG_TRST_RT_CPU1_P3_N @T6G_MB_LIB.T6G(SCH_1):JTAG_TRST_RT_CPU1_P3_N    I97 @T6G_MB_LIB.T6G(SCH_1):PAGE462
   FJ9 MODE_RT_CPU1_P3 @T6G_MB_LIB.T6G(SCH_1):MODE_RT_CPU1_P3    I97 @T6G_MB_LIB.T6G(SCH_1):PAGE462
    F2 RST_RT_CPU1_P3_PERST_N @T6G_MB_LIB.T6G(SCH_1):RST_RT_CPU1_P3_PERST_N    I97 @T6G_MB_LIB.T6G(SCH_1):PAGE462
   E18     NC     NC    I97 @T6G_MB_LIB.T6G(SCH_1):PAGE462
   B16     NC     NC    I97 @T6G_MB_LIB.T6G(SCH_1):PAGE462
  FF18 CLK_100M_RETIMER_CPU1_P3_DN @T6G_MB_LIB.T6G(SCH_1):CLK_100M_RETIMER_CPU1_P3_DN    I97 @T6G_MB_LIB.T6G(SCH_1):PAGE462
  FJ16 CLK_100M_RETIMER_CPU1_P3_DP @T6G_MB_LIB.T6G(SCH_1):CLK_100M_RETIMER_CPU1_P3_DP    I97 @T6G_MB_LIB.T6G(SCH_1):PAGE462
  FF11 RST_RT_CPU1_P3_RESET_N @T6G_MB_LIB.T6G(SCH_1):RST_RT_CPU1_P3_RESET_N    I97 @T6G_MB_LIB.T6G(SCH_1):PAGE462
   E11 RXDET_BYP_RT_CPU1_P3 @T6G_MB_LIB.T6G(SCH_1):RXDET_BYP_RT_CPU1_P3    I97 @T6G_MB_LIB.T6G(SCH_1):PAGE462
  FF33 RT_CPU1_P3_SCAN_MODE @T6G_MB_LIB.T6G(SCH_1):RT_CPU1_P3_SCAN_MODE    I97 @T6G_MB_LIB.T6G(SCH_1):PAGE462
   F34 RT_CPU1_P3_ADDR1 @T6G_MB_LIB.T6G(SCH_1):RT_CPU1_P3_ADDR1    I97 @T6G_MB_LIB.T6G(SCH_1):PAGE462
   B23 RT_CPU1_P3_ADDR2 @T6G_MB_LIB.T6G(SCH_1):RT_CPU1_P3_ADDR2    I97 @T6G_MB_LIB.T6G(SCH_1):PAGE462
   B25 RT_CPU1_P3_ADDR3 @T6G_MB_LIB.T6G(SCH_1):RT_CPU1_P3_ADDR3    I97 @T6G_MB_LIB.T6G(SCH_1):PAGE462
   B31 SMB_RT_CPU1_P3_R2_SCL @T6G_MB_LIB.T6G(SCH_1):SMB_RT_CPU1_P3_R2_SCL    I97 @T6G_MB_LIB.T6G(SCH_1):PAGE462
   B28 SMB_RT_CPU1_P3_R2_SDA @T6G_MB_LIB.T6G(SCH_1):SMB_RT_CPU1_P3_R2_SDA    I97 @T6G_MB_LIB.T6G(SCH_1):PAGE462
   E30    GND @T6G_MB_LIB.T6G(SCH_1):GND    I97 @T6G_MB_LIB.T6G(SCH_1):PAGE462
  FF24 TEST0_RT_CPU1_P3 @T6G_MB_LIB.T6G(SCH_1):TEST0_RT_CPU1_P3    I97 @T6G_MB_LIB.T6G(SCH_1):PAGE462
  FF27 TEST1_RT_CPU1_P3 @T6G_MB_LIB.T6G(SCH_1):TEST1_RT_CPU1_P3    I97 @T6G_MB_LIB.T6G(SCH_1):PAGE462
  FF30 TEST2_RT_CPU1_P3 @T6G_MB_LIB.T6G(SCH_1):TEST2_RT_CPU1_P3    I97 @T6G_MB_LIB.T6G(SCH_1):PAGE462
   G35 CLKREQ_RT_CPU1_P3_N @T6G_MB_LIB.T6G(SCH_1):CLKREQ_RT_CPU1_P3_N    I97 @T6G_MB_LIB.T6G(SCH_1):PAGE462
   FF5 SMB_RT_CPU1_P3_ROM_MUX_1D_R_SCL @T6G_MB_LIB.T6G(SCH_1):SMB_RT_CPU1_P3_ROM_MUX_1D_R_SCL    I97 @T6G_MB_LIB.T6G(SCH_1):PAGE462
   FJ3 SMB_RT_CPU1_P3_ROM_MUX_1D_R_SDA @T6G_MB_LIB.T6G(SCH_1):SMB_RT_CPU1_P3_ROM_MUX_1D_R_SDA    I97 @T6G_MB_LIB.T6G(SCH_1):PAGE462
    G1 RT_CPU1_P3_VQPS @T6G_MB_LIB.T6G(SCH_1):RT_CPU1_P3_VQPS     I5 @T6G_MB_LIB.T6G(SCH_1):PAGE463
  BV20 P1V8_CPU1_RT3_1A @T6G_MB_LIB.T6G(SCH_1):P1V8_CPU1_RT3_1A     I5 @T6G_MB_LIB.T6G(SCH_1):PAGE463
  CE17 P1V8_CPU1_RT3_1A @T6G_MB_LIB.T6G(SCH_1):P1V8_CPU1_RT3_1A     I5 @T6G_MB_LIB.T6G(SCH_1):PAGE463
  CE20 P1V8_CPU1_RT3_1A @T6G_MB_LIB.T6G(SCH_1):P1V8_CPU1_RT3_1A     I5 @T6G_MB_LIB.T6G(SCH_1):PAGE463
  CM17 P1V8_CPU1_RT3_1A @T6G_MB_LIB.T6G(SCH_1):P1V8_CPU1_RT3_1A     I5 @T6G_MB_LIB.T6G(SCH_1):PAGE463
  CM20 P1V8_CPU1_RT3_1A @T6G_MB_LIB.T6G(SCH_1):P1V8_CPU1_RT3_1A     I5 @T6G_MB_LIB.T6G(SCH_1):PAGE463
  BL17 P0V9_CPU1_RT_2D @T6G_MB_LIB.T6G(SCH_1):P0V9_CPU1_RT_2D     I5 @T6G_MB_LIB.T6G(SCH_1):PAGE463
  BL20 P0V9_CPU1_RT_2D @T6G_MB_LIB.T6G(SCH_1):P0V9_CPU1_RT_2D     I5 @T6G_MB_LIB.T6G(SCH_1):PAGE463
  CW17 P0V9_CPU1_RT_2D @T6G_MB_LIB.T6G(SCH_1):P0V9_CPU1_RT_2D     I5 @T6G_MB_LIB.T6G(SCH_1):PAGE463
  CW20 P0V9_CPU1_RT_2D @T6G_MB_LIB.T6G(SCH_1):P0V9_CPU1_RT_2D     I5 @T6G_MB_LIB.T6G(SCH_1):PAGE463
  BV17 P1V8_CPU1_RT3_1A_1D @T6G_MB_LIB.T6G(SCH_1):P1V8_CPU1_RT3_1A_1D     I5 @T6G_MB_LIB.T6G(SCH_1):PAGE463
  AC17 P0V9_CPU1_RT3_2A @T6G_MB_LIB.T6G(SCH_1):P0V9_CPU1_RT3_2A     I5 @T6G_MB_LIB.T6G(SCH_1):PAGE463
  AC20 P0V9_CPU1_RT3_2A @T6G_MB_LIB.T6G(SCH_1):P0V9_CPU1_RT3_2A     I5 @T6G_MB_LIB.T6G(SCH_1):PAGE463
  AK17 P0V9_CPU1_RT3_2A @T6G_MB_LIB.T6G(SCH_1):P0V9_CPU1_RT3_2A     I5 @T6G_MB_LIB.T6G(SCH_1):PAGE463
  AK20 P0V9_CPU1_RT3_2A @T6G_MB_LIB.T6G(SCH_1):P0V9_CPU1_RT3_2A     I5 @T6G_MB_LIB.T6G(SCH_1):PAGE463
  AU17 P0V9_CPU1_RT3_2A @T6G_MB_LIB.T6G(SCH_1):P0V9_CPU1_RT3_2A     I5 @T6G_MB_LIB.T6G(SCH_1):PAGE463
  AU20 P0V9_CPU1_RT3_2A @T6G_MB_LIB.T6G(SCH_1):P0V9_CPU1_RT3_2A     I5 @T6G_MB_LIB.T6G(SCH_1):PAGE463
  BD17 P0V9_CPU1_RT3_2A_2D @T6G_MB_LIB.T6G(SCH_1):P0V9_CPU1_RT3_2A_2D     I5 @T6G_MB_LIB.T6G(SCH_1):PAGE463
  BD20 P0V9_CPU1_RT3_2A_2D @T6G_MB_LIB.T6G(SCH_1):P0V9_CPU1_RT3_2A_2D     I5 @T6G_MB_LIB.T6G(SCH_1):PAGE463
  DF17 P0V9_CPU1_RT3_2A_2D @T6G_MB_LIB.T6G(SCH_1):P0V9_CPU1_RT3_2A_2D     I5 @T6G_MB_LIB.T6G(SCH_1):PAGE463
  DF20 P0V9_CPU1_RT3_2A_2D @T6G_MB_LIB.T6G(SCH_1):P0V9_CPU1_RT3_2A_2D     I5 @T6G_MB_LIB.T6G(SCH_1):PAGE463
  DN17 P0V9_CPU1_RT3_2A @T6G_MB_LIB.T6G(SCH_1):P0V9_CPU1_RT3_2A     I5 @T6G_MB_LIB.T6G(SCH_1):PAGE463
  DN20 P0V9_CPU1_RT3_2A @T6G_MB_LIB.T6G(SCH_1):P0V9_CPU1_RT3_2A     I5 @T6G_MB_LIB.T6G(SCH_1):PAGE463
  DY17 P0V9_CPU1_RT3_2A @T6G_MB_LIB.T6G(SCH_1):P0V9_CPU1_RT3_2A     I5 @T6G_MB_LIB.T6G(SCH_1):PAGE463
  DY20 P0V9_CPU1_RT3_2A @T6G_MB_LIB.T6G(SCH_1):P0V9_CPU1_RT3_2A     I5 @T6G_MB_LIB.T6G(SCH_1):PAGE463
  EG17 P0V9_CPU1_RT3_2A @T6G_MB_LIB.T6G(SCH_1):P0V9_CPU1_RT3_2A     I5 @T6G_MB_LIB.T6G(SCH_1):PAGE463
  EG20 P0V9_CPU1_RT3_2A @T6G_MB_LIB.T6G(SCH_1):P0V9_CPU1_RT3_2A     I5 @T6G_MB_LIB.T6G(SCH_1):PAGE463
  EP17 P0V9_CPU1_RT3_2A @T6G_MB_LIB.T6G(SCH_1):P0V9_CPU1_RT3_2A     I5 @T6G_MB_LIB.T6G(SCH_1):PAGE463
  EP20 P0V9_CPU1_RT3_2A @T6G_MB_LIB.T6G(SCH_1):P0V9_CPU1_RT3_2A     I5 @T6G_MB_LIB.T6G(SCH_1):PAGE463
   T17 P0V9_CPU1_RT3_2A @T6G_MB_LIB.T6G(SCH_1):P0V9_CPU1_RT3_2A     I5 @T6G_MB_LIB.T6G(SCH_1):PAGE463
   T20 P0V9_CPU1_RT3_2A @T6G_MB_LIB.T6G(SCH_1):P0V9_CPU1_RT3_2A     I5 @T6G_MB_LIB.T6G(SCH_1):PAGE463
  AC13    GND @T6G_MB_LIB.T6G(SCH_1):GND    I17 @T6G_MB_LIB.T6G(SCH_1):PAGE463
  AC22    GND @T6G_MB_LIB.T6G(SCH_1):GND    I17 @T6G_MB_LIB.T6G(SCH_1):PAGE463
  AC32    GND @T6G_MB_LIB.T6G(SCH_1):GND    I17 @T6G_MB_LIB.T6G(SCH_1):PAGE463
   AC4    GND @T6G_MB_LIB.T6G(SCH_1):GND    I17 @T6G_MB_LIB.T6G(SCH_1):PAGE463
   AD2    GND @T6G_MB_LIB.T6G(SCH_1):GND    I17 @T6G_MB_LIB.T6G(SCH_1):PAGE463
  AD34    GND @T6G_MB_LIB.T6G(SCH_1):GND    I17 @T6G_MB_LIB.T6G(SCH_1):PAGE463
   AE1    GND @T6G_MB_LIB.T6G(SCH_1):GND    I17 @T6G_MB_LIB.T6G(SCH_1):PAGE463
  AE35    GND @T6G_MB_LIB.T6G(SCH_1):GND    I17 @T6G_MB_LIB.T6G(SCH_1):PAGE463
  AK13    GND @T6G_MB_LIB.T6G(SCH_1):GND    I17 @T6G_MB_LIB.T6G(SCH_1):PAGE463
  AK22    GND @T6G_MB_LIB.T6G(SCH_1):GND    I17 @T6G_MB_LIB.T6G(SCH_1):PAGE463
  AK32    GND @T6G_MB_LIB.T6G(SCH_1):GND    I17 @T6G_MB_LIB.T6G(SCH_1):PAGE463
   AK4    GND @T6G_MB_LIB.T6G(SCH_1):GND    I17 @T6G_MB_LIB.T6G(SCH_1):PAGE463
   AL2    GND @T6G_MB_LIB.T6G(SCH_1):GND    I17 @T6G_MB_LIB.T6G(SCH_1):PAGE463
  AL34    GND @T6G_MB_LIB.T6G(SCH_1):GND    I17 @T6G_MB_LIB.T6G(SCH_1):PAGE463
   AM1    GND @T6G_MB_LIB.T6G(SCH_1):GND    I17 @T6G_MB_LIB.T6G(SCH_1):PAGE463
  AM35    GND @T6G_MB_LIB.T6G(SCH_1):GND    I17 @T6G_MB_LIB.T6G(SCH_1):PAGE463
  AU13    GND @T6G_MB_LIB.T6G(SCH_1):GND    I17 @T6G_MB_LIB.T6G(SCH_1):PAGE463
  AU22    GND @T6G_MB_LIB.T6G(SCH_1):GND    I17 @T6G_MB_LIB.T6G(SCH_1):PAGE463
  AU32    GND @T6G_MB_LIB.T6G(SCH_1):GND    I17 @T6G_MB_LIB.T6G(SCH_1):PAGE463
   AU4    GND @T6G_MB_LIB.T6G(SCH_1):GND    I17 @T6G_MB_LIB.T6G(SCH_1):PAGE463
   AV2    GND @T6G_MB_LIB.T6G(SCH_1):GND    I17 @T6G_MB_LIB.T6G(SCH_1):PAGE463
  AV34    GND @T6G_MB_LIB.T6G(SCH_1):GND    I17 @T6G_MB_LIB.T6G(SCH_1):PAGE463
   AW1    GND @T6G_MB_LIB.T6G(SCH_1):GND    I17 @T6G_MB_LIB.T6G(SCH_1):PAGE463
  AW35    GND @T6G_MB_LIB.T6G(SCH_1):GND    I17 @T6G_MB_LIB.T6G(SCH_1):PAGE463
   B19    GND @T6G_MB_LIB.T6G(SCH_1):GND    I17 @T6G_MB_LIB.T6G(SCH_1):PAGE463
  BD13    GND @T6G_MB_LIB.T6G(SCH_1):GND    I17 @T6G_MB_LIB.T6G(SCH_1):PAGE463
  BD22    GND @T6G_MB_LIB.T6G(SCH_1):GND    I17 @T6G_MB_LIB.T6G(SCH_1):PAGE463
  BD32    GND @T6G_MB_LIB.T6G(SCH_1):GND    I17 @T6G_MB_LIB.T6G(SCH_1):PAGE463
   BD4    GND @T6G_MB_LIB.T6G(SCH_1):GND    I17 @T6G_MB_LIB.T6G(SCH_1):PAGE463
   BE2    GND @T6G_MB_LIB.T6G(SCH_1):GND    I17 @T6G_MB_LIB.T6G(SCH_1):PAGE463
  BE34    GND @T6G_MB_LIB.T6G(SCH_1):GND    I17 @T6G_MB_LIB.T6G(SCH_1):PAGE463
   BF1    GND @T6G_MB_LIB.T6G(SCH_1):GND    I17 @T6G_MB_LIB.T6G(SCH_1):PAGE463
  BF35    GND @T6G_MB_LIB.T6G(SCH_1):GND    I17 @T6G_MB_LIB.T6G(SCH_1):PAGE463
  BL13    GND @T6G_MB_LIB.T6G(SCH_1):GND    I17 @T6G_MB_LIB.T6G(SCH_1):PAGE463
  BL22    GND @T6G_MB_LIB.T6G(SCH_1):GND    I17 @T6G_MB_LIB.T6G(SCH_1):PAGE463
  BL32    GND @T6G_MB_LIB.T6G(SCH_1):GND    I17 @T6G_MB_LIB.T6G(SCH_1):PAGE463
   BL4    GND @T6G_MB_LIB.T6G(SCH_1):GND    I17 @T6G_MB_LIB.T6G(SCH_1):PAGE463
   BM2    GND @T6G_MB_LIB.T6G(SCH_1):GND    I17 @T6G_MB_LIB.T6G(SCH_1):PAGE463
  BM34    GND @T6G_MB_LIB.T6G(SCH_1):GND    I17 @T6G_MB_LIB.T6G(SCH_1):PAGE463
   BN1    GND @T6G_MB_LIB.T6G(SCH_1):GND    I17 @T6G_MB_LIB.T6G(SCH_1):PAGE463
  BN35    GND @T6G_MB_LIB.T6G(SCH_1):GND    I17 @T6G_MB_LIB.T6G(SCH_1):PAGE463
  BV13    GND @T6G_MB_LIB.T6G(SCH_1):GND    I17 @T6G_MB_LIB.T6G(SCH_1):PAGE463
  BV22    GND @T6G_MB_LIB.T6G(SCH_1):GND    I17 @T6G_MB_LIB.T6G(SCH_1):PAGE463
  BV32    GND @T6G_MB_LIB.T6G(SCH_1):GND    I17 @T6G_MB_LIB.T6G(SCH_1):PAGE463
   BV4    GND @T6G_MB_LIB.T6G(SCH_1):GND    I17 @T6G_MB_LIB.T6G(SCH_1):PAGE463
   BW2    GND @T6G_MB_LIB.T6G(SCH_1):GND    I17 @T6G_MB_LIB.T6G(SCH_1):PAGE463
  BW34    GND @T6G_MB_LIB.T6G(SCH_1):GND    I17 @T6G_MB_LIB.T6G(SCH_1):PAGE463
   BY1    GND @T6G_MB_LIB.T6G(SCH_1):GND    I17 @T6G_MB_LIB.T6G(SCH_1):PAGE463
  BY35    GND @T6G_MB_LIB.T6G(SCH_1):GND    I17 @T6G_MB_LIB.T6G(SCH_1):PAGE463
  CE13    GND @T6G_MB_LIB.T6G(SCH_1):GND    I17 @T6G_MB_LIB.T6G(SCH_1):PAGE463
  CE22    GND @T6G_MB_LIB.T6G(SCH_1):GND    I17 @T6G_MB_LIB.T6G(SCH_1):PAGE463
  CE32    GND @T6G_MB_LIB.T6G(SCH_1):GND    I17 @T6G_MB_LIB.T6G(SCH_1):PAGE463
   CE4    GND @T6G_MB_LIB.T6G(SCH_1):GND    I17 @T6G_MB_LIB.T6G(SCH_1):PAGE463
   CF2    GND @T6G_MB_LIB.T6G(SCH_1):GND    I17 @T6G_MB_LIB.T6G(SCH_1):PAGE463
  CF34    GND @T6G_MB_LIB.T6G(SCH_1):GND    I17 @T6G_MB_LIB.T6G(SCH_1):PAGE463
   CG1    GND @T6G_MB_LIB.T6G(SCH_1):GND    I17 @T6G_MB_LIB.T6G(SCH_1):PAGE463
  CG35    GND @T6G_MB_LIB.T6G(SCH_1):GND    I17 @T6G_MB_LIB.T6G(SCH_1):PAGE463
  CM13    GND @T6G_MB_LIB.T6G(SCH_1):GND    I17 @T6G_MB_LIB.T6G(SCH_1):PAGE463
  CM22    GND @T6G_MB_LIB.T6G(SCH_1):GND    I17 @T6G_MB_LIB.T6G(SCH_1):PAGE463
  CM32    GND @T6G_MB_LIB.T6G(SCH_1):GND    I17 @T6G_MB_LIB.T6G(SCH_1):PAGE463
   CM4    GND @T6G_MB_LIB.T6G(SCH_1):GND    I17 @T6G_MB_LIB.T6G(SCH_1):PAGE463
   CN2    GND @T6G_MB_LIB.T6G(SCH_1):GND    I17 @T6G_MB_LIB.T6G(SCH_1):PAGE463
  CN34    GND @T6G_MB_LIB.T6G(SCH_1):GND    I17 @T6G_MB_LIB.T6G(SCH_1):PAGE463
   CP1    GND @T6G_MB_LIB.T6G(SCH_1):GND    I17 @T6G_MB_LIB.T6G(SCH_1):PAGE463
  CP35    GND @T6G_MB_LIB.T6G(SCH_1):GND    I17 @T6G_MB_LIB.T6G(SCH_1):PAGE463
  CW13    GND @T6G_MB_LIB.T6G(SCH_1):GND    I17 @T6G_MB_LIB.T6G(SCH_1):PAGE463
  CW22    GND @T6G_MB_LIB.T6G(SCH_1):GND    I17 @T6G_MB_LIB.T6G(SCH_1):PAGE463
  CW32    GND @T6G_MB_LIB.T6G(SCH_1):GND    I17 @T6G_MB_LIB.T6G(SCH_1):PAGE463
   CW4    GND @T6G_MB_LIB.T6G(SCH_1):GND    I17 @T6G_MB_LIB.T6G(SCH_1):PAGE463
   CY2    GND @T6G_MB_LIB.T6G(SCH_1):GND    I17 @T6G_MB_LIB.T6G(SCH_1):PAGE463
  CY34    GND @T6G_MB_LIB.T6G(SCH_1):GND    I17 @T6G_MB_LIB.T6G(SCH_1):PAGE463
   DA1    GND @T6G_MB_LIB.T6G(SCH_1):GND    I17 @T6G_MB_LIB.T6G(SCH_1):PAGE463
  DA35    GND @T6G_MB_LIB.T6G(SCH_1):GND    I17 @T6G_MB_LIB.T6G(SCH_1):PAGE463
  DF13    GND @T6G_MB_LIB.T6G(SCH_1):GND    I17 @T6G_MB_LIB.T6G(SCH_1):PAGE463
  DF22    GND @T6G_MB_LIB.T6G(SCH_1):GND    I17 @T6G_MB_LIB.T6G(SCH_1):PAGE463
  DF32    GND @T6G_MB_LIB.T6G(SCH_1):GND    I17 @T6G_MB_LIB.T6G(SCH_1):PAGE463
   DF4    GND @T6G_MB_LIB.T6G(SCH_1):GND    I17 @T6G_MB_LIB.T6G(SCH_1):PAGE463
   DG2    GND @T6G_MB_LIB.T6G(SCH_1):GND    I17 @T6G_MB_LIB.T6G(SCH_1):PAGE463
  DG34    GND @T6G_MB_LIB.T6G(SCH_1):GND    I17 @T6G_MB_LIB.T6G(SCH_1):PAGE463
   DH1    GND @T6G_MB_LIB.T6G(SCH_1):GND    I17 @T6G_MB_LIB.T6G(SCH_1):PAGE463
  DH35    GND @T6G_MB_LIB.T6G(SCH_1):GND    I17 @T6G_MB_LIB.T6G(SCH_1):PAGE463
  DN13    GND @T6G_MB_LIB.T6G(SCH_1):GND    I17 @T6G_MB_LIB.T6G(SCH_1):PAGE463
    A1 NCF_A1_CPU1_P3_GND @T6G_MB_LIB.T6G(SCH_1):NCF_A1_CPU1_P3_GND    I17 @T6G_MB_LIB.T6G(SCH_1):PAGE463
   A35 NCF_CPU1_P3_GND @T6G_MB_LIB.T6G(SCH_1):NCF_CPU1_P3_GND    I17 @T6G_MB_LIB.T6G(SCH_1):PAGE463
    C2 NCF_CPU1_P3_GND @T6G_MB_LIB.T6G(SCH_1):NCF_CPU1_P3_GND    I17 @T6G_MB_LIB.T6G(SCH_1):PAGE463
   C34 NCF_CPU1_P3_GND @T6G_MB_LIB.T6G(SCH_1):NCF_CPU1_P3_GND    I17 @T6G_MB_LIB.T6G(SCH_1):PAGE463
    D1 NCF_CPU1_P3_GND @T6G_MB_LIB.T6G(SCH_1):NCF_CPU1_P3_GND    I17 @T6G_MB_LIB.T6G(SCH_1):PAGE463
   D35 NCF_CPU1_P3_GND @T6G_MB_LIB.T6G(SCH_1):NCF_CPU1_P3_GND    I17 @T6G_MB_LIB.T6G(SCH_1):PAGE463
   FE2 NCF_CPU1_P3_GND @T6G_MB_LIB.T6G(SCH_1):NCF_CPU1_P3_GND    I17 @T6G_MB_LIB.T6G(SCH_1):PAGE463
  FE34 NCF_CPU1_P3_GND @T6G_MB_LIB.T6G(SCH_1):NCF_CPU1_P3_GND    I17 @T6G_MB_LIB.T6G(SCH_1):PAGE463
   FG1 NCF_CPU1_P3_GND @T6G_MB_LIB.T6G(SCH_1):NCF_CPU1_P3_GND    I17 @T6G_MB_LIB.T6G(SCH_1):PAGE463
  FG35 NCF_CPU1_P3_GND @T6G_MB_LIB.T6G(SCH_1):NCF_CPU1_P3_GND    I17 @T6G_MB_LIB.T6G(SCH_1):PAGE463
   FH2 NCF_CPU1_P3_GND @T6G_MB_LIB.T6G(SCH_1):NCF_CPU1_P3_GND    I17 @T6G_MB_LIB.T6G(SCH_1):PAGE463
  FH34 NCF_CPU1_P3_GND @T6G_MB_LIB.T6G(SCH_1):NCF_CPU1_P3_GND    I17 @T6G_MB_LIB.T6G(SCH_1):PAGE463
  DN22    GND @T6G_MB_LIB.T6G(SCH_1):GND    I17 @T6G_MB_LIB.T6G(SCH_1):PAGE463
  DN32    GND @T6G_MB_LIB.T6G(SCH_1):GND    I17 @T6G_MB_LIB.T6G(SCH_1):PAGE463
   DN4    GND @T6G_MB_LIB.T6G(SCH_1):GND    I17 @T6G_MB_LIB.T6G(SCH_1):PAGE463
   DP2    GND @T6G_MB_LIB.T6G(SCH_1):GND    I17 @T6G_MB_LIB.T6G(SCH_1):PAGE463
  DP34    GND @T6G_MB_LIB.T6G(SCH_1):GND    I17 @T6G_MB_LIB.T6G(SCH_1):PAGE463
   DR1    GND @T6G_MB_LIB.T6G(SCH_1):GND    I17 @T6G_MB_LIB.T6G(SCH_1):PAGE463
  DR35    GND @T6G_MB_LIB.T6G(SCH_1):GND    I17 @T6G_MB_LIB.T6G(SCH_1):PAGE463
  DY13    GND @T6G_MB_LIB.T6G(SCH_1):GND    I17 @T6G_MB_LIB.T6G(SCH_1):PAGE463
  DY22    GND @T6G_MB_LIB.T6G(SCH_1):GND    I17 @T6G_MB_LIB.T6G(SCH_1):PAGE463
  DY32    GND @T6G_MB_LIB.T6G(SCH_1):GND    I17 @T6G_MB_LIB.T6G(SCH_1):PAGE463
   DY4    GND @T6G_MB_LIB.T6G(SCH_1):GND    I17 @T6G_MB_LIB.T6G(SCH_1):PAGE463
   E14    GND @T6G_MB_LIB.T6G(SCH_1):GND    I17 @T6G_MB_LIB.T6G(SCH_1):PAGE463
   E27    GND @T6G_MB_LIB.T6G(SCH_1):GND    I17 @T6G_MB_LIB.T6G(SCH_1):PAGE463
   E33    GND @T6G_MB_LIB.T6G(SCH_1):GND    I17 @T6G_MB_LIB.T6G(SCH_1):PAGE463
   EA2    GND @T6G_MB_LIB.T6G(SCH_1):GND    I17 @T6G_MB_LIB.T6G(SCH_1):PAGE463
  EA34    GND @T6G_MB_LIB.T6G(SCH_1):GND    I17 @T6G_MB_LIB.T6G(SCH_1):PAGE463
   EB1    GND @T6G_MB_LIB.T6G(SCH_1):GND    I17 @T6G_MB_LIB.T6G(SCH_1):PAGE463
  EB35    GND @T6G_MB_LIB.T6G(SCH_1):GND    I17 @T6G_MB_LIB.T6G(SCH_1):PAGE463
  EG13    GND @T6G_MB_LIB.T6G(SCH_1):GND    I17 @T6G_MB_LIB.T6G(SCH_1):PAGE463
  EG22    GND @T6G_MB_LIB.T6G(SCH_1):GND    I17 @T6G_MB_LIB.T6G(SCH_1):PAGE463
  EG32    GND @T6G_MB_LIB.T6G(SCH_1):GND    I17 @T6G_MB_LIB.T6G(SCH_1):PAGE463
   EG4    GND @T6G_MB_LIB.T6G(SCH_1):GND    I17 @T6G_MB_LIB.T6G(SCH_1):PAGE463
   EH2    GND @T6G_MB_LIB.T6G(SCH_1):GND    I17 @T6G_MB_LIB.T6G(SCH_1):PAGE463
  EH34    GND @T6G_MB_LIB.T6G(SCH_1):GND    I17 @T6G_MB_LIB.T6G(SCH_1):PAGE463
   EJ1    GND @T6G_MB_LIB.T6G(SCH_1):GND    I17 @T6G_MB_LIB.T6G(SCH_1):PAGE463
  EJ35    GND @T6G_MB_LIB.T6G(SCH_1):GND    I17 @T6G_MB_LIB.T6G(SCH_1):PAGE463
  EP13    GND @T6G_MB_LIB.T6G(SCH_1):GND    I17 @T6G_MB_LIB.T6G(SCH_1):PAGE463
  EP22    GND @T6G_MB_LIB.T6G(SCH_1):GND    I17 @T6G_MB_LIB.T6G(SCH_1):PAGE463
  EP32    GND @T6G_MB_LIB.T6G(SCH_1):GND    I17 @T6G_MB_LIB.T6G(SCH_1):PAGE463
   EP4    GND @T6G_MB_LIB.T6G(SCH_1):GND    I17 @T6G_MB_LIB.T6G(SCH_1):PAGE463
   ER2    GND @T6G_MB_LIB.T6G(SCH_1):GND    I17 @T6G_MB_LIB.T6G(SCH_1):PAGE463
  ER34    GND @T6G_MB_LIB.T6G(SCH_1):GND    I17 @T6G_MB_LIB.T6G(SCH_1):PAGE463
   ET1    GND @T6G_MB_LIB.T6G(SCH_1):GND    I17 @T6G_MB_LIB.T6G(SCH_1):PAGE463
  ET35    GND @T6G_MB_LIB.T6G(SCH_1):GND    I17 @T6G_MB_LIB.T6G(SCH_1):PAGE463
  FA15    GND @T6G_MB_LIB.T6G(SCH_1):GND    I17 @T6G_MB_LIB.T6G(SCH_1):PAGE463
  FA32    GND @T6G_MB_LIB.T6G(SCH_1):GND    I17 @T6G_MB_LIB.T6G(SCH_1):PAGE463
   FB2    GND @T6G_MB_LIB.T6G(SCH_1):GND    I17 @T6G_MB_LIB.T6G(SCH_1):PAGE463
  FB34    GND @T6G_MB_LIB.T6G(SCH_1):GND    I17 @T6G_MB_LIB.T6G(SCH_1):PAGE463
  FC19    GND @T6G_MB_LIB.T6G(SCH_1):GND    I17 @T6G_MB_LIB.T6G(SCH_1):PAGE463
  FC23    GND @T6G_MB_LIB.T6G(SCH_1):GND    I17 @T6G_MB_LIB.T6G(SCH_1):PAGE463
  FC25    GND @T6G_MB_LIB.T6G(SCH_1):GND    I17 @T6G_MB_LIB.T6G(SCH_1):PAGE463
  FC28    GND @T6G_MB_LIB.T6G(SCH_1):GND    I17 @T6G_MB_LIB.T6G(SCH_1):PAGE463
   FC3    GND @T6G_MB_LIB.T6G(SCH_1):GND    I17 @T6G_MB_LIB.T6G(SCH_1):PAGE463
   FC6    GND @T6G_MB_LIB.T6G(SCH_1):GND    I17 @T6G_MB_LIB.T6G(SCH_1):PAGE463
   FC9    GND @T6G_MB_LIB.T6G(SCH_1):GND    I17 @T6G_MB_LIB.T6G(SCH_1):PAGE463
   FD1    GND @T6G_MB_LIB.T6G(SCH_1):GND    I17 @T6G_MB_LIB.T6G(SCH_1):PAGE463
  FD35    GND @T6G_MB_LIB.T6G(SCH_1):GND    I17 @T6G_MB_LIB.T6G(SCH_1):PAGE463
  FF14    GND @T6G_MB_LIB.T6G(SCH_1):GND    I17 @T6G_MB_LIB.T6G(SCH_1):PAGE463
  FF21    GND @T6G_MB_LIB.T6G(SCH_1):GND    I17 @T6G_MB_LIB.T6G(SCH_1):PAGE463
  FJ12    GND @T6G_MB_LIB.T6G(SCH_1):GND    I17 @T6G_MB_LIB.T6G(SCH_1):PAGE463
  FJ19    GND @T6G_MB_LIB.T6G(SCH_1):GND    I17 @T6G_MB_LIB.T6G(SCH_1):PAGE463
   H12    GND @T6G_MB_LIB.T6G(SCH_1):GND    I17 @T6G_MB_LIB.T6G(SCH_1):PAGE463
   H16    GND @T6G_MB_LIB.T6G(SCH_1):GND    I17 @T6G_MB_LIB.T6G(SCH_1):PAGE463
   H19    GND @T6G_MB_LIB.T6G(SCH_1):GND    I17 @T6G_MB_LIB.T6G(SCH_1):PAGE463
   H31    GND @T6G_MB_LIB.T6G(SCH_1):GND    I17 @T6G_MB_LIB.T6G(SCH_1):PAGE463
   J22    GND @T6G_MB_LIB.T6G(SCH_1):GND    I17 @T6G_MB_LIB.T6G(SCH_1):PAGE463
    J4    GND @T6G_MB_LIB.T6G(SCH_1):GND    I17 @T6G_MB_LIB.T6G(SCH_1):PAGE463
    K2    GND @T6G_MB_LIB.T6G(SCH_1):GND    I17 @T6G_MB_LIB.T6G(SCH_1):PAGE463
   K34    GND @T6G_MB_LIB.T6G(SCH_1):GND    I17 @T6G_MB_LIB.T6G(SCH_1):PAGE463
    L1    GND @T6G_MB_LIB.T6G(SCH_1):GND    I17 @T6G_MB_LIB.T6G(SCH_1):PAGE463
   L35    GND @T6G_MB_LIB.T6G(SCH_1):GND    I17 @T6G_MB_LIB.T6G(SCH_1):PAGE463
   T13    GND @T6G_MB_LIB.T6G(SCH_1):GND    I17 @T6G_MB_LIB.T6G(SCH_1):PAGE463
   T22    GND @T6G_MB_LIB.T6G(SCH_1):GND    I17 @T6G_MB_LIB.T6G(SCH_1):PAGE463
   T32    GND @T6G_MB_LIB.T6G(SCH_1):GND    I17 @T6G_MB_LIB.T6G(SCH_1):PAGE463
    T4    GND @T6G_MB_LIB.T6G(SCH_1):GND    I17 @T6G_MB_LIB.T6G(SCH_1):PAGE463
    U2    GND @T6G_MB_LIB.T6G(SCH_1):GND    I17 @T6G_MB_LIB.T6G(SCH_1):PAGE463
   U34    GND @T6G_MB_LIB.T6G(SCH_1):GND    I17 @T6G_MB_LIB.T6G(SCH_1):PAGE463
    V1    GND @T6G_MB_LIB.T6G(SCH_1):GND    I17 @T6G_MB_LIB.T6G(SCH_1):PAGE463
   V35    GND @T6G_MB_LIB.T6G(SCH_1):GND    I17 @T6G_MB_LIB.T6G(SCH_1):PAGE463
   M26 P5E_CPU1_P3_RX_DP<15> @T6G_MB_LIB.T6G(SCH_1):P5E_CPU1_P3_RX_DP(15)     I1 @T6G_MB_LIB.T6G(SCH_1):PAGE459
   P29 P5E_CPU1_P3_RX_DN<15> @T6G_MB_LIB.T6G(SCH_1):P5E_CPU1_P3_RX_DN(15)     I1 @T6G_MB_LIB.T6G(SCH_1):PAGE459
   W26 P5E_CPU1_P3_RX_DP<14> @T6G_MB_LIB.T6G(SCH_1):P5E_CPU1_P3_RX_DP(14)     I1 @T6G_MB_LIB.T6G(SCH_1):PAGE459
  AA29 P5E_CPU1_P3_RX_DN<14> @T6G_MB_LIB.T6G(SCH_1):P5E_CPU1_P3_RX_DN(14)     I1 @T6G_MB_LIB.T6G(SCH_1):PAGE459
  AF26 P5E_CPU1_P3_RX_DP<13> @T6G_MB_LIB.T6G(SCH_1):P5E_CPU1_P3_RX_DP(13)     I1 @T6G_MB_LIB.T6G(SCH_1):PAGE459
  AH29 P5E_CPU1_P3_RX_DN<13> @T6G_MB_LIB.T6G(SCH_1):P5E_CPU1_P3_RX_DN(13)     I1 @T6G_MB_LIB.T6G(SCH_1):PAGE459
  AN26 P5E_CPU1_P3_RX_DP<12> @T6G_MB_LIB.T6G(SCH_1):P5E_CPU1_P3_RX_DP(12)     I1 @T6G_MB_LIB.T6G(SCH_1):PAGE459
  AR29 P5E_CPU1_P3_RX_DN<12> @T6G_MB_LIB.T6G(SCH_1):P5E_CPU1_P3_RX_DN(12)     I1 @T6G_MB_LIB.T6G(SCH_1):PAGE459
  AY26 P5E_CPU1_P3_RX_DP<11> @T6G_MB_LIB.T6G(SCH_1):P5E_CPU1_P3_RX_DP(11)     I1 @T6G_MB_LIB.T6G(SCH_1):PAGE459
  BB29 P5E_CPU1_P3_RX_DN<11> @T6G_MB_LIB.T6G(SCH_1):P5E_CPU1_P3_RX_DN(11)     I1 @T6G_MB_LIB.T6G(SCH_1):PAGE459
  BG26 P5E_CPU1_P3_RX_DP<10> @T6G_MB_LIB.T6G(SCH_1):P5E_CPU1_P3_RX_DP(10)     I1 @T6G_MB_LIB.T6G(SCH_1):PAGE459
  BJ29 P5E_CPU1_P3_RX_DN<10> @T6G_MB_LIB.T6G(SCH_1):P5E_CPU1_P3_RX_DN(10)     I1 @T6G_MB_LIB.T6G(SCH_1):PAGE459
  BP26 P5E_CPU1_P3_RX_DP<9> @T6G_MB_LIB.T6G(SCH_1):P5E_CPU1_P3_RX_DP(9)     I1 @T6G_MB_LIB.T6G(SCH_1):PAGE459
  BT29 P5E_CPU1_P3_RX_DN<9> @T6G_MB_LIB.T6G(SCH_1):P5E_CPU1_P3_RX_DN(9)     I1 @T6G_MB_LIB.T6G(SCH_1):PAGE459
  CA26 P5E_CPU1_P3_RX_DP<8> @T6G_MB_LIB.T6G(SCH_1):P5E_CPU1_P3_RX_DP(8)     I1 @T6G_MB_LIB.T6G(SCH_1):PAGE459
  CC29 P5E_CPU1_P3_RX_DN<8> @T6G_MB_LIB.T6G(SCH_1):P5E_CPU1_P3_RX_DN(8)     I1 @T6G_MB_LIB.T6G(SCH_1):PAGE459
  CH26 P5E_CPU1_P3_RX_DP<7> @T6G_MB_LIB.T6G(SCH_1):P5E_CPU1_P3_RX_DP(7)    I38 @T6G_MB_LIB.T6G(SCH_1):PAGE459
  CK29 P5E_CPU1_P3_RX_DN<7> @T6G_MB_LIB.T6G(SCH_1):P5E_CPU1_P3_RX_DN(7)    I38 @T6G_MB_LIB.T6G(SCH_1):PAGE459
  CR26 P5E_CPU1_P3_RX_DP<6> @T6G_MB_LIB.T6G(SCH_1):P5E_CPU1_P3_RX_DP(6)    I38 @T6G_MB_LIB.T6G(SCH_1):PAGE459
  CU29 P5E_CPU1_P3_RX_DN<6> @T6G_MB_LIB.T6G(SCH_1):P5E_CPU1_P3_RX_DN(6)    I38 @T6G_MB_LIB.T6G(SCH_1):PAGE459
  DB26 P5E_CPU1_P3_RX_DP<5> @T6G_MB_LIB.T6G(SCH_1):P5E_CPU1_P3_RX_DP(5)    I38 @T6G_MB_LIB.T6G(SCH_1):PAGE459
  DD29 P5E_CPU1_P3_RX_DN<5> @T6G_MB_LIB.T6G(SCH_1):P5E_CPU1_P3_RX_DN(5)    I38 @T6G_MB_LIB.T6G(SCH_1):PAGE459
  DJ26 P5E_CPU1_P3_RX_DP<4> @T6G_MB_LIB.T6G(SCH_1):P5E_CPU1_P3_RX_DP(4)    I38 @T6G_MB_LIB.T6G(SCH_1):PAGE459
  DL29 P5E_CPU1_P3_RX_DN<4> @T6G_MB_LIB.T6G(SCH_1):P5E_CPU1_P3_RX_DN(4)    I38 @T6G_MB_LIB.T6G(SCH_1):PAGE459
  DT26 P5E_CPU1_P3_RX_DP<3> @T6G_MB_LIB.T6G(SCH_1):P5E_CPU1_P3_RX_DP(3)    I38 @T6G_MB_LIB.T6G(SCH_1):PAGE459
  DV29 P5E_CPU1_P3_RX_DN<3> @T6G_MB_LIB.T6G(SCH_1):P5E_CPU1_P3_RX_DN(3)    I38 @T6G_MB_LIB.T6G(SCH_1):PAGE459
  EC26 P5E_CPU1_P3_RX_DP<2> @T6G_MB_LIB.T6G(SCH_1):P5E_CPU1_P3_RX_DP(2)    I38 @T6G_MB_LIB.T6G(SCH_1):PAGE459
  EE29 P5E_CPU1_P3_RX_DN<2> @T6G_MB_LIB.T6G(SCH_1):P5E_CPU1_P3_RX_DN(2)    I38 @T6G_MB_LIB.T6G(SCH_1):PAGE459
  EK26 P5E_CPU1_P3_RX_DP<1> @T6G_MB_LIB.T6G(SCH_1):P5E_CPU1_P3_RX_DP(1)    I38 @T6G_MB_LIB.T6G(SCH_1):PAGE459
  EM29 P5E_CPU1_P3_RX_DN<1> @T6G_MB_LIB.T6G(SCH_1):P5E_CPU1_P3_RX_DN(1)    I38 @T6G_MB_LIB.T6G(SCH_1):PAGE459
  EU26 P5E_CPU1_P3_RX_DP<0> @T6G_MB_LIB.T6G(SCH_1):P5E_CPU1_P3_RX_DP(0)    I38 @T6G_MB_LIB.T6G(SCH_1):PAGE459
  EW29 P5E_CPU1_P3_RX_DN<0> @T6G_MB_LIB.T6G(SCH_1):P5E_CPU1_P3_RX_DN(0)    I38 @T6G_MB_LIB.T6G(SCH_1):PAGE459
   N34 P5E_CPU1_P3_TX_C_DN<15> @T6G_MB_LIB.T6G(SCH_1):P5E_CPU1_P3_TX_C_DN(15)     I1 @T6G_MB_LIB.T6G(SCH_1):PAGE458
   R35 P5E_CPU1_P3_TX_C_DP<15> @T6G_MB_LIB.T6G(SCH_1):P5E_CPU1_P3_TX_C_DP(15)     I1 @T6G_MB_LIB.T6G(SCH_1):PAGE458
   Y34 P5E_CPU1_P3_TX_C_DP<14> @T6G_MB_LIB.T6G(SCH_1):P5E_CPU1_P3_TX_C_DP(14)     I1 @T6G_MB_LIB.T6G(SCH_1):PAGE458
  AB35 P5E_CPU1_P3_TX_C_DN<14> @T6G_MB_LIB.T6G(SCH_1):P5E_CPU1_P3_TX_C_DN(14)     I1 @T6G_MB_LIB.T6G(SCH_1):PAGE458
  AG34 P5E_CPU1_P3_TX_C_DN<13> @T6G_MB_LIB.T6G(SCH_1):P5E_CPU1_P3_TX_C_DN(13)     I1 @T6G_MB_LIB.T6G(SCH_1):PAGE458
  AJ35 P5E_CPU1_P3_TX_C_DP<13> @T6G_MB_LIB.T6G(SCH_1):P5E_CPU1_P3_TX_C_DP(13)     I1 @T6G_MB_LIB.T6G(SCH_1):PAGE458
  AP34 P5E_CPU1_P3_TX_C_DN<12> @T6G_MB_LIB.T6G(SCH_1):P5E_CPU1_P3_TX_C_DN(12)     I1 @T6G_MB_LIB.T6G(SCH_1):PAGE458
  AT35 P5E_CPU1_P3_TX_C_DP<12> @T6G_MB_LIB.T6G(SCH_1):P5E_CPU1_P3_TX_C_DP(12)     I1 @T6G_MB_LIB.T6G(SCH_1):PAGE458
  BA34 P5E_CPU1_P3_TX_C_DN<11> @T6G_MB_LIB.T6G(SCH_1):P5E_CPU1_P3_TX_C_DN(11)     I1 @T6G_MB_LIB.T6G(SCH_1):PAGE458
  BC35 P5E_CPU1_P3_TX_C_DP<11> @T6G_MB_LIB.T6G(SCH_1):P5E_CPU1_P3_TX_C_DP(11)     I1 @T6G_MB_LIB.T6G(SCH_1):PAGE458
  BH34 P5E_CPU1_P3_TX_C_DN<10> @T6G_MB_LIB.T6G(SCH_1):P5E_CPU1_P3_TX_C_DN(10)     I1 @T6G_MB_LIB.T6G(SCH_1):PAGE458
  BK35 P5E_CPU1_P3_TX_C_DP<10> @T6G_MB_LIB.T6G(SCH_1):P5E_CPU1_P3_TX_C_DP(10)     I1 @T6G_MB_LIB.T6G(SCH_1):PAGE458
  BR34 P5E_CPU1_P3_TX_C_DN<9> @T6G_MB_LIB.T6G(SCH_1):P5E_CPU1_P3_TX_C_DN(9)     I1 @T6G_MB_LIB.T6G(SCH_1):PAGE458
  BU35 P5E_CPU1_P3_TX_C_DP<9> @T6G_MB_LIB.T6G(SCH_1):P5E_CPU1_P3_TX_C_DP(9)     I1 @T6G_MB_LIB.T6G(SCH_1):PAGE458
  CB34 P5E_CPU1_P3_TX_C_DN<8> @T6G_MB_LIB.T6G(SCH_1):P5E_CPU1_P3_TX_C_DN(8)     I1 @T6G_MB_LIB.T6G(SCH_1):PAGE458
  CD35 P5E_CPU1_P3_TX_C_DP<8> @T6G_MB_LIB.T6G(SCH_1):P5E_CPU1_P3_TX_C_DP(8)     I1 @T6G_MB_LIB.T6G(SCH_1):PAGE458
  CJ34 P5E_CPU1_P3_TX_C_DN<7> @T6G_MB_LIB.T6G(SCH_1):P5E_CPU1_P3_TX_C_DN(7)    I38 @T6G_MB_LIB.T6G(SCH_1):PAGE458
  CL35 P5E_CPU1_P3_TX_C_DP<7> @T6G_MB_LIB.T6G(SCH_1):P5E_CPU1_P3_TX_C_DP(7)    I38 @T6G_MB_LIB.T6G(SCH_1):PAGE458
  CT34 P5E_CPU1_P3_TX_C_DN<6> @T6G_MB_LIB.T6G(SCH_1):P5E_CPU1_P3_TX_C_DN(6)    I38 @T6G_MB_LIB.T6G(SCH_1):PAGE458
  CV35 P5E_CPU1_P3_TX_C_DP<6> @T6G_MB_LIB.T6G(SCH_1):P5E_CPU1_P3_TX_C_DP(6)    I38 @T6G_MB_LIB.T6G(SCH_1):PAGE458
  DC34 P5E_CPU1_P3_TX_C_DN<5> @T6G_MB_LIB.T6G(SCH_1):P5E_CPU1_P3_TX_C_DN(5)    I38 @T6G_MB_LIB.T6G(SCH_1):PAGE458
  DE35 P5E_CPU1_P3_TX_C_DP<5> @T6G_MB_LIB.T6G(SCH_1):P5E_CPU1_P3_TX_C_DP(5)    I38 @T6G_MB_LIB.T6G(SCH_1):PAGE458
  DK34 P5E_CPU1_P3_TX_C_DN<4> @T6G_MB_LIB.T6G(SCH_1):P5E_CPU1_P3_TX_C_DN(4)    I38 @T6G_MB_LIB.T6G(SCH_1):PAGE458
  DM35 P5E_CPU1_P3_TX_C_DP<4> @T6G_MB_LIB.T6G(SCH_1):P5E_CPU1_P3_TX_C_DP(4)    I38 @T6G_MB_LIB.T6G(SCH_1):PAGE458
  DU34 P5E_CPU1_P3_TX_C_DN<3> @T6G_MB_LIB.T6G(SCH_1):P5E_CPU1_P3_TX_C_DN(3)    I38 @T6G_MB_LIB.T6G(SCH_1):PAGE458
  DW35 P5E_CPU1_P3_TX_C_DP<3> @T6G_MB_LIB.T6G(SCH_1):P5E_CPU1_P3_TX_C_DP(3)    I38 @T6G_MB_LIB.T6G(SCH_1):PAGE458
  ED34 P5E_CPU1_P3_TX_C_DN<2> @T6G_MB_LIB.T6G(SCH_1):P5E_CPU1_P3_TX_C_DN(2)    I38 @T6G_MB_LIB.T6G(SCH_1):PAGE458
  EF35 P5E_CPU1_P3_TX_C_DP<2> @T6G_MB_LIB.T6G(SCH_1):P5E_CPU1_P3_TX_C_DP(2)    I38 @T6G_MB_LIB.T6G(SCH_1):PAGE458
  EL34 P5E_CPU1_P3_TX_C_DP<1> @T6G_MB_LIB.T6G(SCH_1):P5E_CPU1_P3_TX_C_DP(1)    I38 @T6G_MB_LIB.T6G(SCH_1):PAGE458
  EN35 P5E_CPU1_P3_TX_C_DN<1> @T6G_MB_LIB.T6G(SCH_1):P5E_CPU1_P3_TX_C_DN(1)    I38 @T6G_MB_LIB.T6G(SCH_1):PAGE458
  EV34 P5E_CPU1_P3_TX_C_DN<0> @T6G_MB_LIB.T6G(SCH_1):P5E_CPU1_P3_TX_C_DN(0)    I38 @T6G_MB_LIB.T6G(SCH_1):PAGE458
  EY35 P5E_CPU1_P3_TX_C_DP<0> @T6G_MB_LIB.T6G(SCH_1):P5E_CPU1_P3_TX_C_DP(0)    I38 @T6G_MB_LIB.T6G(SCH_1):PAGE458
    M7 P5E_CPU1_P3_TX_BUF_DP<15> @T6G_MB_LIB.T6G(SCH_1):P5E_CPU1_P3_TX_BUF_DP(15)    I46 @T6G_MB_LIB.T6G(SCH_1):PAGE461
   P10 P5E_CPU1_P3_TX_BUF_DN<15> @T6G_MB_LIB.T6G(SCH_1):P5E_CPU1_P3_TX_BUF_DN(15)    I46 @T6G_MB_LIB.T6G(SCH_1):PAGE461
    W7 P5E_CPU1_P3_TX_BUF_DP<14> @T6G_MB_LIB.T6G(SCH_1):P5E_CPU1_P3_TX_BUF_DP(14)    I46 @T6G_MB_LIB.T6G(SCH_1):PAGE461
  AA10 P5E_CPU1_P3_TX_BUF_DN<14> @T6G_MB_LIB.T6G(SCH_1):P5E_CPU1_P3_TX_BUF_DN(14)    I46 @T6G_MB_LIB.T6G(SCH_1):PAGE461
   AF7 P5E_CPU1_P3_TX_BUF_DP<13> @T6G_MB_LIB.T6G(SCH_1):P5E_CPU1_P3_TX_BUF_DP(13)    I46 @T6G_MB_LIB.T6G(SCH_1):PAGE461
  AH10 P5E_CPU1_P3_TX_BUF_DN<13> @T6G_MB_LIB.T6G(SCH_1):P5E_CPU1_P3_TX_BUF_DN(13)    I46 @T6G_MB_LIB.T6G(SCH_1):PAGE461
   AN7 P5E_CPU1_P3_TX_BUF_DP<12> @T6G_MB_LIB.T6G(SCH_1):P5E_CPU1_P3_TX_BUF_DP(12)    I46 @T6G_MB_LIB.T6G(SCH_1):PAGE461
  AR10 P5E_CPU1_P3_TX_BUF_DN<12> @T6G_MB_LIB.T6G(SCH_1):P5E_CPU1_P3_TX_BUF_DN(12)    I46 @T6G_MB_LIB.T6G(SCH_1):PAGE461
   AY7 P5E_CPU1_P3_TX_BUF_DP<11> @T6G_MB_LIB.T6G(SCH_1):P5E_CPU1_P3_TX_BUF_DP(11)    I46 @T6G_MB_LIB.T6G(SCH_1):PAGE461
  BB10 P5E_CPU1_P3_TX_BUF_DN<11> @T6G_MB_LIB.T6G(SCH_1):P5E_CPU1_P3_TX_BUF_DN(11)    I46 @T6G_MB_LIB.T6G(SCH_1):PAGE461
   BG7 P5E_CPU1_P3_TX_BUF_DP<10> @T6G_MB_LIB.T6G(SCH_1):P5E_CPU1_P3_TX_BUF_DP(10)    I46 @T6G_MB_LIB.T6G(SCH_1):PAGE461
  BJ10 P5E_CPU1_P3_TX_BUF_DN<10> @T6G_MB_LIB.T6G(SCH_1):P5E_CPU1_P3_TX_BUF_DN(10)    I46 @T6G_MB_LIB.T6G(SCH_1):PAGE461
   BP7 P5E_CPU1_P3_TX_BUF_DP<9> @T6G_MB_LIB.T6G(SCH_1):P5E_CPU1_P3_TX_BUF_DP(9)    I46 @T6G_MB_LIB.T6G(SCH_1):PAGE461
  BT10 P5E_CPU1_P3_TX_BUF_DN<9> @T6G_MB_LIB.T6G(SCH_1):P5E_CPU1_P3_TX_BUF_DN(9)    I46 @T6G_MB_LIB.T6G(SCH_1):PAGE461
   CA7 P5E_CPU1_P3_TX_BUF_DP<8> @T6G_MB_LIB.T6G(SCH_1):P5E_CPU1_P3_TX_BUF_DP(8)    I46 @T6G_MB_LIB.T6G(SCH_1):PAGE461
  CC10 P5E_CPU1_P3_TX_BUF_DN<8> @T6G_MB_LIB.T6G(SCH_1):P5E_CPU1_P3_TX_BUF_DN(8)    I46 @T6G_MB_LIB.T6G(SCH_1):PAGE461
   CH7 P5E_CPU1_P3_TX_BUF_DP<7> @T6G_MB_LIB.T6G(SCH_1):P5E_CPU1_P3_TX_BUF_DP(7)   I142 @T6G_MB_LIB.T6G(SCH_1):PAGE461
  CK10 P5E_CPU1_P3_TX_BUF_DN<7> @T6G_MB_LIB.T6G(SCH_1):P5E_CPU1_P3_TX_BUF_DN(7)   I142 @T6G_MB_LIB.T6G(SCH_1):PAGE461
   CR7 P5E_CPU1_P3_TX_BUF_DP<6> @T6G_MB_LIB.T6G(SCH_1):P5E_CPU1_P3_TX_BUF_DP(6)   I142 @T6G_MB_LIB.T6G(SCH_1):PAGE461
  CU10 P5E_CPU1_P3_TX_BUF_DN<6> @T6G_MB_LIB.T6G(SCH_1):P5E_CPU1_P3_TX_BUF_DN(6)   I142 @T6G_MB_LIB.T6G(SCH_1):PAGE461
   DB7 P5E_CPU1_P3_TX_BUF_DP<5> @T6G_MB_LIB.T6G(SCH_1):P5E_CPU1_P3_TX_BUF_DP(5)   I142 @T6G_MB_LIB.T6G(SCH_1):PAGE461
  DD10 P5E_CPU1_P3_TX_BUF_DN<5> @T6G_MB_LIB.T6G(SCH_1):P5E_CPU1_P3_TX_BUF_DN(5)   I142 @T6G_MB_LIB.T6G(SCH_1):PAGE461
   DJ7 P5E_CPU1_P3_TX_BUF_DP<4> @T6G_MB_LIB.T6G(SCH_1):P5E_CPU1_P3_TX_BUF_DP(4)   I142 @T6G_MB_LIB.T6G(SCH_1):PAGE461
  DL10 P5E_CPU1_P3_TX_BUF_DN<4> @T6G_MB_LIB.T6G(SCH_1):P5E_CPU1_P3_TX_BUF_DN(4)   I142 @T6G_MB_LIB.T6G(SCH_1):PAGE461
   DT7 P5E_CPU1_P3_TX_BUF_DP<3> @T6G_MB_LIB.T6G(SCH_1):P5E_CPU1_P3_TX_BUF_DP(3)   I142 @T6G_MB_LIB.T6G(SCH_1):PAGE461
  DV10 P5E_CPU1_P3_TX_BUF_DN<3> @T6G_MB_LIB.T6G(SCH_1):P5E_CPU1_P3_TX_BUF_DN(3)   I142 @T6G_MB_LIB.T6G(SCH_1):PAGE461
   EC7 P5E_CPU1_P3_TX_BUF_DP<2> @T6G_MB_LIB.T6G(SCH_1):P5E_CPU1_P3_TX_BUF_DP(2)   I142 @T6G_MB_LIB.T6G(SCH_1):PAGE461
  EE10 P5E_CPU1_P3_TX_BUF_DN<2> @T6G_MB_LIB.T6G(SCH_1):P5E_CPU1_P3_TX_BUF_DN(2)   I142 @T6G_MB_LIB.T6G(SCH_1):PAGE461
   EK7 P5E_CPU1_P3_TX_BUF_DP<1> @T6G_MB_LIB.T6G(SCH_1):P5E_CPU1_P3_TX_BUF_DP(1)   I142 @T6G_MB_LIB.T6G(SCH_1):PAGE461
  EM10 P5E_CPU1_P3_TX_BUF_DN<1> @T6G_MB_LIB.T6G(SCH_1):P5E_CPU1_P3_TX_BUF_DN(1)   I142 @T6G_MB_LIB.T6G(SCH_1):PAGE461
   EU7 P5E_CPU1_P3_TX_BUF_DP<0> @T6G_MB_LIB.T6G(SCH_1):P5E_CPU1_P3_TX_BUF_DP(0)   I142 @T6G_MB_LIB.T6G(SCH_1):PAGE461
  EW10 P5E_CPU1_P3_TX_BUF_DN<0> @T6G_MB_LIB.T6G(SCH_1):P5E_CPU1_P3_TX_BUF_DN(0)   I142 @T6G_MB_LIB.T6G(SCH_1):PAGE461

U6020 TCA9548APWR-TCA9548APWR,SMLF,IC,AL009548K02
     1 RT_SMB_MUX_ADDR0 @T6G_MB_LIB.T6G(SCH_1):RT_SMB_MUX_ADDR0     I1 @T6G_MB_LIB.T6G(SCH_1):PAGE378
     2 RT_SMB_MUX_ADDR1 @T6G_MB_LIB.T6G(SCH_1):RT_SMB_MUX_ADDR1     I1 @T6G_MB_LIB.T6G(SCH_1):PAGE378
     3 RST_SMB_RT_N @T6G_MB_LIB.T6G(SCH_1):RST_SMB_RT_N     I1 @T6G_MB_LIB.T6G(SCH_1):PAGE378
     4 SMB_RT_CPU1_P0_SDA @T6G_MB_LIB.T6G(SCH_1):SMB_RT_CPU1_P0_SDA     I1 @T6G_MB_LIB.T6G(SCH_1):PAGE378
     5 SMB_RT_CPU1_P0_SCL @T6G_MB_LIB.T6G(SCH_1):SMB_RT_CPU1_P0_SCL     I1 @T6G_MB_LIB.T6G(SCH_1):PAGE378
     6 SMB_RT_CPU1_P1_SDA @T6G_MB_LIB.T6G(SCH_1):SMB_RT_CPU1_P1_SDA     I1 @T6G_MB_LIB.T6G(SCH_1):PAGE378
     7 SMB_RT_CPU1_P1_SCL @T6G_MB_LIB.T6G(SCH_1):SMB_RT_CPU1_P1_SCL     I1 @T6G_MB_LIB.T6G(SCH_1):PAGE378
     8 SMB_RT_CPU1_P3_SDA @T6G_MB_LIB.T6G(SCH_1):SMB_RT_CPU1_P3_SDA     I1 @T6G_MB_LIB.T6G(SCH_1):PAGE378
     9 SMB_RT_CPU1_P3_SCL @T6G_MB_LIB.T6G(SCH_1):SMB_RT_CPU1_P3_SCL     I1 @T6G_MB_LIB.T6G(SCH_1):PAGE378
    10 SMB_RT_CPU1_P2_SDA @T6G_MB_LIB.T6G(SCH_1):SMB_RT_CPU1_P2_SDA     I1 @T6G_MB_LIB.T6G(SCH_1):PAGE378
    11 SMB_RT_CPU1_P2_SCL @T6G_MB_LIB.T6G(SCH_1):SMB_RT_CPU1_P2_SCL     I1 @T6G_MB_LIB.T6G(SCH_1):PAGE378
    12    GND @T6G_MB_LIB.T6G(SCH_1):GND     I1 @T6G_MB_LIB.T6G(SCH_1):PAGE378
    24 P1V8_AUX @T6G_MB_LIB.T6G(SCH_1):P1V8_AUX     I1 @T6G_MB_LIB.T6G(SCH_1):PAGE378
    23 SMB_MUX_RT_SDA @T6G_MB_LIB.T6G(SCH_1):SMB_MUX_RT_SDA     I1 @T6G_MB_LIB.T6G(SCH_1):PAGE378
    22 SMB_MUX_RT_SCL @T6G_MB_LIB.T6G(SCH_1):SMB_MUX_RT_SCL     I1 @T6G_MB_LIB.T6G(SCH_1):PAGE378
    21 RT_SMB_MUX_ADDR2 @T6G_MB_LIB.T6G(SCH_1):RT_SMB_MUX_ADDR2     I1 @T6G_MB_LIB.T6G(SCH_1):PAGE378
    20 SMB_RT_CPU0_P2_SCL @T6G_MB_LIB.T6G(SCH_1):SMB_RT_CPU0_P2_SCL     I1 @T6G_MB_LIB.T6G(SCH_1):PAGE378
    19 SMB_RT_CPU0_P2_SDA @T6G_MB_LIB.T6G(SCH_1):SMB_RT_CPU0_P2_SDA     I1 @T6G_MB_LIB.T6G(SCH_1):PAGE378
    18 SMB_RT_CPU0_P3_SCL @T6G_MB_LIB.T6G(SCH_1):SMB_RT_CPU0_P3_SCL     I1 @T6G_MB_LIB.T6G(SCH_1):PAGE378
    17 SMB_RT_CPU0_P3_SDA @T6G_MB_LIB.T6G(SCH_1):SMB_RT_CPU0_P3_SDA     I1 @T6G_MB_LIB.T6G(SCH_1):PAGE378
    16 SMB_RT_CPU0_P1_SCL @T6G_MB_LIB.T6G(SCH_1):SMB_RT_CPU0_P1_SCL     I1 @T6G_MB_LIB.T6G(SCH_1):PAGE378
    15 SMB_RT_CPU0_P1_SDA @T6G_MB_LIB.T6G(SCH_1):SMB_RT_CPU0_P1_SDA     I1 @T6G_MB_LIB.T6G(SCH_1):PAGE378
    14 SMB_RT_CPU0_P0_SCL @T6G_MB_LIB.T6G(SCH_1):SMB_RT_CPU0_P0_SCL     I1 @T6G_MB_LIB.T6G(SCH_1):PAGE378
    13 SMB_RT_CPU0_P0_SDA @T6G_MB_LIB.T6G(SCH_1):SMB_RT_CPU0_P0_SDA     I1 @T6G_MB_LIB.T6G(SCH_1):PAGE378

U8000 NC7SB3157P6X-NC7SB3157P6X,SMLF,IC,ALSB3157000
     1 ESPI_CPU0_ALERT_R1_N @T6G_MB_LIB.T6G(SCH_1):ESPI_CPU0_ALERT_R1_N     I1 @T6G_MB_LIB.T6G(SCH_1):PAGE130
     2    GND @T6G_MB_LIB.T6G(SCH_1):GND     I1 @T6G_MB_LIB.T6G(SCH_1):PAGE130
     3 ESPI_CPU0_ALERT_PLD_N @T6G_MB_LIB.T6G(SCH_1):ESPI_CPU0_ALERT_PLD_N     I1 @T6G_MB_LIB.T6G(SCH_1):PAGE130
     6 FM_ESPI_CPU0_ALERT_R_SEL @T6G_MB_LIB.T6G(SCH_1):FM_ESPI_CPU0_ALERT_R_SEL     I1 @T6G_MB_LIB.T6G(SCH_1):PAGE130
     5 P1V8_AUX @T6G_MB_LIB.T6G(SCH_1):P1V8_AUX     I1 @T6G_MB_LIB.T6G(SCH_1):PAGE130
     4 ESPI_CPU0_ALERT_P0_N @T6G_MB_LIB.T6G(SCH_1):ESPI_CPU0_ALERT_P0_N     I1 @T6G_MB_LIB.T6G(SCH_1):PAGE130

U8001 APX80929SAG7-APX809-29SAG-7,SMLF,IC,AL080929000
     3 P3V3_OCP_SFF_R @T6G_MB_LIB.T6G(SCH_1):P3V3_OCP_SFF_R    I80 @T6G_MB_LIB.T6G(SCH_1):PAGE340
     2 OCP_V3_1_P3V3_R1_PWRGD @T6G_MB_LIB.T6G(SCH_1):OCP_V3_1_P3V3_R1_PWRGD    I80 @T6G_MB_LIB.T6G(SCH_1):PAGE340
     1    GND @T6G_MB_LIB.T6G(SCH_1):GND    I80 @T6G_MB_LIB.T6G(SCH_1):PAGE340

U8002 APX80929SAG7-APX809-29SAG-7,SMLF,IC,AL080929000
     3 P3V3_OCP_V3_2_R @T6G_MB_LIB.T6G(SCH_1):P3V3_OCP_V3_2_R    I67 @T6G_MB_LIB.T6G(SCH_1):PAGE257
     2 OCP_V3_2_P3V3_R1_PWRGD @T6G_MB_LIB.T6G(SCH_1):OCP_V3_2_P3V3_R1_PWRGD    I67 @T6G_MB_LIB.T6G(SCH_1):PAGE257
     1    GND @T6G_MB_LIB.T6G(SCH_1):GND    I67 @T6G_MB_LIB.T6G(SCH_1):PAGE257

U8003 APX80929SAG7-APX809-29SAG-7,SMLF,IC,AL080929000
     3 P3V3_E1S_0_R @T6G_MB_LIB.T6G(SCH_1):P3V3_E1S_0_R    I65 @T6G_MB_LIB.T6G(SCH_1):PAGE323
     2 P3V3_E1S_PWRGD_0_R1 @T6G_MB_LIB.T6G(SCH_1):P3V3_E1S_PWRGD_0_R1    I65 @T6G_MB_LIB.T6G(SCH_1):PAGE323
     1    GND @T6G_MB_LIB.T6G(SCH_1):GND    I65 @T6G_MB_LIB.T6G(SCH_1):PAGE323

U8004 74LVC2G07DW7-74LVC2G07DW-7,SMLF,EMPTY,AL002G07003
     1 FM_AC_PWR_BTN_PLD_N @T6G_MB_LIB.T6G(SCH_1):FM_AC_PWR_BTN_PLD_N    I16 @T6G_MB_LIB.T6G(SCH_1):PAGE365
     3    GND @T6G_MB_LIB.T6G(SCH_1):GND    I16 @T6G_MB_LIB.T6G(SCH_1):PAGE365
     6 FM_AC_PWR_BTN_PLD_ISO_R_N @T6G_MB_LIB.T6G(SCH_1):FM_AC_PWR_BTN_PLD_ISO_R_N    I16 @T6G_MB_LIB.T6G(SCH_1):PAGE365
     4 NC_U8004_2Y @T6G_MB_LIB.T6G(SCH_1):NC_U8004_2Y    I16 @T6G_MB_LIB.T6G(SCH_1):PAGE365
     2    GND @T6G_MB_LIB.T6G(SCH_1):GND    I16 @T6G_MB_LIB.T6G(SCH_1):PAGE365
     5 P3V3_AUX @T6G_MB_LIB.T6G(SCH_1):P3V3_AUX    I16 @T6G_MB_LIB.T6G(SCH_1):PAGE365

U8005 LM4040AIM3X25NOPB-LM4040AIM3X-2.5/NOPB,SMLF,EMPTY,A
     1 OC_P2V5_COMP @T6G_MB_LIB.T6G(SCH_1):OC_P2V5_COMP   I101 @T6G_MB_LIB.T6G(SCH_1):PAGE371
     2    GND @T6G_MB_LIB.T6G(SCH_1):GND   I101 @T6G_MB_LIB.T6G(SCH_1):PAGE371
     3     NC     NC   I101 @T6G_MB_LIB.T6G(SCH_1):PAGE371

U8006 AP331AWG7-AP331AWG-7,SMLF,EMPTY,AL000331011
     3 HSC_OC_VOL @T6G_MB_LIB.T6G(SCH_1):HSC_OC_VOL   I104 @T6G_MB_LIB.T6G(SCH_1):PAGE371
     1 OC_P2V5_COMP @T6G_MB_LIB.T6G(SCH_1):OC_P2V5_COMP   I104 @T6G_MB_LIB.T6G(SCH_1):PAGE371
     4 HSC_D_OC_R2 @T6G_MB_LIB.T6G(SCH_1):HSC_D_OC_R2   I104 @T6G_MB_LIB.T6G(SCH_1):PAGE371
     5 P12V_AUX @T6G_MB_LIB.T6G(SCH_1):P12V_AUX   I104 @T6G_MB_LIB.T6G(SCH_1):PAGE371
     2    GND @T6G_MB_LIB.T6G(SCH_1):GND   I104 @T6G_MB_LIB.T6G(SCH_1):PAGE371

U8007 LM4040AIM3X25NOPB-LM4040AIM3X-2.5/NOPB,SMLF,IC,AL4A
     1 UV_ADR_P2V5_COMP @T6G_MB_LIB.T6G(SCH_1):UV_ADR_P2V5_COMP    I51 @T6G_MB_LIB.T6G(SCH_1):PAGE372
     2    GND @T6G_MB_LIB.T6G(SCH_1):GND    I51 @T6G_MB_LIB.T6G(SCH_1):PAGE372
     3     NC     NC    I51 @T6G_MB_LIB.T6G(SCH_1):PAGE372

U8008 AP331AWG7-AP331AWG-7,SMLF,IC,AL000331011
     3 P12V_AUX_UV_ADR_TRIGGER @T6G_MB_LIB.T6G(SCH_1):P12V_AUX_UV_ADR_TRIGGER    I71 @T6G_MB_LIB.T6G(SCH_1):PAGE372
     1 UV_ADR_P2V5_COMP @T6G_MB_LIB.T6G(SCH_1):UV_ADR_P2V5_COMP    I71 @T6G_MB_LIB.T6G(SCH_1):PAGE372
     4 FM_UV_ADR_TRIGGER_N_R2 @T6G_MB_LIB.T6G(SCH_1):FM_UV_ADR_TRIGGER_N_R2    I71 @T6G_MB_LIB.T6G(SCH_1):PAGE372
     5 P12V_AUX @T6G_MB_LIB.T6G(SCH_1):P12V_AUX    I71 @T6G_MB_LIB.T6G(SCH_1):PAGE372
     2    GND @T6G_MB_LIB.T6G(SCH_1):GND    I71 @T6G_MB_LIB.T6G(SCH_1):PAGE372

U8009 LM4040AIM3X25NOPB-LM4040AIM3X-2.5/NOPB,SMLF,IC,AL4A
     1 UV_P2V5_COMP @T6G_MB_LIB.T6G(SCH_1):UV_P2V5_COMP    I93 @T6G_MB_LIB.T6G(SCH_1):PAGE372
     2    GND @T6G_MB_LIB.T6G(SCH_1):GND    I93 @T6G_MB_LIB.T6G(SCH_1):PAGE372
     3     NC     NC    I93 @T6G_MB_LIB.T6G(SCH_1):PAGE372

U8010 AP331AWG7-AP331AWG-7,SMLF,IC,AL000331011
     3 P12V_AUX_UV_TRIGGER @T6G_MB_LIB.T6G(SCH_1):P12V_AUX_UV_TRIGGER    I80 @T6G_MB_LIB.T6G(SCH_1):PAGE372
     1 UV_P2V5_COMP @T6G_MB_LIB.T6G(SCH_1):UV_P2V5_COMP    I80 @T6G_MB_LIB.T6G(SCH_1):PAGE372
     4 IRQ_UV_DETECT_R2_N @T6G_MB_LIB.T6G(SCH_1):IRQ_UV_DETECT_R2_N    I80 @T6G_MB_LIB.T6G(SCH_1):PAGE372
     5 P12V_AUX @T6G_MB_LIB.T6G(SCH_1):P12V_AUX    I80 @T6G_MB_LIB.T6G(SCH_1):PAGE372
     2    GND @T6G_MB_LIB.T6G(SCH_1):GND    I80 @T6G_MB_LIB.T6G(SCH_1):PAGE372

U8082 74LVC1G126SE7-74LVC1G126SE-7,SMLF,IC,AL1G0126009
     2 IRQ_LVC3_OCP_SFF_WAKE_N @T6G_MB_LIB.T6G(SCH_1):IRQ_LVC3_OCP_SFF_WAKE_N     I8 @T6G_MB_LIB.T6G(SCH_1):PAGE337
     4 OCP_SFF_WAKE_BUFF_N @T6G_MB_LIB.T6G(SCH_1):OCP_SFF_WAKE_BUFF_N     I8 @T6G_MB_LIB.T6G(SCH_1):PAGE337
     5 P3V3_AUX @T6G_MB_LIB.T6G(SCH_1):P3V3_AUX     I8 @T6G_MB_LIB.T6G(SCH_1):PAGE337
     3    GND @T6G_MB_LIB.T6G(SCH_1):GND     I8 @T6G_MB_LIB.T6G(SCH_1):PAGE337
     1 PU_OCP_SFF_WAKE_OE @T6G_MB_LIB.T6G(SCH_1):PU_OCP_SFF_WAKE_OE     I8 @T6G_MB_LIB.T6G(SCH_1):PAGE337

U9001 74LVC1G08W57-74LVC1G08W5-7,SMLF,IC,AL1G0008020
     1 RST_PERST_OCP_SFF_R_N @T6G_MB_LIB.T6G(SCH_1):RST_PERST_OCP_SFF_R_N    I25 @T6G_MB_LIB.T6G(SCH_1):PAGE340
     2 HP_LVC3_OCP_V3_1_PWRGD @T6G_MB_LIB.T6G(SCH_1):HP_LVC3_OCP_V3_1_PWRGD    I25 @T6G_MB_LIB.T6G(SCH_1):PAGE340
     3    GND @T6G_MB_LIB.T6G(SCH_1):GND    I25 @T6G_MB_LIB.T6G(SCH_1):PAGE340
     4 RST_PERST_OCP_SFF_BUF_R_N @T6G_MB_LIB.T6G(SCH_1):RST_PERST_OCP_SFF_BUF_R_N    I25 @T6G_MB_LIB.T6G(SCH_1):PAGE340
     5 P3V3_AUX @T6G_MB_LIB.T6G(SCH_1):P3V3_AUX    I25 @T6G_MB_LIB.T6G(SCH_1):PAGE340

U9002 74LVC1G32GW_SMLF-74LVC1G32GW,IC,ALVC1G32007
     1 HP_LVC3_OCP_V3_1_PWRGD_R1 @T6G_MB_LIB.T6G(SCH_1):HP_LVC3_OCP_V3_1_PWRGD_R1    I74 @T6G_MB_LIB.T6G(SCH_1):PAGE340
     2 FM_PLD_OCP_SFF_AUX_PWR_EN @T6G_MB_LIB.T6G(SCH_1):FM_PLD_OCP_SFF_AUX_PWR_EN    I74 @T6G_MB_LIB.T6G(SCH_1):PAGE340
     4 OCP_SFF_AUX_PWR_EN_R3 @T6G_MB_LIB.T6G(SCH_1):OCP_SFF_AUX_PWR_EN_R3    I74 @T6G_MB_LIB.T6G(SCH_1):PAGE340
     5 P3V3_AUX @T6G_MB_LIB.T6G(SCH_1):P3V3_AUX    I74 @T6G_MB_LIB.T6G(SCH_1):PAGE340
     3    GND @T6G_MB_LIB.T6G(SCH_1):GND    I74 @T6G_MB_LIB.T6G(SCH_1):PAGE340

U9050 74LVC1G08W57-74LVC1G08W5-7,SMLF,IC,AL1G0008020
     1 OCP_V3_1_P3V3_PWRGD @T6G_MB_LIB.T6G(SCH_1):OCP_V3_1_P3V3_PWRGD    I91 @T6G_MB_LIB.T6G(SCH_1):PAGE340
     2 HP_LVC3_OCP_V3_1_P12V_R2_PWRGD @T6G_MB_LIB.T6G(SCH_1):HP_LVC3_OCP_V3_1_P12V_R2_PWRGD    I91 @T6G_MB_LIB.T6G(SCH_1):PAGE340
     3    GND @T6G_MB_LIB.T6G(SCH_1):GND    I91 @T6G_MB_LIB.T6G(SCH_1):PAGE340
     4 HP_LVC3_OCP_V3_1_PWRGD_R2 @T6G_MB_LIB.T6G(SCH_1):HP_LVC3_OCP_V3_1_PWRGD_R2    I91 @T6G_MB_LIB.T6G(SCH_1):PAGE340
     5 P3V3_AUX @T6G_MB_LIB.T6G(SCH_1):P3V3_AUX    I91 @T6G_MB_LIB.T6G(SCH_1):PAGE340

U9051 74LVC1G08W57-74LVC1G08W5-7,SMLF,IC,AL1G0008020
     1 OCP_V3_2_P3V3_PWRGD @T6G_MB_LIB.T6G(SCH_1):OCP_V3_2_P3V3_PWRGD    I78 @T6G_MB_LIB.T6G(SCH_1):PAGE257
     2 HP_LVC3_OCP_V3_2_P12V_PWRGD_R2 @T6G_MB_LIB.T6G(SCH_1):HP_LVC3_OCP_V3_2_P12V_PWRGD_R2    I78 @T6G_MB_LIB.T6G(SCH_1):PAGE257
     3    GND @T6G_MB_LIB.T6G(SCH_1):GND    I78 @T6G_MB_LIB.T6G(SCH_1):PAGE257
     4 HP_LVC3_OCP_V3_2_PWRGD_R2 @T6G_MB_LIB.T6G(SCH_1):HP_LVC3_OCP_V3_2_PWRGD_R2    I78 @T6G_MB_LIB.T6G(SCH_1):PAGE257
     5 P3V3_AUX @T6G_MB_LIB.T6G(SCH_1):P3V3_AUX    I78 @T6G_MB_LIB.T6G(SCH_1):PAGE257

  X1 TP_TDR_4P_FTS_TH-TP_TDR_4P_DIP,EMPTY,TP15
     2 T1_GND @T6G_MB_LIB.T6G(SCH_1):T1_GND    I48 @T6G_MB_LIB.T6G(SCH_1):PAGE265
     3 T1_GND @T6G_MB_LIB.T6G(SCH_1):T1_GND    I48 @T6G_MB_LIB.T6G(SCH_1):PAGE265
     1 TDR_DIFF_80_TOP_DP @T6G_MB_LIB.T6G(SCH_1):TDR_DIFF_80_TOP_DP    I48 @T6G_MB_LIB.T6G(SCH_1):PAGE265
     4 TDR_DIFF_80_TOP_DN @T6G_MB_LIB.T6G(SCH_1):TDR_DIFF_80_TOP_DN    I48 @T6G_MB_LIB.T6G(SCH_1):PAGE265

  X2 TP_TDR_4P_FTS_TH-TP_TDR_4P_DIP,EMPTY,TP15
     2 T1_GND @T6G_MB_LIB.T6G(SCH_1):T1_GND    I47 @T6G_MB_LIB.T6G(SCH_1):PAGE265
     3 T1_GND @T6G_MB_LIB.T6G(SCH_1):T1_GND    I47 @T6G_MB_LIB.T6G(SCH_1):PAGE265
     1 TDR_DIFF_80_IN1_DP @T6G_MB_LIB.T6G(SCH_1):TDR_DIFF_80_IN1_DP    I47 @T6G_MB_LIB.T6G(SCH_1):PAGE265
     4 TDR_DIFF_80_IN1_DN @T6G_MB_LIB.T6G(SCH_1):TDR_DIFF_80_IN1_DN    I47 @T6G_MB_LIB.T6G(SCH_1):PAGE265

  X3 TP_TDR_4P_FTS_TH-TP_TDR_4P_DIP,EMPTY,TP15
     2 T1_GND @T6G_MB_LIB.T6G(SCH_1):T1_GND    I37 @T6G_MB_LIB.T6G(SCH_1):PAGE265
     3 T1_GND @T6G_MB_LIB.T6G(SCH_1):T1_GND    I37 @T6G_MB_LIB.T6G(SCH_1):PAGE265
     1 TDR_DIFF_80_IN2_DP @T6G_MB_LIB.T6G(SCH_1):TDR_DIFF_80_IN2_DP    I37 @T6G_MB_LIB.T6G(SCH_1):PAGE265
     4 TDR_DIFF_80_IN2_DN @T6G_MB_LIB.T6G(SCH_1):TDR_DIFF_80_IN2_DN    I37 @T6G_MB_LIB.T6G(SCH_1):PAGE265

  X4 TP_TDR_4P_FTS_TH-TP_TDR_4P_DIP,EMPTY,TP15
     2 T1_GND @T6G_MB_LIB.T6G(SCH_1):T1_GND    I36 @T6G_MB_LIB.T6G(SCH_1):PAGE265
     3 T1_GND @T6G_MB_LIB.T6G(SCH_1):T1_GND    I36 @T6G_MB_LIB.T6G(SCH_1):PAGE265
     1 TDR_DIFF_80_IN3_DP @T6G_MB_LIB.T6G(SCH_1):TDR_DIFF_80_IN3_DP    I36 @T6G_MB_LIB.T6G(SCH_1):PAGE265
     4 TDR_DIFF_80_IN3_DN @T6G_MB_LIB.T6G(SCH_1):TDR_DIFF_80_IN3_DN    I36 @T6G_MB_LIB.T6G(SCH_1):PAGE265

  X5 TP_TDR_4P_FTS_TH-TP_TDR_4P_DIP,EMPTY,TP15
     2 T1_GND @T6G_MB_LIB.T6G(SCH_1):T1_GND    I35 @T6G_MB_LIB.T6G(SCH_1):PAGE265
     3 T1_GND @T6G_MB_LIB.T6G(SCH_1):T1_GND    I35 @T6G_MB_LIB.T6G(SCH_1):PAGE265
     1 TDR_DIFF_80_IN4_DP @T6G_MB_LIB.T6G(SCH_1):TDR_DIFF_80_IN4_DP    I35 @T6G_MB_LIB.T6G(SCH_1):PAGE265
     4 TDR_DIFF_80_IN4_DN @T6G_MB_LIB.T6G(SCH_1):TDR_DIFF_80_IN4_DN    I35 @T6G_MB_LIB.T6G(SCH_1):PAGE265

  X6 TP_TDR_4P_FTS_TH-TP_TDR_4P_DIP,EMPTY,TP15
     2 T1_GND @T6G_MB_LIB.T6G(SCH_1):T1_GND    I29 @T6G_MB_LIB.T6G(SCH_1):PAGE265
     3 T1_GND @T6G_MB_LIB.T6G(SCH_1):T1_GND    I29 @T6G_MB_LIB.T6G(SCH_1):PAGE265
     1 TDR_DIFF_80_BOT_DP @T6G_MB_LIB.T6G(SCH_1):TDR_DIFF_80_BOT_DP    I29 @T6G_MB_LIB.T6G(SCH_1):PAGE265
     4 TDR_DIFF_80_BOT_DN @T6G_MB_LIB.T6G(SCH_1):TDR_DIFF_80_BOT_DN    I29 @T6G_MB_LIB.T6G(SCH_1):PAGE265

  X7 TP_TDR_4P_FTS_TH-TP_TDR_4P_DIP,EMPTY,TP15
     2 T1_GND @T6G_MB_LIB.T6G(SCH_1):T1_GND    I84 @T6G_MB_LIB.T6G(SCH_1):PAGE265
     3 T1_GND @T6G_MB_LIB.T6G(SCH_1):T1_GND    I84 @T6G_MB_LIB.T6G(SCH_1):PAGE265
     1 TDR_DIFF_80_TOP_DN @T6G_MB_LIB.T6G(SCH_1):TDR_DIFF_80_TOP_DN    I84 @T6G_MB_LIB.T6G(SCH_1):PAGE265
     4 TDR_DIFF_80_TOP_DP @T6G_MB_LIB.T6G(SCH_1):TDR_DIFF_80_TOP_DP    I84 @T6G_MB_LIB.T6G(SCH_1):PAGE265

  X8 TP_TDR_4P_FTS_TH-TP_TDR_4P_DIP,EMPTY,TP15
     2 T1_GND @T6G_MB_LIB.T6G(SCH_1):T1_GND    I82 @T6G_MB_LIB.T6G(SCH_1):PAGE265
     3 T1_GND @T6G_MB_LIB.T6G(SCH_1):T1_GND    I82 @T6G_MB_LIB.T6G(SCH_1):PAGE265
     1 TDR_DIFF_80_IN1_DN @T6G_MB_LIB.T6G(SCH_1):TDR_DIFF_80_IN1_DN    I82 @T6G_MB_LIB.T6G(SCH_1):PAGE265
     4 TDR_DIFF_80_IN1_DP @T6G_MB_LIB.T6G(SCH_1):TDR_DIFF_80_IN1_DP    I82 @T6G_MB_LIB.T6G(SCH_1):PAGE265

  X9 TP_TDR_4P_FTS_TH-TP_TDR_4P_DIP,EMPTY,TP15
     2 T1_GND @T6G_MB_LIB.T6G(SCH_1):T1_GND    I62 @T6G_MB_LIB.T6G(SCH_1):PAGE265
     3 T1_GND @T6G_MB_LIB.T6G(SCH_1):T1_GND    I62 @T6G_MB_LIB.T6G(SCH_1):PAGE265
     1 TDR_DIFF_80_IN2_DN @T6G_MB_LIB.T6G(SCH_1):TDR_DIFF_80_IN2_DN    I62 @T6G_MB_LIB.T6G(SCH_1):PAGE265
     4 TDR_DIFF_80_IN2_DP @T6G_MB_LIB.T6G(SCH_1):TDR_DIFF_80_IN2_DP    I62 @T6G_MB_LIB.T6G(SCH_1):PAGE265

 X10 TP_TDR_4P_FTS_TH-TP_TDR_4P_DIP,EMPTY,TP15
     2 T1_GND @T6G_MB_LIB.T6G(SCH_1):T1_GND    I61 @T6G_MB_LIB.T6G(SCH_1):PAGE265
     3 T1_GND @T6G_MB_LIB.T6G(SCH_1):T1_GND    I61 @T6G_MB_LIB.T6G(SCH_1):PAGE265
     1 TDR_DIFF_80_IN3_DN @T6G_MB_LIB.T6G(SCH_1):TDR_DIFF_80_IN3_DN    I61 @T6G_MB_LIB.T6G(SCH_1):PAGE265
     4 TDR_DIFF_80_IN3_DP @T6G_MB_LIB.T6G(SCH_1):TDR_DIFF_80_IN3_DP    I61 @T6G_MB_LIB.T6G(SCH_1):PAGE265

 X11 TP_TDR_4P_FTS_TH-TP_TDR_4P_DIP,EMPTY,TP15
     2 T1_GND @T6G_MB_LIB.T6G(SCH_1):T1_GND    I96 @T6G_MB_LIB.T6G(SCH_1):PAGE265
     3 T1_GND @T6G_MB_LIB.T6G(SCH_1):T1_GND    I96 @T6G_MB_LIB.T6G(SCH_1):PAGE265
     1 TDR_DIFF_80_IN4_DN @T6G_MB_LIB.T6G(SCH_1):TDR_DIFF_80_IN4_DN    I96 @T6G_MB_LIB.T6G(SCH_1):PAGE265
     4 TDR_DIFF_80_IN4_DP @T6G_MB_LIB.T6G(SCH_1):TDR_DIFF_80_IN4_DP    I96 @T6G_MB_LIB.T6G(SCH_1):PAGE265

 X12 TP_TDR_4P_FTS_TH-TP_TDR_4P_DIP,EMPTY,TP15
     2 T1_GND @T6G_MB_LIB.T6G(SCH_1):T1_GND    I49 @T6G_MB_LIB.T6G(SCH_1):PAGE265
     3 T1_GND @T6G_MB_LIB.T6G(SCH_1):T1_GND    I49 @T6G_MB_LIB.T6G(SCH_1):PAGE265
     1 TDR_DIFF_80_BOT_DN @T6G_MB_LIB.T6G(SCH_1):TDR_DIFF_80_BOT_DN    I49 @T6G_MB_LIB.T6G(SCH_1):PAGE265
     4 TDR_DIFF_80_BOT_DP @T6G_MB_LIB.T6G(SCH_1):TDR_DIFF_80_BOT_DP    I49 @T6G_MB_LIB.T6G(SCH_1):PAGE265

 X25 TP_TDR_4P_FTS_TH-TP_TDR_4P_DIP,EMPTY,TP15
     2 T1_GND @T6G_MB_LIB.T6G(SCH_1):T1_GND    I31 @T6G_MB_LIB.T6G(SCH_1):PAGE265
     3 T1_GND @T6G_MB_LIB.T6G(SCH_1):T1_GND    I31 @T6G_MB_LIB.T6G(SCH_1):PAGE265
     1 TDR_DIFF_80_IN5_DP @T6G_MB_LIB.T6G(SCH_1):TDR_DIFF_80_IN5_DP    I31 @T6G_MB_LIB.T6G(SCH_1):PAGE265
     4 TDR_DIFF_80_IN5_DN @T6G_MB_LIB.T6G(SCH_1):TDR_DIFF_80_IN5_DN    I31 @T6G_MB_LIB.T6G(SCH_1):PAGE265

 X26 TP_TDR_4P_FTS_TH-TP_TDR_4P_DIP,EMPTY,TP15
     2 T1_GND @T6G_MB_LIB.T6G(SCH_1):T1_GND    I30 @T6G_MB_LIB.T6G(SCH_1):PAGE265
     3 T1_GND @T6G_MB_LIB.T6G(SCH_1):T1_GND    I30 @T6G_MB_LIB.T6G(SCH_1):PAGE265
     1 TDR_DIFF_80_IN6_DP @T6G_MB_LIB.T6G(SCH_1):TDR_DIFF_80_IN6_DP    I30 @T6G_MB_LIB.T6G(SCH_1):PAGE265
     4 TDR_DIFF_80_IN6_DN @T6G_MB_LIB.T6G(SCH_1):TDR_DIFF_80_IN6_DN    I30 @T6G_MB_LIB.T6G(SCH_1):PAGE265

 X27 TP_TDR_4P_FTS_TH-TP_TDR_4P_DIP,EMPTY,TP15
     2 T1_GND @T6G_MB_LIB.T6G(SCH_1):T1_GND    I53 @T6G_MB_LIB.T6G(SCH_1):PAGE265
     3 T1_GND @T6G_MB_LIB.T6G(SCH_1):T1_GND    I53 @T6G_MB_LIB.T6G(SCH_1):PAGE265
     1 TDR_DIFF_80_IN5_DN @T6G_MB_LIB.T6G(SCH_1):TDR_DIFF_80_IN5_DN    I53 @T6G_MB_LIB.T6G(SCH_1):PAGE265
     4 TDR_DIFF_80_IN5_DP @T6G_MB_LIB.T6G(SCH_1):TDR_DIFF_80_IN5_DP    I53 @T6G_MB_LIB.T6G(SCH_1):PAGE265

 X28 TP_TDR_4P_FTS_TH-TP_TDR_4P_DIP,EMPTY,TP15
     2 T1_GND @T6G_MB_LIB.T6G(SCH_1):T1_GND    I52 @T6G_MB_LIB.T6G(SCH_1):PAGE265
     3 T1_GND @T6G_MB_LIB.T6G(SCH_1):T1_GND    I52 @T6G_MB_LIB.T6G(SCH_1):PAGE265
     1 TDR_DIFF_80_IN6_DN @T6G_MB_LIB.T6G(SCH_1):TDR_DIFF_80_IN6_DN    I52 @T6G_MB_LIB.T6G(SCH_1):PAGE265
     4 TDR_DIFF_80_IN6_DP @T6G_MB_LIB.T6G(SCH_1):TDR_DIFF_80_IN6_DP    I52 @T6G_MB_LIB.T6G(SCH_1):PAGE265

X8001 TP_TDR_4P_FTS_TH-TP_TDR_4P_DIP,EMPTY,TP15
     2 T1_GND @T6G_MB_LIB.T6G(SCH_1):T1_GND    I89 @T6G_MB_LIB.T6G(SCH_1):PAGE265
     3 T1_GND @T6G_MB_LIB.T6G(SCH_1):T1_GND    I89 @T6G_MB_LIB.T6G(SCH_1):PAGE265
     1 TDR_DIFF_85_TOP_DP @T6G_MB_LIB.T6G(SCH_1):TDR_DIFF_85_TOP_DP    I89 @T6G_MB_LIB.T6G(SCH_1):PAGE265
     4 TDR_DIFF_85_TOP_DN @T6G_MB_LIB.T6G(SCH_1):TDR_DIFF_85_TOP_DN    I89 @T6G_MB_LIB.T6G(SCH_1):PAGE265

X8002 TP_TDR_4P_FTS_TH-TP_TDR_4P_DIP,EMPTY,TP15
     2 T1_GND @T6G_MB_LIB.T6G(SCH_1):T1_GND    I87 @T6G_MB_LIB.T6G(SCH_1):PAGE265
     3 T1_GND @T6G_MB_LIB.T6G(SCH_1):T1_GND    I87 @T6G_MB_LIB.T6G(SCH_1):PAGE265
     1 TDR_DIFF_85_IN1_DP @T6G_MB_LIB.T6G(SCH_1):TDR_DIFF_85_IN1_DP    I87 @T6G_MB_LIB.T6G(SCH_1):PAGE265
     4 TDR_DIFF_85_IN1_DN @T6G_MB_LIB.T6G(SCH_1):TDR_DIFF_85_IN1_DN    I87 @T6G_MB_LIB.T6G(SCH_1):PAGE265

X8003 TP_TDR_4P_FTS_TH-TP_TDR_4P_DIP,EMPTY,TP15
     2 T1_GND @T6G_MB_LIB.T6G(SCH_1):T1_GND    I70 @T6G_MB_LIB.T6G(SCH_1):PAGE265
     3 T1_GND @T6G_MB_LIB.T6G(SCH_1):T1_GND    I70 @T6G_MB_LIB.T6G(SCH_1):PAGE265
     1 TDR_DIFF_85_IN2_DP @T6G_MB_LIB.T6G(SCH_1):TDR_DIFF_85_IN2_DP    I70 @T6G_MB_LIB.T6G(SCH_1):PAGE265
     4 TDR_DIFF_85_IN2_DN @T6G_MB_LIB.T6G(SCH_1):TDR_DIFF_85_IN2_DN    I70 @T6G_MB_LIB.T6G(SCH_1):PAGE265

X8004 TP_TDR_4P_FTS_TH-TP_TDR_4P_DIP,EMPTY,TP15
     2 T1_GND @T6G_MB_LIB.T6G(SCH_1):T1_GND    I68 @T6G_MB_LIB.T6G(SCH_1):PAGE265
     3 T1_GND @T6G_MB_LIB.T6G(SCH_1):T1_GND    I68 @T6G_MB_LIB.T6G(SCH_1):PAGE265
     1 TDR_DIFF_85_IN3_DP @T6G_MB_LIB.T6G(SCH_1):TDR_DIFF_85_IN3_DP    I68 @T6G_MB_LIB.T6G(SCH_1):PAGE265
     4 TDR_DIFF_85_IN3_DN @T6G_MB_LIB.T6G(SCH_1):TDR_DIFF_85_IN3_DN    I68 @T6G_MB_LIB.T6G(SCH_1):PAGE265

X8005 TP_TDR_4P_FTS_TH-TP_TDR_4P_DIP,EMPTY,TP15
     2 T1_GND @T6G_MB_LIB.T6G(SCH_1):T1_GND    I66 @T6G_MB_LIB.T6G(SCH_1):PAGE265
     3 T1_GND @T6G_MB_LIB.T6G(SCH_1):T1_GND    I66 @T6G_MB_LIB.T6G(SCH_1):PAGE265
     1 TDR_DIFF_85_IN4_DP @T6G_MB_LIB.T6G(SCH_1):TDR_DIFF_85_IN4_DP    I66 @T6G_MB_LIB.T6G(SCH_1):PAGE265
     4 TDR_DIFF_85_IN4_DN @T6G_MB_LIB.T6G(SCH_1):TDR_DIFF_85_IN4_DN    I66 @T6G_MB_LIB.T6G(SCH_1):PAGE265

X8006 TP_TDR_4P_FTS_TH-TP_TDR_4P_DIP,EMPTY,TP15
     2 T1_GND @T6G_MB_LIB.T6G(SCH_1):T1_GND    I56 @T6G_MB_LIB.T6G(SCH_1):PAGE265
     3 T1_GND @T6G_MB_LIB.T6G(SCH_1):T1_GND    I56 @T6G_MB_LIB.T6G(SCH_1):PAGE265
     1 TDR_DIFF_85_BOT_DP @T6G_MB_LIB.T6G(SCH_1):TDR_DIFF_85_BOT_DP    I56 @T6G_MB_LIB.T6G(SCH_1):PAGE265
     4 TDR_DIFF_85_BOT_DN @T6G_MB_LIB.T6G(SCH_1):TDR_DIFF_85_BOT_DN    I56 @T6G_MB_LIB.T6G(SCH_1):PAGE265

X8007 TP_TDR_4P_FTS_TH-TP_TDR_4P_DIP,EMPTY,TP15
     2 T1_GND @T6G_MB_LIB.T6G(SCH_1):T1_GND    I92 @T6G_MB_LIB.T6G(SCH_1):PAGE265
     3 T1_GND @T6G_MB_LIB.T6G(SCH_1):T1_GND    I92 @T6G_MB_LIB.T6G(SCH_1):PAGE265
     1 TDR_DIFF_85_TOP_DN @T6G_MB_LIB.T6G(SCH_1):TDR_DIFF_85_TOP_DN    I92 @T6G_MB_LIB.T6G(SCH_1):PAGE265
     4 TDR_DIFF_85_TOP_DP @T6G_MB_LIB.T6G(SCH_1):TDR_DIFF_85_TOP_DP    I92 @T6G_MB_LIB.T6G(SCH_1):PAGE265

X8008 TP_TDR_4P_FTS_TH-TP_TDR_4P_DIP,EMPTY,TP15
     2 T1_GND @T6G_MB_LIB.T6G(SCH_1):T1_GND    I90 @T6G_MB_LIB.T6G(SCH_1):PAGE265
     3 T1_GND @T6G_MB_LIB.T6G(SCH_1):T1_GND    I90 @T6G_MB_LIB.T6G(SCH_1):PAGE265
     1 TDR_DIFF_85_IN1_DN @T6G_MB_LIB.T6G(SCH_1):TDR_DIFF_85_IN1_DN    I90 @T6G_MB_LIB.T6G(SCH_1):PAGE265
     4 TDR_DIFF_85_IN1_DP @T6G_MB_LIB.T6G(SCH_1):TDR_DIFF_85_IN1_DP    I90 @T6G_MB_LIB.T6G(SCH_1):PAGE265

X8009 TP_TDR_4P_FTS_TH-TP_TDR_4P_DIP,EMPTY,TP15
     2 T1_GND @T6G_MB_LIB.T6G(SCH_1):T1_GND    I79 @T6G_MB_LIB.T6G(SCH_1):PAGE265
     3 T1_GND @T6G_MB_LIB.T6G(SCH_1):T1_GND    I79 @T6G_MB_LIB.T6G(SCH_1):PAGE265
     1 TDR_DIFF_85_IN2_DN @T6G_MB_LIB.T6G(SCH_1):TDR_DIFF_85_IN2_DN    I79 @T6G_MB_LIB.T6G(SCH_1):PAGE265
     4 TDR_DIFF_85_IN2_DP @T6G_MB_LIB.T6G(SCH_1):TDR_DIFF_85_IN2_DP    I79 @T6G_MB_LIB.T6G(SCH_1):PAGE265

X8010 TP_TDR_4P_FTS_TH-TP_TDR_4P_DIP,EMPTY,TP15
     2 T1_GND @T6G_MB_LIB.T6G(SCH_1):T1_GND    I78 @T6G_MB_LIB.T6G(SCH_1):PAGE265
     3 T1_GND @T6G_MB_LIB.T6G(SCH_1):T1_GND    I78 @T6G_MB_LIB.T6G(SCH_1):PAGE265
     1 TDR_DIFF_85_IN3_DN @T6G_MB_LIB.T6G(SCH_1):TDR_DIFF_85_IN3_DN    I78 @T6G_MB_LIB.T6G(SCH_1):PAGE265
     4 TDR_DIFF_85_IN3_DP @T6G_MB_LIB.T6G(SCH_1):TDR_DIFF_85_IN3_DP    I78 @T6G_MB_LIB.T6G(SCH_1):PAGE265

X8011 TP_TDR_4P_FTS_TH-TP_TDR_4P_DIP,EMPTY,TP15
     2 T1_GND @T6G_MB_LIB.T6G(SCH_1):T1_GND    I76 @T6G_MB_LIB.T6G(SCH_1):PAGE265
     3 T1_GND @T6G_MB_LIB.T6G(SCH_1):T1_GND    I76 @T6G_MB_LIB.T6G(SCH_1):PAGE265
     1 TDR_DIFF_85_IN4_DN @T6G_MB_LIB.T6G(SCH_1):TDR_DIFF_85_IN4_DN    I76 @T6G_MB_LIB.T6G(SCH_1):PAGE265
     4 TDR_DIFF_85_IN4_DP @T6G_MB_LIB.T6G(SCH_1):TDR_DIFF_85_IN4_DP    I76 @T6G_MB_LIB.T6G(SCH_1):PAGE265

X8012 TP_TDR_4P_FTS_TH-TP_TDR_4P_DIP,EMPTY,TP15
     2 T1_GND @T6G_MB_LIB.T6G(SCH_1):T1_GND    I94 @T6G_MB_LIB.T6G(SCH_1):PAGE265
     3 T1_GND @T6G_MB_LIB.T6G(SCH_1):T1_GND    I94 @T6G_MB_LIB.T6G(SCH_1):PAGE265
     1 TDR_DIFF_85_BOT_DN @T6G_MB_LIB.T6G(SCH_1):TDR_DIFF_85_BOT_DN    I94 @T6G_MB_LIB.T6G(SCH_1):PAGE265
     4 TDR_DIFF_85_BOT_DP @T6G_MB_LIB.T6G(SCH_1):TDR_DIFF_85_BOT_DP    I94 @T6G_MB_LIB.T6G(SCH_1):PAGE265

X8025 TP_TDR_4P_FTS_TH-TP_TDR_4P_DIP,EMPTY,TP15
     2 T1_GND @T6G_MB_LIB.T6G(SCH_1):T1_GND    I60 @T6G_MB_LIB.T6G(SCH_1):PAGE265
     3 T1_GND @T6G_MB_LIB.T6G(SCH_1):T1_GND    I60 @T6G_MB_LIB.T6G(SCH_1):PAGE265
     1 TDR_DIFF_85_IN5_DP @T6G_MB_LIB.T6G(SCH_1):TDR_DIFF_85_IN5_DP    I60 @T6G_MB_LIB.T6G(SCH_1):PAGE265
     4 TDR_DIFF_85_IN5_DN @T6G_MB_LIB.T6G(SCH_1):TDR_DIFF_85_IN5_DN    I60 @T6G_MB_LIB.T6G(SCH_1):PAGE265

X8026 TP_TDR_4P_FTS_TH-TP_TDR_4P_DIP,EMPTY,TP15
     2 T1_GND @T6G_MB_LIB.T6G(SCH_1):T1_GND    I58 @T6G_MB_LIB.T6G(SCH_1):PAGE265
     3 T1_GND @T6G_MB_LIB.T6G(SCH_1):T1_GND    I58 @T6G_MB_LIB.T6G(SCH_1):PAGE265
     1 TDR_DIFF_85_IN6_DP @T6G_MB_LIB.T6G(SCH_1):TDR_DIFF_85_IN6_DP    I58 @T6G_MB_LIB.T6G(SCH_1):PAGE265
     4 TDR_DIFF_85_IN6_DN @T6G_MB_LIB.T6G(SCH_1):TDR_DIFF_85_IN6_DN    I58 @T6G_MB_LIB.T6G(SCH_1):PAGE265

X8027 TP_TDR_4P_FTS_TH-TP_TDR_4P_DIP,EMPTY,TP15
     2 T1_GND @T6G_MB_LIB.T6G(SCH_1):T1_GND    I74 @T6G_MB_LIB.T6G(SCH_1):PAGE265
     3 T1_GND @T6G_MB_LIB.T6G(SCH_1):T1_GND    I74 @T6G_MB_LIB.T6G(SCH_1):PAGE265
     1 TDR_DIFF_85_IN5_DN @T6G_MB_LIB.T6G(SCH_1):TDR_DIFF_85_IN5_DN    I74 @T6G_MB_LIB.T6G(SCH_1):PAGE265
     4 TDR_DIFF_85_IN5_DP @T6G_MB_LIB.T6G(SCH_1):TDR_DIFF_85_IN5_DP    I74 @T6G_MB_LIB.T6G(SCH_1):PAGE265

X8028 TP_TDR_4P_FTS_TH-TP_TDR_4P_DIP,EMPTY,TP15
     2 T1_GND @T6G_MB_LIB.T6G(SCH_1):T1_GND    I73 @T6G_MB_LIB.T6G(SCH_1):PAGE265
     3 T1_GND @T6G_MB_LIB.T6G(SCH_1):T1_GND    I73 @T6G_MB_LIB.T6G(SCH_1):PAGE265
     1 TDR_DIFF_85_IN6_DN @T6G_MB_LIB.T6G(SCH_1):TDR_DIFF_85_IN6_DN    I73 @T6G_MB_LIB.T6G(SCH_1):PAGE265
     4 TDR_DIFF_85_IN6_DP @T6G_MB_LIB.T6G(SCH_1):TDR_DIFF_85_IN6_DP    I73 @T6G_MB_LIB.T6G(SCH_1):PAGE265

X9002 TP_TDR_4P_FTS_TH-TP_TDR_4P_DIP,EMPTY,TP15
     2 T1_GND @T6G_MB_LIB.T6G(SCH_1):T1_GND    I12 @T6G_MB_LIB.T6G(SCH_1):PAGE266
     3 T1_GND @T6G_MB_LIB.T6G(SCH_1):T1_GND    I12 @T6G_MB_LIB.T6G(SCH_1):PAGE266
     1 TDR_DIFF_85_NECK_IN1_DP @T6G_MB_LIB.T6G(SCH_1):TDR_DIFF_85_NECK_IN1_DP    I12 @T6G_MB_LIB.T6G(SCH_1):PAGE266
     4 TDR_DIFF_85_NECK_IN1_DN @T6G_MB_LIB.T6G(SCH_1):TDR_DIFF_85_NECK_IN1_DN    I12 @T6G_MB_LIB.T6G(SCH_1):PAGE266

X9003 TP_TDR_4P_FTS_TH-TP_TDR_4P_DIP,EMPTY,TP15
     2 T1_GND @T6G_MB_LIB.T6G(SCH_1):T1_GND    I10 @T6G_MB_LIB.T6G(SCH_1):PAGE266
     3 T1_GND @T6G_MB_LIB.T6G(SCH_1):T1_GND    I10 @T6G_MB_LIB.T6G(SCH_1):PAGE266
     1 TDR_DIFF_85_NECK_IN2_DP @T6G_MB_LIB.T6G(SCH_1):TDR_DIFF_85_NECK_IN2_DP    I10 @T6G_MB_LIB.T6G(SCH_1):PAGE266
     4 TDR_DIFF_85_NECK_IN2_DN @T6G_MB_LIB.T6G(SCH_1):TDR_DIFF_85_NECK_IN2_DN    I10 @T6G_MB_LIB.T6G(SCH_1):PAGE266

X9004 TP_TDR_4P_FTS_TH-TP_TDR_4P_DIP,EMPTY,TP15
     2 T1_GND @T6G_MB_LIB.T6G(SCH_1):T1_GND     I8 @T6G_MB_LIB.T6G(SCH_1):PAGE266
     3 T1_GND @T6G_MB_LIB.T6G(SCH_1):T1_GND     I8 @T6G_MB_LIB.T6G(SCH_1):PAGE266
     1 TDR_DIFF_85_NECK_IN3_DP @T6G_MB_LIB.T6G(SCH_1):TDR_DIFF_85_NECK_IN3_DP     I8 @T6G_MB_LIB.T6G(SCH_1):PAGE266
     4 TDR_DIFF_85_NECK_IN3_DN @T6G_MB_LIB.T6G(SCH_1):TDR_DIFF_85_NECK_IN3_DN     I8 @T6G_MB_LIB.T6G(SCH_1):PAGE266

X9005 TP_TDR_4P_FTS_TH-TP_TDR_4P_DIP,EMPTY,TP15
     2 T1_GND @T6G_MB_LIB.T6G(SCH_1):T1_GND     I7 @T6G_MB_LIB.T6G(SCH_1):PAGE266
     3 T1_GND @T6G_MB_LIB.T6G(SCH_1):T1_GND     I7 @T6G_MB_LIB.T6G(SCH_1):PAGE266
     1 TDR_DIFF_85_NECK_IN4_DP @T6G_MB_LIB.T6G(SCH_1):TDR_DIFF_85_NECK_IN4_DP     I7 @T6G_MB_LIB.T6G(SCH_1):PAGE266
     4 TDR_DIFF_85_NECK_IN4_DN @T6G_MB_LIB.T6G(SCH_1):TDR_DIFF_85_NECK_IN4_DN     I7 @T6G_MB_LIB.T6G(SCH_1):PAGE266

X9008 TP_TDR_4P_FTS_TH-TP_TDR_4P_DIP,EMPTY,TP15
     2 T1_GND @T6G_MB_LIB.T6G(SCH_1):T1_GND    I38 @T6G_MB_LIB.T6G(SCH_1):PAGE266
     3 T1_GND @T6G_MB_LIB.T6G(SCH_1):T1_GND    I38 @T6G_MB_LIB.T6G(SCH_1):PAGE266
     1 TDR_DIFF_85_NECK_IN1_DN @T6G_MB_LIB.T6G(SCH_1):TDR_DIFF_85_NECK_IN1_DN    I38 @T6G_MB_LIB.T6G(SCH_1):PAGE266
     4 TDR_DIFF_85_NECK_IN1_DP @T6G_MB_LIB.T6G(SCH_1):TDR_DIFF_85_NECK_IN1_DP    I38 @T6G_MB_LIB.T6G(SCH_1):PAGE266

X9009 TP_TDR_4P_FTS_TH-TP_TDR_4P_DIP,EMPTY,TP15
     2 T1_GND @T6G_MB_LIB.T6G(SCH_1):T1_GND    I37 @T6G_MB_LIB.T6G(SCH_1):PAGE266
     3 T1_GND @T6G_MB_LIB.T6G(SCH_1):T1_GND    I37 @T6G_MB_LIB.T6G(SCH_1):PAGE266
     1 TDR_DIFF_85_NECK_IN2_DN @T6G_MB_LIB.T6G(SCH_1):TDR_DIFF_85_NECK_IN2_DN    I37 @T6G_MB_LIB.T6G(SCH_1):PAGE266
     4 TDR_DIFF_85_NECK_IN2_DP @T6G_MB_LIB.T6G(SCH_1):TDR_DIFF_85_NECK_IN2_DP    I37 @T6G_MB_LIB.T6G(SCH_1):PAGE266

X9010 TP_TDR_4P_FTS_TH-TP_TDR_4P_DIP,EMPTY,TP15
     2 T1_GND @T6G_MB_LIB.T6G(SCH_1):T1_GND    I16 @T6G_MB_LIB.T6G(SCH_1):PAGE266
     3 T1_GND @T6G_MB_LIB.T6G(SCH_1):T1_GND    I16 @T6G_MB_LIB.T6G(SCH_1):PAGE266
     1 TDR_DIFF_85_NECK_IN3_DN @T6G_MB_LIB.T6G(SCH_1):TDR_DIFF_85_NECK_IN3_DN    I16 @T6G_MB_LIB.T6G(SCH_1):PAGE266
     4 TDR_DIFF_85_NECK_IN3_DP @T6G_MB_LIB.T6G(SCH_1):TDR_DIFF_85_NECK_IN3_DP    I16 @T6G_MB_LIB.T6G(SCH_1):PAGE266

X9011 TP_TDR_4P_FTS_TH-TP_TDR_4P_DIP,EMPTY,TP15
     2 T1_GND @T6G_MB_LIB.T6G(SCH_1):T1_GND    I17 @T6G_MB_LIB.T6G(SCH_1):PAGE266
     3 T1_GND @T6G_MB_LIB.T6G(SCH_1):T1_GND    I17 @T6G_MB_LIB.T6G(SCH_1):PAGE266
     1 TDR_DIFF_85_NECK_IN4_DN @T6G_MB_LIB.T6G(SCH_1):TDR_DIFF_85_NECK_IN4_DN    I17 @T6G_MB_LIB.T6G(SCH_1):PAGE266
     4 TDR_DIFF_85_NECK_IN4_DP @T6G_MB_LIB.T6G(SCH_1):TDR_DIFF_85_NECK_IN4_DP    I17 @T6G_MB_LIB.T6G(SCH_1):PAGE266

X9025 TP_TDR_4P_FTS_TH-TP_TDR_4P_DIP,EMPTY,TP15
     2 T1_GND @T6G_MB_LIB.T6G(SCH_1):T1_GND     I4 @T6G_MB_LIB.T6G(SCH_1):PAGE266
     3 T1_GND @T6G_MB_LIB.T6G(SCH_1):T1_GND     I4 @T6G_MB_LIB.T6G(SCH_1):PAGE266
     1 TDR_DIFF_85_NECK_IN5_DP @T6G_MB_LIB.T6G(SCH_1):TDR_DIFF_85_NECK_IN5_DP     I4 @T6G_MB_LIB.T6G(SCH_1):PAGE266
     4 TDR_DIFF_85_NECK_IN5_DN @T6G_MB_LIB.T6G(SCH_1):TDR_DIFF_85_NECK_IN5_DN     I4 @T6G_MB_LIB.T6G(SCH_1):PAGE266

X9026 TP_TDR_4P_FTS_TH-TP_TDR_4P_DIP,EMPTY,TP15
     2 T1_GND @T6G_MB_LIB.T6G(SCH_1):T1_GND     I2 @T6G_MB_LIB.T6G(SCH_1):PAGE266
     3 T1_GND @T6G_MB_LIB.T6G(SCH_1):T1_GND     I2 @T6G_MB_LIB.T6G(SCH_1):PAGE266
     1 TDR_DIFF_85_NECK_IN6_DP @T6G_MB_LIB.T6G(SCH_1):TDR_DIFF_85_NECK_IN6_DP     I2 @T6G_MB_LIB.T6G(SCH_1):PAGE266
     4 TDR_DIFF_85_NECK_IN6_DN @T6G_MB_LIB.T6G(SCH_1):TDR_DIFF_85_NECK_IN6_DN     I2 @T6G_MB_LIB.T6G(SCH_1):PAGE266

X9027 TP_TDR_4P_FTS_TH-TP_TDR_4P_DIP,EMPTY,TP15
     2 T1_GND @T6G_MB_LIB.T6G(SCH_1):T1_GND    I15 @T6G_MB_LIB.T6G(SCH_1):PAGE266
     3 T1_GND @T6G_MB_LIB.T6G(SCH_1):T1_GND    I15 @T6G_MB_LIB.T6G(SCH_1):PAGE266
     1 TDR_DIFF_85_NECK_IN5_DN @T6G_MB_LIB.T6G(SCH_1):TDR_DIFF_85_NECK_IN5_DN    I15 @T6G_MB_LIB.T6G(SCH_1):PAGE266
     4 TDR_DIFF_85_NECK_IN5_DP @T6G_MB_LIB.T6G(SCH_1):TDR_DIFF_85_NECK_IN5_DP    I15 @T6G_MB_LIB.T6G(SCH_1):PAGE266

X9028 TP_TDR_4P_FTS_TH-TP_TDR_4P_DIP,EMPTY,TP15
     2 T1_GND @T6G_MB_LIB.T6G(SCH_1):T1_GND    I13 @T6G_MB_LIB.T6G(SCH_1):PAGE266
     3 T1_GND @T6G_MB_LIB.T6G(SCH_1):T1_GND    I13 @T6G_MB_LIB.T6G(SCH_1):PAGE266
     1 TDR_DIFF_85_NECK_IN6_DN @T6G_MB_LIB.T6G(SCH_1):TDR_DIFF_85_NECK_IN6_DN    I13 @T6G_MB_LIB.T6G(SCH_1):PAGE266
     4 TDR_DIFF_85_NECK_IN6_DP @T6G_MB_LIB.T6G(SCH_1):TDR_DIFF_85_NECK_IN6_DP    I13 @T6G_MB_LIB.T6G(SCH_1):PAGE266

  Y2 Q_XTAL_4P_13BI_24GND-48MHZ,SMLF,MISC,BG648000076
     1 XTAL_CPU0_X48M_X1 @T6G_MB_LIB.T6G(SCH_1):XTAL_CPU0_X48M_X1   I103 @T6G_MB_LIB.T6G(SCH_1):PAGE28
     2    GND @T6G_MB_LIB.T6G(SCH_1):GND   I103 @T6G_MB_LIB.T6G(SCH_1):PAGE28
     4    GND @T6G_MB_LIB.T6G(SCH_1):GND   I103 @T6G_MB_LIB.T6G(SCH_1):PAGE28
     3 XTAL_CPU0_X48M_X2_R @T6G_MB_LIB.T6G(SCH_1):XTAL_CPU0_X48M_X2_R   I103 @T6G_MB_LIB.T6G(SCH_1):PAGE28

  Y3 Q_CRYSTAL_SMLF-32.768KHZ,IC,BG632768012
     1 XTAL_CPU0_X32K_X1 @T6G_MB_LIB.T6G(SCH_1):XTAL_CPU0_X32K_X1   I140 @T6G_MB_LIB.T6G(SCH_1):PAGE28
     2 XTAL_CPU0_X32K_X2 @T6G_MB_LIB.T6G(SCH_1):XTAL_CPU0_X32K_X2   I140 @T6G_MB_LIB.T6G(SCH_1):PAGE28

  Y4 Q_XTAL_4P_13BI_24GND-48MHZ,SMLF,MISC,BG648000076
     1 XTAL_CPU1_X48M_X1 @T6G_MB_LIB.T6G(SCH_1):XTAL_CPU1_X48M_X1    I12 @T6G_MB_LIB.T6G(SCH_1):PAGE55
     2    GND @T6G_MB_LIB.T6G(SCH_1):GND    I12 @T6G_MB_LIB.T6G(SCH_1):PAGE55
     4    GND @T6G_MB_LIB.T6G(SCH_1):GND    I12 @T6G_MB_LIB.T6G(SCH_1):PAGE55
     3 XTAL_CPU1_X48M_X2_R @T6G_MB_LIB.T6G(SCH_1):XTAL_CPU1_X48M_X2_R    I12 @T6G_MB_LIB.T6G(SCH_1):PAGE55

  Y5 Q_CRYSTAL_SMLF-32.768KHZ,EMPTY,BG632768012
     1 XTAL_CPU1_R_X32K_X1 @T6G_MB_LIB.T6G(SCH_1):XTAL_CPU1_R_X32K_X1     I7 @T6G_MB_LIB.T6G(SCH_1):PAGE55
     2 XTAL_CPU1_R_X32K_X2 @T6G_MB_LIB.T6G(SCH_1):XTAL_CPU1_R_X32K_X2     I7 @T6G_MB_LIB.T6G(SCH_1):PAGE55

  Y9 Q_XTAL_4P_13BI_24GND-26MHZ,SMLF,MISC,BG626000049
     1 XTAL_USB_CPU0_HUB1_XIN @T6G_MB_LIB.T6G(SCH_1):XTAL_USB_CPU0_HUB1_XIN    I14 @T6G_MB_LIB.T6G(SCH_1):PAGE153
     2    GND @T6G_MB_LIB.T6G(SCH_1):GND    I14 @T6G_MB_LIB.T6G(SCH_1):PAGE153
     4    GND @T6G_MB_LIB.T6G(SCH_1):GND    I14 @T6G_MB_LIB.T6G(SCH_1):PAGE153
     3 XTAL_USB_CPU0_HUB1_XOUT @T6G_MB_LIB.T6G(SCH_1):XTAL_USB_CPU0_HUB1_XOUT    I14 @T6G_MB_LIB.T6G(SCH_1):PAGE153

Y6000 Q_XTAL_4P_13BI_24GND-24MHZ,SMLF,MISC,BG624000101
     1 XTAL_USB_CPU0_HUB2_XIN @T6G_MB_LIB.T6G(SCH_1):XTAL_USB_CPU0_HUB2_XIN   I164 @T6G_MB_LIB.T6G(SCH_1):PAGE157
     2    GND @T6G_MB_LIB.T6G(SCH_1):GND   I164 @T6G_MB_LIB.T6G(SCH_1):PAGE157
     4    GND @T6G_MB_LIB.T6G(SCH_1):GND   I164 @T6G_MB_LIB.T6G(SCH_1):PAGE157
     3 XTAL_USB_CPU0_HUB2_XOUT @T6G_MB_LIB.T6G(SCH_1):XTAL_USB_CPU0_HUB2_XOUT   I164 @T6G_MB_LIB.T6G(SCH_1):PAGE157

Y8003 Q_XTAL_4P_13BI_24GND-25MHZ,SMLF,MISC,BG6250000L4
     1 CLK_GEN2_XTAL_IN_R @T6G_MB_LIB.T6G(SCH_1):CLK_GEN2_XTAL_IN_R    I14 @T6G_MB_LIB.T6G(SCH_1):PAGE232
     2    GND @T6G_MB_LIB.T6G(SCH_1):GND    I14 @T6G_MB_LIB.T6G(SCH_1):PAGE232
     4    GND @T6G_MB_LIB.T6G(SCH_1):GND    I14 @T6G_MB_LIB.T6G(SCH_1):PAGE232
     3 CLK_GEN2_XTAL_OUT @T6G_MB_LIB.T6G(SCH_1):CLK_GEN2_XTAL_OUT    I14 @T6G_MB_LIB.T6G(SCH_1):PAGE232

Y8004 Q_XTAL_4P_13BI_24GND-12MHZ,SMLF,MISC,BG6120000B0
     1 USB_HUB_XTAL_IN @T6G_MB_LIB.T6G(SCH_1):USB_HUB_XTAL_IN   I210 @T6G_MB_LIB.T6G(SCH_1):PAGE358
     2    GND @T6G_MB_LIB.T6G(SCH_1):GND   I210 @T6G_MB_LIB.T6G(SCH_1):PAGE358
     4    GND @T6G_MB_LIB.T6G(SCH_1):GND   I210 @T6G_MB_LIB.T6G(SCH_1):PAGE358
     3 USB_HUB_XTAL_OUT @T6G_MB_LIB.T6G(SCH_1):USB_HUB_XTAL_OUT   I210 @T6G_MB_LIB.T6G(SCH_1):PAGE358

END GLOBAL PART CROSS REFERENCE
